( ConstraintFile "baseboard_fab2"
	( constraintHeader
		( objectKey
			( logical )
		)
		( version
			( 16.6 )
		)
		( revisionNumber
			( logicalViewRevNum 4375 )
			( physicalViewRevNum 0 )
			( otherViewRevNum 0 )
		)
		( contents
			( dictionaryExtensions )
			( worksheetCustomizations )
			( electricalConstraints )
			( netClasses )
			( properties )
		)
		( precision
			( units mil )
			( numberOfDecimalPlaces 2 )
		)
	)
	( DictionaryExtensions
		( Attribute
			( Name "BOM_COST" )
			( Description " " )
			( Value
				( DataType ( dString ) )
				( Status  sProperty  sPackage )
			)
			( Objects
				( ValidObjects  oGate  oGateDefn  oBlock  oPart  oDesign  oSystem  oPartDefn  oNet )
				( NoInherit
					( oGate oPin )
				)
			)
			( Analysis
			)
		)
		( Attribute
			( Name "MATERIAL" )
			( Description " " )
			( Value
				( DataType ( dString ) )
				( Status  sProperty  sPackage )
			)
			( Objects
				( ValidObjects  oGate  oGateDefn  oBlock  oPart  oDesign  oSystem  oPartDefn )
				( NoInherit
					( oGate oPin )
				)
			)
			( Analysis
			)
		)
		( Attribute
			( Name "SEC_TYPE" )
			( Description " " )
			( Value
				( DataType ( dString ) )
				( Status  sProperty  sPackage )
			)
			( Objects
				( ValidObjects  oGate  oGateDefn  oBlock  oPart  oDesign  oSystem  oPartDefn )
				( NoInherit
					( oGate oPin )
				)
			)
			( Analysis
			)
		)
		( Attribute
			( Name "TOLERANCE" )
			( Description " " )
			( Value
				( DataType ( dString ) )
				( Status  sProperty  sPackage )
			)
			( Objects
				( ValidObjects  oGate  oGateDefn  oBlock  oPart  oDesign  oSystem  oPartDefn )
				( NoInherit
					( oGate oPin )
				)
			)
			( Analysis
			)
		)
		( Attribute
			( Name "WATTAGE" )
			( Description " " )
			( Value
				( DataType ( dString ) )
				( Status  sProperty  sPackage )
			)
			( Objects
				( ValidObjects  oGate  oGateDefn  oBlock  oPart  oDesign  oSystem  oPartDefn )
				( NoInherit
					( oGate oPin )
				)
			)
			( Analysis
			)
		)
		( Attribute
			( Name "SKT_NUMBER" )
			( Description " " )
			( Value
				( DataType ( dString ) )
				( Status  sProperty  sPackage )
			)
			( Objects
				( ValidObjects  oGate  oGateDefn  oBlock  oPart  oDesign  oSystem  oPartDefn )
				( NoInherit
					( oGate oPin )
				)
			)
			( Analysis
			)
		)
		( Attribute
			( Name "CD_SEC" )
			( Description " " )
			( Value
				( DataType ( dString ) )
				( Status  sProperty  sPackage )
			)
			( Objects
				( ValidObjects  oGate  oGateDefn  oBlock  oPart  oDesign  oSystem  oPartDefn )
				( NoInherit
					( oGate oPin )
				)
			)
			( Analysis
			)
		)
		( Attribute
			( Name "CDS_LMAN_SYM_OUTLINE" )
			( Description " " )
			( Value
				( DataType ( dString ) )
				( Status  sProperty  sPackage )
			)
			( Objects
				( ValidObjects  oGate  oGateDefn  oBlock  oPart  oDesign  oSystem  oPartDefn )
				( NoInherit
					( oGate oPin )
				)
			)
			( Analysis
			)
		)
		( Attribute
			( Name "SKU" )
			( Description " " )
			( Value
				( DataType ( dString ) )
				( Status  sProperty  sPackage )
			)
			( Objects
				( ValidObjects  oGate  oGateDefn  oBlock  oPart  oDesign  oSystem  oPartDefn )
				( NoInherit
					( oGate oPin )
				)
			)
			( Analysis
			)
		)
		( Attribute
			( Name "COLOR" )
			( Description " " )
			( Value
				( DataType ( dString ) )
				( Status  sProperty  sPackage )
			)
			( Objects
				( ValidObjects  oGate  oGateDefn  oBlock  oPart  oDesign  oSystem  oPartDefn )
				( NoInherit
					( oGate oPin )
				)
			)
			( Analysis
			)
		)
		( Attribute
			( Name "VOLATGE" )
			( Description " " )
			( Value
				( DataType ( dString ) )
				( Status  sProperty  sPackage )
			)
			( Objects
				( ValidObjects  oNet  oXnet  oPinPair  oBus  oDiffPair  oECSet )
			)
			( Analysis
			)
		)
		( Attribute
			( Name "SPOF" )
			( Description " " )
			( Value
				( DataType ( dString ) )
				( Status  sProperty  sPackage )
			)
			( Objects
				( ValidObjects  oGate  oGateDefn  oBlock  oPart  oDesign  oSystem  oPartDefn )
				( NoInherit
					( oGate oPin )
				)
			)
			( Analysis
			)
		)
		( Attribute
			( Name "PIN_SHORT" )
			( Description " " )
			( Value
				( DataType ( dString ) )
				( Status  sProperty  sPackage )
			)
			( Objects
				( ValidObjects  oGate  oGateDefn  oBlock  oPart  oDesign  oSystem  oPartDefn )
				( NoInherit
					( oGate oPin )
				)
			)
			( Analysis
			)
		)
		( Attribute
			( Name "BOM" )
			( Description " " )
			( Value
				( DataType ( dString ) )
				( Status  sProperty  sPackage )
			)
			( Objects
				( ValidObjects  oGate  oGateDefn  oBlock  oPart  oDesign  oSystem  oPartDefn )
				( NoInherit
					( oGate oPin )
				)
			)
			( Analysis
			)
		)
		( Attribute
			( Name "FIN" )
			( Description " " )
			( Value
				( DataType ( dString ) )
				( Status  sProperty  sPackage )
			)
			( Objects
				( ValidObjects  oGate  oGateDefn  oBlock  oPart  oDesign  oSystem  oPartDefn )
				( NoInherit
					( oGate oPin )
				)
			)
			( Analysis
			)
		)
		( Attribute
			( Name "P1V5_STBY_IBMC" )
			( Description " " )
			( Value
				( DataType ( dString ) )
				( Status  sProperty  sPackage )
			)
			( Objects
				( ValidObjects  oGate  oGateDefn  oBlock  oPart  oDesign  oSystem  oPartDefn )
				( NoInherit
					( oGate oPin )
				)
			)
			( Analysis
			)
		)
		( Attribute
			( Name "P1V5_STBY_IBMC_VR" )
			( Description " " )
			( Value
				( DataType ( dString ) )
				( Status  sProperty  sPackage )
			)
			( Objects
				( ValidObjects  oGate  oGateDefn  oBlock  oPart  oDesign  oSystem  oPartDefn )
				( NoInherit
					( oGate oPin )
				)
			)
			( Analysis
			)
		)
		( Attribute
			( Name "DIMMSIED" )
			( Description " " )
			( Value
				( DataType ( dString ) )
				( Status  sProperty  sPackage )
			)
			( Objects
				( ValidObjects  oGate  oGateDefn  oBlock  oPart  oDesign  oSystem  oPartDefn )
				( NoInherit
					( oGate oPin )
				)
			)
			( Analysis
			)
		)
		( Attribute
			( Name "DIMMSIDE" )
			( Description " " )
			( Value
				( DataType ( dString ) )
				( Status  sProperty  sPackage )
			)
			( Objects
				( ValidObjects  oGate  oGateDefn  oBlock  oPart  oDesign  oSystem  oPartDefn )
				( NoInherit
					( oGate oPin )
				)
			)
			( Analysis
			)
		)
		( Attribute
			( Name "$location" )
			( Description "" )
			( Value
				( DataType ( dString ) )
				( Status  sProperty )
			)
			( Objects
				( ValidObjects  oAll )
			)
			( Analysis
			)
		)
		( Attribute
			( Name "$sec" )
			( Description "" )
			( Value
				( DataType ( dString ) )
				( Status  sProperty )
			)
			( Objects
				( ValidObjects  oAll )
			)
			( Analysis
			)
		)
		( Attribute
			( Name "RATED_CURRENT" )
			( Description " " )
			( Value
				( DataType ( dString ) )
				( Status  sProperty  sPackage )
			)
			( Objects
				( ValidObjects  oGate  oGateDefn  oBlock  oPart  oDesign  oSystem  oPartDefn )
				( NoInherit
					( oGate oPin )
				)
			)
			( Analysis
			)
		)
		( Attribute
			( Name "STATUS" )
			( Description " " )
			( Value
				( DataType ( dString ) )
				( Status  sProperty  sPackage )
			)
			( Objects
				( ValidObjects  oGate  oGateDefn  oBlock  oPart  oDesign  oSystem  oPartDefn )
				( NoInherit
					( oGate oPin )
				)
			)
			( Analysis
			)
		)
		( Attribute
			( Name "STTATUS" )
			( Description " " )
			( Value
				( DataType ( dString ) )
				( Status  sProperty  sPackage )
			)
			( Objects
				( ValidObjects  oGate  oGateDefn  oBlock  oPart  oDesign  oSystem  oPartDefn )
				( NoInherit
					( oGate oPin )
				)
			)
			( Analysis
			)
		)
		( Attribute
			( Name "SIDE_SKU" )
			( Description " " )
			( Value
				( DataType ( dString ) )
				( Status  sProperty  sPackage )
			)
			( Objects
				( ValidObjects  oGate  oGateDefn  oBlock  oPart  oDesign  oSystem  oPartDefn )
				( NoInherit
					( oGate oPin )
				)
			)
			( Analysis
			)
		)
		( Attribute
			( Name "POP" )
			( Description " " )
			( Value
				( DataType ( dString ) )
				( Status  sProperty  sPackage )
			)
			( Objects
				( ValidObjects  oGate  oGateDefn  oBlock  oPart  oDesign  oSystem  oPartDefn )
				( NoInherit
					( oGate oPin )
				)
			)
			( Analysis
			)
		)
		( Attribute
			( Name "CONFIG" )
			( Description " " )
			( Value
				( DataType ( dString ) )
				( Status  sProperty  sPackage )
			)
			( Objects
				( ValidObjects  oGate  oGateDefn  oBlock  oPart  oDesign  oSystem  oPartDefn )
				( NoInherit
					( oGate oPin )
				)
			)
			( Analysis
			)
		)
		( Attribute
			( Name "BOM_SS_CAP" )
			( Description " " )
			( Value
				( DataType ( dString ) )
				( Status  sProperty  sPackage )
			)
			( Objects
				( ValidObjects  oGate  oGateDefn  oBlock  oPart  oDesign  oSystem  oPartDefn )
				( NoInherit
					( oGate oPin )
				)
			)
			( Analysis
			)
		)
		( Attribute
			( Name "NOPOP" )
			( Description " " )
			( Value
				( DataType ( dString ) )
				( Status  sProperty  sPackage )
			)
			( Objects
				( ValidObjects  oGate  oGateDefn  oBlock  oPart  oDesign  oSystem  oPartDefn )
				( NoInherit
					( oGate oPin )
				)
			)
			( Analysis
			)
		)
		( Attribute
			( Name "MODULE" )
			( Description " " )
			( Value
				( DataType ( dString ) )
				( Status  sProperty  sPackage )
			)
			( Objects
				( ValidObjects  oGate  oGateDefn  oBlock  oPart  oDesign  oSystem  oPartDefn )
				( NoInherit
					( oGate oPin )
				)
			)
			( Analysis
			)
		)
		( Attribute
			( Name "BOM_DS" )
			( Description " " )
			( Value
				( DataType ( dString ) )
				( Status  sProperty  sPackage )
			)
			( Objects
				( ValidObjects  oGate  oGateDefn  oBlock  oPart  oDesign  oSystem  oPartDefn )
				( NoInherit
					( oGate oPin )
				)
			)
			( Analysis
			)
		)
		( Attribute
			( Name "BOM_SS" )
			( Description " " )
			( Value
				( DataType ( dString ) )
				( Status  sProperty  sPackage )
			)
			( Objects
				( ValidObjects  oGate  oGateDefn  oBlock  oPart  oDesign  oSystem  oPartDefn )
				( NoInherit
					( oGate oPin )
				)
			)
			( Analysis
			)
		)
		( Attribute
			( Name "ATTRIBUTE" )
			( Description " " )
			( Value
				( DataType ( dString ) )
				( Status  sProperty  sPackage )
			)
			( Objects
				( ValidObjects  oGate  oGateDefn  oBlock  oPart  oDesign  oSystem  oPartDefn )
				( NoInherit
					( oGate oPin )
				)
			)
			( Analysis
			)
		)
		( Attribute
			( Name "RATED" )
			( Description " " )
			( Value
				( DataType ( dString ) )
				( Status  sProperty  sPackage )
			)
			( Objects
				( ValidObjects  oGate  oGateDefn  oBlock  oPart  oDesign  oSystem  oPartDefn )
				( NoInherit
					( oGate oPin )
				)
			)
			( Analysis
			)
		)
		( Attribute
			( Name "PACK_SIZE" )
			( Description " " )
			( Value
				( DataType ( dString ) )
				( Status  sProperty  sPackage )
			)
			( Objects
				( ValidObjects  oGate  oGateDefn  oBlock  oPart  oDesign  oSystem  oPartDefn )
				( NoInherit
					( oGate oPin )
				)
			)
			( Analysis
			)
		)
		( Attribute
			( Name "TYPE" )
			( Description " " )
			( Value
				( DataType ( dString ) )
				( Status  sProperty  sPackage )
			)
			( Objects
				( ValidObjects  oGate  oGateDefn  oBlock  oPart  oDesign  oSystem  oPartDefn )
				( NoInherit
					( oGate oPin )
				)
			)
			( Analysis
			)
		)
		( Attribute
			( Name "NEW_VALUE" )
			( Description " " )
			( Value
				( DataType ( dString ) )
				( Status  sProperty  sPackage )
			)
			( Objects
				( ValidObjects  oGate  oGateDefn  oBlock  oPart  oDesign  oSystem  oPartDefn )
				( NoInherit
					( oGate oPin )
				)
			)
			( Analysis
			)
		)
		( Attribute
			( Name "NEW_PACK_SIZE" )
			( Description " " )
			( Value
				( DataType ( dString ) )
				( Status  sProperty  sPackage )
			)
			( Objects
				( ValidObjects  oGate  oGateDefn  oBlock  oPart  oDesign  oSystem  oPartDefn )
				( NoInherit
					( oGate oPin )
				)
			)
			( Analysis
			)
		)
		( Attribute
			( Name "NEW_RATED" )
			( Description " " )
			( Value
				( DataType ( dString ) )
				( Status  sProperty  sPackage )
			)
			( Objects
				( ValidObjects  oGate  oGateDefn  oBlock  oPart  oDesign  oSystem  oPartDefn )
				( NoInherit
					( oGate oPin )
				)
			)
			( Analysis
			)
		)
		( Attribute
			( Name "NEW_TYPE" )
			( Description " " )
			( Value
				( DataType ( dString ) )
				( Status  sProperty  sPackage )
			)
			( Objects
				( ValidObjects  oGate  oGateDefn  oBlock  oPart  oDesign  oSystem  oPartDefn )
				( NoInherit
					( oGate oPin )
				)
			)
			( Analysis
			)
		)
		( Attribute
			( Name "NEW_MATERIAL" )
			( Description " " )
			( Value
				( DataType ( dString ) )
				( Status  sProperty  sPackage )
			)
			( Objects
				( ValidObjects  oGate  oGateDefn  oBlock  oPart  oDesign  oSystem  oPartDefn )
				( NoInherit
					( oGate oPin )
				)
			)
			( Analysis
			)
		)
		( Attribute
			( Name "NEW_SIZE" )
			( Description " " )
			( Value
				( DataType ( dString ) )
				( Status  sProperty  sPackage )
			)
			( Objects
				( ValidObjects  oGate  oGateDefn  oBlock  oPart  oDesign  oSystem  oPartDefn )
				( NoInherit
					( oGate oPin )
				)
			)
			( Analysis
			)
		)
		( Attribute
			( Name "NEW_PN" )
			( Description " " )
			( Value
				( DataType ( dString ) )
				( Status  sProperty  sPackage )
			)
			( Objects
				( ValidObjects  oGate  oGateDefn  oBlock  oPart  oDesign  oSystem  oPartDefn )
				( NoInherit
					( oGate oPin )
				)
			)
			( Analysis
			)
		)
		( Attribute
			( Name "SS_VALUE" )
			( Description " " )
			( Value
				( DataType ( dString ) )
				( Status  sProperty  sPackage )
			)
			( Objects
				( ValidObjects  oGate  oGateDefn  oBlock  oPart  oDesign  oSystem  oPartDefn )
				( NoInherit
					( oGate oPin )
				)
			)
			( Analysis
			)
		)
		( Attribute
			( Name "DS_VALUE" )
			( Description " " )
			( Value
				( DataType ( dString ) )
				( Status  sProperty  sPackage )
			)
			( Objects
				( ValidObjects  oGate  oGateDefn  oBlock  oPart  oDesign  oSystem  oPartDefn )
				( NoInherit
					( oGate oPin )
				)
			)
			( Analysis
			)
		)
		( Attribute
			( Name "SS_ISAT" )
			( Description " " )
			( Value
				( DataType ( dString ) )
				( Status  sProperty  sPackage )
			)
			( Objects
				( ValidObjects  oGate  oGateDefn  oBlock  oPart  oDesign  oSystem  oPartDefn )
				( NoInherit
					( oGate oPin )
				)
			)
			( Analysis
			)
		)
		( Attribute
			( Name "FAIR_SS" )
			( Description " " )
			( Value
				( DataType ( dString ) )
				( Status  sProperty  sPackage )
			)
			( Objects
				( ValidObjects  oGate  oGateDefn  oBlock  oPart  oDesign  oSystem  oPartDefn )
				( NoInherit
					( oGate oPin )
				)
			)
			( Analysis
			)
		)
	)
	( designConstraints
		( ruleChanges
			( allRules )
			( design "baseboard_fab2"
				( attribute "CDS_EXPORT_CONTENTS_MASK" "33330"
				)
				( attribute "CDS_EDIT_PNS_STATUS" "1"
					( Origin gFrontEnd )
				)
			)
			( signal "@baseboard_fab2_lib.baseboard_fab2(sch_1):a_cpu0_abc_rcomp0"
				( attribute "CDS_PHYS_NET_NAME" "A_CPU0_ABC_RCOMP0"
					( Origin gPackager )
				)
				( objectStatus "A_CPU0_ABC_RCOMP0" )
			)
			( signal "@baseboard_fab2_lib.baseboard_fab2(sch_1):a_cpu0_abc_rcomp1"
				( attribute "CDS_PHYS_NET_NAME" "A_CPU0_ABC_RCOMP1"
					( Origin gPackager )
				)
				( objectStatus "A_CPU0_ABC_RCOMP1" )
			)
			( signal "@baseboard_fab2_lib.baseboard_fab2(sch_1):a_cpu0_abc_rcomp2"
				( attribute "CDS_PHYS_NET_NAME" "A_CPU0_ABC_RCOMP2"
					( Origin gPackager )
				)
				( objectStatus "A_CPU0_ABC_RCOMP2" )
			)
			( signal "@baseboard_fab2_lib.baseboard_fab2(sch_1):a_cpu0_def_rcomp0"
				( attribute "CDS_PHYS_NET_NAME" "A_CPU0_DEF_RCOMP0"
					( Origin gPackager )
				)
				( objectStatus "A_CPU0_DEF_RCOMP0" )
			)
			( signal "@baseboard_fab2_lib.baseboard_fab2(sch_1):a_cpu0_def_rcomp1"
				( attribute "CDS_PHYS_NET_NAME" "A_CPU0_DEF_RCOMP1"
					( Origin gPackager )
				)
				( objectStatus "A_CPU0_DEF_RCOMP1" )
			)
			( signal "@baseboard_fab2_lib.baseboard_fab2(sch_1):a_cpu0_def_rcomp2"
				( attribute "CDS_PHYS_NET_NAME" "A_CPU0_DEF_RCOMP2"
					( Origin gPackager )
				)
				( objectStatus "A_CPU0_DEF_RCOMP2" )
			)
			( signal "@baseboard_fab2_lib.baseboard_fab2(sch_1):a_cpu0_mcp01_rbias"
				( attribute "CDS_PHYS_NET_NAME" "A_CPU0_MCP01_RBIAS"
					( Origin gPackager )
				)
				( objectStatus "A_CPU0_MCP01_RBIAS" )
			)
			( signal "@baseboard_fab2_lib.baseboard_fab2(sch_1):a_cpu0_pe012_rbias"
				( attribute "CDS_PHYS_NET_NAME" "A_CPU0_PE012_RBIAS"
					( Origin gPackager )
				)
				( objectStatus "A_CPU0_PE012_RBIAS" )
			)
			( signal "@baseboard_fab2_lib.baseboard_fab2(sch_1):a_cpu0_pe3_rbias"
				( attribute "CDS_PHYS_NET_NAME" "A_CPU0_PE3_RBIAS"
					( Origin gPackager )
				)
				( objectStatus "A_CPU0_PE3_RBIAS" )
			)
			( signal "@baseboard_fab2_lib.baseboard_fab2(sch_1):a_cpu0_upi01_rbias"
				( attribute "CDS_PHYS_NET_NAME" "A_CPU0_UPI01_RBIAS"
					( Origin gPackager )
				)
				( objectStatus "A_CPU0_UPI01_RBIAS" )
			)
			( signal "@baseboard_fab2_lib.baseboard_fab2(sch_1):a_cpu0_upi2_rbias"
				( attribute "CDS_PHYS_NET_NAME" "A_CPU0_UPI2_RBIAS"
					( Origin gPackager )
				)
				( objectStatus "A_CPU0_UPI2_RBIAS" )
			)
			( signal "@baseboard_fab2_lib.baseboard_fab2(sch_1):clk_100m_cpu0_bclk0_dn"
				( attribute "CDS_PHYS_NET_NAME" "CLK_100M_CPU0_BCLK0_DN"
					( Origin gPackager )
				)
				( objectStatus "CLK_100M_CPU0_BCLK0_DN" )
			)
			( signal "@baseboard_fab2_lib.baseboard_fab2(sch_1):clk_100m_cpu0_bclk0_dp"
				( attribute "CDS_PHYS_NET_NAME" "CLK_100M_CPU0_BCLK0_DP"
					( Origin gPackager )
				)
				( objectStatus "CLK_100M_CPU0_BCLK0_DP" )
			)
			( signal "@baseboard_fab2_lib.baseboard_fab2(sch_1):clk_100m_cpu0_bclk1_dn"
				( attribute "CDS_PHYS_NET_NAME" "CLK_100M_CPU0_BCLK1_DN"
					( Origin gPackager )
				)
				( objectStatus "CLK_100M_CPU0_BCLK1_DN" )
			)
			( signal "@baseboard_fab2_lib.baseboard_fab2(sch_1):clk_100m_cpu0_bclk1_dp"
				( attribute "CDS_PHYS_NET_NAME" "CLK_100M_CPU0_BCLK1_DP"
					( Origin gPackager )
				)
				( objectStatus "CLK_100M_CPU0_BCLK1_DP" )
			)
			( signal "@baseboard_fab2_lib.baseboard_fab2(sch_1):clk_100m_cpu0_bclk2_dn"
				( attribute "CDS_PHYS_NET_NAME" "CLK_100M_CPU0_BCLK2_DN"
					( Origin gPackager )
				)
				( objectStatus "CLK_100M_CPU0_BCLK2_DN" )
			)
			( signal "@baseboard_fab2_lib.baseboard_fab2(sch_1):clk_100m_cpu0_bclk2_dp"
				( attribute "CDS_PHYS_NET_NAME" "CLK_100M_CPU0_BCLK2_DP"
					( Origin gPackager )
				)
				( objectStatus "CLK_100M_CPU0_BCLK2_DP" )
			)
			( signal "@baseboard_fab2_lib.baseboard_fab2(sch_1):fm_cpu0_pkgid0"
				( attribute "CDS_PHYS_NET_NAME" "FM_CPU0_PKGID0"
					( Origin gPackager )
				)
				( objectStatus "FM_CPU0_PKGID0" )
			)
			( signal "@baseboard_fab2_lib.baseboard_fab2(sch_1):fm_cpu0_pkgid1"
				( attribute "CDS_PHYS_NET_NAME" "FM_CPU0_PKGID1"
					( Origin gPackager )
				)
				( objectStatus "FM_CPU0_PKGID1" )
			)
			( signal "@baseboard_fab2_lib.baseboard_fab2(sch_1):fm_cpu0_pkgid2"
				( attribute "CDS_PHYS_NET_NAME" "FM_CPU0_PKGID2"
					( Origin gPackager )
				)
				( objectStatus "FM_CPU0_PKGID2" )
			)
			( signal "@baseboard_fab2_lib.baseboard_fab2(sch_1):fm_cpu0_proc_id0"
				( attribute "CDS_PHYS_NET_NAME" "FM_CPU0_PROC_ID0"
					( Origin gPackager )
				)
				( objectStatus "FM_CPU0_PROC_ID0" )
			)
			( signal "@baseboard_fab2_lib.baseboard_fab2(sch_1):fm_cpu0_proc_id1"
				( attribute "CDS_PHYS_NET_NAME" "FM_CPU0_PROC_ID1"
					( Origin gPackager )
				)
				( objectStatus "FM_CPU0_PROC_ID1" )
			)
			( signal "@baseboard_fab2_lib.baseboard_fab2(sch_1):fm_cpu0_sktocc_lvt3_n"
				( attribute "CDS_PHYS_NET_NAME" "FM_CPU0_SKTOCC_LVT3_N"
					( Origin gPackager )
				)
				( attribute "PHYS_NET_NAME" "FM_CPU0_SKTOCC_LVT3_N"
					( Origin gPackager )
				)
				( objectStatus "FM_CPU0_SKTOCC_LVT3_N" )
			)
			( signal "@baseboard_fab2_lib.baseboard_fab2(sch_1):fm_cpu0_sm_wp"
				( attribute "CDS_PHYS_NET_NAME" "FM_CPU0_SM_WP"
					( Origin gPackager )
				)
				( objectStatus "FM_CPU0_SM_WP" )
			)
			( signal "@baseboard_fab2_lib.baseboard_fab2(sch_1):gnd"
				( alias ( signalRef "@baseboard_fab2_lib.baseboard_fab2(sch_1):page21_gnd") )
				( alias ( signalRef "@baseboard_fab2_lib.baseboard_fab2(sch_1):page22_gnd") )
				( alias ( signalRef "@baseboard_fab2_lib.baseboard_fab2(sch_1):page35_gnd") )
				( alias ( signalRef "@baseboard_fab2_lib.baseboard_fab2(sch_1):page37_gnd") )
				( alias ( signalRef "@baseboard_fab2_lib.baseboard_fab2(sch_1):page38_gnd") )
				( alias ( signalRef "@baseboard_fab2_lib.baseboard_fab2(sch_1):page40_gnd") )
				( alias ( signalRef "@baseboard_fab2_lib.baseboard_fab2(sch_1):page41_gnd") )
				( alias ( signalRef "@baseboard_fab2_lib.baseboard_fab2(sch_1):page42_gnd") )
				( alias ( signalRef "@baseboard_fab2_lib.baseboard_fab2(sch_1):page43_gnd") )
				( alias ( signalRef "@baseboard_fab2_lib.baseboard_fab2(sch_1):page44_gnd") )
				( alias ( signalRef "@baseboard_fab2_lib.baseboard_fab2(sch_1):page45_gnd") )
				( alias ( signalRef "@baseboard_fab2_lib.baseboard_fab2(sch_1):page46_gnd") )
				( alias ( signalRef "@baseboard_fab2_lib.baseboard_fab2(sch_1):page47_gnd") )
				( alias ( signalRef "@baseboard_fab2_lib.baseboard_fab2(sch_1):page48_gnd") )
				( alias ( signalRef "@baseboard_fab2_lib.baseboard_fab2(sch_1):page49_gnd") )
				( alias ( signalRef "@baseboard_fab2_lib.baseboard_fab2(sch_1):page50_gnd") )
				( alias ( signalRef "@baseboard_fab2_lib.baseboard_fab2(sch_1):page51_gnd") )
				( alias ( signalRef "@baseboard_fab2_lib.baseboard_fab2(sch_1):page52_gnd") )
				( alias ( signalRef "@baseboard_fab2_lib.baseboard_fab2(sch_1):page53_gnd") )
				( alias ( signalRef "@baseboard_fab2_lib.baseboard_fab2(sch_1):page54_gnd") )
				( alias ( signalRef "@baseboard_fab2_lib.baseboard_fab2(sch_1):page55_gnd") )
				( alias ( signalRef "@baseboard_fab2_lib.baseboard_fab2(sch_1):page56_gnd") )
				( alias ( signalRef "@baseboard_fab2_lib.baseboard_fab2(sch_1):page69_gnd") )
				( alias ( signalRef "@baseboard_fab2_lib.baseboard_fab2(sch_1):page71_gnd") )
				( alias ( signalRef "@baseboard_fab2_lib.baseboard_fab2(sch_1):page72_gnd") )
				( alias ( signalRef "@baseboard_fab2_lib.baseboard_fab2(sch_1):page74_gnd") )
				( alias ( signalRef "@baseboard_fab2_lib.baseboard_fab2(sch_1):page75_gnd") )
				( alias ( signalRef "@baseboard_fab2_lib.baseboard_fab2(sch_1):page76_gnd") )
				( alias ( signalRef "@baseboard_fab2_lib.baseboard_fab2(sch_1):page77_gnd") )
				( alias ( signalRef "@baseboard_fab2_lib.baseboard_fab2(sch_1):page78_gnd") )
				( alias ( signalRef "@baseboard_fab2_lib.baseboard_fab2(sch_1):page79_gnd") )
				( alias ( signalRef "@baseboard_fab2_lib.baseboard_fab2(sch_1):page80_gnd") )
				( alias ( signalRef "@baseboard_fab2_lib.baseboard_fab2(sch_1):page81_gnd") )
				( alias ( signalRef "@baseboard_fab2_lib.baseboard_fab2(sch_1):page82_gnd") )
				( alias ( signalRef "@baseboard_fab2_lib.baseboard_fab2(sch_1):page83_gnd") )
				( alias ( signalRef "@baseboard_fab2_lib.baseboard_fab2(sch_1):page84_gnd") )
				( alias ( signalRef "@baseboard_fab2_lib.baseboard_fab2(sch_1):page85_gnd") )
				( alias ( signalRef "@baseboard_fab2_lib.baseboard_fab2(sch_1):page86_gnd") )
				( alias ( signalRef "@baseboard_fab2_lib.baseboard_fab2(sch_1):page87_gnd") )
				( alias ( signalRef "@baseboard_fab2_lib.baseboard_fab2(sch_1):page88_gnd") )
				( alias ( signalRef "@baseboard_fab2_lib.baseboard_fab2(sch_1):page89_gnd") )
				( alias ( signalRef "@baseboard_fab2_lib.baseboard_fab2(sch_1):page90_gnd") )
				( alias ( signalRef "@baseboard_fab2_lib.baseboard_fab2(sch_1):page91_gnd") )
				( alias ( signalRef "@baseboard_fab2_lib.baseboard_fab2(sch_1):page92_gnd") )
				( alias ( signalRef "@baseboard_fab2_lib.baseboard_fab2(sch_1):page93_gnd") )
				( alias ( signalRef "@baseboard_fab2_lib.baseboard_fab2(sch_1):page94_gnd") )
				( alias ( signalRef "@baseboard_fab2_lib.baseboard_fab2(sch_1):page95_gnd") )
				( alias ( signalRef "@baseboard_fab2_lib.baseboard_fab2(sch_1):page96_gnd") )
				( alias ( signalRef "@baseboard_fab2_lib.baseboard_fab2(sch_1):page97_gnd") )
				( alias ( signalRef "@baseboard_fab2_lib.baseboard_fab2(sch_1):page98_gnd") )
				( alias ( signalRef "@baseboard_fab2_lib.baseboard_fab2(sch_1):page99_gnd") )
				( alias ( signalRef "@baseboard_fab2_lib.baseboard_fab2(sch_1):page100_gnd") )
				( alias ( signalRef "@baseboard_fab2_lib.baseboard_fab2(sch_1):page101_gnd") )
				( alias ( signalRef "@baseboard_fab2_lib.baseboard_fab2(sch_1):page102_gnd") )
				( alias ( signalRef "@baseboard_fab2_lib.baseboard_fab2(sch_1):page103_gnd") )
				( alias ( signalRef "@baseboard_fab2_lib.baseboard_fab2(sch_1):page104_gnd") )
				( alias ( signalRef "@baseboard_fab2_lib.baseboard_fab2(sch_1):page108_gnd") )
				( alias ( signalRef "@baseboard_fab2_lib.baseboard_fab2(sch_1):page109_gnd") )
				( alias ( signalRef "@baseboard_fab2_lib.baseboard_fab2(sch_1):page111_gnd") )
				( alias ( signalRef "@baseboard_fab2_lib.baseboard_fab2(sch_1):page112_gnd") )
				( alias ( signalRef "@baseboard_fab2_lib.baseboard_fab2(sch_1):page113_gnd") )
				( alias ( signalRef "@baseboard_fab2_lib.baseboard_fab2(sch_1):page114_gnd") )
				( alias ( signalRef "@baseboard_fab2_lib.baseboard_fab2(sch_1):page115_gnd") )
				( alias ( signalRef "@baseboard_fab2_lib.baseboard_fab2(sch_1):page116_gnd") )
				( alias ( signalRef "@baseboard_fab2_lib.baseboard_fab2(sch_1):page118_gnd") )
				( alias ( signalRef "@baseboard_fab2_lib.baseboard_fab2(sch_1):page119_gnd") )
				( alias ( signalRef "@baseboard_fab2_lib.baseboard_fab2(sch_1):page120_gnd") )
				( alias ( signalRef "@baseboard_fab2_lib.baseboard_fab2(sch_1):page121_gnd") )
				( alias ( signalRef "@baseboard_fab2_lib.baseboard_fab2(sch_1):page123_gnd") )
				( alias ( signalRef "@baseboard_fab2_lib.baseboard_fab2(sch_1):page124_gnd") )
				( alias ( signalRef "@baseboard_fab2_lib.baseboard_fab2(sch_1):page125_gnd") )
				( alias ( signalRef "@baseboard_fab2_lib.baseboard_fab2(sch_1):page126_gnd") )
				( alias ( signalRef "@baseboard_fab2_lib.baseboard_fab2(sch_1):page127_gnd") )
				( alias ( signalRef "@baseboard_fab2_lib.baseboard_fab2(sch_1):page130_gnd") )
				( alias ( signalRef "@baseboard_fab2_lib.baseboard_fab2(sch_1):page131_gnd") )
				( alias ( signalRef "@baseboard_fab2_lib.baseboard_fab2(sch_1):page132_gnd") )
				( alias ( signalRef "@baseboard_fab2_lib.baseboard_fab2(sch_1):page133_gnd") )
				( alias ( signalRef "@baseboard_fab2_lib.baseboard_fab2(sch_1):page134_gnd") )
				( alias ( signalRef "@baseboard_fab2_lib.baseboard_fab2(sch_1):page135_gnd") )
				( alias ( signalRef "@baseboard_fab2_lib.baseboard_fab2(sch_1):page136_gnd") )
				( alias ( signalRef "@baseboard_fab2_lib.baseboard_fab2(sch_1):page137_gnd") )
				( alias ( signalRef "@baseboard_fab2_lib.baseboard_fab2(sch_1):page139_gnd") )
				( alias ( signalRef "@baseboard_fab2_lib.baseboard_fab2(sch_1):page140_gnd") )
				( alias ( signalRef "@baseboard_fab2_lib.baseboard_fab2(sch_1):page141_gnd") )
				( alias ( signalRef "@baseboard_fab2_lib.baseboard_fab2(sch_1):page142_gnd") )
				( alias ( signalRef "@baseboard_fab2_lib.baseboard_fab2(sch_1):page152_gnd") )
				( alias ( signalRef "@baseboard_fab2_lib.baseboard_fab2(sch_1):page153_gnd") )
				( alias ( signalRef "@baseboard_fab2_lib.baseboard_fab2(sch_1):page154_gnd") )
				( alias ( signalRef "@baseboard_fab2_lib.baseboard_fab2(sch_1):page155_gnd") )
				( alias ( signalRef "@baseboard_fab2_lib.baseboard_fab2(sch_1):page156_gnd") )
				( alias ( signalRef "@baseboard_fab2_lib.baseboard_fab2(sch_1):page157_gnd") )
				( alias ( signalRef "@baseboard_fab2_lib.baseboard_fab2(sch_1):page158_gnd") )
				( alias ( signalRef "@baseboard_fab2_lib.baseboard_fab2(sch_1):page161_gnd") )
				( alias ( signalRef "@baseboard_fab2_lib.baseboard_fab2(sch_1):page162_gnd") )
				( alias ( signalRef "@baseboard_fab2_lib.baseboard_fab2(sch_1):page163_gnd") )
				( alias ( signalRef "@baseboard_fab2_lib.baseboard_fab2(sch_1):page164_gnd") )
				( alias ( signalRef "@baseboard_fab2_lib.baseboard_fab2(sch_1):page166_gnd") )
				( alias ( signalRef "@baseboard_fab2_lib.baseboard_fab2(sch_1):page167_gnd") )
				( alias ( signalRef "@baseboard_fab2_lib.baseboard_fab2(sch_1):page168_gnd") )
				( alias ( signalRef "@baseboard_fab2_lib.baseboard_fab2(sch_1):page169_gnd") )
				( alias ( signalRef "@baseboard_fab2_lib.baseboard_fab2(sch_1):page170_gnd") )
				( alias ( signalRef "@baseboard_fab2_lib.baseboard_fab2(sch_1):page172_gnd") )
				( alias ( signalRef "@baseboard_fab2_lib.baseboard_fab2(sch_1):page173_gnd") )
				( alias ( signalRef "@baseboard_fab2_lib.baseboard_fab2(sch_1):page175_gnd") )
				( alias ( signalRef "@baseboard_fab2_lib.baseboard_fab2(sch_1):page176_gnd") )
				( alias ( signalRef "@baseboard_fab2_lib.baseboard_fab2(sch_1):page177_gnd") )
				( alias ( signalRef "@baseboard_fab2_lib.baseboard_fab2(sch_1):page181_gnd") )
				( alias ( signalRef "@baseboard_fab2_lib.baseboard_fab2(sch_1):page182_gnd") )
				( alias ( signalRef "@baseboard_fab2_lib.baseboard_fab2(sch_1):page184_gnd") )
				( alias ( signalRef "@baseboard_fab2_lib.baseboard_fab2(sch_1):page185_gnd") )
				( alias ( signalRef "@baseboard_fab2_lib.baseboard_fab2(sch_1):page186_gnd") )
				( alias ( signalRef "@baseboard_fab2_lib.baseboard_fab2(sch_1):page187_gnd") )
				( alias ( signalRef "@baseboard_fab2_lib.baseboard_fab2(sch_1):page188_gnd") )
				( alias ( signalRef "@baseboard_fab2_lib.baseboard_fab2(sch_1):page189_gnd") )
				( alias ( signalRef "@baseboard_fab2_lib.baseboard_fab2(sch_1):page192_gnd") )
				( alias ( signalRef "@baseboard_fab2_lib.baseboard_fab2(sch_1):page193_gnd") )
				( alias ( signalRef "@baseboard_fab2_lib.baseboard_fab2(sch_1):page194_gnd") )
				( alias ( signalRef "@baseboard_fab2_lib.baseboard_fab2(sch_1):page195_gnd") )
				( alias ( signalRef "@baseboard_fab2_lib.baseboard_fab2(sch_1):page196_gnd") )
				( alias ( signalRef "@baseboard_fab2_lib.baseboard_fab2(sch_1):page197_gnd") )
				( alias ( signalRef "@baseboard_fab2_lib.baseboard_fab2(sch_1):page198_gnd") )
				( alias ( signalRef "@baseboard_fab2_lib.baseboard_fab2(sch_1):page199_gnd") )
				( alias ( signalRef "@baseboard_fab2_lib.baseboard_fab2(sch_1):page200_gnd") )
				( alias ( signalRef "@baseboard_fab2_lib.baseboard_fab2(sch_1):page201_gnd") )
				( alias ( signalRef "@baseboard_fab2_lib.baseboard_fab2(sch_1):page202_gnd") )
				( alias ( signalRef "@baseboard_fab2_lib.baseboard_fab2(sch_1):page203_gnd") )
				( alias ( signalRef "@baseboard_fab2_lib.baseboard_fab2(sch_1):page204_gnd") )
				( alias ( signalRef "@baseboard_fab2_lib.baseboard_fab2(sch_1):page205_gnd") )
				( alias ( signalRef "@baseboard_fab2_lib.baseboard_fab2(sch_1):page206_gnd") )
				( alias ( signalRef "@baseboard_fab2_lib.baseboard_fab2(sch_1):page207_gnd") )
				( alias ( signalRef "@baseboard_fab2_lib.baseboard_fab2(sch_1):page208_gnd") )
				( alias ( signalRef "@baseboard_fab2_lib.baseboard_fab2(sch_1):page209_gnd") )
				( alias ( signalRef "@baseboard_fab2_lib.baseboard_fab2(sch_1):page210_gnd") )
				( alias ( signalRef "@baseboard_fab2_lib.baseboard_fab2(sch_1):page211_gnd") )
				( alias ( signalRef "@baseboard_fab2_lib.baseboard_fab2(sch_1):page212_gnd") )
				( alias ( signalRef "@baseboard_fab2_lib.baseboard_fab2(sch_1):page213_gnd") )
				( alias ( signalRef "@baseboard_fab2_lib.baseboard_fab2(sch_1):page214_gnd") )
				( alias ( signalRef "@baseboard_fab2_lib.baseboard_fab2(sch_1):page215_gnd") )
				( alias ( signalRef "@baseboard_fab2_lib.baseboard_fab2(sch_1):page216_gnd") )
				( alias ( signalRef "@baseboard_fab2_lib.baseboard_fab2(sch_1):page217_gnd") )
				( alias ( signalRef "@baseboard_fab2_lib.baseboard_fab2(sch_1):page218_gnd") )
				( alias ( signalRef "@baseboard_fab2_lib.baseboard_fab2(sch_1):page219_gnd") )
				( alias ( signalRef "@baseboard_fab2_lib.baseboard_fab2(sch_1):page220_gnd") )
				( alias ( signalRef "@baseboard_fab2_lib.baseboard_fab2(sch_1):page221_gnd") )
				( alias ( signalRef "@baseboard_fab2_lib.baseboard_fab2(sch_1):page222_gnd") )
				( alias ( signalRef "@baseboard_fab2_lib.baseboard_fab2(sch_1):page223_gnd") )
				( alias ( signalRef "@baseboard_fab2_lib.baseboard_fab2(sch_1):page224_gnd") )
				( alias ( signalRef "@baseboard_fab2_lib.baseboard_fab2(sch_1):page225_gnd") )
				( alias ( signalRef "@baseboard_fab2_lib.baseboard_fab2(sch_1):page226_gnd") )
				( alias ( signalRef "@baseboard_fab2_lib.baseboard_fab2(sch_1):page227_gnd") )
				( alias ( signalRef "@baseboard_fab2_lib.baseboard_fab2(sch_1):page228_gnd") )
				( alias ( signalRef "@baseboard_fab2_lib.baseboard_fab2(sch_1):page229_gnd") )
				( alias ( signalRef "@baseboard_fab2_lib.baseboard_fab2(sch_1):page230_gnd") )
				( alias ( signalRef "@baseboard_fab2_lib.baseboard_fab2(sch_1):page231_gnd") )
				( alias ( signalRef "@baseboard_fab2_lib.baseboard_fab2(sch_1):page232_gnd") )
				( alias ( signalRef "@baseboard_fab2_lib.baseboard_fab2(sch_1):page233_gnd") )
				( alias ( signalRef "@baseboard_fab2_lib.baseboard_fab2(sch_1):page234_gnd") )
				( alias ( signalRef "@baseboard_fab2_lib.baseboard_fab2(sch_1):page235_gnd") )
				( alias ( signalRef "@baseboard_fab2_lib.baseboard_fab2(sch_1):page236_gnd") )
				( alias ( signalRef "@baseboard_fab2_lib.baseboard_fab2(sch_1):page237_gnd") )
				( alias ( signalRef "@baseboard_fab2_lib.baseboard_fab2(sch_1):page238_gnd") )
				( alias ( signalRef "@baseboard_fab2_lib.baseboard_fab2(sch_1):page239_gnd") )
				( alias ( signalRef "@baseboard_fab2_lib.baseboard_fab2(sch_1):page240_gnd") )
				( alias ( signalRef "@baseboard_fab2_lib.baseboard_fab2(sch_1):page241_gnd") )
				( alias ( signalRef "@baseboard_fab2_lib.baseboard_fab2(sch_1):page242_gnd") )
				( alias ( signalRef "@baseboard_fab2_lib.baseboard_fab2(sch_1):page243_gnd") )
				( alias ( signalRef "@baseboard_fab2_lib.baseboard_fab2(sch_1):page245_gnd") )
				( alias ( signalRef "@baseboard_fab2_lib.baseboard_fab2(sch_1):page246_gnd") )
				( alias ( signalRef "@baseboard_fab2_lib.baseboard_fab2(sch_1):page247_gnd") )
				( alias ( signalRef "@baseboard_fab2_lib.baseboard_fab2(sch_1):page249_gnd") )
				( alias ( signalRef "@baseboard_fab2_lib.baseboard_fab2(sch_1):page150_gnd") )
				( alias ( signalRef "@baseboard_fab2_lib.baseboard_fab2(sch_1):page143_gnd") )
				( alias ( signalRef "@baseboard_fab2_lib.baseboard_fab2(sch_1):page144_gnd") )
				( alias ( signalRef "@baseboard_fab2_lib.baseboard_fab2(sch_1):page145_gnd") )
				( alias ( signalRef "@baseboard_fab2_lib.baseboard_fab2(sch_1):page146_gnd") )
				( alias ( signalRef "@baseboard_fab2_lib.baseboard_fab2(sch_1):page147_gnd") )
				( alias ( signalRef "@baseboard_fab2_lib.baseboard_fab2(sch_1):page148_gnd") )
				( alias ( signalRef "@baseboard_fab2_lib.baseboard_fab2(sch_1):page151_gnd") )
				( alias ( signalRef "@baseboard_fab2_lib.baseboard_fab2(sch_1):page149_gnd") )
				( alias ( signalRef "@baseboard_fab2_lib.baseboard_fab2(sch_1):page248_gnd") )
				( alias ( signalRef "@baseboard_fab2_lib.baseboard_fab2(sch_1):page250_gnd") )
				( alias ( signalRef "@baseboard_fab2_lib.baseboard_fab2(sch_1):page251_gnd") )
				( alias ( signalRef "@baseboard_fab2_lib.baseboard_fab2(sch_1):page255_gnd") )
				( alias ( signalRef "@baseboard_fab2_lib.baseboard_fab2(sch_1):page253_gnd") )
				( alias ( signalRef "@baseboard_fab2_lib.baseboard_fab2(sch_1):page190_gnd") )
				( alias ( signalRef "@baseboard_fab2_lib.baseboard_fab2(sch_1):page269_gnd") )
				( alias ( signalRef "@baseboard_fab2_lib.baseboard_fab2(sch_1):page268_gnd") )
				( alias ( signalRef "@baseboard_fab2_lib.baseboard_fab2(sch_1):page270_gnd") )
				( alias ( signalRef "@baseboard_fab2_lib.baseboard_fab2(sch_1):page272_gnd") )
				( alias ( signalRef "@baseboard_fab2_lib.baseboard_fab2(sch_1):page271_gnd") )
				( attribute "CDS_PHYS_NET_NAME" "GND"
					( Origin gPackager )
				)
				( attribute "PHYS_NET_NAME" "GND"
					( Origin gPackager )
				)
				( attribute "VOLTAGE" "0.0V"
					( Units "uVoltage" "V" 1.000000)
					( Status sAliasFlattened )
					( Status sAliasConflict )
					( Origin gFrontEnd )
				)
				( attribute "BOM_COST" "TBD"
					( Status sAliasFlattened )
					( Origin gFrontEnd )
				)
				( attribute "ROOM" "TBD"
					( Status sAliasFlattened )
					( Origin gFrontEnd )
				)
				( objectStatus "GND" )
			)
			( signal "@baseboard_fab2_lib.baseboard_fab2(sch_1):page21_gnd"
				( attribute "VOLTAGE" "0.0V"
					( Units "uVoltage" "V" 1.000000)
					( Origin gFrontEnd )
				)
				( objectFlag fObjectAlias )
				( objectStatus "page21_gnd" )
			)
			( signal "@baseboard_fab2_lib.baseboard_fab2(sch_1):page22_gnd"
				( attribute "VOLTAGE" "0.0V"
					( Units "uVoltage" "V" 1.000000)
					( Origin gFrontEnd )
				)
				( objectFlag fObjectAlias )
				( objectStatus "page22_gnd" )
			)
			( signal "@baseboard_fab2_lib.baseboard_fab2(sch_1):page35_gnd"
				( attribute "VOLTAGE" "0.0V"
					( Units "uVoltage" "V" 1.000000)
					( Origin gFrontEnd )
				)
				( objectFlag fObjectAlias )
				( objectStatus "page35_gnd" )
			)
			( signal "@baseboard_fab2_lib.baseboard_fab2(sch_1):page37_gnd"
				( attribute "VOLTAGE" "0.0V"
					( Units "uVoltage" "V" 1.000000)
					( Origin gFrontEnd )
				)
				( objectFlag fObjectAlias )
				( objectStatus "page37_gnd" )
			)
			( signal "@baseboard_fab2_lib.baseboard_fab2(sch_1):page38_gnd"
				( attribute "VOLTAGE" "0.0V"
					( Units "uVoltage" "V" 1.000000)
					( Origin gFrontEnd )
				)
				( objectFlag fObjectAlias )
				( objectStatus "page38_gnd" )
			)
			( signal "@baseboard_fab2_lib.baseboard_fab2(sch_1):page40_gnd"
				( attribute "VOLTAGE" "0.0V"
					( Units "uVoltage" "V" 1.000000)
					( Origin gFrontEnd )
				)
				( objectFlag fObjectAlias )
				( objectStatus "page40_gnd" )
			)
			( signal "@baseboard_fab2_lib.baseboard_fab2(sch_1):page41_gnd"
				( attribute "VOLTAGE" "0.0V"
					( Units "uVoltage" "V" 1.000000)
					( Origin gFrontEnd )
				)
				( objectFlag fObjectAlias )
				( objectStatus "page41_gnd" )
			)
			( signal "@baseboard_fab2_lib.baseboard_fab2(sch_1):page42_gnd"
				( attribute "VOLTAGE" "0"
					( Units "uVoltage" "V" 1.000000)
					( Origin gFrontEnd )
				)
				( objectFlag fObjectAlias )
				( objectStatus "page42_gnd" )
			)
			( signal "@baseboard_fab2_lib.baseboard_fab2(sch_1):page43_gnd"
				( attribute "VOLTAGE" "0"
					( Units "uVoltage" "V" 1.000000)
					( Origin gFrontEnd )
				)
				( objectFlag fObjectAlias )
				( objectStatus "page43_gnd" )
			)
			( signal "@baseboard_fab2_lib.baseboard_fab2(sch_1):page44_gnd"
				( attribute "VOLTAGE" "0"
					( Units "uVoltage" "V" 1.000000)
					( Origin gFrontEnd )
				)
				( objectFlag fObjectAlias )
				( objectStatus "page44_gnd" )
			)
			( signal "@baseboard_fab2_lib.baseboard_fab2(sch_1):page45_gnd"
				( attribute "VOLTAGE" "0"
					( Units "uVoltage" "V" 1.000000)
					( Origin gFrontEnd )
				)
				( objectFlag fObjectAlias )
				( objectStatus "page45_gnd" )
			)
			( signal "@baseboard_fab2_lib.baseboard_fab2(sch_1):page46_gnd"
				( attribute "VOLTAGE" "0"
					( Units "uVoltage" "V" 1.000000)
					( Origin gFrontEnd )
				)
				( objectFlag fObjectAlias )
				( objectStatus "page46_gnd" )
			)
			( signal "@baseboard_fab2_lib.baseboard_fab2(sch_1):page47_gnd"
				( attribute "VOLTAGE" "0"
					( Units "uVoltage" "V" 1.000000)
					( Origin gFrontEnd )
				)
				( objectFlag fObjectAlias )
				( objectStatus "page47_gnd" )
			)
			( signal "@baseboard_fab2_lib.baseboard_fab2(sch_1):page48_gnd"
				( attribute "VOLTAGE" "0"
					( Units "uVoltage" "V" 1.000000)
					( Origin gFrontEnd )
				)
				( objectFlag fObjectAlias )
				( objectStatus "page48_gnd" )
			)
			( signal "@baseboard_fab2_lib.baseboard_fab2(sch_1):page49_gnd"
				( attribute "BOM_COST" "TBD"
					( Origin gFrontEnd )
				)
				( attribute "ROOM" "TBD"
					( Origin gFrontEnd )
				)
				( attribute "VOLTAGE" "0"
					( Units "uVoltage" "V" 1.000000)
					( Origin gFrontEnd )
				)
				( objectFlag fObjectAlias )
				( objectStatus "page49_gnd" )
			)
			( signal "@baseboard_fab2_lib.baseboard_fab2(sch_1):page50_gnd"
				( attribute "VOLTAGE" "0"
					( Units "uVoltage" "V" 1.000000)
					( Origin gFrontEnd )
				)
				( objectFlag fObjectAlias )
				( objectStatus "page50_gnd" )
			)
			( signal "@baseboard_fab2_lib.baseboard_fab2(sch_1):page51_gnd"
				( attribute "VOLTAGE" "0"
					( Units "uVoltage" "V" 1.000000)
					( Origin gFrontEnd )
				)
				( objectFlag fObjectAlias )
				( objectStatus "page51_gnd" )
			)
			( signal "@baseboard_fab2_lib.baseboard_fab2(sch_1):page52_gnd"
				( attribute "VOLTAGE" "0"
					( Units "uVoltage" "V" 1.000000)
					( Origin gFrontEnd )
				)
				( objectFlag fObjectAlias )
				( objectStatus "page52_gnd" )
			)
			( signal "@baseboard_fab2_lib.baseboard_fab2(sch_1):page53_gnd"
				( attribute "VOLTAGE" "0"
					( Units "uVoltage" "V" 1.000000)
					( Origin gFrontEnd )
				)
				( objectFlag fObjectAlias )
				( objectStatus "page53_gnd" )
			)
			( signal "@baseboard_fab2_lib.baseboard_fab2(sch_1):page54_gnd"
				( attribute "VOLTAGE" "0"
					( Units "uVoltage" "V" 1.000000)
					( Origin gFrontEnd )
				)
				( objectFlag fObjectAlias )
				( objectStatus "page54_gnd" )
			)
			( signal "@baseboard_fab2_lib.baseboard_fab2(sch_1):page55_gnd"
				( attribute "VOLTAGE" "0.0V"
					( Units "uVoltage" "V" 1.000000)
					( Origin gFrontEnd )
				)
				( objectFlag fObjectAlias )
				( objectStatus "page55_gnd" )
			)
			( signal "@baseboard_fab2_lib.baseboard_fab2(sch_1):page56_gnd"
				( attribute "VOLTAGE" "0.0V"
					( Units "uVoltage" "V" 1.000000)
					( Origin gFrontEnd )
				)
				( objectFlag fObjectAlias )
				( objectStatus "page56_gnd" )
			)
			( signal "@baseboard_fab2_lib.baseboard_fab2(sch_1):page69_gnd"
				( attribute "VOLTAGE" "0.0V"
					( Units "uVoltage" "V" 1.000000)
					( Origin gFrontEnd )
				)
				( objectFlag fObjectAlias )
				( objectStatus "page69_gnd" )
			)
			( signal "@baseboard_fab2_lib.baseboard_fab2(sch_1):page71_gnd"
				( attribute "VOLTAGE" "0.0V"
					( Units "uVoltage" "V" 1.000000)
					( Origin gFrontEnd )
				)
				( objectFlag fObjectAlias )
				( objectStatus "page71_gnd" )
			)
			( signal "@baseboard_fab2_lib.baseboard_fab2(sch_1):page72_gnd"
				( attribute "VOLTAGE" "0.0V"
					( Units "uVoltage" "V" 1.000000)
					( Origin gFrontEnd )
				)
				( objectFlag fObjectAlias )
				( objectStatus "page72_gnd" )
			)
			( signal "@baseboard_fab2_lib.baseboard_fab2(sch_1):page74_gnd"
				( attribute "VOLTAGE" "0.0V"
					( Units "uVoltage" "V" 1.000000)
					( Origin gFrontEnd )
				)
				( objectFlag fObjectAlias )
				( objectStatus "page74_gnd" )
			)
			( signal "@baseboard_fab2_lib.baseboard_fab2(sch_1):page75_gnd"
				( attribute "VOLTAGE" "0.0V"
					( Units "uVoltage" "V" 1.000000)
					( Origin gFrontEnd )
				)
				( objectFlag fObjectAlias )
				( objectStatus "page75_gnd" )
			)
			( signal "@baseboard_fab2_lib.baseboard_fab2(sch_1):page76_gnd"
				( attribute "VOLTAGE" "0"
					( Units "uVoltage" "V" 1.000000)
					( Origin gFrontEnd )
				)
				( objectFlag fObjectAlias )
				( objectStatus "page76_gnd" )
			)
			( signal "@baseboard_fab2_lib.baseboard_fab2(sch_1):page77_gnd"
				( attribute "VOLTAGE" "0"
					( Units "uVoltage" "V" 1.000000)
					( Origin gFrontEnd )
				)
				( objectFlag fObjectAlias )
				( objectStatus "page77_gnd" )
			)
			( signal "@baseboard_fab2_lib.baseboard_fab2(sch_1):page78_gnd"
				( attribute "VOLTAGE" "0.0V"
					( Units "uVoltage" "V" 1.000000)
					( Origin gFrontEnd )
				)
				( objectFlag fObjectAlias )
				( objectStatus "page78_gnd" )
			)
			( signal "@baseboard_fab2_lib.baseboard_fab2(sch_1):page79_gnd"
				( attribute "VOLTAGE" "0"
					( Units "uVoltage" "V" 1.000000)
					( Origin gFrontEnd )
				)
				( objectFlag fObjectAlias )
				( objectStatus "page79_gnd" )
			)
			( signal "@baseboard_fab2_lib.baseboard_fab2(sch_1):page80_gnd"
				( attribute "VOLTAGE" "0"
					( Units "uVoltage" "V" 1.000000)
					( Origin gFrontEnd )
				)
				( objectFlag fObjectAlias )
				( objectStatus "page80_gnd" )
			)
			( signal "@baseboard_fab2_lib.baseboard_fab2(sch_1):page81_gnd"
				( attribute "VOLTAGE" "0"
					( Units "uVoltage" "V" 1.000000)
					( Origin gFrontEnd )
				)
				( objectFlag fObjectAlias )
				( objectStatus "page81_gnd" )
			)
			( signal "@baseboard_fab2_lib.baseboard_fab2(sch_1):page82_gnd"
				( attribute "VOLTAGE" "0"
					( Units "uVoltage" "V" 1.000000)
					( Origin gFrontEnd )
				)
				( objectFlag fObjectAlias )
				( objectStatus "page82_gnd" )
			)
			( signal "@baseboard_fab2_lib.baseboard_fab2(sch_1):page83_gnd"
				( attribute "VOLTAGE" "0"
					( Units "uVoltage" "V" 1.000000)
					( Origin gFrontEnd )
				)
				( objectFlag fObjectAlias )
				( objectStatus "page83_gnd" )
			)
			( signal "@baseboard_fab2_lib.baseboard_fab2(sch_1):page84_gnd"
				( attribute "VOLTAGE" "0"
					( Units "uVoltage" "V" 1.000000)
					( Origin gFrontEnd )
				)
				( objectFlag fObjectAlias )
				( objectStatus "page84_gnd" )
			)
			( signal "@baseboard_fab2_lib.baseboard_fab2(sch_1):page85_gnd"
				( attribute "VOLTAGE" "0"
					( Units "uVoltage" "V" 1.000000)
					( Origin gFrontEnd )
				)
				( objectFlag fObjectAlias )
				( objectStatus "page85_gnd" )
			)
			( signal "@baseboard_fab2_lib.baseboard_fab2(sch_1):page86_gnd"
				( attribute "VOLTAGE" "0"
					( Units "uVoltage" "V" 1.000000)
					( Origin gFrontEnd )
				)
				( objectFlag fObjectAlias )
				( objectStatus "page86_gnd" )
			)
			( signal "@baseboard_fab2_lib.baseboard_fab2(sch_1):page87_gnd"
				( attribute "VOLTAGE" "0"
					( Units "uVoltage" "V" 1.000000)
					( Origin gFrontEnd )
				)
				( objectFlag fObjectAlias )
				( objectStatus "page87_gnd" )
			)
			( signal "@baseboard_fab2_lib.baseboard_fab2(sch_1):page88_gnd"
				( attribute "VOLTAGE" "0"
					( Units "uVoltage" "V" 1.000000)
					( Origin gFrontEnd )
				)
				( objectFlag fObjectAlias )
				( objectStatus "page88_gnd" )
			)
			( signal "@baseboard_fab2_lib.baseboard_fab2(sch_1):page89_gnd"
				( attribute "VOLTAGE" "0.0V"
					( Units "uVoltage" "V" 1.000000)
					( Origin gFrontEnd )
				)
				( objectFlag fObjectAlias )
				( objectStatus "page89_gnd" )
			)
			( signal "@baseboard_fab2_lib.baseboard_fab2(sch_1):page90_gnd"
				( attribute "VOLTAGE" "0"
					( Units "uVoltage" "V" 1.000000)
					( Origin gFrontEnd )
				)
				( objectFlag fObjectAlias )
				( objectStatus "page90_gnd" )
			)
			( signal "@baseboard_fab2_lib.baseboard_fab2(sch_1):page91_gnd"
				( attribute "VOLTAGE" "0.0V"
					( Units "uVoltage" "V" 1.000000)
					( Origin gFrontEnd )
				)
				( objectFlag fObjectAlias )
				( objectStatus "page91_gnd" )
			)
			( signal "@baseboard_fab2_lib.baseboard_fab2(sch_1):page92_gnd"
				( attribute "VOLTAGE" "0"
					( Units "uVoltage" "V" 1.000000)
					( Origin gFrontEnd )
				)
				( objectFlag fObjectAlias )
				( objectStatus "page92_gnd" )
			)
			( signal "@baseboard_fab2_lib.baseboard_fab2(sch_1):page93_gnd"
				( attribute "VOLTAGE" "0"
					( Units "uVoltage" "V" 1.000000)
					( Origin gFrontEnd )
				)
				( objectFlag fObjectAlias )
				( objectStatus "page93_gnd" )
			)
			( signal "@baseboard_fab2_lib.baseboard_fab2(sch_1):page94_gnd"
				( attribute "VOLTAGE" "0"
					( Units "uVoltage" "V" 1.000000)
					( Origin gFrontEnd )
				)
				( objectFlag fObjectAlias )
				( objectStatus "page94_gnd" )
			)
			( signal "@baseboard_fab2_lib.baseboard_fab2(sch_1):page95_gnd"
				( attribute "VOLTAGE" "0"
					( Units "uVoltage" "V" 1.000000)
					( Origin gFrontEnd )
				)
				( objectFlag fObjectAlias )
				( objectStatus "page95_gnd" )
			)
			( signal "@baseboard_fab2_lib.baseboard_fab2(sch_1):page96_gnd"
				( attribute "VOLTAGE" "0.0V"
					( Units "uVoltage" "V" 1.000000)
					( Origin gFrontEnd )
				)
				( objectFlag fObjectAlias )
				( objectStatus "page96_gnd" )
			)
			( signal "@baseboard_fab2_lib.baseboard_fab2(sch_1):page97_gnd"
				( attribute "VOLTAGE" "0.0V"
					( Units "uVoltage" "V" 1.000000)
					( Origin gFrontEnd )
				)
				( objectFlag fObjectAlias )
				( objectStatus "page97_gnd" )
			)
			( signal "@baseboard_fab2_lib.baseboard_fab2(sch_1):page98_gnd"
				( attribute "VOLTAGE" "0"
					( Units "uVoltage" "V" 1.000000)
					( Origin gFrontEnd )
				)
				( objectFlag fObjectAlias )
				( objectStatus "page98_gnd" )
			)
			( signal "@baseboard_fab2_lib.baseboard_fab2(sch_1):page99_gnd"
				( attribute "VOLTAGE" "0"
					( Units "uVoltage" "V" 1.000000)
					( Origin gFrontEnd )
				)
				( objectFlag fObjectAlias )
				( objectStatus "page99_gnd" )
			)
			( signal "@baseboard_fab2_lib.baseboard_fab2(sch_1):page100_gnd"
				( attribute "VOLTAGE" "0"
					( Units "uVoltage" "V" 1.000000)
					( Origin gFrontEnd )
				)
				( objectFlag fObjectAlias )
				( objectStatus "page100_gnd" )
			)
			( signal "@baseboard_fab2_lib.baseboard_fab2(sch_1):page101_gnd"
				( attribute "VOLTAGE" "0.0V"
					( Units "uVoltage" "V" 1.000000)
					( Origin gFrontEnd )
				)
				( objectFlag fObjectAlias )
				( objectStatus "page101_gnd" )
			)
			( signal "@baseboard_fab2_lib.baseboard_fab2(sch_1):page102_gnd"
				( attribute "VOLTAGE" "0.0V"
					( Units "uVoltage" "V" 1.000000)
					( Origin gFrontEnd )
				)
				( objectFlag fObjectAlias )
				( objectStatus "page102_gnd" )
			)
			( signal "@baseboard_fab2_lib.baseboard_fab2(sch_1):page103_gnd"
				( attribute "VOLTAGE" "0.0V"
					( Units "uVoltage" "V" 1.000000)
					( Origin gFrontEnd )
				)
				( objectFlag fObjectAlias )
				( objectStatus "page103_gnd" )
			)
			( signal "@baseboard_fab2_lib.baseboard_fab2(sch_1):page104_gnd"
				( attribute "VOLTAGE" "0.0V"
					( Units "uVoltage" "V" 1.000000)
					( Origin gFrontEnd )
				)
				( objectFlag fObjectAlias )
				( objectStatus "page104_gnd" )
			)
			( signal "@baseboard_fab2_lib.baseboard_fab2(sch_1):page108_gnd"
				( attribute "VOLTAGE" "0"
					( Units "uVoltage" "V" 1.000000)
					( Origin gFrontEnd )
				)
				( objectFlag fObjectAlias )
				( objectStatus "page108_gnd" )
			)
			( signal "@baseboard_fab2_lib.baseboard_fab2(sch_1):page109_gnd"
				( attribute "VOLTAGE" "0"
					( Units "uVoltage" "V" 1.000000)
					( Origin gFrontEnd )
				)
				( objectFlag fObjectAlias )
				( objectStatus "page109_gnd" )
			)
			( signal "@baseboard_fab2_lib.baseboard_fab2(sch_1):page111_gnd"
				( attribute "VOLTAGE" "0.0V"
					( Units "uVoltage" "V" 1.000000)
					( Origin gFrontEnd )
				)
				( objectFlag fObjectAlias )
				( objectStatus "page111_gnd" )
			)
			( signal "@baseboard_fab2_lib.baseboard_fab2(sch_1):page112_gnd"
				( attribute "VOLTAGE" "0.0V"
					( Units "uVoltage" "V" 1.000000)
					( Origin gFrontEnd )
				)
				( objectFlag fObjectAlias )
				( objectStatus "page112_gnd" )
			)
			( signal "@baseboard_fab2_lib.baseboard_fab2(sch_1):page113_gnd"
				( attribute "VOLTAGE" "0.0V"
					( Units "uVoltage" "V" 1.000000)
					( Origin gFrontEnd )
				)
				( objectFlag fObjectAlias )
				( objectStatus "page113_gnd" )
			)
			( signal "@baseboard_fab2_lib.baseboard_fab2(sch_1):page114_gnd"
				( attribute "VOLTAGE" "0.0V"
					( Units "uVoltage" "V" 1.000000)
					( Origin gFrontEnd )
				)
				( objectFlag fObjectAlias )
				( objectStatus "page114_gnd" )
			)
			( signal "@baseboard_fab2_lib.baseboard_fab2(sch_1):page115_gnd"
				( attribute "VOLTAGE" "0.0V"
					( Units "uVoltage" "V" 1.000000)
					( Origin gFrontEnd )
				)
				( objectFlag fObjectAlias )
				( objectStatus "page115_gnd" )
			)
			( signal "@baseboard_fab2_lib.baseboard_fab2(sch_1):page116_gnd"
				( attribute "VOLTAGE" "0.0V"
					( Units "uVoltage" "V" 1.000000)
					( Origin gFrontEnd )
				)
				( objectFlag fObjectAlias )
				( objectStatus "page116_gnd" )
			)
			( signal "@baseboard_fab2_lib.baseboard_fab2(sch_1):page118_gnd"
				( attribute "VOLTAGE" "0.0V"
					( Units "uVoltage" "V" 1.000000)
					( Origin gFrontEnd )
				)
				( objectFlag fObjectAlias )
				( objectStatus "page118_gnd" )
			)
			( signal "@baseboard_fab2_lib.baseboard_fab2(sch_1):page119_gnd"
				( attribute "VOLTAGE" "0.0V"
					( Units "uVoltage" "V" 1.000000)
					( Origin gFrontEnd )
				)
				( objectFlag fObjectAlias )
				( objectStatus "page119_gnd" )
			)
			( signal "@baseboard_fab2_lib.baseboard_fab2(sch_1):page120_gnd"
				( attribute "VOLTAGE" "0.0V"
					( Units "uVoltage" "V" 1.000000)
					( Origin gFrontEnd )
				)
				( objectFlag fObjectAlias )
				( objectStatus "page120_gnd" )
			)
			( signal "@baseboard_fab2_lib.baseboard_fab2(sch_1):page121_gnd"
				( attribute "VOLTAGE" "0.0V"
					( Units "uVoltage" "V" 1.000000)
					( Origin gFrontEnd )
				)
				( objectFlag fObjectAlias )
				( objectStatus "page121_gnd" )
			)
			( signal "@baseboard_fab2_lib.baseboard_fab2(sch_1):page123_gnd"
				( attribute "VOLTAGE" "0.0V"
					( Units "uVoltage" "V" 1.000000)
					( Origin gFrontEnd )
				)
				( objectFlag fObjectAlias )
				( objectStatus "page123_gnd" )
			)
			( signal "@baseboard_fab2_lib.baseboard_fab2(sch_1):page124_gnd"
				( attribute "VOLTAGE" "0.0V"
					( Units "uVoltage" "V" 1.000000)
					( Origin gFrontEnd )
				)
				( objectFlag fObjectAlias )
				( objectStatus "page124_gnd" )
			)
			( signal "@baseboard_fab2_lib.baseboard_fab2(sch_1):page125_gnd"
				( attribute "VOLTAGE" "0.0V"
					( Units "uVoltage" "V" 1.000000)
					( Origin gFrontEnd )
				)
				( objectFlag fObjectAlias )
				( objectStatus "page125_gnd" )
			)
			( signal "@baseboard_fab2_lib.baseboard_fab2(sch_1):page126_gnd"
				( attribute "VOLTAGE" "0.0V"
					( Units "uVoltage" "V" 1.000000)
					( Origin gFrontEnd )
				)
				( objectFlag fObjectAlias )
				( objectStatus "page126_gnd" )
			)
			( signal "@baseboard_fab2_lib.baseboard_fab2(sch_1):page127_gnd"
				( attribute "VOLTAGE" "0.0V"
					( Units "uVoltage" "V" 1.000000)
					( Origin gFrontEnd )
				)
				( objectFlag fObjectAlias )
				( objectStatus "page127_gnd" )
			)
			( signal "@baseboard_fab2_lib.baseboard_fab2(sch_1):page130_gnd"
				( attribute "VOLTAGE" "0"
					( Units "uVoltage" "V" 1.000000)
					( Origin gFrontEnd )
				)
				( objectFlag fObjectAlias )
				( objectStatus "page130_gnd" )
			)
			( signal "@baseboard_fab2_lib.baseboard_fab2(sch_1):page131_gnd"
				( attribute "VOLTAGE" "0"
					( Units "uVoltage" "V" 1.000000)
					( Origin gFrontEnd )
				)
				( objectFlag fObjectAlias )
				( objectStatus "page131_gnd" )
			)
			( signal "@baseboard_fab2_lib.baseboard_fab2(sch_1):page132_gnd"
				( attribute "VOLTAGE" "0.0V"
					( Units "uVoltage" "V" 1.000000)
					( Origin gFrontEnd )
				)
				( objectFlag fObjectAlias )
				( objectStatus "page132_gnd" )
			)
			( signal "@baseboard_fab2_lib.baseboard_fab2(sch_1):page133_gnd"
				( attribute "VOLTAGE" "0"
					( Units "uVoltage" "V" 1.000000)
					( Origin gFrontEnd )
				)
				( objectFlag fObjectAlias )
				( objectStatus "page133_gnd" )
			)
			( signal "@baseboard_fab2_lib.baseboard_fab2(sch_1):page134_gnd"
				( attribute "VOLTAGE" "0"
					( Units "uVoltage" "V" 1.000000)
					( Origin gFrontEnd )
				)
				( objectFlag fObjectAlias )
				( objectStatus "page134_gnd" )
			)
			( signal "@baseboard_fab2_lib.baseboard_fab2(sch_1):page135_gnd"
				( attribute "VOLTAGE" "0.0V"
					( Units "uVoltage" "V" 1.000000)
					( Origin gFrontEnd )
				)
				( objectFlag fObjectAlias )
				( objectStatus "page135_gnd" )
			)
			( signal "@baseboard_fab2_lib.baseboard_fab2(sch_1):page136_gnd"
				( attribute "VOLTAGE" "0"
					( Units "uVoltage" "V" 1.000000)
					( Origin gFrontEnd )
				)
				( objectFlag fObjectAlias )
				( objectStatus "page136_gnd" )
			)
			( signal "@baseboard_fab2_lib.baseboard_fab2(sch_1):page137_gnd"
				( attribute "VOLTAGE" "0.0V"
					( Units "uVoltage" "V" 1.000000)
					( Origin gFrontEnd )
				)
				( objectFlag fObjectAlias )
				( objectStatus "page137_gnd" )
			)
			( signal "@baseboard_fab2_lib.baseboard_fab2(sch_1):page139_gnd"
				( attribute "VOLTAGE" "0.0V"
					( Units "uVoltage" "V" 1.000000)
					( Origin gFrontEnd )
				)
				( objectFlag fObjectAlias )
				( objectStatus "page139_gnd" )
			)
			( signal "@baseboard_fab2_lib.baseboard_fab2(sch_1):page140_gnd"
				( attribute "VOLTAGE" "0.0V"
					( Units "uVoltage" "V" 1.000000)
					( Origin gFrontEnd )
				)
				( objectFlag fObjectAlias )
				( objectStatus "page140_gnd" )
			)
			( signal "@baseboard_fab2_lib.baseboard_fab2(sch_1):page141_gnd"
				( attribute "VOLTAGE" "0.0V"
					( Units "uVoltage" "V" 1.000000)
					( Origin gFrontEnd )
				)
				( objectFlag fObjectAlias )
				( objectStatus "page141_gnd" )
			)
			( signal "@baseboard_fab2_lib.baseboard_fab2(sch_1):page142_gnd"
				( attribute "VOLTAGE" "0.0V"
					( Units "uVoltage" "V" 1.000000)
					( Origin gFrontEnd )
				)
				( objectFlag fObjectAlias )
				( objectStatus "page142_gnd" )
			)
			( signal "@baseboard_fab2_lib.baseboard_fab2(sch_1):page152_gnd"
				( attribute "VOLTAGE" "0.0V"
					( Units "uVoltage" "V" 1.000000)
					( Origin gFrontEnd )
				)
				( objectFlag fObjectAlias )
				( objectStatus "page152_gnd" )
			)
			( signal "@baseboard_fab2_lib.baseboard_fab2(sch_1):page153_gnd"
				( attribute "VOLTAGE" "0.0V"
					( Units "uVoltage" "V" 1.000000)
					( Origin gFrontEnd )
				)
				( objectFlag fObjectAlias )
				( objectStatus "page153_gnd" )
			)
			( signal "@baseboard_fab2_lib.baseboard_fab2(sch_1):page154_gnd"
				( attribute "VOLTAGE" "0.0V"
					( Units "uVoltage" "V" 1.000000)
					( Origin gFrontEnd )
				)
				( objectFlag fObjectAlias )
				( objectStatus "page154_gnd" )
			)
			( signal "@baseboard_fab2_lib.baseboard_fab2(sch_1):page155_gnd"
				( attribute "VOLTAGE" "0.0V"
					( Units "uVoltage" "V" 1.000000)
					( Origin gFrontEnd )
				)
				( objectFlag fObjectAlias )
				( objectStatus "page155_gnd" )
			)
			( signal "@baseboard_fab2_lib.baseboard_fab2(sch_1):page156_gnd"
				( attribute "VOLTAGE" "0.0V"
					( Units "uVoltage" "V" 1.000000)
					( Origin gFrontEnd )
				)
				( objectFlag fObjectAlias )
				( objectStatus "page156_gnd" )
			)
			( signal "@baseboard_fab2_lib.baseboard_fab2(sch_1):page157_gnd"
				( attribute "VOLTAGE" "0.0V"
					( Units "uVoltage" "V" 1.000000)
					( Origin gFrontEnd )
				)
				( objectFlag fObjectAlias )
				( objectStatus "page157_gnd" )
			)
			( signal "@baseboard_fab2_lib.baseboard_fab2(sch_1):page158_gnd"
				( attribute "VOLTAGE" "0.0V"
					( Units "uVoltage" "V" 1.000000)
					( Origin gFrontEnd )
				)
				( objectFlag fObjectAlias )
				( objectStatus "page158_gnd" )
			)
			( signal "@baseboard_fab2_lib.baseboard_fab2(sch_1):page161_gnd"
				( attribute "VOLTAGE" "0.0V"
					( Units "uVoltage" "V" 1.000000)
					( Origin gFrontEnd )
				)
				( objectFlag fObjectAlias )
				( objectStatus "page161_gnd" )
			)
			( signal "@baseboard_fab2_lib.baseboard_fab2(sch_1):page162_gnd"
				( attribute "VOLTAGE" "0.0V"
					( Units "uVoltage" "V" 1.000000)
					( Origin gFrontEnd )
				)
				( objectFlag fObjectAlias )
				( objectStatus "page162_gnd" )
			)
			( signal "@baseboard_fab2_lib.baseboard_fab2(sch_1):page163_gnd"
				( attribute "VOLTAGE" "0"
					( Units "uVoltage" "V" 1.000000)
					( Origin gFrontEnd )
				)
				( objectFlag fObjectAlias )
				( objectStatus "page163_gnd" )
			)
			( signal "@baseboard_fab2_lib.baseboard_fab2(sch_1):page164_gnd"
				( attribute "VOLTAGE" "0.0V"
					( Units "uVoltage" "V" 1.000000)
					( Origin gFrontEnd )
				)
				( objectFlag fObjectAlias )
				( objectStatus "page164_gnd" )
			)
			( signal "@baseboard_fab2_lib.baseboard_fab2(sch_1):page166_gnd"
				( attribute "VOLTAGE" "0.0V"
					( Units "uVoltage" "V" 1.000000)
					( Origin gFrontEnd )
				)
				( objectFlag fObjectAlias )
				( objectStatus "page166_gnd" )
			)
			( signal "@baseboard_fab2_lib.baseboard_fab2(sch_1):page167_gnd"
				( attribute "VOLTAGE" "0.0V"
					( Units "uVoltage" "V" 1.000000)
					( Origin gFrontEnd )
				)
				( objectFlag fObjectAlias )
				( objectStatus "page167_gnd" )
			)
			( signal "@baseboard_fab2_lib.baseboard_fab2(sch_1):page168_gnd"
				( attribute "VOLTAGE" "0.0V"
					( Units "uVoltage" "V" 1.000000)
					( Origin gFrontEnd )
				)
				( objectFlag fObjectAlias )
				( objectStatus "page168_gnd" )
			)
			( signal "@baseboard_fab2_lib.baseboard_fab2(sch_1):page169_gnd"
				( attribute "VOLTAGE" "0"
					( Units "uVoltage" "V" 1.000000)
					( Origin gFrontEnd )
				)
				( objectFlag fObjectAlias )
				( objectStatus "page169_gnd" )
			)
			( signal "@baseboard_fab2_lib.baseboard_fab2(sch_1):page170_gnd"
				( attribute "VOLTAGE" "0.0V"
					( Units "uVoltage" "V" 1.000000)
					( Origin gFrontEnd )
				)
				( objectFlag fObjectAlias )
				( objectStatus "page170_gnd" )
			)
			( signal "@baseboard_fab2_lib.baseboard_fab2(sch_1):page172_gnd"
				( attribute "VOLTAGE" "0"
					( Units "uVoltage" "V" 1.000000)
					( Origin gFrontEnd )
				)
				( objectFlag fObjectAlias )
				( objectStatus "page172_gnd" )
			)
			( signal "@baseboard_fab2_lib.baseboard_fab2(sch_1):page173_gnd"
				( attribute "VOLTAGE" "0.0V"
					( Units "uVoltage" "V" 1.000000)
					( Origin gFrontEnd )
				)
				( objectFlag fObjectAlias )
				( objectStatus "page173_gnd" )
			)
			( signal "@baseboard_fab2_lib.baseboard_fab2(sch_1):page175_gnd"
				( attribute "VOLTAGE" "0.0V"
					( Units "uVoltage" "V" 1.000000)
					( Origin gFrontEnd )
				)
				( objectFlag fObjectAlias )
				( objectStatus "page175_gnd" )
			)
			( signal "@baseboard_fab2_lib.baseboard_fab2(sch_1):page176_gnd"
				( attribute "VOLTAGE" "0"
					( Units "uVoltage" "V" 1.000000)
					( Origin gFrontEnd )
				)
				( objectFlag fObjectAlias )
				( objectStatus "page176_gnd" )
			)
			( signal "@baseboard_fab2_lib.baseboard_fab2(sch_1):page177_gnd"
				( attribute "VOLTAGE" "0"
					( Units "uVoltage" "V" 1.000000)
					( Origin gFrontEnd )
				)
				( objectFlag fObjectAlias )
				( objectStatus "page177_gnd" )
			)
			( signal "@baseboard_fab2_lib.baseboard_fab2(sch_1):page181_gnd"
				( attribute "VOLTAGE" "0"
					( Units "uVoltage" "V" 1.000000)
					( Origin gFrontEnd )
				)
				( objectFlag fObjectAlias )
				( objectStatus "page181_gnd" )
			)
			( signal "@baseboard_fab2_lib.baseboard_fab2(sch_1):page182_gnd"
				( attribute "VOLTAGE" "0"
					( Units "uVoltage" "V" 1.000000)
					( Origin gFrontEnd )
				)
				( objectFlag fObjectAlias )
				( objectStatus "page182_gnd" )
			)
			( signal "@baseboard_fab2_lib.baseboard_fab2(sch_1):page184_gnd"
				( attribute "VOLTAGE" "0"
					( Units "uVoltage" "V" 1.000000)
					( Origin gFrontEnd )
				)
				( objectFlag fObjectAlias )
				( objectStatus "page184_gnd" )
			)
			( signal "@baseboard_fab2_lib.baseboard_fab2(sch_1):page185_gnd"
				( attribute "VOLTAGE" "0.0V"
					( Units "uVoltage" "V" 1.000000)
					( Origin gFrontEnd )
				)
				( objectFlag fObjectAlias )
				( objectStatus "page185_gnd" )
			)
			( signal "@baseboard_fab2_lib.baseboard_fab2(sch_1):page186_gnd"
				( attribute "VOLTAGE" "0"
					( Units "uVoltage" "V" 1.000000)
					( Origin gFrontEnd )
				)
				( objectFlag fObjectAlias )
				( objectStatus "page186_gnd" )
			)
			( signal "@baseboard_fab2_lib.baseboard_fab2(sch_1):page187_gnd"
				( attribute "VOLTAGE" "0"
					( Units "uVoltage" "V" 1.000000)
					( Origin gFrontEnd )
				)
				( objectFlag fObjectAlias )
				( objectStatus "page187_gnd" )
			)
			( signal "@baseboard_fab2_lib.baseboard_fab2(sch_1):page188_gnd"
				( attribute "VOLTAGE" "0"
					( Units "uVoltage" "V" 1.000000)
					( Origin gFrontEnd )
				)
				( objectFlag fObjectAlias )
				( objectStatus "page188_gnd" )
			)
			( signal "@baseboard_fab2_lib.baseboard_fab2(sch_1):page189_gnd"
				( attribute "VOLTAGE" "0.0V"
					( Units "uVoltage" "V" 1.000000)
					( Origin gFrontEnd )
				)
				( objectFlag fObjectAlias )
				( objectStatus "page189_gnd" )
			)
			( signal "@baseboard_fab2_lib.baseboard_fab2(sch_1):page192_gnd"
				( attribute "VOLTAGE" "0.0V"
					( Units "uVoltage" "V" 1.000000)
					( Origin gFrontEnd )
				)
				( objectFlag fObjectAlias )
				( objectStatus "page192_gnd" )
			)
			( signal "@baseboard_fab2_lib.baseboard_fab2(sch_1):page193_gnd"
				( attribute "VOLTAGE" "0.0V"
					( Units "uVoltage" "V" 1.000000)
					( Origin gFrontEnd )
				)
				( objectFlag fObjectAlias )
				( objectStatus "page193_gnd" )
			)
			( signal "@baseboard_fab2_lib.baseboard_fab2(sch_1):page194_gnd"
				( attribute "VOLTAGE" "0"
					( Units "uVoltage" "V" 1.000000)
					( Origin gFrontEnd )
				)
				( objectFlag fObjectAlias )
				( objectStatus "page194_gnd" )
			)
			( signal "@baseboard_fab2_lib.baseboard_fab2(sch_1):page195_gnd"
				( attribute "VOLTAGE" "0.0V"
					( Units "uVoltage" "V" 1.000000)
					( Origin gFrontEnd )
				)
				( objectFlag fObjectAlias )
				( objectStatus "page195_gnd" )
			)
			( signal "@baseboard_fab2_lib.baseboard_fab2(sch_1):page196_gnd"
				( attribute "VOLTAGE" "0.0V"
					( Units "uVoltage" "V" 1.000000)
					( Origin gFrontEnd )
				)
				( objectFlag fObjectAlias )
				( objectStatus "page196_gnd" )
			)
			( signal "@baseboard_fab2_lib.baseboard_fab2(sch_1):page197_gnd"
				( attribute "VOLTAGE" "0.0V"
					( Units "uVoltage" "V" 1.000000)
					( Origin gFrontEnd )
				)
				( objectFlag fObjectAlias )
				( objectStatus "page197_gnd" )
			)
			( signal "@baseboard_fab2_lib.baseboard_fab2(sch_1):page198_gnd"
				( attribute "VOLTAGE" "0.0V"
					( Units "uVoltage" "V" 1.000000)
					( Origin gFrontEnd )
				)
				( objectFlag fObjectAlias )
				( objectStatus "page198_gnd" )
			)
			( signal "@baseboard_fab2_lib.baseboard_fab2(sch_1):page199_gnd"
				( attribute "VOLTAGE" "0"
					( Units "uVoltage" "V" 1.000000)
					( Origin gFrontEnd )
				)
				( objectFlag fObjectAlias )
				( objectStatus "page199_gnd" )
			)
			( signal "@baseboard_fab2_lib.baseboard_fab2(sch_1):page200_gnd"
				( attribute "VOLTAGE" "0.0V"
					( Units "uVoltage" "V" 1.000000)
					( Origin gFrontEnd )
				)
				( objectFlag fObjectAlias )
				( objectStatus "page200_gnd" )
			)
			( signal "@baseboard_fab2_lib.baseboard_fab2(sch_1):page201_gnd"
				( attribute "VOLTAGE" "0"
					( Units "uVoltage" "V" 1.000000)
					( Origin gFrontEnd )
				)
				( objectFlag fObjectAlias )
				( objectStatus "page201_gnd" )
			)
			( signal "@baseboard_fab2_lib.baseboard_fab2(sch_1):page202_gnd"
				( attribute "VOLTAGE" "0"
					( Units "uVoltage" "V" 1.000000)
					( Origin gFrontEnd )
				)
				( objectFlag fObjectAlias )
				( objectStatus "page202_gnd" )
			)
			( signal "@baseboard_fab2_lib.baseboard_fab2(sch_1):page203_gnd"
				( attribute "VOLTAGE" "0"
					( Units "uVoltage" "V" 1.000000)
					( Origin gFrontEnd )
				)
				( objectFlag fObjectAlias )
				( objectStatus "page203_gnd" )
			)
			( signal "@baseboard_fab2_lib.baseboard_fab2(sch_1):page204_gnd"
				( attribute "VOLTAGE" "0"
					( Units "uVoltage" "V" 1.000000)
					( Origin gFrontEnd )
				)
				( objectFlag fObjectAlias )
				( objectStatus "page204_gnd" )
			)
			( signal "@baseboard_fab2_lib.baseboard_fab2(sch_1):page205_gnd"
				( attribute "VOLTAGE" "0"
					( Units "uVoltage" "V" 1.000000)
					( Origin gFrontEnd )
				)
				( objectFlag fObjectAlias )
				( objectStatus "page205_gnd" )
			)
			( signal "@baseboard_fab2_lib.baseboard_fab2(sch_1):page206_gnd"
				( attribute "VOLTAGE" "0"
					( Units "uVoltage" "V" 1.000000)
					( Origin gFrontEnd )
				)
				( objectFlag fObjectAlias )
				( objectStatus "page206_gnd" )
			)
			( signal "@baseboard_fab2_lib.baseboard_fab2(sch_1):page207_gnd"
				( attribute "VOLTAGE" "0"
					( Units "uVoltage" "V" 1.000000)
					( Origin gFrontEnd )
				)
				( objectFlag fObjectAlias )
				( objectStatus "page207_gnd" )
			)
			( signal "@baseboard_fab2_lib.baseboard_fab2(sch_1):page208_gnd"
				( attribute "VOLTAGE" "0"
					( Units "uVoltage" "V" 1.000000)
					( Origin gFrontEnd )
				)
				( objectFlag fObjectAlias )
				( objectStatus "page208_gnd" )
			)
			( signal "@baseboard_fab2_lib.baseboard_fab2(sch_1):page209_gnd"
				( attribute "VOLTAGE" "0"
					( Units "uVoltage" "V" 1.000000)
					( Origin gFrontEnd )
				)
				( objectFlag fObjectAlias )
				( objectStatus "page209_gnd" )
			)
			( signal "@baseboard_fab2_lib.baseboard_fab2(sch_1):page210_gnd"
				( attribute "VOLTAGE" "0"
					( Units "uVoltage" "V" 1.000000)
					( Origin gFrontEnd )
				)
				( objectFlag fObjectAlias )
				( objectStatus "page210_gnd" )
			)
			( signal "@baseboard_fab2_lib.baseboard_fab2(sch_1):page211_gnd"
				( attribute "VOLTAGE" "0"
					( Units "uVoltage" "V" 1.000000)
					( Origin gFrontEnd )
				)
				( objectFlag fObjectAlias )
				( objectStatus "page211_gnd" )
			)
			( signal "@baseboard_fab2_lib.baseboard_fab2(sch_1):page212_gnd"
				( attribute "VOLTAGE" "0"
					( Units "uVoltage" "V" 1.000000)
					( Origin gFrontEnd )
				)
				( objectFlag fObjectAlias )
				( objectStatus "page212_gnd" )
			)
			( signal "@baseboard_fab2_lib.baseboard_fab2(sch_1):page213_gnd"
				( attribute "VOLTAGE" "0"
					( Units "uVoltage" "V" 1.000000)
					( Origin gFrontEnd )
				)
				( objectFlag fObjectAlias )
				( objectStatus "page213_gnd" )
			)
			( signal "@baseboard_fab2_lib.baseboard_fab2(sch_1):page214_gnd"
				( attribute "VOLTAGE" "0"
					( Units "uVoltage" "V" 1.000000)
					( Origin gFrontEnd )
				)
				( objectFlag fObjectAlias )
				( objectStatus "page214_gnd" )
			)
			( signal "@baseboard_fab2_lib.baseboard_fab2(sch_1):page215_gnd"
				( attribute "VOLTAGE" "0"
					( Units "uVoltage" "V" 1.000000)
					( Origin gFrontEnd )
				)
				( objectFlag fObjectAlias )
				( objectStatus "page215_gnd" )
			)
			( signal "@baseboard_fab2_lib.baseboard_fab2(sch_1):page216_gnd"
				( attribute "VOLTAGE" "0"
					( Units "uVoltage" "V" 1.000000)
					( Origin gFrontEnd )
				)
				( objectFlag fObjectAlias )
				( objectStatus "page216_gnd" )
			)
			( signal "@baseboard_fab2_lib.baseboard_fab2(sch_1):page217_gnd"
				( attribute "VOLTAGE" "0"
					( Units "uVoltage" "V" 1.000000)
					( Origin gFrontEnd )
				)
				( objectFlag fObjectAlias )
				( objectStatus "page217_gnd" )
			)
			( signal "@baseboard_fab2_lib.baseboard_fab2(sch_1):page218_gnd"
				( attribute "VOLTAGE" "0"
					( Units "uVoltage" "V" 1.000000)
					( Origin gFrontEnd )
				)
				( objectFlag fObjectAlias )
				( objectStatus "page218_gnd" )
			)
			( signal "@baseboard_fab2_lib.baseboard_fab2(sch_1):page219_gnd"
				( attribute "VOLTAGE" "0"
					( Units "uVoltage" "V" 1.000000)
					( Origin gFrontEnd )
				)
				( objectFlag fObjectAlias )
				( objectStatus "page219_gnd" )
			)
			( signal "@baseboard_fab2_lib.baseboard_fab2(sch_1):page220_gnd"
				( attribute "VOLTAGE" "0"
					( Units "uVoltage" "V" 1.000000)
					( Origin gFrontEnd )
				)
				( objectFlag fObjectAlias )
				( objectStatus "page220_gnd" )
			)
			( signal "@baseboard_fab2_lib.baseboard_fab2(sch_1):page221_gnd"
				( attribute "VOLTAGE" "0.0V"
					( Units "uVoltage" "V" 1.000000)
					( Origin gFrontEnd )
				)
				( objectFlag fObjectAlias )
				( objectStatus "page221_gnd" )
			)
			( signal "@baseboard_fab2_lib.baseboard_fab2(sch_1):page222_gnd"
				( attribute "VOLTAGE" "0.0V"
					( Units "uVoltage" "V" 1.000000)
					( Origin gFrontEnd )
				)
				( objectFlag fObjectAlias )
				( objectStatus "page222_gnd" )
			)
			( signal "@baseboard_fab2_lib.baseboard_fab2(sch_1):page223_gnd"
				( attribute "VOLTAGE" "0"
					( Units "uVoltage" "V" 1.000000)
					( Origin gFrontEnd )
				)
				( objectFlag fObjectAlias )
				( objectStatus "page223_gnd" )
			)
			( signal "@baseboard_fab2_lib.baseboard_fab2(sch_1):page224_gnd"
				( attribute "VOLTAGE" "0"
					( Units "uVoltage" "V" 1.000000)
					( Origin gFrontEnd )
				)
				( objectFlag fObjectAlias )
				( objectStatus "page224_gnd" )
			)
			( signal "@baseboard_fab2_lib.baseboard_fab2(sch_1):page225_gnd"
				( attribute "VOLTAGE" "0"
					( Units "uVoltage" "V" 1.000000)
					( Origin gFrontEnd )
				)
				( objectFlag fObjectAlias )
				( objectStatus "page225_gnd" )
			)
			( signal "@baseboard_fab2_lib.baseboard_fab2(sch_1):page226_gnd"
				( attribute "VOLTAGE" "0"
					( Units "uVoltage" "V" 1.000000)
					( Origin gFrontEnd )
				)
				( objectFlag fObjectAlias )
				( objectStatus "page226_gnd" )
			)
			( signal "@baseboard_fab2_lib.baseboard_fab2(sch_1):page227_gnd"
				( attribute "VOLTAGE" "0"
					( Units "uVoltage" "V" 1.000000)
					( Origin gFrontEnd )
				)
				( objectFlag fObjectAlias )
				( objectStatus "page227_gnd" )
			)
			( signal "@baseboard_fab2_lib.baseboard_fab2(sch_1):page228_gnd"
				( attribute "VOLTAGE" "0"
					( Units "uVoltage" "V" 1.000000)
					( Origin gFrontEnd )
				)
				( objectFlag fObjectAlias )
				( objectStatus "page228_gnd" )
			)
			( signal "@baseboard_fab2_lib.baseboard_fab2(sch_1):page229_gnd"
				( attribute "VOLTAGE" "0.0V"
					( Units "uVoltage" "V" 1.000000)
					( Origin gFrontEnd )
				)
				( objectFlag fObjectAlias )
				( objectStatus "page229_gnd" )
			)
			( signal "@baseboard_fab2_lib.baseboard_fab2(sch_1):page230_gnd"
				( attribute "VOLTAGE" "0.0V"
					( Units "uVoltage" "V" 1.000000)
					( Origin gFrontEnd )
				)
				( objectFlag fObjectAlias )
				( objectStatus "page230_gnd" )
			)
			( signal "@baseboard_fab2_lib.baseboard_fab2(sch_1):page231_gnd"
				( attribute "VOLTAGE" "0"
					( Units "uVoltage" "V" 1.000000)
					( Origin gFrontEnd )
				)
				( objectFlag fObjectAlias )
				( objectStatus "page231_gnd" )
			)
			( signal "@baseboard_fab2_lib.baseboard_fab2(sch_1):page232_gnd"
				( attribute "VOLTAGE" "0"
					( Units "uVoltage" "V" 1.000000)
					( Origin gFrontEnd )
				)
				( objectFlag fObjectAlias )
				( objectStatus "page232_gnd" )
			)
			( signal "@baseboard_fab2_lib.baseboard_fab2(sch_1):page233_gnd"
				( attribute "VOLTAGE" "0"
					( Units "uVoltage" "V" 1.000000)
					( Origin gFrontEnd )
				)
				( objectFlag fObjectAlias )
				( objectStatus "page233_gnd" )
			)
			( signal "@baseboard_fab2_lib.baseboard_fab2(sch_1):page234_gnd"
				( attribute "VOLTAGE" "0"
					( Units "uVoltage" "V" 1.000000)
					( Origin gFrontEnd )
				)
				( objectFlag fObjectAlias )
				( objectStatus "page234_gnd" )
			)
			( signal "@baseboard_fab2_lib.baseboard_fab2(sch_1):page235_gnd"
				( attribute "VOLTAGE" "0"
					( Units "uVoltage" "V" 1.000000)
					( Origin gFrontEnd )
				)
				( objectFlag fObjectAlias )
				( objectStatus "page235_gnd" )
			)
			( signal "@baseboard_fab2_lib.baseboard_fab2(sch_1):page236_gnd"
				( attribute "VOLTAGE" "0.0V"
					( Units "uVoltage" "V" 1.000000)
					( Origin gFrontEnd )
				)
				( objectFlag fObjectAlias )
				( objectStatus "page236_gnd" )
			)
			( signal "@baseboard_fab2_lib.baseboard_fab2(sch_1):page237_gnd"
				( attribute "VOLTAGE" "0.0V"
					( Units "uVoltage" "V" 1.000000)
					( Origin gFrontEnd )
				)
				( objectFlag fObjectAlias )
				( objectStatus "page237_gnd" )
			)
			( signal "@baseboard_fab2_lib.baseboard_fab2(sch_1):page238_gnd"
				( attribute "VOLTAGE" "0.0V"
					( Units "uVoltage" "V" 1.000000)
					( Origin gFrontEnd )
				)
				( objectFlag fObjectAlias )
				( objectStatus "page238_gnd" )
			)
			( signal "@baseboard_fab2_lib.baseboard_fab2(sch_1):page239_gnd"
				( attribute "VOLTAGE" "0.0V"
					( Units "uVoltage" "V" 1.000000)
					( Origin gFrontEnd )
				)
				( objectFlag fObjectAlias )
				( objectStatus "page239_gnd" )
			)
			( signal "@baseboard_fab2_lib.baseboard_fab2(sch_1):page240_gnd"
				( attribute "VOLTAGE" "0"
					( Units "uVoltage" "V" 1.000000)
					( Origin gFrontEnd )
				)
				( objectFlag fObjectAlias )
				( objectStatus "page240_gnd" )
			)
			( signal "@baseboard_fab2_lib.baseboard_fab2(sch_1):page241_gnd"
				( attribute "VOLTAGE" "0"
					( Units "uVoltage" "V" 1.000000)
					( Origin gFrontEnd )
				)
				( objectFlag fObjectAlias )
				( objectStatus "page241_gnd" )
			)
			( signal "@baseboard_fab2_lib.baseboard_fab2(sch_1):page242_gnd"
				( attribute "VOLTAGE" "0"
					( Units "uVoltage" "V" 1.000000)
					( Origin gFrontEnd )
				)
				( objectFlag fObjectAlias )
				( objectStatus "page242_gnd" )
			)
			( signal "@baseboard_fab2_lib.baseboard_fab2(sch_1):page243_gnd"
				( attribute "VOLTAGE" "0"
					( Units "uVoltage" "V" 1.000000)
					( Origin gFrontEnd )
				)
				( objectFlag fObjectAlias )
				( objectStatus "page243_gnd" )
			)
			( signal "@baseboard_fab2_lib.baseboard_fab2(sch_1):page245_gnd"
				( attribute "BOM_COST" "TBD"
					( Origin gFrontEnd )
				)
				( attribute "CDS_PHYS_NET_NAME" "GND"
					( Origin gPackager )
				)
				( attribute "ROOM" "TBD"
					( Origin gFrontEnd )
				)
				( attribute "VOLTAGE" "0"
					( Units "uVoltage" "V" 1.000000)
					( Origin gFrontEnd )
				)
				( objectFlag fObjectAlias )
				( objectStatus "page245_gnd" )
			)
			( signal "@baseboard_fab2_lib.baseboard_fab2(sch_1):page246_gnd"
				( attribute "VOLTAGE" "0"
					( Units "uVoltage" "V" 1.000000)
					( Origin gFrontEnd )
				)
				( objectFlag fObjectAlias )
				( objectStatus "page246_gnd" )
			)
			( signal "@baseboard_fab2_lib.baseboard_fab2(sch_1):page247_gnd"
				( attribute "VOLTAGE" "0"
					( Units "uVoltage" "V" 1.000000)
					( Origin gFrontEnd )
				)
				( objectFlag fObjectAlias )
				( objectStatus "page247_gnd" )
			)
			( signal "@baseboard_fab2_lib.baseboard_fab2(sch_1):page249_gnd"
				( attribute "VOLTAGE" "0.0V"
					( Units "uVoltage" "V" 1.000000)
					( Origin gFrontEnd )
				)
				( objectFlag fObjectAlias )
				( objectStatus "page249_gnd" )
			)
			( signal "@baseboard_fab2_lib.baseboard_fab2(sch_1):page150_gnd"
				( attribute "VOLTAGE" "0.0V"
					( Units "uVoltage" "V" 1.000000)
					( Origin gFrontEnd )
				)
				( objectFlag fObjectAlias )
				( objectStatus "page150_gnd" )
			)
			( signal "@baseboard_fab2_lib.baseboard_fab2(sch_1):page143_gnd"
				( attribute "VOLTAGE" "0.0V"
					( Units "uVoltage" "V" 1.000000)
					( Origin gFrontEnd )
				)
				( objectFlag fObjectAlias )
				( objectStatus "page143_gnd" )
			)
			( signal "@baseboard_fab2_lib.baseboard_fab2(sch_1):page144_gnd"
				( attribute "VOLTAGE" "0.0V"
					( Units "uVoltage" "V" 1.000000)
					( Origin gFrontEnd )
				)
				( objectFlag fObjectAlias )
				( objectStatus "page144_gnd" )
			)
			( signal "@baseboard_fab2_lib.baseboard_fab2(sch_1):page145_gnd"
				( attribute "VOLTAGE" "0.0V"
					( Units "uVoltage" "V" 1.000000)
					( Origin gFrontEnd )
				)
				( objectFlag fObjectAlias )
				( objectStatus "page145_gnd" )
			)
			( signal "@baseboard_fab2_lib.baseboard_fab2(sch_1):page146_gnd"
				( attribute "VOLTAGE" "0.0V"
					( Units "uVoltage" "V" 1.000000)
					( Origin gFrontEnd )
				)
				( objectFlag fObjectAlias )
				( objectStatus "page146_gnd" )
			)
			( signal "@baseboard_fab2_lib.baseboard_fab2(sch_1):page147_gnd"
				( attribute "VOLTAGE" "0.0V"
					( Units "uVoltage" "V" 1.000000)
					( Origin gFrontEnd )
				)
				( objectFlag fObjectAlias )
				( objectStatus "page147_gnd" )
			)
			( signal "@baseboard_fab2_lib.baseboard_fab2(sch_1):page148_gnd"
				( attribute "VOLTAGE" "0.0V"
					( Units "uVoltage" "V" 1.000000)
					( Origin gFrontEnd )
				)
				( objectFlag fObjectAlias )
				( objectStatus "page148_gnd" )
			)
			( signal "@baseboard_fab2_lib.baseboard_fab2(sch_1):page151_gnd"
				( attribute "VOLTAGE" "0.0V"
					( Units "uVoltage" "V" 1.000000)
					( Origin gFrontEnd )
				)
				( objectFlag fObjectAlias )
				( objectStatus "page151_gnd" )
			)
			( signal "@baseboard_fab2_lib.baseboard_fab2(sch_1):page149_gnd"
				( attribute "VOLTAGE" "0.0V"
					( Units "uVoltage" "V" 1.000000)
					( Origin gFrontEnd )
				)
				( objectFlag fObjectAlias )
				( objectStatus "page149_gnd" )
			)
			( signal "@baseboard_fab2_lib.baseboard_fab2(sch_1):page248_gnd"
				( attribute "VOLTAGE" "0.0V"
					( Units "uVoltage" "V" 1.000000)
					( Origin gFrontEnd )
				)
				( objectFlag fObjectAlias )
				( objectStatus "page248_gnd" )
			)
			( signal "@baseboard_fab2_lib.baseboard_fab2(sch_1):page250_gnd"
				( attribute "VOLTAGE" "0.0V"
					( Units "uVoltage" "V" 1.000000)
					( Origin gFrontEnd )
				)
				( objectFlag fObjectAlias )
				( objectStatus "page250_gnd" )
			)
			( signal "@baseboard_fab2_lib.baseboard_fab2(sch_1):page251_gnd"
				( attribute "VOLTAGE" "0.0V"
					( Units "uVoltage" "V" 1.000000)
					( Origin gFrontEnd )
				)
				( objectFlag fObjectAlias )
				( objectStatus "page251_gnd" )
			)
			( signal "@baseboard_fab2_lib.baseboard_fab2(sch_1):page255_gnd"
				( attribute "VOLTAGE" "0.0V"
					( Units "uVoltage" "V" 1.000000)
					( Origin gFrontEnd )
				)
				( objectFlag fObjectAlias )
				( objectStatus "page255_gnd" )
			)
			( signal "@baseboard_fab2_lib.baseboard_fab2(sch_1):page253_gnd"
				( attribute "VOLTAGE" "0.0V"
					( Units "uVoltage" "V" 1.000000)
					( Origin gFrontEnd )
				)
				( objectFlag fObjectAlias )
				( objectStatus "page253_gnd" )
			)
			( signal "@baseboard_fab2_lib.baseboard_fab2(sch_1):page190_gnd"
				( attribute "VOLTAGE" "0.0V"
					( Units "uVoltage" "V" 1.000000)
					( Origin gFrontEnd )
				)
				( objectFlag fObjectAlias )
				( objectStatus "page190_gnd" )
			)
			( signal "@baseboard_fab2_lib.baseboard_fab2(sch_1):page269_gnd"
				( attribute "VOLTAGE" "0.0V"
					( Units "uVoltage" "V" 1.000000)
					( Origin gFrontEnd )
				)
				( objectFlag fObjectAlias )
				( objectStatus "page269_gnd" )
			)
			( signal "@baseboard_fab2_lib.baseboard_fab2(sch_1):page268_gnd"
				( attribute "VOLTAGE" "0.0V"
					( Units "uVoltage" "V" 1.000000)
					( Origin gFrontEnd )
				)
				( objectFlag fObjectAlias )
				( objectStatus "page268_gnd" )
			)
			( signal "@baseboard_fab2_lib.baseboard_fab2(sch_1):page270_gnd"
				( attribute "VOLTAGE" "0.0V"
					( Units "uVoltage" "V" 1.000000)
					( Origin gFrontEnd )
				)
				( objectFlag fObjectAlias )
				( objectStatus "page270_gnd" )
			)
			( signal "@baseboard_fab2_lib.baseboard_fab2(sch_1):page272_gnd"
				( attribute "VOLTAGE" "0.0V"
					( Units "uVoltage" "V" 1.000000)
					( Origin gFrontEnd )
				)
				( objectFlag fObjectAlias )
				( objectStatus "page272_gnd" )
			)
			( signal "@baseboard_fab2_lib.baseboard_fab2(sch_1):page271_gnd"
				( attribute "VOLTAGE" "0.0V"
					( Units "uVoltage" "V" 1.000000)
					( Origin gFrontEnd )
				)
				( objectFlag fObjectAlias )
				( objectStatus "page271_gnd" )
			)
			( signal "@baseboard_fab2_lib.baseboard_fab2(sch_1):bmc_vga_vsync"
				( attribute "CDS_PHYS_NET_NAME" "BMC_VGA_VSYNC"
					( Origin gPackager )
				)
				( objectStatus "BMC_VGA_VSYNC" )
			)
			( signal "@baseboard_fab2_lib.baseboard_fab2(sch_1):fm_adr_smi_gpio_n"
				( attribute "CDS_PHYS_NET_NAME" "FM_ADR_SMI_GPIO_N"
					( Origin gPackager )
				)
				( objectStatus "FM_ADR_SMI_GPIO_N" )
			)
			( signal "@baseboard_fab2_lib.baseboard_fab2(sch_1):irq_dimm_save_lvt3_n"
				( alias ( signalRef "@baseboard_fab2_lib.baseboard_fab2(sch_1):page145_irq_dimm_save_lvt3_n") )
				( attribute "CDS_PHYS_NET_NAME" "IRQ_DIMM_SAVE_LVT3_N"
					( Origin gPackager )
				)
				( objectStatus "IRQ_DIMM_SAVE_LVT3_N" )
			)
			( signal "@baseboard_fab2_lib.baseboard_fab2(sch_1):page145_irq_dimm_save_lvt3_n"
				( attribute "CDS_PHYS_NET_NAME" "IRQ_DIMM_SAVE_LVT3_N"
					( Origin gPackager )
				)
				( attribute "PHYS_NET_NAME" "IRQ_DIMM_SAVE_LVT3_N"
					( Origin gFrontEnd )
				)
				( objectFlag fObjectAlias )
				( objectStatus "page145_irq_dimm_save_lvt3_n" )
			)
			( signal "@baseboard_fab2_lib.baseboard_fab2(sch_1):h_cpu0_bmcinit"
				( attribute "CDS_PHYS_NET_NAME" "H_CPU0_BMCINIT"
					( Origin gPackager )
				)
				( objectStatus "H_CPU0_BMCINIT" )
			)
			( signal "@baseboard_fab2_lib.baseboard_fab2(sch_1):h_cpu0_caterr_g_n"
				( attribute "CDS_PHYS_NET_NAME" "H_CPU0_CATERR_G_N"
					( Origin gPackager )
				)
				( objectStatus "H_CPU0_CATERR_G_N" )
			)
			( signal "@baseboard_fab2_lib.baseboard_fab2(sch_1):h_cpu0_err0_g_n"
				( attribute "CDS_PHYS_NET_NAME" "H_CPU0_ERR0_G_N"
					( Origin gPackager )
				)
				( objectStatus "H_CPU0_ERR0_G_N" )
			)
			( signal "@baseboard_fab2_lib.baseboard_fab2(sch_1):h_cpu0_err1_g_n"
				( attribute "CDS_PHYS_NET_NAME" "H_CPU0_ERR1_G_N"
					( Origin gPackager )
				)
				( objectStatus "H_CPU0_ERR1_G_N" )
			)
			( signal "@baseboard_fab2_lib.baseboard_fab2(sch_1):h_cpu0_err2_g_n"
				( attribute "CDS_PHYS_NET_NAME" "H_CPU0_ERR2_G_N"
					( Origin gPackager )
				)
				( objectStatus "H_CPU0_ERR2_G_N" )
			)
			( signal "@baseboard_fab2_lib.baseboard_fab2(sch_1):h_cpu0_fast_wake_n"
				( attribute "CDS_PHYS_NET_NAME" "H_CPU0_FAST_WAKE_N"
					( Origin gPackager )
				)
				( objectStatus "H_CPU0_FAST_WAKE_N" )
			)
			( signal "@baseboard_fab2_lib.baseboard_fab2(sch_1):h_cpu0_memabc_memhot_g_n"
				( attribute "CDS_PHYS_NET_NAME" "H_CPU0_MEMABC_MEMHOT_G_N"
					( Origin gPackager )
				)
				( objectStatus "H_CPU0_MEMABC_MEMHOT_G_N" )
			)
			( signal "@baseboard_fab2_lib.baseboard_fab2(sch_1):h_cpu0_memdef_memhot_g_n"
				( attribute "CDS_PHYS_NET_NAME" "H_CPU0_MEMDEF_MEMHOT_G_N"
					( Origin gPackager )
				)
				( objectStatus "H_CPU0_MEMDEF_MEMHOT_G_N" )
			)
			( signal "@baseboard_fab2_lib.baseboard_fab2(sch_1):h_cpu0_msmi_g_n"
				( attribute "CDS_PHYS_NET_NAME" "H_CPU0_MSMI_G_N"
					( Origin gPackager )
				)
				( objectStatus "H_CPU0_MSMI_G_N" )
			)
			( signal "@baseboard_fab2_lib.baseboard_fab2(sch_1):h_cpu0_prochot_g_n"
				( attribute "CDS_PHYS_NET_NAME" "H_CPU0_PROCHOT_G_N"
					( Origin gPackager )
				)
				( objectStatus "H_CPU0_PROCHOT_G_N" )
			)
			( signal "@baseboard_fab2_lib.baseboard_fab2(sch_1):h_cpu0_thermtrip_g_n"
				( attribute "CDS_PHYS_NET_NAME" "H_CPU0_THERMTRIP_G_N"
					( Origin gPackager )
				)
				( objectStatus "H_CPU0_THERMTRIP_G_N" )
			)
			( signal "@baseboard_fab2_lib.baseboard_fab2(sch_1):h_pm_sync_gtl"
				( attribute "CDS_PHYS_NET_NAME" "H_PM_SYNC_GTL"
					( Origin gPackager )
				)
				( objectStatus "H_PM_SYNC_GTL" )
			)
			( signal "@baseboard_fab2_lib.baseboard_fab2(sch_1):h_pm_sync_gtl_r1"
				( attribute "CDS_PHYS_NET_NAME" "H_PM_SYNC_GTL_R1"
					( Origin gPackager )
				)
				( objectStatus "H_PM_SYNC_GTL_R1" )
			)
			( signal "@baseboard_fab2_lib.baseboard_fab2(sch_1):h_pmsync_clk_24m"
				( attribute "CDS_PHYS_NET_NAME" "H_PMSYNC_CLK_24M"
					( Origin gPackager )
				)
				( objectStatus "H_PMSYNC_CLK_24M" )
			)
			( signal "@baseboard_fab2_lib.baseboard_fab2(sch_1):h_pmsync_clk_24m_cpu0"
				( attribute "CDS_PHYS_NET_NAME" "H_PMSYNC_CLK_24M_CPU0"
					( Origin gPackager )
				)
				( objectStatus "H_PMSYNC_CLK_24M_CPU0" )
			)
			( signal "@baseboard_fab2_lib.baseboard_fab2(sch_1):m_a_cpu_vref"
				( attribute "CDS_PHYS_NET_NAME" "M_A_CPU_VREF"
					( Origin gPackager )
				)
				( objectStatus "M_A_CPU_VREF" )
			)
			( signal "@baseboard_fab2_lib.baseboard_fab2(sch_1):m_abc_rst_n"
				( attribute "CDS_PHYS_NET_NAME" "M_ABC_RST_N"
					( Origin gPackager )
				)
				( objectStatus "M_ABC_RST_N" )
			)
			( signal "@baseboard_fab2_lib.baseboard_fab2(sch_1):m_b_cpu_vref"
				( attribute "CDS_PHYS_NET_NAME" "M_B_CPU_VREF"
					( Origin gPackager )
				)
				( objectStatus "M_B_CPU_VREF" )
			)
			( signal "@baseboard_fab2_lib.baseboard_fab2(sch_1):m_c_cpu_vref"
				( attribute "CDS_PHYS_NET_NAME" "M_C_CPU_VREF"
					( Origin gPackager )
				)
				( objectStatus "M_C_CPU_VREF" )
			)
			( signal "@baseboard_fab2_lib.baseboard_fab2(sch_1):m_d_cpu_vref"
				( attribute "CDS_PHYS_NET_NAME" "M_D_CPU_VREF"
					( Origin gPackager )
				)
				( objectStatus "M_D_CPU_VREF" )
			)
			( signal "@baseboard_fab2_lib.baseboard_fab2(sch_1):m_def_rst_n"
				( attribute "CDS_PHYS_NET_NAME" "M_DEF_RST_N"
					( Origin gPackager )
				)
				( objectStatus "M_DEF_RST_N" )
			)
			( signal "@baseboard_fab2_lib.baseboard_fab2(sch_1):m_e_cpu_vref"
				( attribute "CDS_PHYS_NET_NAME" "M_E_CPU_VREF"
					( Origin gPackager )
				)
				( objectStatus "M_E_CPU_VREF" )
			)
			( signal "@baseboard_fab2_lib.baseboard_fab2(sch_1):m_f_cpu_vref"
				( attribute "CDS_PHYS_NET_NAME" "M_F_CPU_VREF"
					( Origin gPackager )
				)
				( objectStatus "M_F_CPU_VREF" )
			)
			( signal "@baseboard_fab2_lib.baseboard_fab2(sch_1):p3v3_stby"
				( alias ( signalRef "@baseboard_fab2_lib.baseboard_fab2(sch_1):page21_p3v3_stby") )
				( alias ( signalRef "@baseboard_fab2_lib.baseboard_fab2(sch_1):page38_p3v3_stby") )
				( alias ( signalRef "@baseboard_fab2_lib.baseboard_fab2(sch_1):page55_p3v3_stby") )
				( alias ( signalRef "@baseboard_fab2_lib.baseboard_fab2(sch_1):page72_p3v3_stby") )
				( alias ( signalRef "@baseboard_fab2_lib.baseboard_fab2(sch_1):page89_p3v3_stby") )
				( alias ( signalRef "@baseboard_fab2_lib.baseboard_fab2(sch_1):page94_p3v3_stby") )
				( alias ( signalRef "@baseboard_fab2_lib.baseboard_fab2(sch_1):page95_p3v3_stby") )
				( alias ( signalRef "@baseboard_fab2_lib.baseboard_fab2(sch_1):page96_p3v3_stby") )
				( alias ( signalRef "@baseboard_fab2_lib.baseboard_fab2(sch_1):page101_p3v3_stby") )
				( alias ( signalRef "@baseboard_fab2_lib.baseboard_fab2(sch_1):page108_p3v3_stby") )
				( alias ( signalRef "@baseboard_fab2_lib.baseboard_fab2(sch_1):page111_p3v3_stby") )
				( alias ( signalRef "@baseboard_fab2_lib.baseboard_fab2(sch_1):page112_p3v3_stby") )
				( alias ( signalRef "@baseboard_fab2_lib.baseboard_fab2(sch_1):page113_p3v3_stby") )
				( alias ( signalRef "@baseboard_fab2_lib.baseboard_fab2(sch_1):page118_p3v3_stby") )
				( alias ( signalRef "@baseboard_fab2_lib.baseboard_fab2(sch_1):page119_p3v3_stby") )
				( alias ( signalRef "@baseboard_fab2_lib.baseboard_fab2(sch_1):page121_p3v3_stby") )
				( alias ( signalRef "@baseboard_fab2_lib.baseboard_fab2(sch_1):page122_p3v3_stby") )
				( alias ( signalRef "@baseboard_fab2_lib.baseboard_fab2(sch_1):page125_p3v3_stby") )
				( alias ( signalRef "@baseboard_fab2_lib.baseboard_fab2(sch_1):page126_p3v3_stby") )
				( alias ( signalRef "@baseboard_fab2_lib.baseboard_fab2(sch_1):page130_p3v3_stby") )
				( alias ( signalRef "@baseboard_fab2_lib.baseboard_fab2(sch_1):page133_p3v3_stby") )
				( alias ( signalRef "@baseboard_fab2_lib.baseboard_fab2(sch_1):page134_p3v3_stby") )
				( alias ( signalRef "@baseboard_fab2_lib.baseboard_fab2(sch_1):page135_p3v3_stby") )
				( alias ( signalRef "@baseboard_fab2_lib.baseboard_fab2(sch_1):page136_p3v3_stby") )
				( alias ( signalRef "@baseboard_fab2_lib.baseboard_fab2(sch_1):page137_p3v3_stby") )
				( alias ( signalRef "@baseboard_fab2_lib.baseboard_fab2(sch_1):page138_p3v3_stby") )
				( alias ( signalRef "@baseboard_fab2_lib.baseboard_fab2(sch_1):page139_p3v3_stby") )
				( alias ( signalRef "@baseboard_fab2_lib.baseboard_fab2(sch_1):page140_p3v3_stby") )
				( alias ( signalRef "@baseboard_fab2_lib.baseboard_fab2(sch_1):page141_p3v3_stby") )
				( alias ( signalRef "@baseboard_fab2_lib.baseboard_fab2(sch_1):page142_p3v3_stby") )
				( alias ( signalRef "@baseboard_fab2_lib.baseboard_fab2(sch_1):page150_p3v3_stby") )
				( alias ( signalRef "@baseboard_fab2_lib.baseboard_fab2(sch_1):page153_p3v3_stby") )
				( alias ( signalRef "@baseboard_fab2_lib.baseboard_fab2(sch_1):page154_p3v3_stby") )
				( alias ( signalRef "@baseboard_fab2_lib.baseboard_fab2(sch_1):page155_p3v3_stby") )
				( alias ( signalRef "@baseboard_fab2_lib.baseboard_fab2(sch_1):page156_p3v3_stby") )
				( alias ( signalRef "@baseboard_fab2_lib.baseboard_fab2(sch_1):page157_p3v3_stby") )
				( alias ( signalRef "@baseboard_fab2_lib.baseboard_fab2(sch_1):page158_p3v3_stby") )
				( alias ( signalRef "@baseboard_fab2_lib.baseboard_fab2(sch_1):page159_p3v3_stby") )
				( alias ( signalRef "@baseboard_fab2_lib.baseboard_fab2(sch_1):page160_p3v3_stby") )
				( alias ( signalRef "@baseboard_fab2_lib.baseboard_fab2(sch_1):page161_p3v3_stby") )
				( alias ( signalRef "@baseboard_fab2_lib.baseboard_fab2(sch_1):page162_p3v3_stby") )
				( alias ( signalRef "@baseboard_fab2_lib.baseboard_fab2(sch_1):page163_p3v3_stby") )
				( alias ( signalRef "@baseboard_fab2_lib.baseboard_fab2(sch_1):page164_p3v3_stby") )
				( alias ( signalRef "@baseboard_fab2_lib.baseboard_fab2(sch_1):page167_p3v3_stby") )
				( alias ( signalRef "@baseboard_fab2_lib.baseboard_fab2(sch_1):page168_p3v3_stby") )
				( alias ( signalRef "@baseboard_fab2_lib.baseboard_fab2(sch_1):page169_p3v3_stby") )
				( alias ( signalRef "@baseboard_fab2_lib.baseboard_fab2(sch_1):page170_p3v3_stby") )
				( alias ( signalRef "@baseboard_fab2_lib.baseboard_fab2(sch_1):page175_p3v3_stby") )
				( alias ( signalRef "@baseboard_fab2_lib.baseboard_fab2(sch_1):page176_p3v3_stby") )
				( alias ( signalRef "@baseboard_fab2_lib.baseboard_fab2(sch_1):page177_p3v3_stby") )
				( alias ( signalRef "@baseboard_fab2_lib.baseboard_fab2(sch_1):page178_p3v3_stby") )
				( alias ( signalRef "@baseboard_fab2_lib.baseboard_fab2(sch_1):page181_p3v3_stby") )
				( alias ( signalRef "@baseboard_fab2_lib.baseboard_fab2(sch_1):page184_p3v3_stby") )
				( alias ( signalRef "@baseboard_fab2_lib.baseboard_fab2(sch_1):page185_p3v3_stby") )
				( alias ( signalRef "@baseboard_fab2_lib.baseboard_fab2(sch_1):page186_p3v3_stby") )
				( alias ( signalRef "@baseboard_fab2_lib.baseboard_fab2(sch_1):page188_p3v3_stby") )
				( alias ( signalRef "@baseboard_fab2_lib.baseboard_fab2(sch_1):page189_p3v3_stby") )
				( alias ( signalRef "@baseboard_fab2_lib.baseboard_fab2(sch_1):page191_p3v3_stby") )
				( alias ( signalRef "@baseboard_fab2_lib.baseboard_fab2(sch_1):page192_p3v3_stby") )
				( alias ( signalRef "@baseboard_fab2_lib.baseboard_fab2(sch_1):page193_p3v3_stby") )
				( alias ( signalRef "@baseboard_fab2_lib.baseboard_fab2(sch_1):page194_p3v3_stby") )
				( alias ( signalRef "@baseboard_fab2_lib.baseboard_fab2(sch_1):page196_p3v3_stby") )
				( alias ( signalRef "@baseboard_fab2_lib.baseboard_fab2(sch_1):page198_p3v3_stby") )
				( alias ( signalRef "@baseboard_fab2_lib.baseboard_fab2(sch_1):page200_p3v3_stby") )
				( alias ( signalRef "@baseboard_fab2_lib.baseboard_fab2(sch_1):page201_p3v3_stby") )
				( alias ( signalRef "@baseboard_fab2_lib.baseboard_fab2(sch_1):page206_p3v3_stby") )
				( alias ( signalRef "@baseboard_fab2_lib.baseboard_fab2(sch_1):page211_p3v3_stby") )
				( alias ( signalRef "@baseboard_fab2_lib.baseboard_fab2(sch_1):page213_p3v3_stby") )
				( alias ( signalRef "@baseboard_fab2_lib.baseboard_fab2(sch_1):page215_p3v3_stby") )
				( alias ( signalRef "@baseboard_fab2_lib.baseboard_fab2(sch_1):page218_p3v3_stby") )
				( alias ( signalRef "@baseboard_fab2_lib.baseboard_fab2(sch_1):page223_p3v3_stby") )
				( alias ( signalRef "@baseboard_fab2_lib.baseboard_fab2(sch_1):page226_p3v3_stby") )
				( alias ( signalRef "@baseboard_fab2_lib.baseboard_fab2(sch_1):page231_p3v3_stby") )
				( alias ( signalRef "@baseboard_fab2_lib.baseboard_fab2(sch_1):page232_p3v3_stby") )
				( alias ( signalRef "@baseboard_fab2_lib.baseboard_fab2(sch_1):page233_p3v3_stby") )
				( alias ( signalRef "@baseboard_fab2_lib.baseboard_fab2(sch_1):page234_p3v3_stby") )
				( alias ( signalRef "@baseboard_fab2_lib.baseboard_fab2(sch_1):page235_p3v3_stby") )
				( alias ( signalRef "@baseboard_fab2_lib.baseboard_fab2(sch_1):page237_p3v3_stby") )
				( alias ( signalRef "@baseboard_fab2_lib.baseboard_fab2(sch_1):page238_p3v3_stby") )
				( alias ( signalRef "@baseboard_fab2_lib.baseboard_fab2(sch_1):page239_p3v3_stby") )
				( alias ( signalRef "@baseboard_fab2_lib.baseboard_fab2(sch_1):page240_p3v3_stby") )
				( alias ( signalRef "@baseboard_fab2_lib.baseboard_fab2(sch_1):page246_p3v3_stby") )
				( alias ( signalRef "@baseboard_fab2_lib.baseboard_fab2(sch_1):page247_p3v3_stby") )
				( alias ( signalRef "@baseboard_fab2_lib.baseboard_fab2(sch_1):page249_p3v3_stby") )
				( alias ( signalRef "@baseboard_fab2_lib.baseboard_fab2(sch_1):page145_p3v3_stby") )
				( alias ( signalRef "@baseboard_fab2_lib.baseboard_fab2(sch_1):page148_p3v3_stby") )
				( alias ( signalRef "@baseboard_fab2_lib.baseboard_fab2(sch_1):page151_p3v3_stby") )
				( alias ( signalRef "@baseboard_fab2_lib.baseboard_fab2(sch_1):page147_p3v3_stby") )
				( alias ( signalRef "@baseboard_fab2_lib.baseboard_fab2(sch_1):page149_p3v3_stby") )
				( alias ( signalRef "@baseboard_fab2_lib.baseboard_fab2(sch_1):page248_p3v3_stby") )
				( alias ( signalRef "@baseboard_fab2_lib.baseboard_fab2(sch_1):page187_p3v3_stby") )
				( alias ( signalRef "@baseboard_fab2_lib.baseboard_fab2(sch_1):page250_p3v3_stby") )
				( alias ( signalRef "@baseboard_fab2_lib.baseboard_fab2(sch_1):page251_p3v3_stby") )
				( alias ( signalRef "@baseboard_fab2_lib.baseboard_fab2(sch_1):page183_p3v3_stby") )
				( alias ( signalRef "@baseboard_fab2_lib.baseboard_fab2(sch_1):page166_p3v3_stby") )
				( alias ( signalRef "@baseboard_fab2_lib.baseboard_fab2(sch_1):page269_p3v3_stby") )
				( alias ( signalRef "@baseboard_fab2_lib.baseboard_fab2(sch_1):page268_p3v3_stby") )
				( alias ( signalRef "@baseboard_fab2_lib.baseboard_fab2(sch_1):page245_p3v3_stby") )
				( alias ( signalRef "@baseboard_fab2_lib.baseboard_fab2(sch_1):page120_p3v3_stby") )
				( attribute "CDS_PHYS_NET_NAME" "P3V3_STBY"
					( Origin gPackager )
				)
				( attribute "VOLTAGE" "3.3V"
					( Units "uVoltage" "V" 1.000000)
					( Status sAliasFlattened )
					( Status sAliasConflict )
					( Origin gFrontEnd )
				)
				( objectStatus "P3V3_STBY" )
			)
			( signal "@baseboard_fab2_lib.baseboard_fab2(sch_1):page21_p3v3_stby"
				( attribute "VOLTAGE" "3.3V"
					( Units "uVoltage" "V" 1.000000)
					( Origin gFrontEnd )
				)
				( objectFlag fObjectAlias )
				( objectStatus "page21_p3v3_stby" )
			)
			( signal "@baseboard_fab2_lib.baseboard_fab2(sch_1):page38_p3v3_stby"
				( attribute "VOLTAGE" "3.3V"
					( Units "uVoltage" "V" 1.000000)
					( Origin gFrontEnd )
				)
				( objectFlag fObjectAlias )
				( objectStatus "page38_p3v3_stby" )
			)
			( signal "@baseboard_fab2_lib.baseboard_fab2(sch_1):page55_p3v3_stby"
				( attribute "VOLTAGE" "3.3V"
					( Units "uVoltage" "V" 1.000000)
					( Origin gFrontEnd )
				)
				( objectFlag fObjectAlias )
				( objectStatus "page55_p3v3_stby" )
			)
			( signal "@baseboard_fab2_lib.baseboard_fab2(sch_1):page72_p3v3_stby"
				( attribute "VOLTAGE" "3.3V"
					( Units "uVoltage" "V" 1.000000)
					( Origin gFrontEnd )
				)
				( objectFlag fObjectAlias )
				( objectStatus "page72_p3v3_stby" )
			)
			( signal "@baseboard_fab2_lib.baseboard_fab2(sch_1):page89_p3v3_stby"
				( attribute "VOLTAGE" "3.3V"
					( Units "uVoltage" "V" 1.000000)
					( Origin gFrontEnd )
				)
				( objectFlag fObjectAlias )
				( objectStatus "page89_p3v3_stby" )
			)
			( signal "@baseboard_fab2_lib.baseboard_fab2(sch_1):page94_p3v3_stby"
				( attribute "VOLTAGE" "3.3V"
					( Units "uVoltage" "V" 1.000000)
					( Origin gFrontEnd )
				)
				( objectFlag fObjectAlias )
				( objectStatus "page94_p3v3_stby" )
			)
			( signal "@baseboard_fab2_lib.baseboard_fab2(sch_1):page95_p3v3_stby"
				( attribute "VOLTAGE" "3.3V"
					( Units "uVoltage" "V" 1.000000)
					( Origin gFrontEnd )
				)
				( objectFlag fObjectAlias )
				( objectStatus "page95_p3v3_stby" )
			)
			( signal "@baseboard_fab2_lib.baseboard_fab2(sch_1):page96_p3v3_stby"
				( attribute "VOLTAGE" "3.3V"
					( Units "uVoltage" "V" 1.000000)
					( Origin gFrontEnd )
				)
				( objectFlag fObjectAlias )
				( objectStatus "page96_p3v3_stby" )
			)
			( signal "@baseboard_fab2_lib.baseboard_fab2(sch_1):page101_p3v3_stby"
				( attribute "VOLTAGE" "3.3"
					( Units "uVoltage" "V" 1.000000)
					( Origin gFrontEnd )
				)
				( objectFlag fObjectAlias )
				( objectStatus "page101_p3v3_stby" )
			)
			( signal "@baseboard_fab2_lib.baseboard_fab2(sch_1):page108_p3v3_stby"
				( attribute "VOLTAGE" "3.3V"
					( Units "uVoltage" "V" 1.000000)
					( Origin gFrontEnd )
				)
				( objectFlag fObjectAlias )
				( objectStatus "page108_p3v3_stby" )
			)
			( signal "@baseboard_fab2_lib.baseboard_fab2(sch_1):page111_p3v3_stby"
				( attribute "VOLTAGE" "3.3V"
					( Units "uVoltage" "V" 1.000000)
					( Origin gFrontEnd )
				)
				( objectFlag fObjectAlias )
				( objectStatus "page111_p3v3_stby" )
			)
			( signal "@baseboard_fab2_lib.baseboard_fab2(sch_1):page112_p3v3_stby"
				( attribute "VOLTAGE" "+3.3V"
					( Units "uVoltage" "V" 1.000000)
					( Origin gFrontEnd )
				)
				( objectFlag fObjectAlias )
				( objectStatus "page112_p3v3_stby" )
			)
			( signal "@baseboard_fab2_lib.baseboard_fab2(sch_1):page113_p3v3_stby"
				( attribute "VOLTAGE" "3.3V"
					( Units "uVoltage" "V" 1.000000)
					( Origin gFrontEnd )
				)
				( objectFlag fObjectAlias )
				( objectStatus "page113_p3v3_stby" )
			)
			( signal "@baseboard_fab2_lib.baseboard_fab2(sch_1):page118_p3v3_stby"
				( attribute "VOLTAGE" "3.3V"
					( Units "uVoltage" "V" 1.000000)
					( Origin gFrontEnd )
				)
				( objectFlag fObjectAlias )
				( objectStatus "page118_p3v3_stby" )
			)
			( signal "@baseboard_fab2_lib.baseboard_fab2(sch_1):page119_p3v3_stby"
				( attribute "VOLTAGE" "3.3V"
					( Units "uVoltage" "V" 1.000000)
					( Origin gFrontEnd )
				)
				( objectFlag fObjectAlias )
				( objectStatus "page119_p3v3_stby" )
			)
			( signal "@baseboard_fab2_lib.baseboard_fab2(sch_1):page121_p3v3_stby"
				( attribute "VOLTAGE" "3.3V"
					( Units "uVoltage" "V" 1.000000)
					( Origin gFrontEnd )
				)
				( objectFlag fObjectAlias )
				( objectStatus "page121_p3v3_stby" )
			)
			( signal "@baseboard_fab2_lib.baseboard_fab2(sch_1):page122_p3v3_stby"
				( attribute "VOLTAGE" "3.3V"
					( Units "uVoltage" "V" 1.000000)
					( Origin gFrontEnd )
				)
				( objectFlag fObjectAlias )
				( objectStatus "page122_p3v3_stby" )
			)
			( signal "@baseboard_fab2_lib.baseboard_fab2(sch_1):page125_p3v3_stby"
				( attribute "VOLTAGE" "3.3V"
					( Units "uVoltage" "V" 1.000000)
					( Origin gFrontEnd )
				)
				( objectFlag fObjectAlias )
				( objectStatus "page125_p3v3_stby" )
			)
			( signal "@baseboard_fab2_lib.baseboard_fab2(sch_1):page126_p3v3_stby"
				( attribute "VOLTAGE" "3.3V"
					( Units "uVoltage" "V" 1.000000)
					( Origin gFrontEnd )
				)
				( objectFlag fObjectAlias )
				( objectStatus "page126_p3v3_stby" )
			)
			( signal "@baseboard_fab2_lib.baseboard_fab2(sch_1):page130_p3v3_stby"
				( attribute "VOLTAGE" "3.3V"
					( Units "uVoltage" "V" 1.000000)
					( Origin gFrontEnd )
				)
				( objectFlag fObjectAlias )
				( objectStatus "page130_p3v3_stby" )
			)
			( signal "@baseboard_fab2_lib.baseboard_fab2(sch_1):page133_p3v3_stby"
				( attribute "VOLTAGE" "3.3V"
					( Units "uVoltage" "V" 1.000000)
					( Origin gFrontEnd )
				)
				( objectFlag fObjectAlias )
				( objectStatus "page133_p3v3_stby" )
			)
			( signal "@baseboard_fab2_lib.baseboard_fab2(sch_1):page134_p3v3_stby"
				( attribute "VOLTAGE" "3.3V"
					( Units "uVoltage" "V" 1.000000)
					( Origin gFrontEnd )
				)
				( objectFlag fObjectAlias )
				( objectStatus "page134_p3v3_stby" )
			)
			( signal "@baseboard_fab2_lib.baseboard_fab2(sch_1):page135_p3v3_stby"
				( attribute "VOLTAGE" "3.3V"
					( Units "uVoltage" "V" 1.000000)
					( Origin gFrontEnd )
				)
				( objectFlag fObjectAlias )
				( objectStatus "page135_p3v3_stby" )
			)
			( signal "@baseboard_fab2_lib.baseboard_fab2(sch_1):page136_p3v3_stby"
				( attribute "VOLTAGE" "3.3V"
					( Units "uVoltage" "V" 1.000000)
					( Origin gFrontEnd )
				)
				( objectFlag fObjectAlias )
				( objectStatus "page136_p3v3_stby" )
			)
			( signal "@baseboard_fab2_lib.baseboard_fab2(sch_1):page137_p3v3_stby"
				( attribute "VOLTAGE" "3.3V"
					( Units "uVoltage" "V" 1.000000)
					( Origin gFrontEnd )
				)
				( objectFlag fObjectAlias )
				( objectStatus "page137_p3v3_stby" )
			)
			( signal "@baseboard_fab2_lib.baseboard_fab2(sch_1):page138_p3v3_stby"
				( attribute "VOLTAGE" "3.3V"
					( Units "uVoltage" "V" 1.000000)
					( Origin gFrontEnd )
				)
				( objectFlag fObjectAlias )
				( objectStatus "page138_p3v3_stby" )
			)
			( signal "@baseboard_fab2_lib.baseboard_fab2(sch_1):page139_p3v3_stby"
				( attribute "VOLTAGE" "3.3V"
					( Units "uVoltage" "V" 1.000000)
					( Origin gFrontEnd )
				)
				( objectFlag fObjectAlias )
				( objectStatus "page139_p3v3_stby" )
			)
			( signal "@baseboard_fab2_lib.baseboard_fab2(sch_1):page140_p3v3_stby"
				( attribute "VOLTAGE" "3.3V"
					( Units "uVoltage" "V" 1.000000)
					( Origin gFrontEnd )
				)
				( objectFlag fObjectAlias )
				( objectStatus "page140_p3v3_stby" )
			)
			( signal "@baseboard_fab2_lib.baseboard_fab2(sch_1):page141_p3v3_stby"
				( attribute "VOLTAGE" "3.3V"
					( Units "uVoltage" "V" 1.000000)
					( Origin gFrontEnd )
				)
				( objectFlag fObjectAlias )
				( objectStatus "page141_p3v3_stby" )
			)
			( signal "@baseboard_fab2_lib.baseboard_fab2(sch_1):page142_p3v3_stby"
				( attribute "VOLTAGE" "3.3V"
					( Units "uVoltage" "V" 1.000000)
					( Origin gFrontEnd )
				)
				( objectFlag fObjectAlias )
				( objectStatus "page142_p3v3_stby" )
			)
			( signal "@baseboard_fab2_lib.baseboard_fab2(sch_1):page150_p3v3_stby"
				( attribute "VOLTAGE" "3.3V"
					( Units "uVoltage" "V" 1.000000)
					( Origin gFrontEnd )
				)
				( objectFlag fObjectAlias )
				( objectStatus "page150_p3v3_stby" )
			)
			( signal "@baseboard_fab2_lib.baseboard_fab2(sch_1):page153_p3v3_stby"
				( attribute "VOLTAGE" "3.3V"
					( Units "uVoltage" "V" 1.000000)
					( Origin gFrontEnd )
				)
				( objectFlag fObjectAlias )
				( objectStatus "page153_p3v3_stby" )
			)
			( signal "@baseboard_fab2_lib.baseboard_fab2(sch_1):page154_p3v3_stby"
				( attribute "VOLTAGE" "3.3V"
					( Units "uVoltage" "V" 1.000000)
					( Origin gFrontEnd )
				)
				( objectFlag fObjectAlias )
				( objectStatus "page154_p3v3_stby" )
			)
			( signal "@baseboard_fab2_lib.baseboard_fab2(sch_1):page155_p3v3_stby"
				( attribute "VOLTAGE" "3.3V"
					( Units "uVoltage" "V" 1.000000)
					( Origin gFrontEnd )
				)
				( objectFlag fObjectAlias )
				( objectStatus "page155_p3v3_stby" )
			)
			( signal "@baseboard_fab2_lib.baseboard_fab2(sch_1):page156_p3v3_stby"
				( attribute "VOLTAGE" "3.3V"
					( Units "uVoltage" "V" 1.000000)
					( Origin gFrontEnd )
				)
				( objectFlag fObjectAlias )
				( objectStatus "page156_p3v3_stby" )
			)
			( signal "@baseboard_fab2_lib.baseboard_fab2(sch_1):page157_p3v3_stby"
				( attribute "VOLTAGE" "3.3V"
					( Units "uVoltage" "V" 1.000000)
					( Origin gFrontEnd )
				)
				( objectFlag fObjectAlias )
				( objectStatus "page157_p3v3_stby" )
			)
			( signal "@baseboard_fab2_lib.baseboard_fab2(sch_1):page158_p3v3_stby"
				( attribute "VOLTAGE" "3.3V"
					( Units "uVoltage" "V" 1.000000)
					( Origin gFrontEnd )
				)
				( objectFlag fObjectAlias )
				( objectStatus "page158_p3v3_stby" )
			)
			( signal "@baseboard_fab2_lib.baseboard_fab2(sch_1):page159_p3v3_stby"
				( attribute "VOLTAGE" "3.3V"
					( Units "uVoltage" "V" 1.000000)
					( Origin gFrontEnd )
				)
				( objectFlag fObjectAlias )
				( objectStatus "page159_p3v3_stby" )
			)
			( signal "@baseboard_fab2_lib.baseboard_fab2(sch_1):page160_p3v3_stby"
				( attribute "VOLTAGE" "3.3V"
					( Units "uVoltage" "V" 1.000000)
					( Origin gFrontEnd )
				)
				( objectFlag fObjectAlias )
				( objectStatus "page160_p3v3_stby" )
			)
			( signal "@baseboard_fab2_lib.baseboard_fab2(sch_1):page161_p3v3_stby"
				( attribute "VOLTAGE" "3.3V"
					( Units "uVoltage" "V" 1.000000)
					( Origin gFrontEnd )
				)
				( objectFlag fObjectAlias )
				( objectStatus "page161_p3v3_stby" )
			)
			( signal "@baseboard_fab2_lib.baseboard_fab2(sch_1):page162_p3v3_stby"
				( attribute "VOLTAGE" "3.3V"
					( Units "uVoltage" "V" 1.000000)
					( Origin gFrontEnd )
				)
				( objectFlag fObjectAlias )
				( objectStatus "page162_p3v3_stby" )
			)
			( signal "@baseboard_fab2_lib.baseboard_fab2(sch_1):page163_p3v3_stby"
				( attribute "VOLTAGE" "3.3V"
					( Units "uVoltage" "V" 1.000000)
					( Origin gFrontEnd )
				)
				( objectFlag fObjectAlias )
				( objectStatus "page163_p3v3_stby" )
			)
			( signal "@baseboard_fab2_lib.baseboard_fab2(sch_1):page164_p3v3_stby"
				( attribute "VOLTAGE" "3.3V"
					( Units "uVoltage" "V" 1.000000)
					( Origin gFrontEnd )
				)
				( objectFlag fObjectAlias )
				( objectStatus "page164_p3v3_stby" )
			)
			( signal "@baseboard_fab2_lib.baseboard_fab2(sch_1):page167_p3v3_stby"
				( attribute "VOLTAGE" "3.3V"
					( Units "uVoltage" "V" 1.000000)
					( Origin gFrontEnd )
				)
				( objectFlag fObjectAlias )
				( objectStatus "page167_p3v3_stby" )
			)
			( signal "@baseboard_fab2_lib.baseboard_fab2(sch_1):page168_p3v3_stby"
				( attribute "VOLTAGE" "3.3V"
					( Units "uVoltage" "V" 1.000000)
					( Origin gFrontEnd )
				)
				( objectFlag fObjectAlias )
				( objectStatus "page168_p3v3_stby" )
			)
			( signal "@baseboard_fab2_lib.baseboard_fab2(sch_1):page169_p3v3_stby"
				( attribute "VOLTAGE" "3.3V"
					( Units "uVoltage" "V" 1.000000)
					( Origin gFrontEnd )
				)
				( objectFlag fObjectAlias )
				( objectStatus "page169_p3v3_stby" )
			)
			( signal "@baseboard_fab2_lib.baseboard_fab2(sch_1):page170_p3v3_stby"
				( attribute "VOLTAGE" "3.3V"
					( Units "uVoltage" "V" 1.000000)
					( Origin gFrontEnd )
				)
				( objectFlag fObjectAlias )
				( objectStatus "page170_p3v3_stby" )
			)
			( signal "@baseboard_fab2_lib.baseboard_fab2(sch_1):page175_p3v3_stby"
				( attribute "VOLTAGE" "3.3V"
					( Units "uVoltage" "V" 1.000000)
					( Origin gFrontEnd )
				)
				( objectFlag fObjectAlias )
				( objectStatus "page175_p3v3_stby" )
			)
			( signal "@baseboard_fab2_lib.baseboard_fab2(sch_1):page176_p3v3_stby"
				( attribute "VOLTAGE" "3.3V"
					( Units "uVoltage" "V" 1.000000)
					( Origin gFrontEnd )
				)
				( objectFlag fObjectAlias )
				( objectStatus "page176_p3v3_stby" )
			)
			( signal "@baseboard_fab2_lib.baseboard_fab2(sch_1):page177_p3v3_stby"
				( attribute "VOLTAGE" "3.3V"
					( Units "uVoltage" "V" 1.000000)
					( Origin gFrontEnd )
				)
				( objectFlag fObjectAlias )
				( objectStatus "page177_p3v3_stby" )
			)
			( signal "@baseboard_fab2_lib.baseboard_fab2(sch_1):page178_p3v3_stby"
				( attribute "VOLTAGE" "3.3V"
					( Units "uVoltage" "V" 1.000000)
					( Origin gFrontEnd )
				)
				( objectFlag fObjectAlias )
				( objectStatus "page178_p3v3_stby" )
			)
			( signal "@baseboard_fab2_lib.baseboard_fab2(sch_1):page181_p3v3_stby"
				( attribute "VOLTAGE" "3.3V"
					( Units "uVoltage" "V" 1.000000)
					( Origin gFrontEnd )
				)
				( objectFlag fObjectAlias )
				( objectStatus "page181_p3v3_stby" )
			)
			( signal "@baseboard_fab2_lib.baseboard_fab2(sch_1):page184_p3v3_stby"
				( attribute "VOLTAGE" "3.3V"
					( Units "uVoltage" "V" 1.000000)
					( Origin gFrontEnd )
				)
				( objectFlag fObjectAlias )
				( objectStatus "page184_p3v3_stby" )
			)
			( signal "@baseboard_fab2_lib.baseboard_fab2(sch_1):page185_p3v3_stby"
				( attribute "VOLTAGE" "3.3V"
					( Units "uVoltage" "V" 1.000000)
					( Origin gFrontEnd )
				)
				( objectFlag fObjectAlias )
				( objectStatus "page185_p3v3_stby" )
			)
			( signal "@baseboard_fab2_lib.baseboard_fab2(sch_1):page186_p3v3_stby"
				( attribute "VOLTAGE" "3.3V"
					( Units "uVoltage" "V" 1.000000)
					( Origin gFrontEnd )
				)
				( objectFlag fObjectAlias )
				( objectStatus "page186_p3v3_stby" )
			)
			( signal "@baseboard_fab2_lib.baseboard_fab2(sch_1):page188_p3v3_stby"
				( attribute "VOLTAGE" "3.3V"
					( Units "uVoltage" "V" 1.000000)
					( Origin gFrontEnd )
				)
				( objectFlag fObjectAlias )
				( objectStatus "page188_p3v3_stby" )
			)
			( signal "@baseboard_fab2_lib.baseboard_fab2(sch_1):page189_p3v3_stby"
				( attribute "VOLTAGE" "3.3V"
					( Units "uVoltage" "V" 1.000000)
					( Origin gFrontEnd )
				)
				( objectFlag fObjectAlias )
				( objectStatus "page189_p3v3_stby" )
			)
			( signal "@baseboard_fab2_lib.baseboard_fab2(sch_1):page191_p3v3_stby"
				( attribute "VOLTAGE" "3.3V"
					( Units "uVoltage" "V" 1.000000)
					( Origin gFrontEnd )
				)
				( objectFlag fObjectAlias )
				( objectStatus "page191_p3v3_stby" )
			)
			( signal "@baseboard_fab2_lib.baseboard_fab2(sch_1):page192_p3v3_stby"
				( attribute "VOLTAGE" "3.3V"
					( Units "uVoltage" "V" 1.000000)
					( Origin gFrontEnd )
				)
				( objectFlag fObjectAlias )
				( objectStatus "page192_p3v3_stby" )
			)
			( signal "@baseboard_fab2_lib.baseboard_fab2(sch_1):page193_p3v3_stby"
				( attribute "VOLTAGE" "+3.3V"
					( Units "uVoltage" "V" 1.000000)
					( Origin gFrontEnd )
				)
				( objectFlag fObjectAlias )
				( objectStatus "page193_p3v3_stby" )
			)
			( signal "@baseboard_fab2_lib.baseboard_fab2(sch_1):page194_p3v3_stby"
				( attribute "VOLTAGE" "+3.3V"
					( Units "uVoltage" "V" 1.000000)
					( Origin gFrontEnd )
				)
				( objectFlag fObjectAlias )
				( objectStatus "page194_p3v3_stby" )
			)
			( signal "@baseboard_fab2_lib.baseboard_fab2(sch_1):page196_p3v3_stby"
				( attribute "VOLTAGE" "3.3V"
					( Units "uVoltage" "V" 1.000000)
					( Origin gFrontEnd )
				)
				( objectFlag fObjectAlias )
				( objectStatus "page196_p3v3_stby" )
			)
			( signal "@baseboard_fab2_lib.baseboard_fab2(sch_1):page198_p3v3_stby"
				( attribute "VOLTAGE" "3.3V"
					( Units "uVoltage" "V" 1.000000)
					( Origin gFrontEnd )
				)
				( objectFlag fObjectAlias )
				( objectStatus "page198_p3v3_stby" )
			)
			( signal "@baseboard_fab2_lib.baseboard_fab2(sch_1):page200_p3v3_stby"
				( attribute "VOLTAGE" "+3.3V"
					( Units "uVoltage" "V" 1.000000)
					( Origin gFrontEnd )
				)
				( objectFlag fObjectAlias )
				( objectStatus "page200_p3v3_stby" )
			)
			( signal "@baseboard_fab2_lib.baseboard_fab2(sch_1):page201_p3v3_stby"
				( attribute "VOLTAGE" "3.3V"
					( Units "uVoltage" "V" 1.000000)
					( Origin gFrontEnd )
				)
				( objectFlag fObjectAlias )
				( objectStatus "page201_p3v3_stby" )
			)
			( signal "@baseboard_fab2_lib.baseboard_fab2(sch_1):page206_p3v3_stby"
				( attribute "VOLTAGE" "3.3V"
					( Units "uVoltage" "V" 1.000000)
					( Origin gFrontEnd )
				)
				( objectFlag fObjectAlias )
				( objectStatus "page206_p3v3_stby" )
			)
			( signal "@baseboard_fab2_lib.baseboard_fab2(sch_1):page211_p3v3_stby"
				( attribute "VOLTAGE" "3.3V"
					( Units "uVoltage" "V" 1.000000)
					( Origin gFrontEnd )
				)
				( objectFlag fObjectAlias )
				( objectStatus "page211_p3v3_stby" )
			)
			( signal "@baseboard_fab2_lib.baseboard_fab2(sch_1):page213_p3v3_stby"
				( attribute "VOLTAGE" "3.3V"
					( Units "uVoltage" "V" 1.000000)
					( Origin gFrontEnd )
				)
				( objectFlag fObjectAlias )
				( objectStatus "page213_p3v3_stby" )
			)
			( signal "@baseboard_fab2_lib.baseboard_fab2(sch_1):page215_p3v3_stby"
				( attribute "VOLTAGE" "3.3V"
					( Units "uVoltage" "V" 1.000000)
					( Origin gFrontEnd )
				)
				( objectFlag fObjectAlias )
				( objectStatus "page215_p3v3_stby" )
			)
			( signal "@baseboard_fab2_lib.baseboard_fab2(sch_1):page218_p3v3_stby"
				( attribute "VOLTAGE" "3.3V"
					( Units "uVoltage" "V" 1.000000)
					( Origin gFrontEnd )
				)
				( objectFlag fObjectAlias )
				( objectStatus "page218_p3v3_stby" )
			)
			( signal "@baseboard_fab2_lib.baseboard_fab2(sch_1):page223_p3v3_stby"
				( attribute "VOLTAGE" "3.3V"
					( Units "uVoltage" "V" 1.000000)
					( Origin gFrontEnd )
				)
				( objectFlag fObjectAlias )
				( objectStatus "page223_p3v3_stby" )
			)
			( signal "@baseboard_fab2_lib.baseboard_fab2(sch_1):page226_p3v3_stby"
				( attribute "VOLTAGE" "3.3V"
					( Units "uVoltage" "V" 1.000000)
					( Origin gFrontEnd )
				)
				( objectFlag fObjectAlias )
				( objectStatus "page226_p3v3_stby" )
			)
			( signal "@baseboard_fab2_lib.baseboard_fab2(sch_1):page231_p3v3_stby"
				( attribute "VOLTAGE" "+3.3V"
					( Units "uVoltage" "V" 1.000000)
					( Origin gFrontEnd )
				)
				( objectFlag fObjectAlias )
				( objectStatus "page231_p3v3_stby" )
			)
			( signal "@baseboard_fab2_lib.baseboard_fab2(sch_1):page232_p3v3_stby"
				( attribute "VOLTAGE" "+3.3V"
					( Units "uVoltage" "V" 1.000000)
					( Origin gFrontEnd )
				)
				( objectFlag fObjectAlias )
				( objectStatus "page232_p3v3_stby" )
			)
			( signal "@baseboard_fab2_lib.baseboard_fab2(sch_1):page233_p3v3_stby"
				( attribute "VOLTAGE" "+3.3V"
					( Units "uVoltage" "V" 1.000000)
					( Origin gFrontEnd )
				)
				( objectFlag fObjectAlias )
				( objectStatus "page233_p3v3_stby" )
			)
			( signal "@baseboard_fab2_lib.baseboard_fab2(sch_1):page234_p3v3_stby"
				( attribute "VOLTAGE" "+3.3V"
					( Units "uVoltage" "V" 1.000000)
					( Origin gFrontEnd )
				)
				( objectFlag fObjectAlias )
				( objectStatus "page234_p3v3_stby" )
			)
			( signal "@baseboard_fab2_lib.baseboard_fab2(sch_1):page235_p3v3_stby"
				( attribute "VOLTAGE" "3.3V"
					( Units "uVoltage" "V" 1.000000)
					( Origin gFrontEnd )
				)
				( objectFlag fObjectAlias )
				( objectStatus "page235_p3v3_stby" )
			)
			( signal "@baseboard_fab2_lib.baseboard_fab2(sch_1):page237_p3v3_stby"
				( attribute "VOLTAGE" "3.3V"
					( Units "uVoltage" "V" 1.000000)
					( Origin gFrontEnd )
				)
				( objectFlag fObjectAlias )
				( objectStatus "page237_p3v3_stby" )
			)
			( signal "@baseboard_fab2_lib.baseboard_fab2(sch_1):page238_p3v3_stby"
				( attribute "VOLTAGE" "3.3V"
					( Units "uVoltage" "V" 1.000000)
					( Origin gFrontEnd )
				)
				( objectFlag fObjectAlias )
				( objectStatus "page238_p3v3_stby" )
			)
			( signal "@baseboard_fab2_lib.baseboard_fab2(sch_1):page239_p3v3_stby"
				( attribute "VOLTAGE" "3.3V"
					( Units "uVoltage" "V" 1.000000)
					( Origin gFrontEnd )
				)
				( objectFlag fObjectAlias )
				( objectStatus "page239_p3v3_stby" )
			)
			( signal "@baseboard_fab2_lib.baseboard_fab2(sch_1):page240_p3v3_stby"
				( attribute "VOLTAGE" "+3.3V"
					( Units "uVoltage" "V" 1.000000)
					( Origin gFrontEnd )
				)
				( objectFlag fObjectAlias )
				( objectStatus "page240_p3v3_stby" )
			)
			( signal "@baseboard_fab2_lib.baseboard_fab2(sch_1):page246_p3v3_stby"
				( attribute "VOLTAGE" "3.3V"
					( Units "uVoltage" "V" 1.000000)
					( Origin gFrontEnd )
				)
				( objectFlag fObjectAlias )
				( objectStatus "page246_p3v3_stby" )
			)
			( signal "@baseboard_fab2_lib.baseboard_fab2(sch_1):page247_p3v3_stby"
				( attribute "VOLTAGE" "3.3V"
					( Units "uVoltage" "V" 1.000000)
					( Origin gFrontEnd )
				)
				( objectFlag fObjectAlias )
				( objectStatus "page247_p3v3_stby" )
			)
			( signal "@baseboard_fab2_lib.baseboard_fab2(sch_1):page249_p3v3_stby"
				( attribute "VOLTAGE" "3.3V"
					( Units "uVoltage" "V" 1.000000)
					( Origin gFrontEnd )
				)
				( objectFlag fObjectAlias )
				( objectStatus "page249_p3v3_stby" )
			)
			( signal "@baseboard_fab2_lib.baseboard_fab2(sch_1):page145_p3v3_stby"
				( attribute "VOLTAGE" "3.3V"
					( Units "uVoltage" "V" 1.000000)
					( Origin gFrontEnd )
				)
				( objectFlag fObjectAlias )
				( objectStatus "page145_p3v3_stby" )
			)
			( signal "@baseboard_fab2_lib.baseboard_fab2(sch_1):page148_p3v3_stby"
				( attribute "VOLTAGE" "3.3V"
					( Units "uVoltage" "V" 1.000000)
					( Origin gFrontEnd )
				)
				( objectFlag fObjectAlias )
				( objectStatus "page148_p3v3_stby" )
			)
			( signal "@baseboard_fab2_lib.baseboard_fab2(sch_1):page151_p3v3_stby"
				( attribute "VOLTAGE" "3.3V"
					( Units "uVoltage" "V" 1.000000)
					( Origin gFrontEnd )
				)
				( objectFlag fObjectAlias )
				( objectStatus "page151_p3v3_stby" )
			)
			( signal "@baseboard_fab2_lib.baseboard_fab2(sch_1):page147_p3v3_stby"
				( attribute "VOLTAGE" "3.3V"
					( Units "uVoltage" "V" 1.000000)
					( Origin gFrontEnd )
				)
				( objectFlag fObjectAlias )
				( objectStatus "page147_p3v3_stby" )
			)
			( signal "@baseboard_fab2_lib.baseboard_fab2(sch_1):page149_p3v3_stby"
				( attribute "VOLTAGE" "3.3V"
					( Units "uVoltage" "V" 1.000000)
					( Origin gFrontEnd )
				)
				( objectFlag fObjectAlias )
				( objectStatus "page149_p3v3_stby" )
			)
			( signal "@baseboard_fab2_lib.baseboard_fab2(sch_1):page248_p3v3_stby"
				( attribute "VOLTAGE" "3.3V"
					( Units "uVoltage" "V" 1.000000)
					( Origin gFrontEnd )
				)
				( objectFlag fObjectAlias )
				( objectStatus "page248_p3v3_stby" )
			)
			( signal "@baseboard_fab2_lib.baseboard_fab2(sch_1):page187_p3v3_stby"
				( attribute "VOLTAGE" "3.3V"
					( Units "uVoltage" "V" 1.000000)
					( Origin gFrontEnd )
				)
				( objectFlag fObjectAlias )
				( objectStatus "page187_p3v3_stby" )
			)
			( signal "@baseboard_fab2_lib.baseboard_fab2(sch_1):page250_p3v3_stby"
				( attribute "VOLTAGE" "3.3V"
					( Units "uVoltage" "V" 1.000000)
					( Origin gFrontEnd )
				)
				( objectFlag fObjectAlias )
				( objectStatus "page250_p3v3_stby" )
			)
			( signal "@baseboard_fab2_lib.baseboard_fab2(sch_1):page251_p3v3_stby"
				( attribute "VOLTAGE" "3.3V"
					( Units "uVoltage" "V" 1.000000)
					( Origin gFrontEnd )
				)
				( objectFlag fObjectAlias )
				( objectStatus "page251_p3v3_stby" )
			)
			( signal "@baseboard_fab2_lib.baseboard_fab2(sch_1):page183_p3v3_stby"
				( attribute "VOLTAGE" "3.3V"
					( Units "uVoltage" "V" 1.000000)
					( Origin gFrontEnd )
				)
				( objectFlag fObjectAlias )
				( objectStatus "page183_p3v3_stby" )
			)
			( signal "@baseboard_fab2_lib.baseboard_fab2(sch_1):page166_p3v3_stby"
				( attribute "VOLTAGE" "3.3V"
					( Units "uVoltage" "V" 1.000000)
					( Origin gFrontEnd )
				)
				( objectFlag fObjectAlias )
				( objectStatus "page166_p3v3_stby" )
			)
			( signal "@baseboard_fab2_lib.baseboard_fab2(sch_1):page269_p3v3_stby"
				( attribute "VOLTAGE" "3.3V"
					( Units "uVoltage" "V" 1.000000)
					( Origin gFrontEnd )
				)
				( objectFlag fObjectAlias )
				( objectStatus "page269_p3v3_stby" )
			)
			( signal "@baseboard_fab2_lib.baseboard_fab2(sch_1):page268_p3v3_stby"
				( attribute "VOLTAGE" "3.3V"
					( Units "uVoltage" "V" 1.000000)
					( Origin gFrontEnd )
				)
				( objectFlag fObjectAlias )
				( objectStatus "page268_p3v3_stby" )
			)
			( signal "@baseboard_fab2_lib.baseboard_fab2(sch_1):page245_p3v3_stby"
				( attribute "VOLTAGE" "+3.3V"
					( Units "uVoltage" "V" 1.000000)
					( Origin gFrontEnd )
				)
				( objectFlag fObjectAlias )
				( objectStatus "page245_p3v3_stby" )
			)
			( signal "@baseboard_fab2_lib.baseboard_fab2(sch_1):page120_p3v3_stby"
				( attribute "VOLTAGE" "3.3V"
					( Units "uVoltage" "V" 1.000000)
					( Origin gFrontEnd )
				)
				( objectFlag fObjectAlias )
				( objectStatus "page120_p3v3_stby" )
			)
			( signal "@baseboard_fab2_lib.baseboard_fab2(sch_1):rmii_bmc_ocp_txd1_r"
				( attribute "CDS_PHYS_NET_NAME" "RMII_BMC_OCP_TXD1_R"
					( Origin gPackager )
				)
				( objectStatus "RMII_BMC_OCP_TXD1_R" )
			)
			( signal "@baseboard_fab2_lib.baseboard_fab2(sch_1):pd_cpu0_bist_enable"
				( attribute "CDS_PHYS_NET_NAME" "PD_CPU0_BIST_ENABLE"
					( Origin gPackager )
				)
				( objectStatus "PD_CPU0_BIST_ENABLE" )
			)
			( signal "@baseboard_fab2_lib.baseboard_fab2(sch_1):pd_cpu0_ksfc_dis"
				( attribute "CDS_PHYS_NET_NAME" "PD_CPU0_KSFC_DIS"
					( Origin gPackager )
				)
				( objectStatus "PD_CPU0_KSFC_DIS" )
			)
			( signal "@baseboard_fab2_lib.baseboard_fab2(sch_1):pd_cpu0_test12"
				( attribute "CDS_PHYS_NET_NAME" "PD_CPU0_TEST12"
					( Origin gPackager )
				)
				( objectStatus "PD_CPU0_TEST12" )
			)
			( signal "@baseboard_fab2_lib.baseboard_fab2(sch_1):pd_cpu0_test13"
				( attribute "CDS_PHYS_NET_NAME" "PD_CPU0_TEST13"
					( Origin gPackager )
				)
				( objectStatus "PD_CPU0_TEST13" )
			)
			( signal "@baseboard_fab2_lib.baseboard_fab2(sch_1):pd_cpu0_test14"
				( attribute "CDS_PHYS_NET_NAME" "PD_CPU0_TEST14"
					( Origin gPackager )
				)
				( objectStatus "PD_CPU0_TEST14" )
			)
			( signal "@baseboard_fab2_lib.baseboard_fab2(sch_1):pd_cpu0_txt_plten"
				( attribute "CDS_PHYS_NET_NAME" "PD_CPU0_TXT_PLTEN"
					( Origin gPackager )
				)
				( objectStatus "PD_CPU0_TXT_PLTEN" )
			)
			( signal "@baseboard_fab2_lib.baseboard_fab2(sch_1):pd_pirom_cpu0_addr0"
				( attribute "CDS_PHYS_NET_NAME" "PD_PIROM_CPU0_ADDR0"
					( Origin gPackager )
				)
				( objectStatus "PD_PIROM_CPU0_ADDR0" )
			)
			( signal "@baseboard_fab2_lib.baseboard_fab2(sch_1):pd_pirom_cpu0_addr1"
				( attribute "CDS_PHYS_NET_NAME" "PD_PIROM_CPU0_ADDR1"
					( Origin gPackager )
				)
				( objectStatus "PD_PIROM_CPU0_ADDR1" )
			)
			( signal "@baseboard_fab2_lib.baseboard_fab2(sch_1):pd_pirom_cpu0_addr2"
				( attribute "CDS_PHYS_NET_NAME" "PD_PIROM_CPU0_ADDR2"
					( Origin gPackager )
				)
				( objectStatus "PD_PIROM_CPU0_ADDR2" )
			)
			( signal "@baseboard_fab2_lib.baseboard_fab2(sch_1):peci_cpu_g"
				( attribute "CDS_PHYS_NET_NAME" "PECI_CPU_G"
					( Origin gPackager )
				)
				( objectStatus "PECI_CPU_G" )
			)
			( signal "@baseboard_fab2_lib.baseboard_fab2(sch_1):pu_cpu0_frmagent"
				( attribute "CDS_PHYS_NET_NAME" "PU_CPU0_FRMAGENT"
					( Origin gPackager )
				)
				( objectStatus "PU_CPU0_FRMAGENT" )
			)
			( signal "@baseboard_fab2_lib.baseboard_fab2(sch_1):pu_cpu0_legacy_skt"
				( attribute "CDS_PHYS_NET_NAME" "PU_CPU0_LEGACY_SKT"
					( Origin gPackager )
				)
				( objectStatus "PU_CPU0_LEGACY_SKT" )
			)
			( signal "@baseboard_fab2_lib.baseboard_fab2(sch_1):pu_cpu0_safe_mode_boot"
				( attribute "CDS_PHYS_NET_NAME" "PU_CPU0_SAFE_MODE_BOOT"
					( Origin gPackager )
				)
				( objectStatus "PU_CPU0_SAFE_MODE_BOOT" )
			)
			( signal "@baseboard_fab2_lib.baseboard_fab2(sch_1):pu_cpu0_socket_id_0"
				( attribute "CDS_PHYS_NET_NAME" "PU_CPU0_SOCKET_ID_0"
					( Origin gPackager )
				)
				( objectStatus "PU_CPU0_SOCKET_ID_0" )
			)
			( signal "@baseboard_fab2_lib.baseboard_fab2(sch_1):pu_cpu0_socket_id_1"
				( attribute "CDS_PHYS_NET_NAME" "PU_CPU0_SOCKET_ID_1"
					( Origin gPackager )
				)
				( objectStatus "PU_CPU0_SOCKET_ID_1" )
			)
			( signal "@baseboard_fab2_lib.baseboard_fab2(sch_1):pu_cpu0_tsc_sync"
				( attribute "CDS_PHYS_NET_NAME" "PU_CPU0_TSC_SYNC"
					( Origin gPackager )
				)
				( objectStatus "PU_CPU0_TSC_SYNC" )
			)
			( signal "@baseboard_fab2_lib.baseboard_fab2(sch_1):pu_cpu0_txt_agent"
				( attribute "CDS_PHYS_NET_NAME" "PU_CPU0_TXT_AGENT"
					( Origin gPackager )
				)
				( objectStatus "PU_CPU0_TXT_AGENT" )
			)
			( signal "@baseboard_fab2_lib.baseboard_fab2(sch_1):pvccio_cpu0"
				( alias ( signalRef "@baseboard_fab2_lib.baseboard_fab2(sch_1):page21_pvccio_cpu0") )
				( alias ( signalRef "@baseboard_fab2_lib.baseboard_fab2(sch_1):page37_pvccio_cpu0") )
				( alias ( signalRef "@baseboard_fab2_lib.baseboard_fab2(sch_1):page38_pvccio_cpu0") )
				( alias ( signalRef "@baseboard_fab2_lib.baseboard_fab2(sch_1):page39_pvccio_cpu0") )
				( alias ( signalRef "@baseboard_fab2_lib.baseboard_fab2(sch_1):page42_pvccio_cpu0") )
				( alias ( signalRef "@baseboard_fab2_lib.baseboard_fab2(sch_1):page90_pvccio_cpu0") )
				( alias ( signalRef "@baseboard_fab2_lib.baseboard_fab2(sch_1):page92_pvccio_cpu0") )
				( alias ( signalRef "@baseboard_fab2_lib.baseboard_fab2(sch_1):page93_pvccio_cpu0") )
				( alias ( signalRef "@baseboard_fab2_lib.baseboard_fab2(sch_1):page96_pvccio_cpu0") )
				( alias ( signalRef "@baseboard_fab2_lib.baseboard_fab2(sch_1):page97_pvccio_cpu0") )
				( alias ( signalRef "@baseboard_fab2_lib.baseboard_fab2(sch_1):page99_pvccio_cpu0") )
				( alias ( signalRef "@baseboard_fab2_lib.baseboard_fab2(sch_1):page111_pvccio_cpu0") )
				( alias ( signalRef "@baseboard_fab2_lib.baseboard_fab2(sch_1):page112_pvccio_cpu0") )
				( alias ( signalRef "@baseboard_fab2_lib.baseboard_fab2(sch_1):page152_pvccio_cpu0") )
				( alias ( signalRef "@baseboard_fab2_lib.baseboard_fab2(sch_1):page166_pvccio_cpu0") )
				( alias ( signalRef "@baseboard_fab2_lib.baseboard_fab2(sch_1):page194_pvccio_cpu0") )
				( alias ( signalRef "@baseboard_fab2_lib.baseboard_fab2(sch_1):page201_pvccio_cpu0") )
				( alias ( signalRef "@baseboard_fab2_lib.baseboard_fab2(sch_1):page211_pvccio_cpu0") )
				( alias ( signalRef "@baseboard_fab2_lib.baseboard_fab2(sch_1):page212_pvccio_cpu0") )
				( alias ( signalRef "@baseboard_fab2_lib.baseboard_fab2(sch_1):page215_pvccio_cpu0") )
				( alias ( signalRef "@baseboard_fab2_lib.baseboard_fab2(sch_1):page218_pvccio_cpu0") )
				( alias ( signalRef "@baseboard_fab2_lib.baseboard_fab2(sch_1):page148_pvccio_cpu0") )
				( alias ( signalRef "@baseboard_fab2_lib.baseboard_fab2(sch_1):page248_pvccio_cpu0") )
				( attribute "CDS_PHYS_NET_NAME" "PVCCIO_CPU0"
					( Origin gPackager )
				)
				( attribute "VOLTAGE" "1.1V"
					( Units "uVoltage" "V" 1.000000)
					( Status sAliasFlattened )
					( Origin gFrontEnd )
				)
				( objectStatus "PVCCIO_CPU0" )
			)
			( signal "@baseboard_fab2_lib.baseboard_fab2(sch_1):page21_pvccio_cpu0"
				( attribute "VOLTAGE" "1.1V"
					( Units "uVoltage" "V" 1.000000)
					( Origin gFrontEnd )
				)
				( objectFlag fObjectAlias )
				( objectStatus "page21_pvccio_cpu0" )
			)
			( signal "@baseboard_fab2_lib.baseboard_fab2(sch_1):page37_pvccio_cpu0"
				( attribute "VOLTAGE" "1.1V"
					( Units "uVoltage" "V" 1.000000)
					( Origin gFrontEnd )
				)
				( objectFlag fObjectAlias )
				( objectStatus "page37_pvccio_cpu0" )
			)
			( signal "@baseboard_fab2_lib.baseboard_fab2(sch_1):page38_pvccio_cpu0"
				( attribute "VOLTAGE" "1.1V"
					( Units "uVoltage" "V" 1.000000)
					( Origin gFrontEnd )
				)
				( objectFlag fObjectAlias )
				( objectStatus "page38_pvccio_cpu0" )
			)
			( signal "@baseboard_fab2_lib.baseboard_fab2(sch_1):page39_pvccio_cpu0"
				( attribute "VOLTAGE" "1.1V"
					( Units "uVoltage" "V" 1.000000)
					( Origin gFrontEnd )
				)
				( objectFlag fObjectAlias )
				( objectStatus "page39_pvccio_cpu0" )
			)
			( signal "@baseboard_fab2_lib.baseboard_fab2(sch_1):page42_pvccio_cpu0"
				( attribute "VOLTAGE" "1.1V"
					( Units "uVoltage" "V" 1.000000)
					( Origin gFrontEnd )
				)
				( objectFlag fObjectAlias )
				( objectStatus "page42_pvccio_cpu0" )
			)
			( signal "@baseboard_fab2_lib.baseboard_fab2(sch_1):page90_pvccio_cpu0"
				( attribute "VOLTAGE" "1.1V"
					( Units "uVoltage" "V" 1.000000)
					( Origin gFrontEnd )
				)
				( objectFlag fObjectAlias )
				( objectStatus "page90_pvccio_cpu0" )
			)
			( signal "@baseboard_fab2_lib.baseboard_fab2(sch_1):page92_pvccio_cpu0"
				( attribute "VOLTAGE" "1.1V"
					( Units "uVoltage" "V" 1.000000)
					( Origin gFrontEnd )
				)
				( objectFlag fObjectAlias )
				( objectStatus "page92_pvccio_cpu0" )
			)
			( signal "@baseboard_fab2_lib.baseboard_fab2(sch_1):page93_pvccio_cpu0"
				( attribute "VOLTAGE" "1.1V"
					( Units "uVoltage" "V" 1.000000)
					( Origin gFrontEnd )
				)
				( objectFlag fObjectAlias )
				( objectStatus "page93_pvccio_cpu0" )
			)
			( signal "@baseboard_fab2_lib.baseboard_fab2(sch_1):page96_pvccio_cpu0"
				( attribute "VOLTAGE" "1.1V"
					( Units "uVoltage" "V" 1.000000)
					( Origin gFrontEnd )
				)
				( objectFlag fObjectAlias )
				( objectStatus "page96_pvccio_cpu0" )
			)
			( signal "@baseboard_fab2_lib.baseboard_fab2(sch_1):page97_pvccio_cpu0"
				( attribute "VOLTAGE" "1.1V"
					( Units "uVoltage" "V" 1.000000)
					( Origin gFrontEnd )
				)
				( objectFlag fObjectAlias )
				( objectStatus "page97_pvccio_cpu0" )
			)
			( signal "@baseboard_fab2_lib.baseboard_fab2(sch_1):page99_pvccio_cpu0"
				( attribute "VOLTAGE" "1.1V"
					( Units "uVoltage" "V" 1.000000)
					( Origin gFrontEnd )
				)
				( objectFlag fObjectAlias )
				( objectStatus "page99_pvccio_cpu0" )
			)
			( signal "@baseboard_fab2_lib.baseboard_fab2(sch_1):page111_pvccio_cpu0"
				( attribute "VOLTAGE" "1.1V"
					( Units "uVoltage" "V" 1.000000)
					( Origin gFrontEnd )
				)
				( objectFlag fObjectAlias )
				( objectStatus "page111_pvccio_cpu0" )
			)
			( signal "@baseboard_fab2_lib.baseboard_fab2(sch_1):page112_pvccio_cpu0"
				( attribute "VOLTAGE" "1.1V"
					( Units "uVoltage" "V" 1.000000)
					( Origin gFrontEnd )
				)
				( objectFlag fObjectAlias )
				( objectStatus "page112_pvccio_cpu0" )
			)
			( signal "@baseboard_fab2_lib.baseboard_fab2(sch_1):page152_pvccio_cpu0"
				( attribute "VOLTAGE" "1.1V"
					( Units "uVoltage" "V" 1.000000)
					( Origin gFrontEnd )
				)
				( objectFlag fObjectAlias )
				( objectStatus "page152_pvccio_cpu0" )
			)
			( signal "@baseboard_fab2_lib.baseboard_fab2(sch_1):page166_pvccio_cpu0"
				( attribute "VOLTAGE" "1.1V"
					( Units "uVoltage" "V" 1.000000)
					( Origin gFrontEnd )
				)
				( objectFlag fObjectAlias )
				( objectStatus "page166_pvccio_cpu0" )
			)
			( signal "@baseboard_fab2_lib.baseboard_fab2(sch_1):page194_pvccio_cpu0"
				( attribute "VOLTAGE" "1.1V"
					( Units "uVoltage" "V" 1.000000)
					( Origin gFrontEnd )
				)
				( objectFlag fObjectAlias )
				( objectStatus "page194_pvccio_cpu0" )
			)
			( signal "@baseboard_fab2_lib.baseboard_fab2(sch_1):page201_pvccio_cpu0"
				( attribute "VOLTAGE" "1.1V"
					( Units "uVoltage" "V" 1.000000)
					( Origin gFrontEnd )
				)
				( objectFlag fObjectAlias )
				( objectStatus "page201_pvccio_cpu0" )
			)
			( signal "@baseboard_fab2_lib.baseboard_fab2(sch_1):page211_pvccio_cpu0"
				( attribute "VOLTAGE" "1.1V"
					( Units "uVoltage" "V" 1.000000)
					( Origin gFrontEnd )
				)
				( objectFlag fObjectAlias )
				( objectStatus "page211_pvccio_cpu0" )
			)
			( signal "@baseboard_fab2_lib.baseboard_fab2(sch_1):page212_pvccio_cpu0"
				( attribute "VOLTAGE" "1.1V"
					( Units "uVoltage" "V" 1.000000)
					( Origin gFrontEnd )
				)
				( objectFlag fObjectAlias )
				( objectStatus "page212_pvccio_cpu0" )
			)
			( signal "@baseboard_fab2_lib.baseboard_fab2(sch_1):page215_pvccio_cpu0"
				( attribute "VOLTAGE" "1.1V"
					( Units "uVoltage" "V" 1.000000)
					( Origin gFrontEnd )
				)
				( objectFlag fObjectAlias )
				( objectStatus "page215_pvccio_cpu0" )
			)
			( signal "@baseboard_fab2_lib.baseboard_fab2(sch_1):page218_pvccio_cpu0"
				( attribute "VOLTAGE" "1.1V"
					( Units "uVoltage" "V" 1.000000)
					( Origin gFrontEnd )
				)
				( objectFlag fObjectAlias )
				( objectStatus "page218_pvccio_cpu0" )
			)
			( signal "@baseboard_fab2_lib.baseboard_fab2(sch_1):page148_pvccio_cpu0"
				( attribute "VOLTAGE" "1.1V"
					( Units "uVoltage" "V" 1.000000)
					( Origin gFrontEnd )
				)
				( objectFlag fObjectAlias )
				( objectStatus "page148_pvccio_cpu0" )
			)
			( signal "@baseboard_fab2_lib.baseboard_fab2(sch_1):page248_pvccio_cpu0"
				( attribute "VOLTAGE" "1.1V"
					( Units "uVoltage" "V" 1.000000)
					( Origin gFrontEnd )
				)
				( objectFlag fObjectAlias )
				( objectStatus "page248_pvccio_cpu0" )
			)
			( signal "@baseboard_fab2_lib.baseboard_fab2(sch_1):p1v15_aux_bmc"
				( alias ( signalRef "@baseboard_fab2_lib.baseboard_fab2(sch_1):page238_p1v15_aux_bmc") )
				( alias ( signalRef "@baseboard_fab2_lib.baseboard_fab2(sch_1):page148_p1v15_aux_bmc") )
				( alias ( signalRef "@baseboard_fab2_lib.baseboard_fab2(sch_1):page149_p1v15_aux_bmc") )
				( attribute "CDS_PHYS_NET_NAME" "P1V15_AUX_BMC"
					( Origin gPackager )
				)
				( attribute "VOLTAGE" "1.5"
					( Units "uVoltage" "V" 1.000000)
					( Status sAliasFlattened )
					( Origin gFrontEnd )
				)
				( objectStatus "P1V15_AUX_BMC" )
			)
			( signal "@baseboard_fab2_lib.baseboard_fab2(sch_1):page238_p1v15_aux_bmc"
				( attribute "VOLTAGE" "1.5"
					( Units "uVoltage" "V" 1.000000)
					( Origin gFrontEnd )
				)
				( objectFlag fObjectAlias )
				( objectStatus "page238_p1v15_aux_bmc" )
			)
			( signal "@baseboard_fab2_lib.baseboard_fab2(sch_1):page148_p1v15_aux_bmc"
				( objectFlag fObjectAlias )
				( objectStatus "page148_p1v15_aux_bmc" )
			)
			( signal "@baseboard_fab2_lib.baseboard_fab2(sch_1):page149_p1v15_aux_bmc"
				( objectFlag fObjectAlias )
				( objectStatus "page149_p1v15_aux_bmc" )
			)
			( signal "@baseboard_fab2_lib.baseboard_fab2(sch_1):pwrgd_cpu0_drampwrok_abc_g"
				( attribute "CDS_PHYS_NET_NAME" "PWRGD_CPU0_DRAMPWROK_ABC_G"
					( Origin gPackager )
				)
				( objectStatus "PWRGD_CPU0_DRAMPWROK_ABC_G" )
			)
			( signal "@baseboard_fab2_lib.baseboard_fab2(sch_1):pwrgd_cpu0_drampwrok_def_g"
				( attribute "CDS_PHYS_NET_NAME" "PWRGD_CPU0_DRAMPWROK_DEF_G"
					( Origin gPackager )
				)
				( objectStatus "PWRGD_CPU0_DRAMPWROK_DEF_G" )
			)
			( signal "@baseboard_fab2_lib.baseboard_fab2(sch_1):pwrgd_cpu0_g"
				( attribute "CDS_PHYS_NET_NAME" "PWRGD_CPU0_G"
					( Origin gPackager )
				)
				( objectStatus "PWRGD_CPU0_G" )
			)
			( signal "@baseboard_fab2_lib.baseboard_fab2(sch_1):rst_cpu0_g_n"
				( attribute "CDS_PHYS_NET_NAME" "RST_CPU0_G_N"
					( Origin gPackager )
				)
				( objectStatus "RST_CPU0_G_N" )
			)
			( signal "@baseboard_fab2_lib.baseboard_fab2(sch_1):smb_ddr_abc_scl_g_r"
				( attribute "CDS_PHYS_NET_NAME" "SMB_DDR_ABC_SCL_G_R"
					( Origin gPackager )
				)
				( objectStatus "SMB_DDR_ABC_SCL_G_R" )
			)
			( signal "@baseboard_fab2_lib.baseboard_fab2(sch_1):smb_ddr_abc_sda_g_r"
				( attribute "CDS_PHYS_NET_NAME" "SMB_DDR_ABC_SDA_G_R"
					( Origin gPackager )
				)
				( objectStatus "SMB_DDR_ABC_SDA_G_R" )
			)
			( signal "@baseboard_fab2_lib.baseboard_fab2(sch_1):smb_ddr_def_scl_g_r"
				( attribute "CDS_PHYS_NET_NAME" "SMB_DDR_DEF_SCL_G_R"
					( Origin gPackager )
				)
				( objectStatus "SMB_DDR_DEF_SCL_G_R" )
			)
			( signal "@baseboard_fab2_lib.baseboard_fab2(sch_1):smb_ddr_def_sda_g_r"
				( attribute "CDS_PHYS_NET_NAME" "SMB_DDR_DEF_SDA_G_R"
					( Origin gPackager )
				)
				( objectStatus "SMB_DDR_DEF_SDA_G_R" )
			)
			( signal "@baseboard_fab2_lib.baseboard_fab2(sch_1):smb_pirom_cpu0_scl"
				( attribute "CDS_PHYS_NET_NAME" "SMB_PIROM_CPU0_SCL"
					( Origin gPackager )
				)
				( objectStatus "SMB_PIROM_CPU0_SCL" )
			)
			( signal "@baseboard_fab2_lib.baseboard_fab2(sch_1):smb_pirom_cpu0_sda"
				( attribute "CDS_PHYS_NET_NAME" "SMB_PIROM_CPU0_SDA"
					( Origin gPackager )
				)
				( objectStatus "SMB_PIROM_CPU0_SDA" )
			)
			( signal "@baseboard_fab2_lib.baseboard_fab2(sch_1):svid_alert0_cpu0_n"
				( attribute "CDS_PHYS_NET_NAME" "SVID_ALERT0_CPU0_N"
					( Origin gPackager )
				)
				( objectStatus "SVID_ALERT0_CPU0_N" )
			)
			( signal "@baseboard_fab2_lib.baseboard_fab2(sch_1):svid_alert0_cpu0_r_n"
				( attribute "CDS_PHYS_NET_NAME" "SVID_ALERT0_CPU0_R_N"
					( Origin gPackager )
				)
				( objectStatus "SVID_ALERT0_CPU0_R_N" )
			)
			( signal "@baseboard_fab2_lib.baseboard_fab2(sch_1):svid_alert1_cpu0_n"
				( attribute "CDS_PHYS_NET_NAME" "SVID_ALERT1_CPU0_N"
					( Origin gPackager )
				)
				( objectStatus "SVID_ALERT1_CPU0_N" )
			)
			( signal "@baseboard_fab2_lib.baseboard_fab2(sch_1):svid_alert1_cpu0_r_n"
				( attribute "CDS_PHYS_NET_NAME" "SVID_ALERT1_CPU0_R_N"
					( Origin gPackager )
				)
				( objectStatus "SVID_ALERT1_CPU0_R_N" )
			)
			( signal "@baseboard_fab2_lib.baseboard_fab2(sch_1):svid_clk0_cpu0"
				( attribute "CDS_PHYS_NET_NAME" "SVID_CLK0_CPU0"
					( Origin gPackager )
				)
				( objectStatus "SVID_CLK0_CPU0" )
			)
			( signal "@baseboard_fab2_lib.baseboard_fab2(sch_1):svid_clk0_cpu0_r"
				( attribute "CDS_PHYS_NET_NAME" "SVID_CLK0_CPU0_R"
					( Origin gPackager )
				)
				( objectStatus "SVID_CLK0_CPU0_R" )
			)
			( signal "@baseboard_fab2_lib.baseboard_fab2(sch_1):svid_clk1_cpu0"
				( attribute "CDS_PHYS_NET_NAME" "SVID_CLK1_CPU0"
					( Origin gPackager )
				)
				( objectStatus "SVID_CLK1_CPU0" )
			)
			( signal "@baseboard_fab2_lib.baseboard_fab2(sch_1):svid_clk1_cpu0_r"
				( attribute "CDS_PHYS_NET_NAME" "SVID_CLK1_CPU0_R"
					( Origin gPackager )
				)
				( objectStatus "SVID_CLK1_CPU0_R" )
			)
			( signal "@baseboard_fab2_lib.baseboard_fab2(sch_1):svid_dio0_cpu0"
				( attribute "CDS_PHYS_NET_NAME" "SVID_DIO0_CPU0"
					( Origin gPackager )
				)
				( objectStatus "SVID_DIO0_CPU0" )
			)
			( signal "@baseboard_fab2_lib.baseboard_fab2(sch_1):svid_dio0_cpu0_r"
				( attribute "CDS_PHYS_NET_NAME" "SVID_DIO0_CPU0_R"
					( Origin gPackager )
				)
				( objectStatus "SVID_DIO0_CPU0_R" )
			)
			( signal "@baseboard_fab2_lib.baseboard_fab2(sch_1):svid_dio1_cpu0"
				( attribute "CDS_PHYS_NET_NAME" "SVID_DIO1_CPU0"
					( Origin gPackager )
				)
				( objectStatus "SVID_DIO1_CPU0" )
			)
			( signal "@baseboard_fab2_lib.baseboard_fab2(sch_1):svid_dio1_cpu0_r"
				( attribute "CDS_PHYS_NET_NAME" "SVID_DIO1_CPU0_R"
					( Origin gPackager )
				)
				( objectStatus "SVID_DIO1_CPU0_R" )
			)
			( signal "@baseboard_fab2_lib.baseboard_fab2(sch_1):tp_cpu0_procdis_g_n"
				( attribute "CDS_PHYS_NET_NAME" "TP_CPU0_PROCDIS_G_N"
					( Origin gPackager )
				)
				( objectStatus "TP_CPU0_PROCDIS_G_N" )
			)
			( signal "@baseboard_fab2_lib.baseboard_fab2(sch_1):tp_cpu0_socket_id_2"
				( attribute "CDS_PHYS_NET_NAME" "TP_CPU0_SOCKET_ID_2"
					( Origin gPackager )
				)
				( objectStatus "TP_CPU0_SOCKET_ID_2" )
			)
			( signal "@baseboard_fab2_lib.baseboard_fab2(sch_1):tp_nmi_cpu0"
				( attribute "CDS_PHYS_NET_NAME" "TP_NMI_CPU0"
					( Origin gPackager )
				)
				( objectStatus "TP_NMI_CPU0" )
			)
			( signal "@baseboard_fab2_lib.baseboard_fab2(sch_1):tp_xdp_cpu0_obsdata_a0_mbp2_n"
				( attribute "CDS_PHYS_NET_NAME" "TP_XDP_CPU0_OBSDATA_A0_MBP2_N"
					( Origin gPackager )
				)
				( objectStatus "TP_XDP_CPU0_OBSDATA_A0_MBP2_N" )
			)
			( signal "@baseboard_fab2_lib.baseboard_fab2(sch_1):tp_xdp_cpu0_obsdata_a1_mbp3_n"
				( attribute "CDS_PHYS_NET_NAME" "TP_XDP_CPU0_OBSDATA_A1_MBP3_N"
					( Origin gPackager )
				)
				( objectStatus "TP_XDP_CPU0_OBSDATA_A1_MBP3_N" )
			)
			( signal "@baseboard_fab2_lib.baseboard_fab2(sch_1):tp_xdp_cpu0_obsdata_a2_mbp4_n"
				( attribute "CDS_PHYS_NET_NAME" "TP_XDP_CPU0_OBSDATA_A2_MBP4_N"
					( Origin gPackager )
				)
				( objectStatus "TP_XDP_CPU0_OBSDATA_A2_MBP4_N" )
			)
			( signal "@baseboard_fab2_lib.baseboard_fab2(sch_1):tp_xdp_cpu0_obsdata_a3_mbp5_n"
				( attribute "CDS_PHYS_NET_NAME" "TP_XDP_CPU0_OBSDATA_A3_MBP5_N"
					( Origin gPackager )
				)
				( objectStatus "TP_XDP_CPU0_OBSDATA_A3_MBP5_N" )
			)
			( signal "@baseboard_fab2_lib.baseboard_fab2(sch_1):xdp_cpu0_tdo"
				( attribute "CDS_PHYS_NET_NAME" "XDP_CPU0_TDO"
					( Origin gPackager )
				)
				( objectStatus "XDP_CPU0_TDO" )
			)
			( signal "@baseboard_fab2_lib.baseboard_fab2(sch_1):xdp_cpu_mbp0_n"
				( attribute "CDS_PHYS_NET_NAME" "XDP_CPU_MBP0_N"
					( Origin gPackager )
				)
				( objectStatus "XDP_CPU_MBP0_N" )
			)
			( signal "@baseboard_fab2_lib.baseboard_fab2(sch_1):xdp_cpu_mbp1_n"
				( attribute "CDS_PHYS_NET_NAME" "XDP_CPU_MBP1_N"
					( Origin gPackager )
				)
				( objectStatus "XDP_CPU_MBP1_N" )
			)
			( signal "@baseboard_fab2_lib.baseboard_fab2(sch_1):xdp_cpu_obsfn_b0_mbp6_n"
				( attribute "CDS_PHYS_NET_NAME" "XDP_CPU_OBSFN_B0_MBP6_N"
					( Origin gPackager )
				)
				( objectStatus "XDP_CPU_OBSFN_B0_MBP6_N" )
			)
			( signal "@baseboard_fab2_lib.baseboard_fab2(sch_1):xdp_cpu_obsfn_b1_mbp7_n"
				( attribute "CDS_PHYS_NET_NAME" "XDP_CPU_OBSFN_B1_MBP7_N"
					( Origin gPackager )
				)
				( objectStatus "XDP_CPU_OBSFN_B1_MBP7_N" )
			)
			( signal "@baseboard_fab2_lib.baseboard_fab2(sch_1):xdp_cpu_prdy_n"
				( attribute "CDS_PHYS_NET_NAME" "XDP_CPU_PRDY_N"
					( Origin gPackager )
				)
				( objectStatus "XDP_CPU_PRDY_N" )
			)
			( signal "@baseboard_fab2_lib.baseboard_fab2(sch_1):xdp_cpu_preq_n"
				( attribute "CDS_PHYS_NET_NAME" "XDP_CPU_PREQ_N"
					( Origin gPackager )
				)
				( objectStatus "XDP_CPU_PREQ_N" )
			)
			( signal "@baseboard_fab2_lib.baseboard_fab2(sch_1):xdp_cpu_tck0"
				( attribute "CDS_PHYS_NET_NAME" "XDP_CPU_TCK0"
					( Origin gPackager )
				)
				( objectStatus "XDP_CPU_TCK0" )
			)
			( signal "@baseboard_fab2_lib.baseboard_fab2(sch_1):xdp_cpu_tdi"
				( attribute "CDS_PHYS_NET_NAME" "XDP_CPU_TDI"
					( Origin gPackager )
				)
				( objectStatus "XDP_CPU_TDI" )
			)
			( signal "@baseboard_fab2_lib.baseboard_fab2(sch_1):xdp_cpu_tms"
				( attribute "CDS_PHYS_NET_NAME" "XDP_CPU_TMS"
					( Origin gPackager )
				)
				( objectStatus "XDP_CPU_TMS" )
			)
			( signal "@baseboard_fab2_lib.baseboard_fab2(sch_1):xdp_cpu_trst_n"
				( attribute "CDS_PHYS_NET_NAME" "XDP_CPU_TRST_N"
					( Origin gPackager )
				)
				( objectStatus "XDP_CPU_TRST_N" )
			)
			( signal "@baseboard_fab2_lib.baseboard_fab2(sch_1):clk_100m_cpu0_rc_refclk0_dn"
				( attribute "CDS_PHYS_NET_NAME" "CLK_100M_CPU0_RC_REFCLK0_DN"
					( Origin gPackager )
				)
				( objectStatus "CLK_100M_CPU0_RC_REFCLK0_DN" )
			)
			( signal "@baseboard_fab2_lib.baseboard_fab2(sch_1):clk_100m_cpu0_rc_refclk0_dp"
				( attribute "CDS_PHYS_NET_NAME" "CLK_100M_CPU0_RC_REFCLK0_DP"
					( Origin gPackager )
				)
				( objectStatus "CLK_100M_CPU0_RC_REFCLK0_DP" )
			)
			( signal "@baseboard_fab2_lib.baseboard_fab2(sch_1):clk_322m_osc_cpu0_rc_dn"
				( attribute "CDS_PHYS_NET_NAME" "CLK_322M_OSC_CPU0_RC_DN"
					( Origin gPackager )
				)
				( objectStatus "CLK_322M_OSC_CPU0_RC_DN" )
			)
			( signal "@baseboard_fab2_lib.baseboard_fab2(sch_1):clk_322m_osc_cpu0_rc_dp"
				( attribute "CDS_PHYS_NET_NAME" "CLK_322M_OSC_CPU0_RC_DP"
					( Origin gPackager )
				)
				( objectStatus "CLK_322M_OSC_CPU0_RC_DP" )
			)
			( signal "@baseboard_fab2_lib.baseboard_fab2(sch_1):fm_cpu0_rc_error_n"
				( attribute "CDS_PHYS_NET_NAME" "FM_CPU0_RC_ERROR_N"
					( Origin gPackager )
				)
				( attribute "PHYS_NET_NAME" "FM_CPU0_RC_ERROR_N"
					( Origin gPackager )
				)
				( objectStatus "FM_CPU0_RC_ERROR_N" )
			)
			( signal "@baseboard_fab2_lib.baseboard_fab2(sch_1):h_cpu0_fivr_fault_g"
				( attribute "CDS_PHYS_NET_NAME" "H_CPU0_FIVR_FAULT_G"
					( Origin gPackager )
				)
				( objectStatus "H_CPU0_FIVR_FAULT_G" )
			)
			( signal "@baseboard_fab2_lib.baseboard_fab2(sch_1):p1v8_mcp_cpu0"
				( alias ( signalRef "@baseboard_fab2_lib.baseboard_fab2(sch_1):page22_p1v8_mcp_cpu0") )
				( alias ( signalRef "@baseboard_fab2_lib.baseboard_fab2(sch_1):page38_p1v8_mcp_cpu0") )
				( alias ( signalRef "@baseboard_fab2_lib.baseboard_fab2(sch_1):page113_p1v8_mcp_cpu0") )
				( alias ( signalRef "@baseboard_fab2_lib.baseboard_fab2(sch_1):page194_p1v8_mcp_cpu0") )
				( attribute "VOLTAGE" "+1.8V"
					( Units "uVoltage" "V" 1.000000)
					( Status sAliasFlattened )
					( Origin gFrontEnd )
				)
				( attribute "CDS_PHYS_NET_NAME" "P1V8_MCP_CPU0"
					( Origin gPackager )
				)
				( objectStatus "P1V8_MCP_CPU0" )
			)
			( signal "@baseboard_fab2_lib.baseboard_fab2(sch_1):page22_p1v8_mcp_cpu0"
				( objectFlag fObjectAlias )
				( objectStatus "page22_p1v8_mcp_cpu0" )
			)
			( signal "@baseboard_fab2_lib.baseboard_fab2(sch_1):page38_p1v8_mcp_cpu0"
				( attribute "VOLTAGE" "+1.8V"
					( Units "uVoltage" "V" 1.000000)
					( Origin gFrontEnd )
				)
				( objectFlag fObjectAlias )
				( objectStatus "page38_p1v8_mcp_cpu0" )
			)
			( signal "@baseboard_fab2_lib.baseboard_fab2(sch_1):page113_p1v8_mcp_cpu0"
				( objectFlag fObjectAlias )
				( objectStatus "page113_p1v8_mcp_cpu0" )
			)
			( signal "@baseboard_fab2_lib.baseboard_fab2(sch_1):page194_p1v8_mcp_cpu0"
				( objectFlag fObjectAlias )
				( objectStatus "page194_p1v8_mcp_cpu0" )
			)
			( signal "@baseboard_fab2_lib.baseboard_fab2(sch_1):pd_cpu0_dmimode_override"
				( attribute "CDS_PHYS_NET_NAME" "PD_CPU0_DMIMODE_OVERRIDE"
					( Origin gPackager )
				)
				( objectStatus "PD_CPU0_DMIMODE_OVERRIDE" )
			)
			( signal "@baseboard_fab2_lib.baseboard_fab2(sch_1):pd_cpu0_rsvd_test_1"
				( attribute "CDS_PHYS_NET_NAME" "PD_CPU0_RSVD_TEST_1"
					( Origin gPackager )
				)
				( objectStatus "PD_CPU0_RSVD_TEST_1" )
			)
			( signal "@baseboard_fab2_lib.baseboard_fab2(sch_1):pd_cpu0_rsvd_test_2"
				( attribute "CDS_PHYS_NET_NAME" "PD_CPU0_RSVD_TEST_2"
					( Origin gPackager )
				)
				( objectStatus "PD_CPU0_RSVD_TEST_2" )
			)
			( signal "@baseboard_fab2_lib.baseboard_fab2(sch_1):pvccmcp_cpu0"
				( alias ( signalRef "@baseboard_fab2_lib.baseboard_fab2(sch_1):page22_pvccmcp_cpu0") )
				( alias ( signalRef "@baseboard_fab2_lib.baseboard_fab2(sch_1):page29_pvccmcp_cpu0") )
				( alias ( signalRef "@baseboard_fab2_lib.baseboard_fab2(sch_1):page36_pvccmcp_cpu0") )
				( alias ( signalRef "@baseboard_fab2_lib.baseboard_fab2(sch_1):page38_pvccmcp_cpu0") )
				( alias ( signalRef "@baseboard_fab2_lib.baseboard_fab2(sch_1):page39_pvccmcp_cpu0") )
				( alias ( signalRef "@baseboard_fab2_lib.baseboard_fab2(sch_1):page42_pvccmcp_cpu0") )
				( alias ( signalRef "@baseboard_fab2_lib.baseboard_fab2(sch_1):page194_pvccmcp_cpu0") )
				( attribute "VOLTAGE" "1.2V"
					( Units "uVoltage" "V" 1.000000)
					( Status sAliasFlattened )
					( Origin gFrontEnd )
				)
				( attribute "CDS_PHYS_NET_NAME" "PVCCMCP_CPU0"
					( Origin gPackager )
				)
				( objectStatus "PVCCMCP_CPU0" )
			)
			( signal "@baseboard_fab2_lib.baseboard_fab2(sch_1):page22_pvccmcp_cpu0"
				( objectFlag fObjectAlias )
				( objectStatus "page22_pvccmcp_cpu0" )
			)
			( signal "@baseboard_fab2_lib.baseboard_fab2(sch_1):page29_pvccmcp_cpu0"
				( objectFlag fObjectAlias )
				( objectStatus "page29_pvccmcp_cpu0" )
			)
			( signal "@baseboard_fab2_lib.baseboard_fab2(sch_1):page36_pvccmcp_cpu0"
				( objectFlag fObjectAlias )
				( objectStatus "page36_pvccmcp_cpu0" )
			)
			( signal "@baseboard_fab2_lib.baseboard_fab2(sch_1):page38_pvccmcp_cpu0"
				( objectFlag fObjectAlias )
				( objectStatus "page38_pvccmcp_cpu0" )
			)
			( signal "@baseboard_fab2_lib.baseboard_fab2(sch_1):page39_pvccmcp_cpu0"
				( objectFlag fObjectAlias )
				( objectStatus "page39_pvccmcp_cpu0" )
			)
			( signal "@baseboard_fab2_lib.baseboard_fab2(sch_1):page42_pvccmcp_cpu0"
				( objectFlag fObjectAlias )
				( objectStatus "page42_pvccmcp_cpu0" )
			)
			( signal "@baseboard_fab2_lib.baseboard_fab2(sch_1):page194_pvccmcp_cpu0"
				( attribute "VOLTAGE" "1.2V"
					( Units "uVoltage" "V" 1.000000)
					( Origin gFrontEnd )
				)
				( objectFlag fObjectAlias )
				( objectStatus "page194_pvccmcp_cpu0" )
			)
			( signal "@baseboard_fab2_lib.baseboard_fab2(sch_1):tp_cpu0_rsvd_194"
				( attribute "CDS_PHYS_NET_NAME" "TP_CPU0_RSVD_194"
					( Origin gPackager )
				)
				( objectStatus "TP_CPU0_RSVD_194" )
			)
			( signal "@baseboard_fab2_lib.baseboard_fab2(sch_1):tp_cpu0_rsvd_198"
				( attribute "CDS_PHYS_NET_NAME" "TP_CPU0_RSVD_198"
					( Origin gPackager )
				)
				( objectStatus "TP_CPU0_RSVD_198" )
			)
			( signal "@baseboard_fab2_lib.baseboard_fab2(sch_1):tp_cpu0_rsvd_199"
				( attribute "CDS_PHYS_NET_NAME" "TP_CPU0_RSVD_199"
					( Origin gPackager )
				)
				( objectStatus "TP_CPU0_RSVD_199" )
			)
			( signal "@baseboard_fab2_lib.baseboard_fab2(sch_1):tp_cpu0_rsvd_204"
				( attribute "CDS_PHYS_NET_NAME" "TP_CPU0_RSVD_204"
					( Origin gPackager )
				)
				( objectStatus "TP_CPU0_RSVD_204" )
			)
			( signal "@baseboard_fab2_lib.baseboard_fab2(sch_1):tp_cpu0_rsvd_205"
				( attribute "CDS_PHYS_NET_NAME" "TP_CPU0_RSVD_205"
					( Origin gPackager )
				)
				( objectStatus "TP_CPU0_RSVD_205" )
			)
			( signal "@baseboard_fab2_lib.baseboard_fab2(sch_1):tp_cpu0_rsvd_208"
				( attribute "CDS_PHYS_NET_NAME" "TP_CPU0_RSVD_208"
					( Origin gPackager )
				)
				( objectStatus "TP_CPU0_RSVD_208" )
			)
			( signal "@baseboard_fab2_lib.baseboard_fab2(sch_1):tp_cpu0_rsvd_210"
				( attribute "CDS_PHYS_NET_NAME" "TP_CPU0_RSVD_210"
					( Origin gPackager )
				)
				( objectStatus "TP_CPU0_RSVD_210" )
			)
			( signal "@baseboard_fab2_lib.baseboard_fab2(sch_1):tp_cpu0_rsvd_211"
				( attribute "CDS_PHYS_NET_NAME" "TP_CPU0_RSVD_211"
					( Origin gPackager )
				)
				( objectStatus "TP_CPU0_RSVD_211" )
			)
			( signal "@baseboard_fab2_lib.baseboard_fab2(sch_1):tp_cpu0_rsvd_212"
				( attribute "CDS_PHYS_NET_NAME" "TP_CPU0_RSVD_212"
					( Origin gPackager )
				)
				( objectStatus "TP_CPU0_RSVD_212" )
			)
			( signal "@baseboard_fab2_lib.baseboard_fab2(sch_1):tp_cpu0_rsvd_214"
				( attribute "CDS_PHYS_NET_NAME" "TP_CPU0_RSVD_214"
					( Origin gPackager )
				)
				( objectStatus "TP_CPU0_RSVD_214" )
			)
			( signal "@baseboard_fab2_lib.baseboard_fab2(sch_1):tp_cpu0_rsvd_216"
				( attribute "CDS_PHYS_NET_NAME" "TP_CPU0_RSVD_216"
					( Origin gPackager )
				)
				( objectStatus "TP_CPU0_RSVD_216" )
			)
			( signal "@baseboard_fab2_lib.baseboard_fab2(sch_1):tp_cpu0_rsvd_217"
				( attribute "CDS_PHYS_NET_NAME" "TP_CPU0_RSVD_217"
					( Origin gPackager )
				)
				( objectStatus "TP_CPU0_RSVD_217" )
			)
			( signal "@baseboard_fab2_lib.baseboard_fab2(sch_1):tp_cpu0_rsvd_218"
				( attribute "CDS_PHYS_NET_NAME" "TP_CPU0_RSVD_218"
					( Origin gPackager )
				)
				( objectStatus "TP_CPU0_RSVD_218" )
			)
			( signal "@baseboard_fab2_lib.baseboard_fab2(sch_1):tp_cpu0_rsvd_219"
				( attribute "CDS_PHYS_NET_NAME" "TP_CPU0_RSVD_219"
					( Origin gPackager )
				)
				( objectStatus "TP_CPU0_RSVD_219" )
			)
			( signal "@baseboard_fab2_lib.baseboard_fab2(sch_1):tp_cpu0_rsvd_222"
				( attribute "CDS_PHYS_NET_NAME" "TP_CPU0_RSVD_222"
					( Origin gPackager )
				)
				( objectStatus "TP_CPU0_RSVD_222" )
			)
			( signal "@baseboard_fab2_lib.baseboard_fab2(sch_1):tp_cpu0_rsvd_223"
				( attribute "CDS_PHYS_NET_NAME" "TP_CPU0_RSVD_223"
					( Origin gPackager )
				)
				( objectStatus "TP_CPU0_RSVD_223" )
			)
			( signal "@baseboard_fab2_lib.baseboard_fab2(sch_1):tp_cpu0_rsvd_224"
				( attribute "CDS_PHYS_NET_NAME" "TP_CPU0_RSVD_224"
					( Origin gPackager )
				)
				( objectStatus "TP_CPU0_RSVD_224" )
			)
			( signal "@baseboard_fab2_lib.baseboard_fab2(sch_1):tp_cpu0_rsvd_225"
				( attribute "CDS_PHYS_NET_NAME" "TP_CPU0_RSVD_225"
					( Origin gPackager )
				)
				( objectStatus "TP_CPU0_RSVD_225" )
			)
			( signal "@baseboard_fab2_lib.baseboard_fab2(sch_1):tp_cpu0_rsvd_226"
				( attribute "CDS_PHYS_NET_NAME" "TP_CPU0_RSVD_226"
					( Origin gPackager )
				)
				( objectStatus "TP_CPU0_RSVD_226" )
			)
			( signal "@baseboard_fab2_lib.baseboard_fab2(sch_1):tp_cpu0_rsvd_227"
				( attribute "CDS_PHYS_NET_NAME" "TP_CPU0_RSVD_227"
					( Origin gPackager )
				)
				( objectStatus "TP_CPU0_RSVD_227" )
			)
			( signal "@baseboard_fab2_lib.baseboard_fab2(sch_1):tp_cpu0_rsvd_228"
				( attribute "CDS_PHYS_NET_NAME" "TP_CPU0_RSVD_228"
					( Origin gPackager )
				)
				( objectStatus "TP_CPU0_RSVD_228" )
			)
			( signal "@baseboard_fab2_lib.baseboard_fab2(sch_1):tp_cpu0_rsvd_229"
				( attribute "CDS_PHYS_NET_NAME" "TP_CPU0_RSVD_229"
					( Origin gPackager )
				)
				( objectStatus "TP_CPU0_RSVD_229" )
			)
			( signal "@baseboard_fab2_lib.baseboard_fab2(sch_1):tp_cpu0_rsvd_230"
				( attribute "CDS_PHYS_NET_NAME" "TP_CPU0_RSVD_230"
					( Origin gPackager )
				)
				( objectStatus "TP_CPU0_RSVD_230" )
			)
			( signal "@baseboard_fab2_lib.baseboard_fab2(sch_1):tp_cpu0_rsvd_231"
				( attribute "CDS_PHYS_NET_NAME" "TP_CPU0_RSVD_231"
					( Origin gPackager )
				)
				( objectStatus "TP_CPU0_RSVD_231" )
			)
			( signal "@baseboard_fab2_lib.baseboard_fab2(sch_1):tp_cpu0_rsvd_232"
				( attribute "CDS_PHYS_NET_NAME" "TP_CPU0_RSVD_232"
					( Origin gPackager )
				)
				( objectStatus "TP_CPU0_RSVD_232" )
			)
			( signal "@baseboard_fab2_lib.baseboard_fab2(sch_1):tp_cpu0_rsvd_233"
				( attribute "CDS_PHYS_NET_NAME" "TP_CPU0_RSVD_233"
					( Origin gPackager )
				)
				( objectStatus "TP_CPU0_RSVD_233" )
			)
			( signal "@baseboard_fab2_lib.baseboard_fab2(sch_1):tp_cpu0_rsvd_234"
				( attribute "CDS_PHYS_NET_NAME" "TP_CPU0_RSVD_234"
					( Origin gPackager )
				)
				( objectStatus "TP_CPU0_RSVD_234" )
			)
			( signal "@baseboard_fab2_lib.baseboard_fab2(sch_1):tp_cpu0_rsvd_235"
				( attribute "CDS_PHYS_NET_NAME" "TP_CPU0_RSVD_235"
					( Origin gPackager )
				)
				( objectStatus "TP_CPU0_RSVD_235" )
			)
			( signal "@baseboard_fab2_lib.baseboard_fab2(sch_1):tp_cpu0_rsvd_236"
				( attribute "CDS_PHYS_NET_NAME" "TP_CPU0_RSVD_236"
					( Origin gPackager )
				)
				( objectStatus "TP_CPU0_RSVD_236" )
			)
			( signal "@baseboard_fab2_lib.baseboard_fab2(sch_1):tp_cpu0_rsvd_237"
				( attribute "CDS_PHYS_NET_NAME" "TP_CPU0_RSVD_237"
					( Origin gPackager )
				)
				( objectStatus "TP_CPU0_RSVD_237" )
			)
			( signal "@baseboard_fab2_lib.baseboard_fab2(sch_1):tp_cpu0_rsvd_238"
				( attribute "CDS_PHYS_NET_NAME" "TP_CPU0_RSVD_238"
					( Origin gPackager )
				)
				( objectStatus "TP_CPU0_RSVD_238" )
			)
			( signal "@baseboard_fab2_lib.baseboard_fab2(sch_1):tp_cpu0_rsvd_239"
				( attribute "CDS_PHYS_NET_NAME" "TP_CPU0_RSVD_239"
					( Origin gPackager )
				)
				( objectStatus "TP_CPU0_RSVD_239" )
			)
			( signal "@baseboard_fab2_lib.baseboard_fab2(sch_1):tp_cpu0_rsvd_240"
				( attribute "CDS_PHYS_NET_NAME" "TP_CPU0_RSVD_240"
					( Origin gPackager )
				)
				( objectStatus "TP_CPU0_RSVD_240" )
			)
			( signal "@baseboard_fab2_lib.baseboard_fab2(sch_1):tp_cpu0_rsvd_241"
				( attribute "CDS_PHYS_NET_NAME" "TP_CPU0_RSVD_241"
					( Origin gPackager )
				)
				( objectStatus "TP_CPU0_RSVD_241" )
			)
			( signal "@baseboard_fab2_lib.baseboard_fab2(sch_1):tp_cpu0_rsvd_242"
				( attribute "CDS_PHYS_NET_NAME" "TP_CPU0_RSVD_242"
					( Origin gPackager )
				)
				( objectStatus "TP_CPU0_RSVD_242" )
			)
			( signal "@baseboard_fab2_lib.baseboard_fab2(sch_1):tp_cpu0_rsvd_243"
				( attribute "CDS_PHYS_NET_NAME" "TP_CPU0_RSVD_243"
					( Origin gPackager )
				)
				( objectStatus "TP_CPU0_RSVD_243" )
			)
			( signal "@baseboard_fab2_lib.baseboard_fab2(sch_1):tp_cpu0_rsvd_244"
				( attribute "CDS_PHYS_NET_NAME" "TP_CPU0_RSVD_244"
					( Origin gPackager )
				)
				( objectStatus "TP_CPU0_RSVD_244" )
			)
			( signal "@baseboard_fab2_lib.baseboard_fab2(sch_1):tp_cpu0_rsvd_245"
				( attribute "CDS_PHYS_NET_NAME" "TP_CPU0_RSVD_245"
					( Origin gPackager )
				)
				( objectStatus "TP_CPU0_RSVD_245" )
			)
			( signal "@baseboard_fab2_lib.baseboard_fab2(sch_1):tp_cpu0_rsvd_246"
				( attribute "CDS_PHYS_NET_NAME" "TP_CPU0_RSVD_246"
					( Origin gPackager )
				)
				( objectStatus "TP_CPU0_RSVD_246" )
			)
			( signal "@baseboard_fab2_lib.baseboard_fab2(sch_1):tp_cpu0_rsvd_247"
				( attribute "CDS_PHYS_NET_NAME" "TP_CPU0_RSVD_247"
					( Origin gPackager )
				)
				( objectStatus "TP_CPU0_RSVD_247" )
			)
			( signal "@baseboard_fab2_lib.baseboard_fab2(sch_1):tp_cpu0_rsvd_248"
				( attribute "CDS_PHYS_NET_NAME" "TP_CPU0_RSVD_248"
					( Origin gPackager )
				)
				( objectStatus "TP_CPU0_RSVD_248" )
			)
			( signal "@baseboard_fab2_lib.baseboard_fab2(sch_1):tp_cpu0_rsvd_249"
				( attribute "CDS_PHYS_NET_NAME" "TP_CPU0_RSVD_249"
					( Origin gPackager )
				)
				( objectStatus "TP_CPU0_RSVD_249" )
			)
			( signal "@baseboard_fab2_lib.baseboard_fab2(sch_1):tp_cpu0_rsvd_250"
				( attribute "CDS_PHYS_NET_NAME" "TP_CPU0_RSVD_250"
					( Origin gPackager )
				)
				( objectStatus "TP_CPU0_RSVD_250" )
			)
			( signal "@baseboard_fab2_lib.baseboard_fab2(sch_1):tp_cpu0_rsvd_251"
				( attribute "CDS_PHYS_NET_NAME" "TP_CPU0_RSVD_251"
					( Origin gPackager )
				)
				( objectStatus "TP_CPU0_RSVD_251" )
			)
			( signal "@baseboard_fab2_lib.baseboard_fab2(sch_1):tp_cpu0_rsvd_252"
				( attribute "CDS_PHYS_NET_NAME" "TP_CPU0_RSVD_252"
					( Origin gPackager )
				)
				( objectStatus "TP_CPU0_RSVD_252" )
			)
			( signal "@baseboard_fab2_lib.baseboard_fab2(sch_1):tp_cpu0_rsvd_253"
				( attribute "CDS_PHYS_NET_NAME" "TP_CPU0_RSVD_253"
					( Origin gPackager )
				)
				( objectStatus "TP_CPU0_RSVD_253" )
			)
			( signal "@baseboard_fab2_lib.baseboard_fab2(sch_1):tp_cpu0_rsvd_254"
				( attribute "CDS_PHYS_NET_NAME" "TP_CPU0_RSVD_254"
					( Origin gPackager )
				)
				( objectStatus "TP_CPU0_RSVD_254" )
			)
			( signal "@baseboard_fab2_lib.baseboard_fab2(sch_1):tp_cpu0_rsvd_256"
				( attribute "CDS_PHYS_NET_NAME" "TP_CPU0_RSVD_256"
					( Origin gPackager )
				)
				( objectStatus "TP_CPU0_RSVD_256" )
			)
			( signal "@baseboard_fab2_lib.baseboard_fab2(sch_1):tp_cpu0_rsvd_258"
				( attribute "CDS_PHYS_NET_NAME" "TP_CPU0_RSVD_258"
					( Origin gPackager )
				)
				( objectStatus "TP_CPU0_RSVD_258" )
			)
			( signal "@baseboard_fab2_lib.baseboard_fab2(sch_1):tp_cpu0_rsvd_259"
				( attribute "CDS_PHYS_NET_NAME" "TP_CPU0_RSVD_259"
					( Origin gPackager )
				)
				( objectStatus "TP_CPU0_RSVD_259" )
			)
			( signal "@baseboard_fab2_lib.baseboard_fab2(sch_1):tp_cpu0_rsvd_260"
				( attribute "CDS_PHYS_NET_NAME" "TP_CPU0_RSVD_260"
					( Origin gPackager )
				)
				( objectStatus "TP_CPU0_RSVD_260" )
			)
			( signal "@baseboard_fab2_lib.baseboard_fab2(sch_1):tp_cpu0_rsvd_261"
				( attribute "CDS_PHYS_NET_NAME" "TP_CPU0_RSVD_261"
					( Origin gPackager )
				)
				( objectStatus "TP_CPU0_RSVD_261" )
			)
			( signal "@baseboard_fab2_lib.baseboard_fab2(sch_1):tp_cpu0_rsvd_262"
				( attribute "CDS_PHYS_NET_NAME" "TP_CPU0_RSVD_262"
					( Origin gPackager )
				)
				( objectStatus "TP_CPU0_RSVD_262" )
			)
			( signal "@baseboard_fab2_lib.baseboard_fab2(sch_1):tp_cpu0_rsvd_263"
				( attribute "CDS_PHYS_NET_NAME" "TP_CPU0_RSVD_263"
					( Origin gPackager )
				)
				( objectStatus "TP_CPU0_RSVD_263" )
			)
			( signal "@baseboard_fab2_lib.baseboard_fab2(sch_1):tp_cpu0_rsvd_264"
				( attribute "CDS_PHYS_NET_NAME" "TP_CPU0_RSVD_264"
					( Origin gPackager )
				)
				( objectStatus "TP_CPU0_RSVD_264" )
			)
			( signal "@baseboard_fab2_lib.baseboard_fab2(sch_1):tp_cpu0_rsvd_265"
				( attribute "CDS_PHYS_NET_NAME" "TP_CPU0_RSVD_265"
					( Origin gPackager )
				)
				( objectStatus "TP_CPU0_RSVD_265" )
			)
			( signal "@baseboard_fab2_lib.baseboard_fab2(sch_1):tp_cpu0_rsvd_266"
				( attribute "CDS_PHYS_NET_NAME" "TP_CPU0_RSVD_266"
					( Origin gPackager )
				)
				( objectStatus "TP_CPU0_RSVD_266" )
			)
			( signal "@baseboard_fab2_lib.baseboard_fab2(sch_1):tp_cpu0_rsvd_267"
				( attribute "CDS_PHYS_NET_NAME" "TP_CPU0_RSVD_267"
					( Origin gPackager )
				)
				( objectStatus "TP_CPU0_RSVD_267" )
			)
			( signal "@baseboard_fab2_lib.baseboard_fab2(sch_1):tp_cpu0_rsvd_268"
				( attribute "CDS_PHYS_NET_NAME" "TP_CPU0_RSVD_268"
					( Origin gPackager )
				)
				( objectStatus "TP_CPU0_RSVD_268" )
			)
			( signal "@baseboard_fab2_lib.baseboard_fab2(sch_1):tp_cpu0_rsvd_269"
				( attribute "CDS_PHYS_NET_NAME" "TP_CPU0_RSVD_269"
					( Origin gPackager )
				)
				( objectStatus "TP_CPU0_RSVD_269" )
			)
			( signal "@baseboard_fab2_lib.baseboard_fab2(sch_1):tp_cpu0_rsvd_270"
				( attribute "CDS_PHYS_NET_NAME" "TP_CPU0_RSVD_270"
					( Origin gPackager )
				)
				( objectStatus "TP_CPU0_RSVD_270" )
			)
			( signal "@baseboard_fab2_lib.baseboard_fab2(sch_1):tp_cpu0_rsvd_271"
				( attribute "CDS_PHYS_NET_NAME" "TP_CPU0_RSVD_271"
					( Origin gPackager )
				)
				( objectStatus "TP_CPU0_RSVD_271" )
			)
			( signal "@baseboard_fab2_lib.baseboard_fab2(sch_1):tp_cpu0_rsvd_272"
				( attribute "CDS_PHYS_NET_NAME" "TP_CPU0_RSVD_272"
					( Origin gPackager )
				)
				( objectStatus "TP_CPU0_RSVD_272" )
			)
			( signal "@baseboard_fab2_lib.baseboard_fab2(sch_1):tp_cpu0_rsvd_273"
				( attribute "CDS_PHYS_NET_NAME" "TP_CPU0_RSVD_273"
					( Origin gPackager )
				)
				( objectStatus "TP_CPU0_RSVD_273" )
			)
			( signal "@baseboard_fab2_lib.baseboard_fab2(sch_1):tp_cpu0_rsvd_274"
				( attribute "CDS_PHYS_NET_NAME" "TP_CPU0_RSVD_274"
					( Origin gPackager )
				)
				( objectStatus "TP_CPU0_RSVD_274" )
			)
			( signal "@baseboard_fab2_lib.baseboard_fab2(sch_1):tp_cpu0_rsvd_275"
				( attribute "CDS_PHYS_NET_NAME" "TP_CPU0_RSVD_275"
					( Origin gPackager )
				)
				( objectStatus "TP_CPU0_RSVD_275" )
			)
			( signal "@baseboard_fab2_lib.baseboard_fab2(sch_1):tp_cpu0_rsvd_276"
				( attribute "CDS_PHYS_NET_NAME" "TP_CPU0_RSVD_276"
					( Origin gPackager )
				)
				( objectStatus "TP_CPU0_RSVD_276" )
			)
			( signal "@baseboard_fab2_lib.baseboard_fab2(sch_1):tp_cpu0_rsvd_277"
				( attribute "CDS_PHYS_NET_NAME" "TP_CPU0_RSVD_277"
					( Origin gPackager )
				)
				( objectStatus "TP_CPU0_RSVD_277" )
			)
			( signal "@baseboard_fab2_lib.baseboard_fab2(sch_1):tp_cpu0_rsvd_278"
				( attribute "CDS_PHYS_NET_NAME" "TP_CPU0_RSVD_278"
					( Origin gPackager )
				)
				( objectStatus "TP_CPU0_RSVD_278" )
			)
			( signal "@baseboard_fab2_lib.baseboard_fab2(sch_1):tp_cpu0_rsvd_279"
				( attribute "CDS_PHYS_NET_NAME" "TP_CPU0_RSVD_279"
					( Origin gPackager )
				)
				( objectStatus "TP_CPU0_RSVD_279" )
			)
			( signal "@baseboard_fab2_lib.baseboard_fab2(sch_1):tp_cpu0_rsvd_280"
				( attribute "CDS_PHYS_NET_NAME" "TP_CPU0_RSVD_280"
					( Origin gPackager )
				)
				( objectStatus "TP_CPU0_RSVD_280" )
			)
			( signal "@baseboard_fab2_lib.baseboard_fab2(sch_1):tp_cpu0_rsvd_281"
				( attribute "CDS_PHYS_NET_NAME" "TP_CPU0_RSVD_281"
					( Origin gPackager )
				)
				( objectStatus "TP_CPU0_RSVD_281" )
			)
			( signal "@baseboard_fab2_lib.baseboard_fab2(sch_1):tp_cpu0_rsvd_282"
				( attribute "CDS_PHYS_NET_NAME" "TP_CPU0_RSVD_282"
					( Origin gPackager )
				)
				( objectStatus "TP_CPU0_RSVD_282" )
			)
			( signal "@baseboard_fab2_lib.baseboard_fab2(sch_1):tp_cpu0_rsvd_283"
				( attribute "CDS_PHYS_NET_NAME" "TP_CPU0_RSVD_283"
					( Origin gPackager )
				)
				( objectStatus "TP_CPU0_RSVD_283" )
			)
			( signal "@baseboard_fab2_lib.baseboard_fab2(sch_1):tp_cpu0_rsvd_284"
				( attribute "CDS_PHYS_NET_NAME" "TP_CPU0_RSVD_284"
					( Origin gPackager )
				)
				( objectStatus "TP_CPU0_RSVD_284" )
			)
			( signal "@baseboard_fab2_lib.baseboard_fab2(sch_1):tp_cpu0_rsvd_285"
				( attribute "CDS_PHYS_NET_NAME" "TP_CPU0_RSVD_285"
					( Origin gPackager )
				)
				( objectStatus "TP_CPU0_RSVD_285" )
			)
			( signal "@baseboard_fab2_lib.baseboard_fab2(sch_1):tp_cpu0_rsvd_286"
				( attribute "CDS_PHYS_NET_NAME" "TP_CPU0_RSVD_286"
					( Origin gPackager )
				)
				( objectStatus "TP_CPU0_RSVD_286" )
			)
			( signal "@baseboard_fab2_lib.baseboard_fab2(sch_1):tp_cpu0_rsvd_287"
				( attribute "CDS_PHYS_NET_NAME" "TP_CPU0_RSVD_287"
					( Origin gPackager )
				)
				( objectStatus "TP_CPU0_RSVD_287" )
			)
			( signal "@baseboard_fab2_lib.baseboard_fab2(sch_1):tp_cpu0_rsvd_288"
				( attribute "CDS_PHYS_NET_NAME" "TP_CPU0_RSVD_288"
					( Origin gPackager )
				)
				( objectStatus "TP_CPU0_RSVD_288" )
			)
			( signal "@baseboard_fab2_lib.baseboard_fab2(sch_1):tp_cpu0_rsvd_289"
				( attribute "CDS_PHYS_NET_NAME" "TP_CPU0_RSVD_289"
					( Origin gPackager )
				)
				( objectStatus "TP_CPU0_RSVD_289" )
			)
			( signal "@baseboard_fab2_lib.baseboard_fab2(sch_1):tp_cpu0_rsvd_290"
				( attribute "CDS_PHYS_NET_NAME" "TP_CPU0_RSVD_290"
					( Origin gPackager )
				)
				( objectStatus "TP_CPU0_RSVD_290" )
			)
			( signal "@baseboard_fab2_lib.baseboard_fab2(sch_1):tp_cpu0_rsvd_291"
				( attribute "CDS_PHYS_NET_NAME" "TP_CPU0_RSVD_291"
					( Origin gPackager )
				)
				( objectStatus "TP_CPU0_RSVD_291" )
			)
			( signal "@baseboard_fab2_lib.baseboard_fab2(sch_1):tp_cpu0_rsvd_292"
				( attribute "CDS_PHYS_NET_NAME" "TP_CPU0_RSVD_292"
					( Origin gPackager )
				)
				( objectStatus "TP_CPU0_RSVD_292" )
			)
			( signal "@baseboard_fab2_lib.baseboard_fab2(sch_1):tp_cpu0_rsvd_293"
				( attribute "CDS_PHYS_NET_NAME" "TP_CPU0_RSVD_293"
					( Origin gPackager )
				)
				( objectStatus "TP_CPU0_RSVD_293" )
			)
			( signal "@baseboard_fab2_lib.baseboard_fab2(sch_1):tp_cpu0_rsvd_298"
				( attribute "CDS_PHYS_NET_NAME" "TP_CPU0_RSVD_298"
					( Origin gPackager )
				)
				( objectStatus "TP_CPU0_RSVD_298" )
			)
			( signal "@baseboard_fab2_lib.baseboard_fab2(sch_1):tp_cpu0_rsvd_299"
				( attribute "CDS_PHYS_NET_NAME" "TP_CPU0_RSVD_299"
					( Origin gPackager )
				)
				( objectStatus "TP_CPU0_RSVD_299" )
			)
			( signal "@baseboard_fab2_lib.baseboard_fab2(sch_1):tp_cpu0_rsvd_300"
				( attribute "CDS_PHYS_NET_NAME" "TP_CPU0_RSVD_300"
					( Origin gPackager )
				)
				( objectStatus "TP_CPU0_RSVD_300" )
			)
			( signal "@baseboard_fab2_lib.baseboard_fab2(sch_1):tp_cpu0_rsvd_303"
				( attribute "CDS_PHYS_NET_NAME" "TP_CPU0_RSVD_303"
					( Origin gPackager )
				)
				( objectStatus "TP_CPU0_RSVD_303" )
			)
			( signal "@baseboard_fab2_lib.baseboard_fab2(sch_1):tp_cpu0_rsvd_304"
				( attribute "CDS_PHYS_NET_NAME" "TP_CPU0_RSVD_304"
					( Origin gPackager )
				)
				( objectStatus "TP_CPU0_RSVD_304" )
			)
			( signal "@baseboard_fab2_lib.baseboard_fab2(sch_1):tp_cpu0_rsvd_test_11"
				( attribute "CDS_PHYS_NET_NAME" "TP_CPU0_RSVD_TEST_11"
					( Origin gPackager )
				)
				( objectStatus "TP_CPU0_RSVD_TEST_11" )
			)
			( signal "@baseboard_fab2_lib.baseboard_fab2(sch_1):tp_cpu0_rsvd_test_3"
				( attribute "CDS_PHYS_NET_NAME" "TP_CPU0_RSVD_TEST_3"
					( Origin gPackager )
				)
				( objectStatus "TP_CPU0_RSVD_TEST_3" )
			)
			( signal "@baseboard_fab2_lib.baseboard_fab2(sch_1):tp_cpu0_rsvd_test_4"
				( attribute "CDS_PHYS_NET_NAME" "TP_CPU0_RSVD_TEST_4"
					( Origin gPackager )
				)
				( objectStatus "TP_CPU0_RSVD_TEST_4" )
			)
			( signal "@baseboard_fab2_lib.baseboard_fab2(sch_1):tp_cpu0_rsvd_test_5"
				( attribute "CDS_PHYS_NET_NAME" "TP_CPU0_RSVD_TEST_5"
					( Origin gPackager )
				)
				( objectStatus "TP_CPU0_RSVD_TEST_5" )
			)
			( signal "@baseboard_fab2_lib.baseboard_fab2(sch_1):vsense_p1v8mcp_cpu0_skt_vrtn"
				( attribute "CDS_PHYS_NET_NAME" "VSENSE_P1V8MCP_CPU0_SKT_VRTN"
					( Origin gPackager )
				)
				( objectStatus "VSENSE_P1V8MCP_CPU0_SKT_VRTN" )
			)
			( signal "@baseboard_fab2_lib.baseboard_fab2(sch_1):vsense_p1v8mcp_cpu0_skt_vsen"
				( attribute "CDS_PHYS_NET_NAME" "VSENSE_P1V8MCP_CPU0_SKT_VSEN"
					( Origin gPackager )
				)
				( objectStatus "VSENSE_P1V8MCP_CPU0_SKT_VSEN" )
			)
			( signal "@baseboard_fab2_lib.baseboard_fab2(sch_1):xdp_cpu_pwr_debug_n"
				( attribute "CDS_PHYS_NET_NAME" "XDP_CPU_PWR_DEBUG_N"
					( Origin gPackager )
				)
				( objectStatus "XDP_CPU_PWR_DEBUG_N" )
			)
			( signal "@baseboard_fab2_lib.baseboard_fab2(sch_1):xdp_present_n"
				( attribute "CDS_PHYS_NET_NAME" "XDP_PRESENT_N"
					( Origin gPackager )
				)
				( objectStatus "XDP_PRESENT_N" )
			)
			( signal "@baseboard_fab2_lib.baseboard_fab2(sch_1):m_a_act_n"
				( attribute "CDS_PHYS_NET_NAME" "M_A_ACT_N"
					( Origin gPackager )
				)
				( objectStatus "M_A_ACT_N" )
			)
			( signal "@baseboard_fab2_lib.baseboard_fab2(sch_1):m_a_alert_n"
				( attribute "CDS_PHYS_NET_NAME" "M_A_ALERT_N"
					( Origin gPackager )
				)
				( objectStatus "M_A_ALERT_N" )
			)
			( signal "@baseboard_fab2_lib.baseboard_fab2(sch_1):m_a_ba(0)"
				( attribute "CDS_PHYS_NET_NAME" "M_A_BA<0>"
					( Origin gPackager )
				)
				( attribute "PNN" "M_A_BA<0>"
					( Origin gPackager )
				)
				( objectStatus "M_A_BA<0>" )
			)
			( signal "@baseboard_fab2_lib.baseboard_fab2(sch_1):m_a_ba(1)"
				( attribute "CDS_PHYS_NET_NAME" "M_A_BA<1>"
					( Origin gPackager )
				)
				( attribute "PNN" "M_A_BA<1>"
					( Origin gPackager )
				)
				( objectStatus "M_A_BA<1>" )
			)
			( signal "@baseboard_fab2_lib.baseboard_fab2(sch_1):m_a_bg(0)"
				( attribute "CDS_PHYS_NET_NAME" "M_A_BG<0>"
					( Origin gPackager )
				)
				( attribute "PNN" "M_A_BG<0>"
					( Origin gPackager )
				)
				( objectStatus "M_A_BG<0>" )
			)
			( signal "@baseboard_fab2_lib.baseboard_fab2(sch_1):m_a_bg(1)"
				( attribute "CDS_PHYS_NET_NAME" "M_A_BG<1>"
					( Origin gPackager )
				)
				( attribute "PNN" "M_A_BG<1>"
					( Origin gPackager )
				)
				( objectStatus "M_A_BG<1>" )
			)
			( signal "@baseboard_fab2_lib.baseboard_fab2(sch_1):m_a_c(2)"
				( attribute "CDS_PHYS_NET_NAME" "M_A_C<2>"
					( Origin gPackager )
				)
				( attribute "PNN" "M_A_C<2>"
					( Origin gPackager )
				)
				( objectStatus "M_A_C<2>" )
			)
			( signal "@baseboard_fab2_lib.baseboard_fab2(sch_1):m_a_cke(0)"
				( attribute "CDS_PHYS_NET_NAME" "M_A_CKE<0>"
					( Origin gPackager )
				)
				( attribute "PNN" "M_A_CKE<0>"
					( Origin gPackager )
				)
				( objectStatus "M_A_CKE<0>" )
			)
			( signal "@baseboard_fab2_lib.baseboard_fab2(sch_1):m_a_cke(1)"
				( attribute "CDS_PHYS_NET_NAME" "M_A_CKE<1>"
					( Origin gPackager )
				)
				( attribute "PNN" "M_A_CKE<1>"
					( Origin gPackager )
				)
				( objectStatus "M_A_CKE<1>" )
			)
			( signal "@baseboard_fab2_lib.baseboard_fab2(sch_1):m_a_cke(2)"
				( attribute "CDS_PHYS_NET_NAME" "M_A_CKE<2>"
					( Origin gPackager )
				)
				( attribute "PNN" "M_A_CKE<2>"
					( Origin gPackager )
				)
				( objectStatus "M_A_CKE<2>" )
			)
			( signal "@baseboard_fab2_lib.baseboard_fab2(sch_1):m_a_cke(3)"
				( attribute "CDS_PHYS_NET_NAME" "M_A_CKE<3>"
					( Origin gPackager )
				)
				( attribute "PNN" "M_A_CKE<3>"
					( Origin gPackager )
				)
				( objectStatus "M_A_CKE<3>" )
			)
			( signal "@baseboard_fab2_lib.baseboard_fab2(sch_1):m_a_clk_dn(0)"
				( attribute "CDS_PHYS_NET_NAME" "M_A_CLK_DN<0>"
					( Origin gPackager )
				)
				( attribute "PNN" "M_A_CLK_DN<0>"
					( Origin gPackager )
				)
				( objectStatus "M_A_CLK_DN<0>" )
			)
			( signal "@baseboard_fab2_lib.baseboard_fab2(sch_1):m_a_clk_dn(1)"
				( attribute "CDS_PHYS_NET_NAME" "M_A_CLK_DN<1>"
					( Origin gPackager )
				)
				( attribute "PNN" "M_A_CLK_DN<1>"
					( Origin gPackager )
				)
				( objectStatus "M_A_CLK_DN<1>" )
			)
			( signal "@baseboard_fab2_lib.baseboard_fab2(sch_1):m_a_clk_dn(2)"
				( attribute "CDS_PHYS_NET_NAME" "M_A_CLK_DN<2>"
					( Origin gPackager )
				)
				( attribute "PNN" "M_A_CLK_DN<2>"
					( Origin gPackager )
				)
				( objectStatus "M_A_CLK_DN<2>" )
			)
			( signal "@baseboard_fab2_lib.baseboard_fab2(sch_1):m_a_clk_dn(3)"
				( attribute "CDS_PHYS_NET_NAME" "M_A_CLK_DN<3>"
					( Origin gPackager )
				)
				( attribute "PNN" "M_A_CLK_DN<3>"
					( Origin gPackager )
				)
				( objectStatus "M_A_CLK_DN<3>" )
			)
			( signal "@baseboard_fab2_lib.baseboard_fab2(sch_1):m_a_clk_dp(0)"
				( attribute "CDS_PHYS_NET_NAME" "M_A_CLK_DP<0>"
					( Origin gPackager )
				)
				( attribute "PNN" "M_A_CLK_DP<0>"
					( Origin gPackager )
				)
				( objectStatus "M_A_CLK_DP<0>" )
			)
			( signal "@baseboard_fab2_lib.baseboard_fab2(sch_1):m_a_clk_dp(1)"
				( attribute "CDS_PHYS_NET_NAME" "M_A_CLK_DP<1>"
					( Origin gPackager )
				)
				( attribute "PNN" "M_A_CLK_DP<1>"
					( Origin gPackager )
				)
				( objectStatus "M_A_CLK_DP<1>" )
			)
			( signal "@baseboard_fab2_lib.baseboard_fab2(sch_1):m_a_clk_dp(2)"
				( attribute "CDS_PHYS_NET_NAME" "M_A_CLK_DP<2>"
					( Origin gPackager )
				)
				( attribute "PNN" "M_A_CLK_DP<2>"
					( Origin gPackager )
				)
				( objectStatus "M_A_CLK_DP<2>" )
			)
			( signal "@baseboard_fab2_lib.baseboard_fab2(sch_1):m_a_clk_dp(3)"
				( attribute "CDS_PHYS_NET_NAME" "M_A_CLK_DP<3>"
					( Origin gPackager )
				)
				( attribute "PNN" "M_A_CLK_DP<3>"
					( Origin gPackager )
				)
				( objectStatus "M_A_CLK_DP<3>" )
			)
			( signal "@baseboard_fab2_lib.baseboard_fab2(sch_1):m_a_cs_n(0)"
				( attribute "CDS_PHYS_NET_NAME" "M_A_CS_N<0>"
					( Origin gPackager )
				)
				( attribute "PNN" "M_A_CS_N<0>"
					( Origin gPackager )
				)
				( objectStatus "M_A_CS_N<0>" )
			)
			( signal "@baseboard_fab2_lib.baseboard_fab2(sch_1):m_a_cs_n(1)"
				( attribute "CDS_PHYS_NET_NAME" "M_A_CS_N<1>"
					( Origin gPackager )
				)
				( attribute "PNN" "M_A_CS_N<1>"
					( Origin gPackager )
				)
				( objectStatus "M_A_CS_N<1>" )
			)
			( signal "@baseboard_fab2_lib.baseboard_fab2(sch_1):m_a_cs_n(2)"
				( attribute "CDS_PHYS_NET_NAME" "M_A_CS_N<2>"
					( Origin gPackager )
				)
				( attribute "PNN" "M_A_CS_N<2>"
					( Origin gPackager )
				)
				( objectStatus "M_A_CS_N<2>" )
			)
			( signal "@baseboard_fab2_lib.baseboard_fab2(sch_1):m_a_cs_n(3)"
				( attribute "CDS_PHYS_NET_NAME" "M_A_CS_N<3>"
					( Origin gPackager )
				)
				( attribute "PNN" "M_A_CS_N<3>"
					( Origin gPackager )
				)
				( objectStatus "M_A_CS_N<3>" )
			)
			( signal "@baseboard_fab2_lib.baseboard_fab2(sch_1):m_a_cs_n(4)"
				( attribute "CDS_PHYS_NET_NAME" "M_A_CS_N<4>"
					( Origin gPackager )
				)
				( attribute "PNN" "M_A_CS_N<4>"
					( Origin gPackager )
				)
				( objectStatus "M_A_CS_N<4>" )
			)
			( signal "@baseboard_fab2_lib.baseboard_fab2(sch_1):m_a_cs_n(5)"
				( attribute "CDS_PHYS_NET_NAME" "M_A_CS_N<5>"
					( Origin gPackager )
				)
				( attribute "PNN" "M_A_CS_N<5>"
					( Origin gPackager )
				)
				( objectStatus "M_A_CS_N<5>" )
			)
			( signal "@baseboard_fab2_lib.baseboard_fab2(sch_1):m_a_cs_n(6)"
				( attribute "CDS_PHYS_NET_NAME" "M_A_CS_N<6>"
					( Origin gPackager )
				)
				( attribute "PNN" "M_A_CS_N<6>"
					( Origin gPackager )
				)
				( objectStatus "M_A_CS_N<6>" )
			)
			( signal "@baseboard_fab2_lib.baseboard_fab2(sch_1):m_a_cs_n(7)"
				( attribute "CDS_PHYS_NET_NAME" "M_A_CS_N<7>"
					( Origin gPackager )
				)
				( attribute "PNN" "M_A_CS_N<7>"
					( Origin gPackager )
				)
				( objectStatus "M_A_CS_N<7>" )
			)
			( signal "@baseboard_fab2_lib.baseboard_fab2(sch_1):m_a_dq(0)"
				( attribute "CDS_PHYS_NET_NAME" "M_A_DQ<0>"
					( Origin gPackager )
				)
				( attribute "PNN" "M_A_DQ<0>"
					( Origin gPackager )
				)
				( objectStatus "M_A_DQ<0>" )
			)
			( signal "@baseboard_fab2_lib.baseboard_fab2(sch_1):m_a_dq(1)"
				( attribute "CDS_PHYS_NET_NAME" "M_A_DQ<1>"
					( Origin gPackager )
				)
				( attribute "PNN" "M_A_DQ<1>"
					( Origin gPackager )
				)
				( objectStatus "M_A_DQ<1>" )
			)
			( signal "@baseboard_fab2_lib.baseboard_fab2(sch_1):m_a_dq(2)"
				( attribute "CDS_PHYS_NET_NAME" "M_A_DQ<2>"
					( Origin gPackager )
				)
				( attribute "PNN" "M_A_DQ<2>"
					( Origin gPackager )
				)
				( objectStatus "M_A_DQ<2>" )
			)
			( signal "@baseboard_fab2_lib.baseboard_fab2(sch_1):m_a_dq(3)"
				( attribute "CDS_PHYS_NET_NAME" "M_A_DQ<3>"
					( Origin gPackager )
				)
				( attribute "PNN" "M_A_DQ<3>"
					( Origin gPackager )
				)
				( objectStatus "M_A_DQ<3>" )
			)
			( signal "@baseboard_fab2_lib.baseboard_fab2(sch_1):m_a_dq(4)"
				( attribute "CDS_PHYS_NET_NAME" "M_A_DQ<4>"
					( Origin gPackager )
				)
				( attribute "PNN" "M_A_DQ<4>"
					( Origin gPackager )
				)
				( objectStatus "M_A_DQ<4>" )
			)
			( signal "@baseboard_fab2_lib.baseboard_fab2(sch_1):m_a_dq(5)"
				( attribute "CDS_PHYS_NET_NAME" "M_A_DQ<5>"
					( Origin gPackager )
				)
				( attribute "PNN" "M_A_DQ<5>"
					( Origin gPackager )
				)
				( objectStatus "M_A_DQ<5>" )
			)
			( signal "@baseboard_fab2_lib.baseboard_fab2(sch_1):m_a_dq(6)"
				( attribute "CDS_PHYS_NET_NAME" "M_A_DQ<6>"
					( Origin gPackager )
				)
				( attribute "PNN" "M_A_DQ<6>"
					( Origin gPackager )
				)
				( objectStatus "M_A_DQ<6>" )
			)
			( signal "@baseboard_fab2_lib.baseboard_fab2(sch_1):m_a_dq(7)"
				( attribute "CDS_PHYS_NET_NAME" "M_A_DQ<7>"
					( Origin gPackager )
				)
				( attribute "PNN" "M_A_DQ<7>"
					( Origin gPackager )
				)
				( objectStatus "M_A_DQ<7>" )
			)
			( signal "@baseboard_fab2_lib.baseboard_fab2(sch_1):m_a_dq(8)"
				( attribute "CDS_PHYS_NET_NAME" "M_A_DQ<8>"
					( Origin gPackager )
				)
				( attribute "PNN" "M_A_DQ<8>"
					( Origin gPackager )
				)
				( objectStatus "M_A_DQ<8>" )
			)
			( signal "@baseboard_fab2_lib.baseboard_fab2(sch_1):m_a_dq(9)"
				( attribute "CDS_PHYS_NET_NAME" "M_A_DQ<9>"
					( Origin gPackager )
				)
				( attribute "PNN" "M_A_DQ<9>"
					( Origin gPackager )
				)
				( objectStatus "M_A_DQ<9>" )
			)
			( signal "@baseboard_fab2_lib.baseboard_fab2(sch_1):m_a_dq(10)"
				( attribute "CDS_PHYS_NET_NAME" "M_A_DQ<10>"
					( Origin gPackager )
				)
				( attribute "PNN" "M_A_DQ<10>"
					( Origin gPackager )
				)
				( objectStatus "M_A_DQ<10>" )
			)
			( signal "@baseboard_fab2_lib.baseboard_fab2(sch_1):m_a_dq(11)"
				( attribute "CDS_PHYS_NET_NAME" "M_A_DQ<11>"
					( Origin gPackager )
				)
				( attribute "PNN" "M_A_DQ<11>"
					( Origin gPackager )
				)
				( objectStatus "M_A_DQ<11>" )
			)
			( signal "@baseboard_fab2_lib.baseboard_fab2(sch_1):m_a_dq(12)"
				( attribute "CDS_PHYS_NET_NAME" "M_A_DQ<12>"
					( Origin gPackager )
				)
				( attribute "PNN" "M_A_DQ<12>"
					( Origin gPackager )
				)
				( objectStatus "M_A_DQ<12>" )
			)
			( signal "@baseboard_fab2_lib.baseboard_fab2(sch_1):m_a_dq(13)"
				( attribute "CDS_PHYS_NET_NAME" "M_A_DQ<13>"
					( Origin gPackager )
				)
				( attribute "PNN" "M_A_DQ<13>"
					( Origin gPackager )
				)
				( objectStatus "M_A_DQ<13>" )
			)
			( signal "@baseboard_fab2_lib.baseboard_fab2(sch_1):m_a_dq(14)"
				( attribute "CDS_PHYS_NET_NAME" "M_A_DQ<14>"
					( Origin gPackager )
				)
				( attribute "PNN" "M_A_DQ<14>"
					( Origin gPackager )
				)
				( objectStatus "M_A_DQ<14>" )
			)
			( signal "@baseboard_fab2_lib.baseboard_fab2(sch_1):m_a_dq(15)"
				( attribute "CDS_PHYS_NET_NAME" "M_A_DQ<15>"
					( Origin gPackager )
				)
				( attribute "PNN" "M_A_DQ<15>"
					( Origin gPackager )
				)
				( objectStatus "M_A_DQ<15>" )
			)
			( signal "@baseboard_fab2_lib.baseboard_fab2(sch_1):m_a_dq(16)"
				( attribute "CDS_PHYS_NET_NAME" "M_A_DQ<16>"
					( Origin gPackager )
				)
				( attribute "PNN" "M_A_DQ<16>"
					( Origin gPackager )
				)
				( objectStatus "M_A_DQ<16>" )
			)
			( signal "@baseboard_fab2_lib.baseboard_fab2(sch_1):m_a_dq(17)"
				( attribute "CDS_PHYS_NET_NAME" "M_A_DQ<17>"
					( Origin gPackager )
				)
				( attribute "PNN" "M_A_DQ<17>"
					( Origin gPackager )
				)
				( objectStatus "M_A_DQ<17>" )
			)
			( signal "@baseboard_fab2_lib.baseboard_fab2(sch_1):m_a_dq(18)"
				( attribute "CDS_PHYS_NET_NAME" "M_A_DQ<18>"
					( Origin gPackager )
				)
				( attribute "PNN" "M_A_DQ<18>"
					( Origin gPackager )
				)
				( objectStatus "M_A_DQ<18>" )
			)
			( signal "@baseboard_fab2_lib.baseboard_fab2(sch_1):m_a_dq(19)"
				( attribute "CDS_PHYS_NET_NAME" "M_A_DQ<19>"
					( Origin gPackager )
				)
				( attribute "PNN" "M_A_DQ<19>"
					( Origin gPackager )
				)
				( objectStatus "M_A_DQ<19>" )
			)
			( signal "@baseboard_fab2_lib.baseboard_fab2(sch_1):m_a_dq(20)"
				( attribute "CDS_PHYS_NET_NAME" "M_A_DQ<20>"
					( Origin gPackager )
				)
				( attribute "PNN" "M_A_DQ<20>"
					( Origin gPackager )
				)
				( objectStatus "M_A_DQ<20>" )
			)
			( signal "@baseboard_fab2_lib.baseboard_fab2(sch_1):m_a_dq(21)"
				( attribute "CDS_PHYS_NET_NAME" "M_A_DQ<21>"
					( Origin gPackager )
				)
				( attribute "PNN" "M_A_DQ<21>"
					( Origin gPackager )
				)
				( objectStatus "M_A_DQ<21>" )
			)
			( signal "@baseboard_fab2_lib.baseboard_fab2(sch_1):m_a_dq(22)"
				( attribute "CDS_PHYS_NET_NAME" "M_A_DQ<22>"
					( Origin gPackager )
				)
				( attribute "PNN" "M_A_DQ<22>"
					( Origin gPackager )
				)
				( objectStatus "M_A_DQ<22>" )
			)
			( signal "@baseboard_fab2_lib.baseboard_fab2(sch_1):m_a_dq(23)"
				( attribute "CDS_PHYS_NET_NAME" "M_A_DQ<23>"
					( Origin gPackager )
				)
				( attribute "PNN" "M_A_DQ<23>"
					( Origin gPackager )
				)
				( objectStatus "M_A_DQ<23>" )
			)
			( signal "@baseboard_fab2_lib.baseboard_fab2(sch_1):m_a_dq(24)"
				( attribute "CDS_PHYS_NET_NAME" "M_A_DQ<24>"
					( Origin gPackager )
				)
				( attribute "PNN" "M_A_DQ<24>"
					( Origin gPackager )
				)
				( objectStatus "M_A_DQ<24>" )
			)
			( signal "@baseboard_fab2_lib.baseboard_fab2(sch_1):m_a_dq(25)"
				( attribute "CDS_PHYS_NET_NAME" "M_A_DQ<25>"
					( Origin gPackager )
				)
				( attribute "PNN" "M_A_DQ<25>"
					( Origin gPackager )
				)
				( objectStatus "M_A_DQ<25>" )
			)
			( signal "@baseboard_fab2_lib.baseboard_fab2(sch_1):m_a_dq(26)"
				( attribute "CDS_PHYS_NET_NAME" "M_A_DQ<26>"
					( Origin gPackager )
				)
				( attribute "PNN" "M_A_DQ<26>"
					( Origin gPackager )
				)
				( objectStatus "M_A_DQ<26>" )
			)
			( signal "@baseboard_fab2_lib.baseboard_fab2(sch_1):m_a_dq(27)"
				( attribute "CDS_PHYS_NET_NAME" "M_A_DQ<27>"
					( Origin gPackager )
				)
				( attribute "PNN" "M_A_DQ<27>"
					( Origin gPackager )
				)
				( objectStatus "M_A_DQ<27>" )
			)
			( signal "@baseboard_fab2_lib.baseboard_fab2(sch_1):m_a_dq(28)"
				( attribute "CDS_PHYS_NET_NAME" "M_A_DQ<28>"
					( Origin gPackager )
				)
				( attribute "PNN" "M_A_DQ<28>"
					( Origin gPackager )
				)
				( objectStatus "M_A_DQ<28>" )
			)
			( signal "@baseboard_fab2_lib.baseboard_fab2(sch_1):m_a_dq(29)"
				( attribute "CDS_PHYS_NET_NAME" "M_A_DQ<29>"
					( Origin gPackager )
				)
				( attribute "PNN" "M_A_DQ<29>"
					( Origin gPackager )
				)
				( objectStatus "M_A_DQ<29>" )
			)
			( signal "@baseboard_fab2_lib.baseboard_fab2(sch_1):m_a_dq(30)"
				( attribute "CDS_PHYS_NET_NAME" "M_A_DQ<30>"
					( Origin gPackager )
				)
				( attribute "PNN" "M_A_DQ<30>"
					( Origin gPackager )
				)
				( objectStatus "M_A_DQ<30>" )
			)
			( signal "@baseboard_fab2_lib.baseboard_fab2(sch_1):m_a_dq(31)"
				( attribute "CDS_PHYS_NET_NAME" "M_A_DQ<31>"
					( Origin gPackager )
				)
				( attribute "PNN" "M_A_DQ<31>"
					( Origin gPackager )
				)
				( objectStatus "M_A_DQ<31>" )
			)
			( signal "@baseboard_fab2_lib.baseboard_fab2(sch_1):m_a_dq(32)"
				( attribute "CDS_PHYS_NET_NAME" "M_A_DQ<32>"
					( Origin gPackager )
				)
				( attribute "PNN" "M_A_DQ<32>"
					( Origin gPackager )
				)
				( objectStatus "M_A_DQ<32>" )
			)
			( signal "@baseboard_fab2_lib.baseboard_fab2(sch_1):m_a_dq(33)"
				( attribute "CDS_PHYS_NET_NAME" "M_A_DQ<33>"
					( Origin gPackager )
				)
				( attribute "PNN" "M_A_DQ<33>"
					( Origin gPackager )
				)
				( objectStatus "M_A_DQ<33>" )
			)
			( signal "@baseboard_fab2_lib.baseboard_fab2(sch_1):m_a_dq(34)"
				( attribute "CDS_PHYS_NET_NAME" "M_A_DQ<34>"
					( Origin gPackager )
				)
				( attribute "PNN" "M_A_DQ<34>"
					( Origin gPackager )
				)
				( objectStatus "M_A_DQ<34>" )
			)
			( signal "@baseboard_fab2_lib.baseboard_fab2(sch_1):m_a_dq(35)"
				( attribute "CDS_PHYS_NET_NAME" "M_A_DQ<35>"
					( Origin gPackager )
				)
				( attribute "PNN" "M_A_DQ<35>"
					( Origin gPackager )
				)
				( objectStatus "M_A_DQ<35>" )
			)
			( signal "@baseboard_fab2_lib.baseboard_fab2(sch_1):m_a_dq(36)"
				( attribute "CDS_PHYS_NET_NAME" "M_A_DQ<36>"
					( Origin gPackager )
				)
				( attribute "PNN" "M_A_DQ<36>"
					( Origin gPackager )
				)
				( objectStatus "M_A_DQ<36>" )
			)
			( signal "@baseboard_fab2_lib.baseboard_fab2(sch_1):m_a_dq(37)"
				( attribute "CDS_PHYS_NET_NAME" "M_A_DQ<37>"
					( Origin gPackager )
				)
				( attribute "PNN" "M_A_DQ<37>"
					( Origin gPackager )
				)
				( objectStatus "M_A_DQ<37>" )
			)
			( signal "@baseboard_fab2_lib.baseboard_fab2(sch_1):m_a_dq(38)"
				( attribute "CDS_PHYS_NET_NAME" "M_A_DQ<38>"
					( Origin gPackager )
				)
				( attribute "PNN" "M_A_DQ<38>"
					( Origin gPackager )
				)
				( objectStatus "M_A_DQ<38>" )
			)
			( signal "@baseboard_fab2_lib.baseboard_fab2(sch_1):m_a_dq(39)"
				( attribute "CDS_PHYS_NET_NAME" "M_A_DQ<39>"
					( Origin gPackager )
				)
				( attribute "PNN" "M_A_DQ<39>"
					( Origin gPackager )
				)
				( objectStatus "M_A_DQ<39>" )
			)
			( signal "@baseboard_fab2_lib.baseboard_fab2(sch_1):m_a_dq(40)"
				( attribute "CDS_PHYS_NET_NAME" "M_A_DQ<40>"
					( Origin gPackager )
				)
				( attribute "PNN" "M_A_DQ<40>"
					( Origin gPackager )
				)
				( objectStatus "M_A_DQ<40>" )
			)
			( signal "@baseboard_fab2_lib.baseboard_fab2(sch_1):m_a_dq(41)"
				( attribute "CDS_PHYS_NET_NAME" "M_A_DQ<41>"
					( Origin gPackager )
				)
				( attribute "PNN" "M_A_DQ<41>"
					( Origin gPackager )
				)
				( objectStatus "M_A_DQ<41>" )
			)
			( signal "@baseboard_fab2_lib.baseboard_fab2(sch_1):m_a_dq(42)"
				( attribute "CDS_PHYS_NET_NAME" "M_A_DQ<42>"
					( Origin gPackager )
				)
				( attribute "PNN" "M_A_DQ<42>"
					( Origin gPackager )
				)
				( objectStatus "M_A_DQ<42>" )
			)
			( signal "@baseboard_fab2_lib.baseboard_fab2(sch_1):m_a_dq(43)"
				( attribute "CDS_PHYS_NET_NAME" "M_A_DQ<43>"
					( Origin gPackager )
				)
				( attribute "PNN" "M_A_DQ<43>"
					( Origin gPackager )
				)
				( objectStatus "M_A_DQ<43>" )
			)
			( signal "@baseboard_fab2_lib.baseboard_fab2(sch_1):m_a_dq(44)"
				( attribute "CDS_PHYS_NET_NAME" "M_A_DQ<44>"
					( Origin gPackager )
				)
				( attribute "PNN" "M_A_DQ<44>"
					( Origin gPackager )
				)
				( objectStatus "M_A_DQ<44>" )
			)
			( signal "@baseboard_fab2_lib.baseboard_fab2(sch_1):m_a_dq(45)"
				( attribute "CDS_PHYS_NET_NAME" "M_A_DQ<45>"
					( Origin gPackager )
				)
				( attribute "PNN" "M_A_DQ<45>"
					( Origin gPackager )
				)
				( objectStatus "M_A_DQ<45>" )
			)
			( signal "@baseboard_fab2_lib.baseboard_fab2(sch_1):m_a_dq(46)"
				( attribute "CDS_PHYS_NET_NAME" "M_A_DQ<46>"
					( Origin gPackager )
				)
				( attribute "PNN" "M_A_DQ<46>"
					( Origin gPackager )
				)
				( objectStatus "M_A_DQ<46>" )
			)
			( signal "@baseboard_fab2_lib.baseboard_fab2(sch_1):m_a_dq(47)"
				( attribute "CDS_PHYS_NET_NAME" "M_A_DQ<47>"
					( Origin gPackager )
				)
				( attribute "PNN" "M_A_DQ<47>"
					( Origin gPackager )
				)
				( objectStatus "M_A_DQ<47>" )
			)
			( signal "@baseboard_fab2_lib.baseboard_fab2(sch_1):m_a_dq(48)"
				( attribute "CDS_PHYS_NET_NAME" "M_A_DQ<48>"
					( Origin gPackager )
				)
				( attribute "PNN" "M_A_DQ<48>"
					( Origin gPackager )
				)
				( objectStatus "M_A_DQ<48>" )
			)
			( signal "@baseboard_fab2_lib.baseboard_fab2(sch_1):m_a_dq(49)"
				( attribute "CDS_PHYS_NET_NAME" "M_A_DQ<49>"
					( Origin gPackager )
				)
				( attribute "PNN" "M_A_DQ<49>"
					( Origin gPackager )
				)
				( objectStatus "M_A_DQ<49>" )
			)
			( signal "@baseboard_fab2_lib.baseboard_fab2(sch_1):m_a_dq(50)"
				( attribute "CDS_PHYS_NET_NAME" "M_A_DQ<50>"
					( Origin gPackager )
				)
				( attribute "PNN" "M_A_DQ<50>"
					( Origin gPackager )
				)
				( objectStatus "M_A_DQ<50>" )
			)
			( signal "@baseboard_fab2_lib.baseboard_fab2(sch_1):m_a_dq(51)"
				( attribute "CDS_PHYS_NET_NAME" "M_A_DQ<51>"
					( Origin gPackager )
				)
				( attribute "PNN" "M_A_DQ<51>"
					( Origin gPackager )
				)
				( objectStatus "M_A_DQ<51>" )
			)
			( signal "@baseboard_fab2_lib.baseboard_fab2(sch_1):m_a_dq(52)"
				( attribute "CDS_PHYS_NET_NAME" "M_A_DQ<52>"
					( Origin gPackager )
				)
				( attribute "PNN" "M_A_DQ<52>"
					( Origin gPackager )
				)
				( objectStatus "M_A_DQ<52>" )
			)
			( signal "@baseboard_fab2_lib.baseboard_fab2(sch_1):m_a_dq(53)"
				( attribute "CDS_PHYS_NET_NAME" "M_A_DQ<53>"
					( Origin gPackager )
				)
				( attribute "PNN" "M_A_DQ<53>"
					( Origin gPackager )
				)
				( objectStatus "M_A_DQ<53>" )
			)
			( signal "@baseboard_fab2_lib.baseboard_fab2(sch_1):m_a_dq(54)"
				( attribute "CDS_PHYS_NET_NAME" "M_A_DQ<54>"
					( Origin gPackager )
				)
				( attribute "PNN" "M_A_DQ<54>"
					( Origin gPackager )
				)
				( objectStatus "M_A_DQ<54>" )
			)
			( signal "@baseboard_fab2_lib.baseboard_fab2(sch_1):m_a_dq(55)"
				( attribute "CDS_PHYS_NET_NAME" "M_A_DQ<55>"
					( Origin gPackager )
				)
				( attribute "PNN" "M_A_DQ<55>"
					( Origin gPackager )
				)
				( objectStatus "M_A_DQ<55>" )
			)
			( signal "@baseboard_fab2_lib.baseboard_fab2(sch_1):m_a_dq(56)"
				( attribute "CDS_PHYS_NET_NAME" "M_A_DQ<56>"
					( Origin gPackager )
				)
				( attribute "PNN" "M_A_DQ<56>"
					( Origin gPackager )
				)
				( objectStatus "M_A_DQ<56>" )
			)
			( signal "@baseboard_fab2_lib.baseboard_fab2(sch_1):m_a_dq(57)"
				( attribute "CDS_PHYS_NET_NAME" "M_A_DQ<57>"
					( Origin gPackager )
				)
				( attribute "PNN" "M_A_DQ<57>"
					( Origin gPackager )
				)
				( objectStatus "M_A_DQ<57>" )
			)
			( signal "@baseboard_fab2_lib.baseboard_fab2(sch_1):m_a_dq(58)"
				( attribute "CDS_PHYS_NET_NAME" "M_A_DQ<58>"
					( Origin gPackager )
				)
				( attribute "PNN" "M_A_DQ<58>"
					( Origin gPackager )
				)
				( objectStatus "M_A_DQ<58>" )
			)
			( signal "@baseboard_fab2_lib.baseboard_fab2(sch_1):m_a_dq(59)"
				( attribute "CDS_PHYS_NET_NAME" "M_A_DQ<59>"
					( Origin gPackager )
				)
				( attribute "PNN" "M_A_DQ<59>"
					( Origin gPackager )
				)
				( objectStatus "M_A_DQ<59>" )
			)
			( signal "@baseboard_fab2_lib.baseboard_fab2(sch_1):m_a_dq(60)"
				( attribute "CDS_PHYS_NET_NAME" "M_A_DQ<60>"
					( Origin gPackager )
				)
				( attribute "PNN" "M_A_DQ<60>"
					( Origin gPackager )
				)
				( objectStatus "M_A_DQ<60>" )
			)
			( signal "@baseboard_fab2_lib.baseboard_fab2(sch_1):m_a_dq(61)"
				( attribute "CDS_PHYS_NET_NAME" "M_A_DQ<61>"
					( Origin gPackager )
				)
				( attribute "PNN" "M_A_DQ<61>"
					( Origin gPackager )
				)
				( objectStatus "M_A_DQ<61>" )
			)
			( signal "@baseboard_fab2_lib.baseboard_fab2(sch_1):m_a_dq(62)"
				( attribute "CDS_PHYS_NET_NAME" "M_A_DQ<62>"
					( Origin gPackager )
				)
				( attribute "PNN" "M_A_DQ<62>"
					( Origin gPackager )
				)
				( objectStatus "M_A_DQ<62>" )
			)
			( signal "@baseboard_fab2_lib.baseboard_fab2(sch_1):m_a_dq(63)"
				( attribute "CDS_PHYS_NET_NAME" "M_A_DQ<63>"
					( Origin gPackager )
				)
				( attribute "PNN" "M_A_DQ<63>"
					( Origin gPackager )
				)
				( objectStatus "M_A_DQ<63>" )
			)
			( signal "@baseboard_fab2_lib.baseboard_fab2(sch_1):m_a_dqs_dn(0)"
				( attribute "CDS_PHYS_NET_NAME" "M_A_DQS_DN<0>"
					( Origin gPackager )
				)
				( attribute "PNN" "M_A_DQS_DN<0>"
					( Origin gPackager )
				)
				( objectStatus "M_A_DQS_DN<0>" )
			)
			( signal "@baseboard_fab2_lib.baseboard_fab2(sch_1):m_a_dqs_dn(1)"
				( attribute "CDS_PHYS_NET_NAME" "M_A_DQS_DN<1>"
					( Origin gPackager )
				)
				( attribute "PNN" "M_A_DQS_DN<1>"
					( Origin gPackager )
				)
				( objectStatus "M_A_DQS_DN<1>" )
			)
			( signal "@baseboard_fab2_lib.baseboard_fab2(sch_1):m_a_dqs_dn(2)"
				( attribute "CDS_PHYS_NET_NAME" "M_A_DQS_DN<2>"
					( Origin gPackager )
				)
				( attribute "PNN" "M_A_DQS_DN<2>"
					( Origin gPackager )
				)
				( objectStatus "M_A_DQS_DN<2>" )
			)
			( signal "@baseboard_fab2_lib.baseboard_fab2(sch_1):m_a_dqs_dn(3)"
				( attribute "CDS_PHYS_NET_NAME" "M_A_DQS_DN<3>"
					( Origin gPackager )
				)
				( attribute "PNN" "M_A_DQS_DN<3>"
					( Origin gPackager )
				)
				( objectStatus "M_A_DQS_DN<3>" )
			)
			( signal "@baseboard_fab2_lib.baseboard_fab2(sch_1):m_a_dqs_dn(4)"
				( attribute "CDS_PHYS_NET_NAME" "M_A_DQS_DN<4>"
					( Origin gPackager )
				)
				( attribute "PNN" "M_A_DQS_DN<4>"
					( Origin gPackager )
				)
				( objectStatus "M_A_DQS_DN<4>" )
			)
			( signal "@baseboard_fab2_lib.baseboard_fab2(sch_1):m_a_dqs_dn(5)"
				( attribute "CDS_PHYS_NET_NAME" "M_A_DQS_DN<5>"
					( Origin gPackager )
				)
				( attribute "PNN" "M_A_DQS_DN<5>"
					( Origin gPackager )
				)
				( objectStatus "M_A_DQS_DN<5>" )
			)
			( signal "@baseboard_fab2_lib.baseboard_fab2(sch_1):m_a_dqs_dn(6)"
				( attribute "CDS_PHYS_NET_NAME" "M_A_DQS_DN<6>"
					( Origin gPackager )
				)
				( attribute "PNN" "M_A_DQS_DN<6>"
					( Origin gPackager )
				)
				( objectStatus "M_A_DQS_DN<6>" )
			)
			( signal "@baseboard_fab2_lib.baseboard_fab2(sch_1):m_a_dqs_dn(7)"
				( attribute "CDS_PHYS_NET_NAME" "M_A_DQS_DN<7>"
					( Origin gPackager )
				)
				( attribute "PNN" "M_A_DQS_DN<7>"
					( Origin gPackager )
				)
				( objectStatus "M_A_DQS_DN<7>" )
			)
			( signal "@baseboard_fab2_lib.baseboard_fab2(sch_1):m_a_dqs_dn(8)"
				( attribute "CDS_PHYS_NET_NAME" "M_A_DQS_DN<8>"
					( Origin gPackager )
				)
				( attribute "PNN" "M_A_DQS_DN<8>"
					( Origin gPackager )
				)
				( objectStatus "M_A_DQS_DN<8>" )
			)
			( signal "@baseboard_fab2_lib.baseboard_fab2(sch_1):m_a_dqs_dn(9)"
				( attribute "CDS_PHYS_NET_NAME" "M_A_DQS_DN<9>"
					( Origin gPackager )
				)
				( attribute "PNN" "M_A_DQS_DN<9>"
					( Origin gPackager )
				)
				( objectStatus "M_A_DQS_DN<9>" )
			)
			( signal "@baseboard_fab2_lib.baseboard_fab2(sch_1):m_a_dqs_dn(10)"
				( attribute "CDS_PHYS_NET_NAME" "M_A_DQS_DN<10>"
					( Origin gPackager )
				)
				( attribute "PNN" "M_A_DQS_DN<10>"
					( Origin gPackager )
				)
				( objectStatus "M_A_DQS_DN<10>" )
			)
			( signal "@baseboard_fab2_lib.baseboard_fab2(sch_1):m_a_dqs_dn(11)"
				( attribute "CDS_PHYS_NET_NAME" "M_A_DQS_DN<11>"
					( Origin gPackager )
				)
				( attribute "PNN" "M_A_DQS_DN<11>"
					( Origin gPackager )
				)
				( objectStatus "M_A_DQS_DN<11>" )
			)
			( signal "@baseboard_fab2_lib.baseboard_fab2(sch_1):m_a_dqs_dn(12)"
				( attribute "CDS_PHYS_NET_NAME" "M_A_DQS_DN<12>"
					( Origin gPackager )
				)
				( attribute "PNN" "M_A_DQS_DN<12>"
					( Origin gPackager )
				)
				( objectStatus "M_A_DQS_DN<12>" )
			)
			( signal "@baseboard_fab2_lib.baseboard_fab2(sch_1):m_a_dqs_dn(13)"
				( attribute "CDS_PHYS_NET_NAME" "M_A_DQS_DN<13>"
					( Origin gPackager )
				)
				( attribute "PNN" "M_A_DQS_DN<13>"
					( Origin gPackager )
				)
				( objectStatus "M_A_DQS_DN<13>" )
			)
			( signal "@baseboard_fab2_lib.baseboard_fab2(sch_1):m_a_dqs_dn(14)"
				( attribute "CDS_PHYS_NET_NAME" "M_A_DQS_DN<14>"
					( Origin gPackager )
				)
				( attribute "PNN" "M_A_DQS_DN<14>"
					( Origin gPackager )
				)
				( objectStatus "M_A_DQS_DN<14>" )
			)
			( signal "@baseboard_fab2_lib.baseboard_fab2(sch_1):m_a_dqs_dn(15)"
				( attribute "CDS_PHYS_NET_NAME" "M_A_DQS_DN<15>"
					( Origin gPackager )
				)
				( attribute "PNN" "M_A_DQS_DN<15>"
					( Origin gPackager )
				)
				( objectStatus "M_A_DQS_DN<15>" )
			)
			( signal "@baseboard_fab2_lib.baseboard_fab2(sch_1):m_a_dqs_dn(16)"
				( attribute "CDS_PHYS_NET_NAME" "M_A_DQS_DN<16>"
					( Origin gPackager )
				)
				( attribute "PNN" "M_A_DQS_DN<16>"
					( Origin gPackager )
				)
				( objectStatus "M_A_DQS_DN<16>" )
			)
			( signal "@baseboard_fab2_lib.baseboard_fab2(sch_1):m_a_dqs_dn(17)"
				( attribute "CDS_PHYS_NET_NAME" "M_A_DQS_DN<17>"
					( Origin gPackager )
				)
				( attribute "PNN" "M_A_DQS_DN<17>"
					( Origin gPackager )
				)
				( objectStatus "M_A_DQS_DN<17>" )
			)
			( signal "@baseboard_fab2_lib.baseboard_fab2(sch_1):m_a_dqs_dp(0)"
				( attribute "CDS_PHYS_NET_NAME" "M_A_DQS_DP<0>"
					( Origin gPackager )
				)
				( attribute "PNN" "M_A_DQS_DP<0>"
					( Origin gPackager )
				)
				( objectStatus "M_A_DQS_DP<0>" )
			)
			( signal "@baseboard_fab2_lib.baseboard_fab2(sch_1):m_a_dqs_dp(1)"
				( attribute "CDS_PHYS_NET_NAME" "M_A_DQS_DP<1>"
					( Origin gPackager )
				)
				( attribute "PNN" "M_A_DQS_DP<1>"
					( Origin gPackager )
				)
				( objectStatus "M_A_DQS_DP<1>" )
			)
			( signal "@baseboard_fab2_lib.baseboard_fab2(sch_1):m_a_dqs_dp(2)"
				( attribute "CDS_PHYS_NET_NAME" "M_A_DQS_DP<2>"
					( Origin gPackager )
				)
				( attribute "PNN" "M_A_DQS_DP<2>"
					( Origin gPackager )
				)
				( objectStatus "M_A_DQS_DP<2>" )
			)
			( signal "@baseboard_fab2_lib.baseboard_fab2(sch_1):m_a_dqs_dp(3)"
				( attribute "CDS_PHYS_NET_NAME" "M_A_DQS_DP<3>"
					( Origin gPackager )
				)
				( attribute "PNN" "M_A_DQS_DP<3>"
					( Origin gPackager )
				)
				( objectStatus "M_A_DQS_DP<3>" )
			)
			( signal "@baseboard_fab2_lib.baseboard_fab2(sch_1):m_a_dqs_dp(4)"
				( attribute "CDS_PHYS_NET_NAME" "M_A_DQS_DP<4>"
					( Origin gPackager )
				)
				( attribute "PNN" "M_A_DQS_DP<4>"
					( Origin gPackager )
				)
				( objectStatus "M_A_DQS_DP<4>" )
			)
			( signal "@baseboard_fab2_lib.baseboard_fab2(sch_1):m_a_dqs_dp(5)"
				( attribute "CDS_PHYS_NET_NAME" "M_A_DQS_DP<5>"
					( Origin gPackager )
				)
				( attribute "PNN" "M_A_DQS_DP<5>"
					( Origin gPackager )
				)
				( objectStatus "M_A_DQS_DP<5>" )
			)
			( signal "@baseboard_fab2_lib.baseboard_fab2(sch_1):m_a_dqs_dp(6)"
				( attribute "CDS_PHYS_NET_NAME" "M_A_DQS_DP<6>"
					( Origin gPackager )
				)
				( attribute "PNN" "M_A_DQS_DP<6>"
					( Origin gPackager )
				)
				( objectStatus "M_A_DQS_DP<6>" )
			)
			( signal "@baseboard_fab2_lib.baseboard_fab2(sch_1):m_a_dqs_dp(7)"
				( attribute "CDS_PHYS_NET_NAME" "M_A_DQS_DP<7>"
					( Origin gPackager )
				)
				( attribute "PNN" "M_A_DQS_DP<7>"
					( Origin gPackager )
				)
				( objectStatus "M_A_DQS_DP<7>" )
			)
			( signal "@baseboard_fab2_lib.baseboard_fab2(sch_1):m_a_dqs_dp(8)"
				( attribute "CDS_PHYS_NET_NAME" "M_A_DQS_DP<8>"
					( Origin gPackager )
				)
				( attribute "PNN" "M_A_DQS_DP<8>"
					( Origin gPackager )
				)
				( objectStatus "M_A_DQS_DP<8>" )
			)
			( signal "@baseboard_fab2_lib.baseboard_fab2(sch_1):m_a_dqs_dp(9)"
				( attribute "CDS_PHYS_NET_NAME" "M_A_DQS_DP<9>"
					( Origin gPackager )
				)
				( attribute "PNN" "M_A_DQS_DP<9>"
					( Origin gPackager )
				)
				( objectStatus "M_A_DQS_DP<9>" )
			)
			( signal "@baseboard_fab2_lib.baseboard_fab2(sch_1):m_a_dqs_dp(10)"
				( attribute "CDS_PHYS_NET_NAME" "M_A_DQS_DP<10>"
					( Origin gPackager )
				)
				( attribute "PNN" "M_A_DQS_DP<10>"
					( Origin gPackager )
				)
				( objectStatus "M_A_DQS_DP<10>" )
			)
			( signal "@baseboard_fab2_lib.baseboard_fab2(sch_1):m_a_dqs_dp(11)"
				( attribute "CDS_PHYS_NET_NAME" "M_A_DQS_DP<11>"
					( Origin gPackager )
				)
				( attribute "PNN" "M_A_DQS_DP<11>"
					( Origin gPackager )
				)
				( objectStatus "M_A_DQS_DP<11>" )
			)
			( signal "@baseboard_fab2_lib.baseboard_fab2(sch_1):m_a_dqs_dp(12)"
				( attribute "CDS_PHYS_NET_NAME" "M_A_DQS_DP<12>"
					( Origin gPackager )
				)
				( attribute "PNN" "M_A_DQS_DP<12>"
					( Origin gPackager )
				)
				( objectStatus "M_A_DQS_DP<12>" )
			)
			( signal "@baseboard_fab2_lib.baseboard_fab2(sch_1):m_a_dqs_dp(13)"
				( attribute "CDS_PHYS_NET_NAME" "M_A_DQS_DP<13>"
					( Origin gPackager )
				)
				( attribute "PNN" "M_A_DQS_DP<13>"
					( Origin gPackager )
				)
				( objectStatus "M_A_DQS_DP<13>" )
			)
			( signal "@baseboard_fab2_lib.baseboard_fab2(sch_1):m_a_dqs_dp(14)"
				( attribute "CDS_PHYS_NET_NAME" "M_A_DQS_DP<14>"
					( Origin gPackager )
				)
				( attribute "PNN" "M_A_DQS_DP<14>"
					( Origin gPackager )
				)
				( objectStatus "M_A_DQS_DP<14>" )
			)
			( signal "@baseboard_fab2_lib.baseboard_fab2(sch_1):m_a_dqs_dp(15)"
				( attribute "CDS_PHYS_NET_NAME" "M_A_DQS_DP<15>"
					( Origin gPackager )
				)
				( attribute "PNN" "M_A_DQS_DP<15>"
					( Origin gPackager )
				)
				( objectStatus "M_A_DQS_DP<15>" )
			)
			( signal "@baseboard_fab2_lib.baseboard_fab2(sch_1):m_a_dqs_dp(16)"
				( attribute "CDS_PHYS_NET_NAME" "M_A_DQS_DP<16>"
					( Origin gPackager )
				)
				( attribute "PNN" "M_A_DQS_DP<16>"
					( Origin gPackager )
				)
				( objectStatus "M_A_DQS_DP<16>" )
			)
			( signal "@baseboard_fab2_lib.baseboard_fab2(sch_1):m_a_dqs_dp(17)"
				( attribute "CDS_PHYS_NET_NAME" "M_A_DQS_DP<17>"
					( Origin gPackager )
				)
				( attribute "PNN" "M_A_DQS_DP<17>"
					( Origin gPackager )
				)
				( objectStatus "M_A_DQS_DP<17>" )
			)
			( signal "@baseboard_fab2_lib.baseboard_fab2(sch_1):m_a_ecc(0)"
				( attribute "CDS_PHYS_NET_NAME" "M_A_ECC<0>"
					( Origin gPackager )
				)
				( attribute "PNN" "M_A_ECC<0>"
					( Origin gPackager )
				)
				( objectStatus "M_A_ECC<0>" )
			)
			( signal "@baseboard_fab2_lib.baseboard_fab2(sch_1):m_a_ecc(1)"
				( attribute "CDS_PHYS_NET_NAME" "M_A_ECC<1>"
					( Origin gPackager )
				)
				( attribute "PNN" "M_A_ECC<1>"
					( Origin gPackager )
				)
				( objectStatus "M_A_ECC<1>" )
			)
			( signal "@baseboard_fab2_lib.baseboard_fab2(sch_1):m_a_ecc(2)"
				( attribute "CDS_PHYS_NET_NAME" "M_A_ECC<2>"
					( Origin gPackager )
				)
				( attribute "PNN" "M_A_ECC<2>"
					( Origin gPackager )
				)
				( objectStatus "M_A_ECC<2>" )
			)
			( signal "@baseboard_fab2_lib.baseboard_fab2(sch_1):m_a_ecc(3)"
				( attribute "CDS_PHYS_NET_NAME" "M_A_ECC<3>"
					( Origin gPackager )
				)
				( attribute "PNN" "M_A_ECC<3>"
					( Origin gPackager )
				)
				( objectStatus "M_A_ECC<3>" )
			)
			( signal "@baseboard_fab2_lib.baseboard_fab2(sch_1):m_a_ecc(4)"
				( attribute "CDS_PHYS_NET_NAME" "M_A_ECC<4>"
					( Origin gPackager )
				)
				( attribute "PNN" "M_A_ECC<4>"
					( Origin gPackager )
				)
				( objectStatus "M_A_ECC<4>" )
			)
			( signal "@baseboard_fab2_lib.baseboard_fab2(sch_1):m_a_ecc(5)"
				( attribute "CDS_PHYS_NET_NAME" "M_A_ECC<5>"
					( Origin gPackager )
				)
				( attribute "PNN" "M_A_ECC<5>"
					( Origin gPackager )
				)
				( objectStatus "M_A_ECC<5>" )
			)
			( signal "@baseboard_fab2_lib.baseboard_fab2(sch_1):m_a_ecc(6)"
				( attribute "CDS_PHYS_NET_NAME" "M_A_ECC<6>"
					( Origin gPackager )
				)
				( attribute "PNN" "M_A_ECC<6>"
					( Origin gPackager )
				)
				( objectStatus "M_A_ECC<6>" )
			)
			( signal "@baseboard_fab2_lib.baseboard_fab2(sch_1):m_a_ecc(7)"
				( attribute "CDS_PHYS_NET_NAME" "M_A_ECC<7>"
					( Origin gPackager )
				)
				( attribute "PNN" "M_A_ECC<7>"
					( Origin gPackager )
				)
				( objectStatus "M_A_ECC<7>" )
			)
			( signal "@baseboard_fab2_lib.baseboard_fab2(sch_1):m_a_ma(0)"
				( attribute "CDS_PHYS_NET_NAME" "M_A_MA<0>"
					( Origin gPackager )
				)
				( attribute "PNN" "M_A_MA<0>"
					( Origin gPackager )
				)
				( objectStatus "M_A_MA<0>" )
			)
			( signal "@baseboard_fab2_lib.baseboard_fab2(sch_1):m_a_ma(1)"
				( attribute "CDS_PHYS_NET_NAME" "M_A_MA<1>"
					( Origin gPackager )
				)
				( attribute "PNN" "M_A_MA<1>"
					( Origin gPackager )
				)
				( objectStatus "M_A_MA<1>" )
			)
			( signal "@baseboard_fab2_lib.baseboard_fab2(sch_1):m_a_ma(2)"
				( attribute "CDS_PHYS_NET_NAME" "M_A_MA<2>"
					( Origin gPackager )
				)
				( attribute "PNN" "M_A_MA<2>"
					( Origin gPackager )
				)
				( objectStatus "M_A_MA<2>" )
			)
			( signal "@baseboard_fab2_lib.baseboard_fab2(sch_1):m_a_ma(3)"
				( attribute "CDS_PHYS_NET_NAME" "M_A_MA<3>"
					( Origin gPackager )
				)
				( attribute "PNN" "M_A_MA<3>"
					( Origin gPackager )
				)
				( objectStatus "M_A_MA<3>" )
			)
			( signal "@baseboard_fab2_lib.baseboard_fab2(sch_1):m_a_ma(4)"
				( attribute "CDS_PHYS_NET_NAME" "M_A_MA<4>"
					( Origin gPackager )
				)
				( attribute "PNN" "M_A_MA<4>"
					( Origin gPackager )
				)
				( objectStatus "M_A_MA<4>" )
			)
			( signal "@baseboard_fab2_lib.baseboard_fab2(sch_1):m_a_ma(5)"
				( attribute "CDS_PHYS_NET_NAME" "M_A_MA<5>"
					( Origin gPackager )
				)
				( attribute "PNN" "M_A_MA<5>"
					( Origin gPackager )
				)
				( objectStatus "M_A_MA<5>" )
			)
			( signal "@baseboard_fab2_lib.baseboard_fab2(sch_1):m_a_ma(6)"
				( attribute "CDS_PHYS_NET_NAME" "M_A_MA<6>"
					( Origin gPackager )
				)
				( attribute "PNN" "M_A_MA<6>"
					( Origin gPackager )
				)
				( objectStatus "M_A_MA<6>" )
			)
			( signal "@baseboard_fab2_lib.baseboard_fab2(sch_1):m_a_ma(7)"
				( attribute "CDS_PHYS_NET_NAME" "M_A_MA<7>"
					( Origin gPackager )
				)
				( attribute "PNN" "M_A_MA<7>"
					( Origin gPackager )
				)
				( objectStatus "M_A_MA<7>" )
			)
			( signal "@baseboard_fab2_lib.baseboard_fab2(sch_1):m_a_ma(8)"
				( attribute "CDS_PHYS_NET_NAME" "M_A_MA<8>"
					( Origin gPackager )
				)
				( attribute "PNN" "M_A_MA<8>"
					( Origin gPackager )
				)
				( objectStatus "M_A_MA<8>" )
			)
			( signal "@baseboard_fab2_lib.baseboard_fab2(sch_1):m_a_ma(9)"
				( attribute "CDS_PHYS_NET_NAME" "M_A_MA<9>"
					( Origin gPackager )
				)
				( attribute "PNN" "M_A_MA<9>"
					( Origin gPackager )
				)
				( objectStatus "M_A_MA<9>" )
			)
			( signal "@baseboard_fab2_lib.baseboard_fab2(sch_1):m_a_ma(10)"
				( attribute "CDS_PHYS_NET_NAME" "M_A_MA<10>"
					( Origin gPackager )
				)
				( attribute "PNN" "M_A_MA<10>"
					( Origin gPackager )
				)
				( objectStatus "M_A_MA<10>" )
			)
			( signal "@baseboard_fab2_lib.baseboard_fab2(sch_1):m_a_ma(11)"
				( attribute "CDS_PHYS_NET_NAME" "M_A_MA<11>"
					( Origin gPackager )
				)
				( attribute "PNN" "M_A_MA<11>"
					( Origin gPackager )
				)
				( objectStatus "M_A_MA<11>" )
			)
			( signal "@baseboard_fab2_lib.baseboard_fab2(sch_1):m_a_ma(12)"
				( attribute "CDS_PHYS_NET_NAME" "M_A_MA<12>"
					( Origin gPackager )
				)
				( attribute "PNN" "M_A_MA<12>"
					( Origin gPackager )
				)
				( objectStatus "M_A_MA<12>" )
			)
			( signal "@baseboard_fab2_lib.baseboard_fab2(sch_1):m_a_ma(13)"
				( attribute "CDS_PHYS_NET_NAME" "M_A_MA<13>"
					( Origin gPackager )
				)
				( attribute "PNN" "M_A_MA<13>"
					( Origin gPackager )
				)
				( objectStatus "M_A_MA<13>" )
			)
			( signal "@baseboard_fab2_lib.baseboard_fab2(sch_1):m_a_ma(14)"
				( attribute "CDS_PHYS_NET_NAME" "M_A_MA<14>"
					( Origin gPackager )
				)
				( attribute "PNN" "M_A_MA<14>"
					( Origin gPackager )
				)
				( objectStatus "M_A_MA<14>" )
			)
			( signal "@baseboard_fab2_lib.baseboard_fab2(sch_1):m_a_ma(15)"
				( attribute "CDS_PHYS_NET_NAME" "M_A_MA<15>"
					( Origin gPackager )
				)
				( attribute "PNN" "M_A_MA<15>"
					( Origin gPackager )
				)
				( objectStatus "M_A_MA<15>" )
			)
			( signal "@baseboard_fab2_lib.baseboard_fab2(sch_1):m_a_ma(16)"
				( attribute "CDS_PHYS_NET_NAME" "M_A_MA<16>"
					( Origin gPackager )
				)
				( attribute "PNN" "M_A_MA<16>"
					( Origin gPackager )
				)
				( objectStatus "M_A_MA<16>" )
			)
			( signal "@baseboard_fab2_lib.baseboard_fab2(sch_1):m_a_ma(17)"
				( attribute "CDS_PHYS_NET_NAME" "M_A_MA<17>"
					( Origin gPackager )
				)
				( attribute "PNN" "M_A_MA<17>"
					( Origin gPackager )
				)
				( objectStatus "M_A_MA<17>" )
			)
			( signal "@baseboard_fab2_lib.baseboard_fab2(sch_1):m_a_odt(0)"
				( attribute "CDS_PHYS_NET_NAME" "M_A_ODT<0>"
					( Origin gPackager )
				)
				( attribute "PNN" "M_A_ODT<0>"
					( Origin gPackager )
				)
				( objectStatus "M_A_ODT<0>" )
			)
			( signal "@baseboard_fab2_lib.baseboard_fab2(sch_1):m_a_odt(1)"
				( attribute "CDS_PHYS_NET_NAME" "M_A_ODT<1>"
					( Origin gPackager )
				)
				( attribute "PNN" "M_A_ODT<1>"
					( Origin gPackager )
				)
				( objectStatus "M_A_ODT<1>" )
			)
			( signal "@baseboard_fab2_lib.baseboard_fab2(sch_1):m_a_odt(2)"
				( attribute "CDS_PHYS_NET_NAME" "M_A_ODT<2>"
					( Origin gPackager )
				)
				( attribute "PNN" "M_A_ODT<2>"
					( Origin gPackager )
				)
				( objectStatus "M_A_ODT<2>" )
			)
			( signal "@baseboard_fab2_lib.baseboard_fab2(sch_1):m_a_odt(3)"
				( attribute "CDS_PHYS_NET_NAME" "M_A_ODT<3>"
					( Origin gPackager )
				)
				( attribute "PNN" "M_A_ODT<3>"
					( Origin gPackager )
				)
				( objectStatus "M_A_ODT<3>" )
			)
			( signal "@baseboard_fab2_lib.baseboard_fab2(sch_1):m_a_par"
				( attribute "CDS_PHYS_NET_NAME" "M_A_PAR"
					( Origin gPackager )
				)
				( objectStatus "M_A_PAR" )
			)
			( signal "@baseboard_fab2_lib.baseboard_fab2(sch_1):m_b_act_n"
				( attribute "CDS_PHYS_NET_NAME" "M_B_ACT_N"
					( Origin gPackager )
				)
				( objectStatus "M_B_ACT_N" )
			)
			( signal "@baseboard_fab2_lib.baseboard_fab2(sch_1):m_b_alert_n"
				( attribute "CDS_PHYS_NET_NAME" "M_B_ALERT_N"
					( Origin gPackager )
				)
				( objectStatus "M_B_ALERT_N" )
			)
			( signal "@baseboard_fab2_lib.baseboard_fab2(sch_1):m_b_ba(0)"
				( attribute "CDS_PHYS_NET_NAME" "M_B_BA<0>"
					( Origin gPackager )
				)
				( attribute "PNN" "M_B_BA<0>"
					( Origin gPackager )
				)
				( objectStatus "M_B_BA<0>" )
			)
			( signal "@baseboard_fab2_lib.baseboard_fab2(sch_1):m_b_ba(1)"
				( attribute "CDS_PHYS_NET_NAME" "M_B_BA<1>"
					( Origin gPackager )
				)
				( attribute "PNN" "M_B_BA<1>"
					( Origin gPackager )
				)
				( objectStatus "M_B_BA<1>" )
			)
			( signal "@baseboard_fab2_lib.baseboard_fab2(sch_1):m_b_bg(0)"
				( attribute "CDS_PHYS_NET_NAME" "M_B_BG<0>"
					( Origin gPackager )
				)
				( attribute "PNN" "M_B_BG<0>"
					( Origin gPackager )
				)
				( objectStatus "M_B_BG<0>" )
			)
			( signal "@baseboard_fab2_lib.baseboard_fab2(sch_1):m_b_bg(1)"
				( attribute "CDS_PHYS_NET_NAME" "M_B_BG<1>"
					( Origin gPackager )
				)
				( attribute "PNN" "M_B_BG<1>"
					( Origin gPackager )
				)
				( objectStatus "M_B_BG<1>" )
			)
			( signal "@baseboard_fab2_lib.baseboard_fab2(sch_1):m_b_c(2)"
				( attribute "CDS_PHYS_NET_NAME" "M_B_C<2>"
					( Origin gPackager )
				)
				( attribute "PNN" "M_B_C<2>"
					( Origin gPackager )
				)
				( objectStatus "M_B_C<2>" )
			)
			( signal "@baseboard_fab2_lib.baseboard_fab2(sch_1):m_b_cke(0)"
				( attribute "CDS_PHYS_NET_NAME" "M_B_CKE<0>"
					( Origin gPackager )
				)
				( attribute "PNN" "M_B_CKE<0>"
					( Origin gPackager )
				)
				( objectStatus "M_B_CKE<0>" )
			)
			( signal "@baseboard_fab2_lib.baseboard_fab2(sch_1):m_b_cke(1)"
				( attribute "CDS_PHYS_NET_NAME" "M_B_CKE<1>"
					( Origin gPackager )
				)
				( attribute "PNN" "M_B_CKE<1>"
					( Origin gPackager )
				)
				( objectStatus "M_B_CKE<1>" )
			)
			( signal "@baseboard_fab2_lib.baseboard_fab2(sch_1):m_b_cke(2)"
				( attribute "CDS_PHYS_NET_NAME" "M_B_CKE<2>"
					( Origin gPackager )
				)
				( attribute "PNN" "M_B_CKE<2>"
					( Origin gPackager )
				)
				( objectStatus "M_B_CKE<2>" )
			)
			( signal "@baseboard_fab2_lib.baseboard_fab2(sch_1):m_b_cke(3)"
				( attribute "CDS_PHYS_NET_NAME" "M_B_CKE<3>"
					( Origin gPackager )
				)
				( attribute "PNN" "M_B_CKE<3>"
					( Origin gPackager )
				)
				( objectStatus "M_B_CKE<3>" )
			)
			( signal "@baseboard_fab2_lib.baseboard_fab2(sch_1):m_b_clk_dn(0)"
				( attribute "CDS_PHYS_NET_NAME" "M_B_CLK_DN<0>"
					( Origin gPackager )
				)
				( attribute "PNN" "M_B_CLK_DN<0>"
					( Origin gPackager )
				)
				( objectStatus "M_B_CLK_DN<0>" )
			)
			( signal "@baseboard_fab2_lib.baseboard_fab2(sch_1):m_b_clk_dn(1)"
				( attribute "CDS_PHYS_NET_NAME" "M_B_CLK_DN<1>"
					( Origin gPackager )
				)
				( attribute "PNN" "M_B_CLK_DN<1>"
					( Origin gPackager )
				)
				( objectStatus "M_B_CLK_DN<1>" )
			)
			( signal "@baseboard_fab2_lib.baseboard_fab2(sch_1):m_b_clk_dn(2)"
				( attribute "CDS_PHYS_NET_NAME" "M_B_CLK_DN<2>"
					( Origin gPackager )
				)
				( attribute "PNN" "M_B_CLK_DN<2>"
					( Origin gPackager )
				)
				( objectStatus "M_B_CLK_DN<2>" )
			)
			( signal "@baseboard_fab2_lib.baseboard_fab2(sch_1):m_b_clk_dn(3)"
				( attribute "CDS_PHYS_NET_NAME" "M_B_CLK_DN<3>"
					( Origin gPackager )
				)
				( attribute "PNN" "M_B_CLK_DN<3>"
					( Origin gPackager )
				)
				( objectStatus "M_B_CLK_DN<3>" )
			)
			( signal "@baseboard_fab2_lib.baseboard_fab2(sch_1):m_b_clk_dp(0)"
				( attribute "CDS_PHYS_NET_NAME" "M_B_CLK_DP<0>"
					( Origin gPackager )
				)
				( attribute "PNN" "M_B_CLK_DP<0>"
					( Origin gPackager )
				)
				( objectStatus "M_B_CLK_DP<0>" )
			)
			( signal "@baseboard_fab2_lib.baseboard_fab2(sch_1):m_b_clk_dp(1)"
				( attribute "CDS_PHYS_NET_NAME" "M_B_CLK_DP<1>"
					( Origin gPackager )
				)
				( attribute "PNN" "M_B_CLK_DP<1>"
					( Origin gPackager )
				)
				( objectStatus "M_B_CLK_DP<1>" )
			)
			( signal "@baseboard_fab2_lib.baseboard_fab2(sch_1):m_b_clk_dp(2)"
				( attribute "CDS_PHYS_NET_NAME" "M_B_CLK_DP<2>"
					( Origin gPackager )
				)
				( attribute "PNN" "M_B_CLK_DP<2>"
					( Origin gPackager )
				)
				( objectStatus "M_B_CLK_DP<2>" )
			)
			( signal "@baseboard_fab2_lib.baseboard_fab2(sch_1):m_b_clk_dp(3)"
				( attribute "CDS_PHYS_NET_NAME" "M_B_CLK_DP<3>"
					( Origin gPackager )
				)
				( attribute "PNN" "M_B_CLK_DP<3>"
					( Origin gPackager )
				)
				( objectStatus "M_B_CLK_DP<3>" )
			)
			( signal "@baseboard_fab2_lib.baseboard_fab2(sch_1):m_b_cs_n(0)"
				( attribute "CDS_PHYS_NET_NAME" "M_B_CS_N<0>"
					( Origin gPackager )
				)
				( attribute "PNN" "M_B_CS_N<0>"
					( Origin gPackager )
				)
				( objectStatus "M_B_CS_N<0>" )
			)
			( signal "@baseboard_fab2_lib.baseboard_fab2(sch_1):m_b_cs_n(1)"
				( attribute "CDS_PHYS_NET_NAME" "M_B_CS_N<1>"
					( Origin gPackager )
				)
				( attribute "PNN" "M_B_CS_N<1>"
					( Origin gPackager )
				)
				( objectStatus "M_B_CS_N<1>" )
			)
			( signal "@baseboard_fab2_lib.baseboard_fab2(sch_1):m_b_cs_n(2)"
				( attribute "CDS_PHYS_NET_NAME" "M_B_CS_N<2>"
					( Origin gPackager )
				)
				( attribute "PNN" "M_B_CS_N<2>"
					( Origin gPackager )
				)
				( objectStatus "M_B_CS_N<2>" )
			)
			( signal "@baseboard_fab2_lib.baseboard_fab2(sch_1):m_b_cs_n(3)"
				( attribute "CDS_PHYS_NET_NAME" "M_B_CS_N<3>"
					( Origin gPackager )
				)
				( attribute "PNN" "M_B_CS_N<3>"
					( Origin gPackager )
				)
				( objectStatus "M_B_CS_N<3>" )
			)
			( signal "@baseboard_fab2_lib.baseboard_fab2(sch_1):m_b_cs_n(4)"
				( attribute "CDS_PHYS_NET_NAME" "M_B_CS_N<4>"
					( Origin gPackager )
				)
				( attribute "PNN" "M_B_CS_N<4>"
					( Origin gPackager )
				)
				( objectStatus "M_B_CS_N<4>" )
			)
			( signal "@baseboard_fab2_lib.baseboard_fab2(sch_1):m_b_cs_n(5)"
				( attribute "CDS_PHYS_NET_NAME" "M_B_CS_N<5>"
					( Origin gPackager )
				)
				( attribute "PNN" "M_B_CS_N<5>"
					( Origin gPackager )
				)
				( objectStatus "M_B_CS_N<5>" )
			)
			( signal "@baseboard_fab2_lib.baseboard_fab2(sch_1):m_b_cs_n(6)"
				( attribute "CDS_PHYS_NET_NAME" "M_B_CS_N<6>"
					( Origin gPackager )
				)
				( attribute "PNN" "M_B_CS_N<6>"
					( Origin gPackager )
				)
				( objectStatus "M_B_CS_N<6>" )
			)
			( signal "@baseboard_fab2_lib.baseboard_fab2(sch_1):m_b_cs_n(7)"
				( attribute "CDS_PHYS_NET_NAME" "M_B_CS_N<7>"
					( Origin gPackager )
				)
				( attribute "PNN" "M_B_CS_N<7>"
					( Origin gPackager )
				)
				( objectStatus "M_B_CS_N<7>" )
			)
			( signal "@baseboard_fab2_lib.baseboard_fab2(sch_1):m_b_dq(0)"
				( attribute "CDS_PHYS_NET_NAME" "M_B_DQ<0>"
					( Origin gPackager )
				)
				( attribute "PNN" "M_B_DQ<0>"
					( Origin gPackager )
				)
				( objectStatus "M_B_DQ<0>" )
			)
			( signal "@baseboard_fab2_lib.baseboard_fab2(sch_1):m_b_dq(1)"
				( attribute "CDS_PHYS_NET_NAME" "M_B_DQ<1>"
					( Origin gPackager )
				)
				( attribute "PNN" "M_B_DQ<1>"
					( Origin gPackager )
				)
				( objectStatus "M_B_DQ<1>" )
			)
			( signal "@baseboard_fab2_lib.baseboard_fab2(sch_1):m_b_dq(2)"
				( attribute "CDS_PHYS_NET_NAME" "M_B_DQ<2>"
					( Origin gPackager )
				)
				( attribute "PNN" "M_B_DQ<2>"
					( Origin gPackager )
				)
				( objectStatus "M_B_DQ<2>" )
			)
			( signal "@baseboard_fab2_lib.baseboard_fab2(sch_1):m_b_dq(3)"
				( attribute "CDS_PHYS_NET_NAME" "M_B_DQ<3>"
					( Origin gPackager )
				)
				( attribute "PNN" "M_B_DQ<3>"
					( Origin gPackager )
				)
				( objectStatus "M_B_DQ<3>" )
			)
			( signal "@baseboard_fab2_lib.baseboard_fab2(sch_1):m_b_dq(4)"
				( attribute "CDS_PHYS_NET_NAME" "M_B_DQ<4>"
					( Origin gPackager )
				)
				( attribute "PNN" "M_B_DQ<4>"
					( Origin gPackager )
				)
				( objectStatus "M_B_DQ<4>" )
			)
			( signal "@baseboard_fab2_lib.baseboard_fab2(sch_1):m_b_dq(5)"
				( attribute "CDS_PHYS_NET_NAME" "M_B_DQ<5>"
					( Origin gPackager )
				)
				( attribute "PNN" "M_B_DQ<5>"
					( Origin gPackager )
				)
				( objectStatus "M_B_DQ<5>" )
			)
			( signal "@baseboard_fab2_lib.baseboard_fab2(sch_1):m_b_dq(6)"
				( attribute "CDS_PHYS_NET_NAME" "M_B_DQ<6>"
					( Origin gPackager )
				)
				( attribute "PNN" "M_B_DQ<6>"
					( Origin gPackager )
				)
				( objectStatus "M_B_DQ<6>" )
			)
			( signal "@baseboard_fab2_lib.baseboard_fab2(sch_1):m_b_dq(7)"
				( attribute "CDS_PHYS_NET_NAME" "M_B_DQ<7>"
					( Origin gPackager )
				)
				( attribute "PNN" "M_B_DQ<7>"
					( Origin gPackager )
				)
				( objectStatus "M_B_DQ<7>" )
			)
			( signal "@baseboard_fab2_lib.baseboard_fab2(sch_1):m_b_dq(8)"
				( attribute "CDS_PHYS_NET_NAME" "M_B_DQ<8>"
					( Origin gPackager )
				)
				( attribute "PNN" "M_B_DQ<8>"
					( Origin gPackager )
				)
				( objectStatus "M_B_DQ<8>" )
			)
			( signal "@baseboard_fab2_lib.baseboard_fab2(sch_1):m_b_dq(9)"
				( attribute "CDS_PHYS_NET_NAME" "M_B_DQ<9>"
					( Origin gPackager )
				)
				( attribute "PNN" "M_B_DQ<9>"
					( Origin gPackager )
				)
				( objectStatus "M_B_DQ<9>" )
			)
			( signal "@baseboard_fab2_lib.baseboard_fab2(sch_1):m_b_dq(10)"
				( attribute "CDS_PHYS_NET_NAME" "M_B_DQ<10>"
					( Origin gPackager )
				)
				( attribute "PNN" "M_B_DQ<10>"
					( Origin gPackager )
				)
				( objectStatus "M_B_DQ<10>" )
			)
			( signal "@baseboard_fab2_lib.baseboard_fab2(sch_1):m_b_dq(11)"
				( attribute "CDS_PHYS_NET_NAME" "M_B_DQ<11>"
					( Origin gPackager )
				)
				( attribute "PNN" "M_B_DQ<11>"
					( Origin gPackager )
				)
				( objectStatus "M_B_DQ<11>" )
			)
			( signal "@baseboard_fab2_lib.baseboard_fab2(sch_1):m_b_dq(12)"
				( attribute "CDS_PHYS_NET_NAME" "M_B_DQ<12>"
					( Origin gPackager )
				)
				( attribute "PNN" "M_B_DQ<12>"
					( Origin gPackager )
				)
				( objectStatus "M_B_DQ<12>" )
			)
			( signal "@baseboard_fab2_lib.baseboard_fab2(sch_1):m_b_dq(13)"
				( attribute "CDS_PHYS_NET_NAME" "M_B_DQ<13>"
					( Origin gPackager )
				)
				( attribute "PNN" "M_B_DQ<13>"
					( Origin gPackager )
				)
				( objectStatus "M_B_DQ<13>" )
			)
			( signal "@baseboard_fab2_lib.baseboard_fab2(sch_1):m_b_dq(14)"
				( attribute "CDS_PHYS_NET_NAME" "M_B_DQ<14>"
					( Origin gPackager )
				)
				( attribute "PNN" "M_B_DQ<14>"
					( Origin gPackager )
				)
				( objectStatus "M_B_DQ<14>" )
			)
			( signal "@baseboard_fab2_lib.baseboard_fab2(sch_1):m_b_dq(15)"
				( attribute "CDS_PHYS_NET_NAME" "M_B_DQ<15>"
					( Origin gPackager )
				)
				( attribute "PNN" "M_B_DQ<15>"
					( Origin gPackager )
				)
				( objectStatus "M_B_DQ<15>" )
			)
			( signal "@baseboard_fab2_lib.baseboard_fab2(sch_1):m_b_dq(16)"
				( attribute "CDS_PHYS_NET_NAME" "M_B_DQ<16>"
					( Origin gPackager )
				)
				( attribute "PNN" "M_B_DQ<16>"
					( Origin gPackager )
				)
				( objectStatus "M_B_DQ<16>" )
			)
			( signal "@baseboard_fab2_lib.baseboard_fab2(sch_1):m_b_dq(17)"
				( attribute "CDS_PHYS_NET_NAME" "M_B_DQ<17>"
					( Origin gPackager )
				)
				( attribute "PNN" "M_B_DQ<17>"
					( Origin gPackager )
				)
				( objectStatus "M_B_DQ<17>" )
			)
			( signal "@baseboard_fab2_lib.baseboard_fab2(sch_1):m_b_dq(18)"
				( attribute "CDS_PHYS_NET_NAME" "M_B_DQ<18>"
					( Origin gPackager )
				)
				( attribute "PNN" "M_B_DQ<18>"
					( Origin gPackager )
				)
				( objectStatus "M_B_DQ<18>" )
			)
			( signal "@baseboard_fab2_lib.baseboard_fab2(sch_1):m_b_dq(19)"
				( attribute "CDS_PHYS_NET_NAME" "M_B_DQ<19>"
					( Origin gPackager )
				)
				( attribute "PNN" "M_B_DQ<19>"
					( Origin gPackager )
				)
				( objectStatus "M_B_DQ<19>" )
			)
			( signal "@baseboard_fab2_lib.baseboard_fab2(sch_1):m_b_dq(20)"
				( attribute "CDS_PHYS_NET_NAME" "M_B_DQ<20>"
					( Origin gPackager )
				)
				( attribute "PNN" "M_B_DQ<20>"
					( Origin gPackager )
				)
				( objectStatus "M_B_DQ<20>" )
			)
			( signal "@baseboard_fab2_lib.baseboard_fab2(sch_1):m_b_dq(21)"
				( attribute "CDS_PHYS_NET_NAME" "M_B_DQ<21>"
					( Origin gPackager )
				)
				( attribute "PNN" "M_B_DQ<21>"
					( Origin gPackager )
				)
				( objectStatus "M_B_DQ<21>" )
			)
			( signal "@baseboard_fab2_lib.baseboard_fab2(sch_1):m_b_dq(22)"
				( attribute "CDS_PHYS_NET_NAME" "M_B_DQ<22>"
					( Origin gPackager )
				)
				( attribute "PNN" "M_B_DQ<22>"
					( Origin gPackager )
				)
				( objectStatus "M_B_DQ<22>" )
			)
			( signal "@baseboard_fab2_lib.baseboard_fab2(sch_1):m_b_dq(23)"
				( attribute "CDS_PHYS_NET_NAME" "M_B_DQ<23>"
					( Origin gPackager )
				)
				( attribute "PNN" "M_B_DQ<23>"
					( Origin gPackager )
				)
				( objectStatus "M_B_DQ<23>" )
			)
			( signal "@baseboard_fab2_lib.baseboard_fab2(sch_1):m_b_dq(24)"
				( attribute "CDS_PHYS_NET_NAME" "M_B_DQ<24>"
					( Origin gPackager )
				)
				( attribute "PNN" "M_B_DQ<24>"
					( Origin gPackager )
				)
				( objectStatus "M_B_DQ<24>" )
			)
			( signal "@baseboard_fab2_lib.baseboard_fab2(sch_1):m_b_dq(25)"
				( attribute "CDS_PHYS_NET_NAME" "M_B_DQ<25>"
					( Origin gPackager )
				)
				( attribute "PNN" "M_B_DQ<25>"
					( Origin gPackager )
				)
				( objectStatus "M_B_DQ<25>" )
			)
			( signal "@baseboard_fab2_lib.baseboard_fab2(sch_1):m_b_dq(26)"
				( attribute "CDS_PHYS_NET_NAME" "M_B_DQ<26>"
					( Origin gPackager )
				)
				( attribute "PNN" "M_B_DQ<26>"
					( Origin gPackager )
				)
				( objectStatus "M_B_DQ<26>" )
			)
			( signal "@baseboard_fab2_lib.baseboard_fab2(sch_1):m_b_dq(27)"
				( attribute "CDS_PHYS_NET_NAME" "M_B_DQ<27>"
					( Origin gPackager )
				)
				( attribute "PNN" "M_B_DQ<27>"
					( Origin gPackager )
				)
				( objectStatus "M_B_DQ<27>" )
			)
			( signal "@baseboard_fab2_lib.baseboard_fab2(sch_1):m_b_dq(28)"
				( attribute "CDS_PHYS_NET_NAME" "M_B_DQ<28>"
					( Origin gPackager )
				)
				( attribute "PNN" "M_B_DQ<28>"
					( Origin gPackager )
				)
				( objectStatus "M_B_DQ<28>" )
			)
			( signal "@baseboard_fab2_lib.baseboard_fab2(sch_1):m_b_dq(29)"
				( attribute "CDS_PHYS_NET_NAME" "M_B_DQ<29>"
					( Origin gPackager )
				)
				( attribute "PNN" "M_B_DQ<29>"
					( Origin gPackager )
				)
				( objectStatus "M_B_DQ<29>" )
			)
			( signal "@baseboard_fab2_lib.baseboard_fab2(sch_1):m_b_dq(30)"
				( attribute "CDS_PHYS_NET_NAME" "M_B_DQ<30>"
					( Origin gPackager )
				)
				( attribute "PNN" "M_B_DQ<30>"
					( Origin gPackager )
				)
				( objectStatus "M_B_DQ<30>" )
			)
			( signal "@baseboard_fab2_lib.baseboard_fab2(sch_1):m_b_dq(31)"
				( attribute "CDS_PHYS_NET_NAME" "M_B_DQ<31>"
					( Origin gPackager )
				)
				( attribute "PNN" "M_B_DQ<31>"
					( Origin gPackager )
				)
				( objectStatus "M_B_DQ<31>" )
			)
			( signal "@baseboard_fab2_lib.baseboard_fab2(sch_1):m_b_dq(32)"
				( attribute "CDS_PHYS_NET_NAME" "M_B_DQ<32>"
					( Origin gPackager )
				)
				( attribute "PNN" "M_B_DQ<32>"
					( Origin gPackager )
				)
				( objectStatus "M_B_DQ<32>" )
			)
			( signal "@baseboard_fab2_lib.baseboard_fab2(sch_1):m_b_dq(33)"
				( attribute "CDS_PHYS_NET_NAME" "M_B_DQ<33>"
					( Origin gPackager )
				)
				( attribute "PNN" "M_B_DQ<33>"
					( Origin gPackager )
				)
				( objectStatus "M_B_DQ<33>" )
			)
			( signal "@baseboard_fab2_lib.baseboard_fab2(sch_1):m_b_dq(34)"
				( attribute "CDS_PHYS_NET_NAME" "M_B_DQ<34>"
					( Origin gPackager )
				)
				( attribute "PNN" "M_B_DQ<34>"
					( Origin gPackager )
				)
				( objectStatus "M_B_DQ<34>" )
			)
			( signal "@baseboard_fab2_lib.baseboard_fab2(sch_1):m_b_dq(35)"
				( attribute "CDS_PHYS_NET_NAME" "M_B_DQ<35>"
					( Origin gPackager )
				)
				( attribute "PNN" "M_B_DQ<35>"
					( Origin gPackager )
				)
				( objectStatus "M_B_DQ<35>" )
			)
			( signal "@baseboard_fab2_lib.baseboard_fab2(sch_1):m_b_dq(36)"
				( attribute "CDS_PHYS_NET_NAME" "M_B_DQ<36>"
					( Origin gPackager )
				)
				( attribute "PNN" "M_B_DQ<36>"
					( Origin gPackager )
				)
				( objectStatus "M_B_DQ<36>" )
			)
			( signal "@baseboard_fab2_lib.baseboard_fab2(sch_1):m_b_dq(37)"
				( attribute "CDS_PHYS_NET_NAME" "M_B_DQ<37>"
					( Origin gPackager )
				)
				( attribute "PNN" "M_B_DQ<37>"
					( Origin gPackager )
				)
				( objectStatus "M_B_DQ<37>" )
			)
			( signal "@baseboard_fab2_lib.baseboard_fab2(sch_1):m_b_dq(38)"
				( attribute "CDS_PHYS_NET_NAME" "M_B_DQ<38>"
					( Origin gPackager )
				)
				( attribute "PNN" "M_B_DQ<38>"
					( Origin gPackager )
				)
				( objectStatus "M_B_DQ<38>" )
			)
			( signal "@baseboard_fab2_lib.baseboard_fab2(sch_1):m_b_dq(39)"
				( attribute "CDS_PHYS_NET_NAME" "M_B_DQ<39>"
					( Origin gPackager )
				)
				( attribute "PNN" "M_B_DQ<39>"
					( Origin gPackager )
				)
				( objectStatus "M_B_DQ<39>" )
			)
			( signal "@baseboard_fab2_lib.baseboard_fab2(sch_1):m_b_dq(40)"
				( attribute "CDS_PHYS_NET_NAME" "M_B_DQ<40>"
					( Origin gPackager )
				)
				( attribute "PNN" "M_B_DQ<40>"
					( Origin gPackager )
				)
				( objectStatus "M_B_DQ<40>" )
			)
			( signal "@baseboard_fab2_lib.baseboard_fab2(sch_1):m_b_dq(41)"
				( attribute "CDS_PHYS_NET_NAME" "M_B_DQ<41>"
					( Origin gPackager )
				)
				( attribute "PNN" "M_B_DQ<41>"
					( Origin gPackager )
				)
				( objectStatus "M_B_DQ<41>" )
			)
			( signal "@baseboard_fab2_lib.baseboard_fab2(sch_1):m_b_dq(42)"
				( attribute "CDS_PHYS_NET_NAME" "M_B_DQ<42>"
					( Origin gPackager )
				)
				( attribute "PNN" "M_B_DQ<42>"
					( Origin gPackager )
				)
				( objectStatus "M_B_DQ<42>" )
			)
			( signal "@baseboard_fab2_lib.baseboard_fab2(sch_1):m_b_dq(43)"
				( attribute "CDS_PHYS_NET_NAME" "M_B_DQ<43>"
					( Origin gPackager )
				)
				( attribute "PNN" "M_B_DQ<43>"
					( Origin gPackager )
				)
				( objectStatus "M_B_DQ<43>" )
			)
			( signal "@baseboard_fab2_lib.baseboard_fab2(sch_1):m_b_dq(44)"
				( attribute "CDS_PHYS_NET_NAME" "M_B_DQ<44>"
					( Origin gPackager )
				)
				( attribute "PNN" "M_B_DQ<44>"
					( Origin gPackager )
				)
				( objectStatus "M_B_DQ<44>" )
			)
			( signal "@baseboard_fab2_lib.baseboard_fab2(sch_1):m_b_dq(45)"
				( attribute "CDS_PHYS_NET_NAME" "M_B_DQ<45>"
					( Origin gPackager )
				)
				( attribute "PNN" "M_B_DQ<45>"
					( Origin gPackager )
				)
				( objectStatus "M_B_DQ<45>" )
			)
			( signal "@baseboard_fab2_lib.baseboard_fab2(sch_1):m_b_dq(46)"
				( attribute "CDS_PHYS_NET_NAME" "M_B_DQ<46>"
					( Origin gPackager )
				)
				( attribute "PNN" "M_B_DQ<46>"
					( Origin gPackager )
				)
				( objectStatus "M_B_DQ<46>" )
			)
			( signal "@baseboard_fab2_lib.baseboard_fab2(sch_1):m_b_dq(47)"
				( attribute "CDS_PHYS_NET_NAME" "M_B_DQ<47>"
					( Origin gPackager )
				)
				( attribute "PNN" "M_B_DQ<47>"
					( Origin gPackager )
				)
				( objectStatus "M_B_DQ<47>" )
			)
			( signal "@baseboard_fab2_lib.baseboard_fab2(sch_1):m_b_dq(48)"
				( attribute "CDS_PHYS_NET_NAME" "M_B_DQ<48>"
					( Origin gPackager )
				)
				( attribute "PNN" "M_B_DQ<48>"
					( Origin gPackager )
				)
				( objectStatus "M_B_DQ<48>" )
			)
			( signal "@baseboard_fab2_lib.baseboard_fab2(sch_1):m_b_dq(49)"
				( attribute "CDS_PHYS_NET_NAME" "M_B_DQ<49>"
					( Origin gPackager )
				)
				( attribute "PNN" "M_B_DQ<49>"
					( Origin gPackager )
				)
				( objectStatus "M_B_DQ<49>" )
			)
			( signal "@baseboard_fab2_lib.baseboard_fab2(sch_1):m_b_dq(50)"
				( attribute "CDS_PHYS_NET_NAME" "M_B_DQ<50>"
					( Origin gPackager )
				)
				( attribute "PNN" "M_B_DQ<50>"
					( Origin gPackager )
				)
				( objectStatus "M_B_DQ<50>" )
			)
			( signal "@baseboard_fab2_lib.baseboard_fab2(sch_1):m_b_dq(51)"
				( attribute "CDS_PHYS_NET_NAME" "M_B_DQ<51>"
					( Origin gPackager )
				)
				( attribute "PNN" "M_B_DQ<51>"
					( Origin gPackager )
				)
				( objectStatus "M_B_DQ<51>" )
			)
			( signal "@baseboard_fab2_lib.baseboard_fab2(sch_1):m_b_dq(52)"
				( attribute "CDS_PHYS_NET_NAME" "M_B_DQ<52>"
					( Origin gPackager )
				)
				( attribute "PNN" "M_B_DQ<52>"
					( Origin gPackager )
				)
				( objectStatus "M_B_DQ<52>" )
			)
			( signal "@baseboard_fab2_lib.baseboard_fab2(sch_1):m_b_dq(53)"
				( attribute "CDS_PHYS_NET_NAME" "M_B_DQ<53>"
					( Origin gPackager )
				)
				( attribute "PNN" "M_B_DQ<53>"
					( Origin gPackager )
				)
				( objectStatus "M_B_DQ<53>" )
			)
			( signal "@baseboard_fab2_lib.baseboard_fab2(sch_1):m_b_dq(54)"
				( attribute "CDS_PHYS_NET_NAME" "M_B_DQ<54>"
					( Origin gPackager )
				)
				( attribute "PNN" "M_B_DQ<54>"
					( Origin gPackager )
				)
				( objectStatus "M_B_DQ<54>" )
			)
			( signal "@baseboard_fab2_lib.baseboard_fab2(sch_1):m_b_dq(55)"
				( attribute "CDS_PHYS_NET_NAME" "M_B_DQ<55>"
					( Origin gPackager )
				)
				( attribute "PNN" "M_B_DQ<55>"
					( Origin gPackager )
				)
				( objectStatus "M_B_DQ<55>" )
			)
			( signal "@baseboard_fab2_lib.baseboard_fab2(sch_1):m_b_dq(56)"
				( attribute "CDS_PHYS_NET_NAME" "M_B_DQ<56>"
					( Origin gPackager )
				)
				( attribute "PNN" "M_B_DQ<56>"
					( Origin gPackager )
				)
				( objectStatus "M_B_DQ<56>" )
			)
			( signal "@baseboard_fab2_lib.baseboard_fab2(sch_1):m_b_dq(57)"
				( attribute "CDS_PHYS_NET_NAME" "M_B_DQ<57>"
					( Origin gPackager )
				)
				( attribute "PNN" "M_B_DQ<57>"
					( Origin gPackager )
				)
				( objectStatus "M_B_DQ<57>" )
			)
			( signal "@baseboard_fab2_lib.baseboard_fab2(sch_1):m_b_dq(58)"
				( attribute "CDS_PHYS_NET_NAME" "M_B_DQ<58>"
					( Origin gPackager )
				)
				( attribute "PNN" "M_B_DQ<58>"
					( Origin gPackager )
				)
				( objectStatus "M_B_DQ<58>" )
			)
			( signal "@baseboard_fab2_lib.baseboard_fab2(sch_1):m_b_dq(59)"
				( attribute "CDS_PHYS_NET_NAME" "M_B_DQ<59>"
					( Origin gPackager )
				)
				( attribute "PNN" "M_B_DQ<59>"
					( Origin gPackager )
				)
				( objectStatus "M_B_DQ<59>" )
			)
			( signal "@baseboard_fab2_lib.baseboard_fab2(sch_1):m_b_dq(60)"
				( attribute "CDS_PHYS_NET_NAME" "M_B_DQ<60>"
					( Origin gPackager )
				)
				( attribute "PNN" "M_B_DQ<60>"
					( Origin gPackager )
				)
				( objectStatus "M_B_DQ<60>" )
			)
			( signal "@baseboard_fab2_lib.baseboard_fab2(sch_1):m_b_dq(61)"
				( attribute "CDS_PHYS_NET_NAME" "M_B_DQ<61>"
					( Origin gPackager )
				)
				( attribute "PNN" "M_B_DQ<61>"
					( Origin gPackager )
				)
				( objectStatus "M_B_DQ<61>" )
			)
			( signal "@baseboard_fab2_lib.baseboard_fab2(sch_1):m_b_dq(62)"
				( attribute "CDS_PHYS_NET_NAME" "M_B_DQ<62>"
					( Origin gPackager )
				)
				( attribute "PNN" "M_B_DQ<62>"
					( Origin gPackager )
				)
				( objectStatus "M_B_DQ<62>" )
			)
			( signal "@baseboard_fab2_lib.baseboard_fab2(sch_1):m_b_dq(63)"
				( attribute "CDS_PHYS_NET_NAME" "M_B_DQ<63>"
					( Origin gPackager )
				)
				( attribute "PNN" "M_B_DQ<63>"
					( Origin gPackager )
				)
				( objectStatus "M_B_DQ<63>" )
			)
			( signal "@baseboard_fab2_lib.baseboard_fab2(sch_1):m_b_dqs_dn(0)"
				( attribute "CDS_PHYS_NET_NAME" "M_B_DQS_DN<0>"
					( Origin gPackager )
				)
				( attribute "PNN" "M_B_DQS_DN<0>"
					( Origin gPackager )
				)
				( objectStatus "M_B_DQS_DN<0>" )
			)
			( signal "@baseboard_fab2_lib.baseboard_fab2(sch_1):m_b_dqs_dn(1)"
				( attribute "CDS_PHYS_NET_NAME" "M_B_DQS_DN<1>"
					( Origin gPackager )
				)
				( attribute "PNN" "M_B_DQS_DN<1>"
					( Origin gPackager )
				)
				( objectStatus "M_B_DQS_DN<1>" )
			)
			( signal "@baseboard_fab2_lib.baseboard_fab2(sch_1):m_b_dqs_dn(2)"
				( attribute "CDS_PHYS_NET_NAME" "M_B_DQS_DN<2>"
					( Origin gPackager )
				)
				( attribute "PNN" "M_B_DQS_DN<2>"
					( Origin gPackager )
				)
				( objectStatus "M_B_DQS_DN<2>" )
			)
			( signal "@baseboard_fab2_lib.baseboard_fab2(sch_1):m_b_dqs_dn(3)"
				( attribute "CDS_PHYS_NET_NAME" "M_B_DQS_DN<3>"
					( Origin gPackager )
				)
				( attribute "PNN" "M_B_DQS_DN<3>"
					( Origin gPackager )
				)
				( objectStatus "M_B_DQS_DN<3>" )
			)
			( signal "@baseboard_fab2_lib.baseboard_fab2(sch_1):m_b_dqs_dn(4)"
				( attribute "CDS_PHYS_NET_NAME" "M_B_DQS_DN<4>"
					( Origin gPackager )
				)
				( attribute "PNN" "M_B_DQS_DN<4>"
					( Origin gPackager )
				)
				( objectStatus "M_B_DQS_DN<4>" )
			)
			( signal "@baseboard_fab2_lib.baseboard_fab2(sch_1):m_b_dqs_dn(5)"
				( attribute "CDS_PHYS_NET_NAME" "M_B_DQS_DN<5>"
					( Origin gPackager )
				)
				( attribute "PNN" "M_B_DQS_DN<5>"
					( Origin gPackager )
				)
				( objectStatus "M_B_DQS_DN<5>" )
			)
			( signal "@baseboard_fab2_lib.baseboard_fab2(sch_1):m_b_dqs_dn(6)"
				( attribute "CDS_PHYS_NET_NAME" "M_B_DQS_DN<6>"
					( Origin gPackager )
				)
				( attribute "PNN" "M_B_DQS_DN<6>"
					( Origin gPackager )
				)
				( objectStatus "M_B_DQS_DN<6>" )
			)
			( signal "@baseboard_fab2_lib.baseboard_fab2(sch_1):m_b_dqs_dn(7)"
				( attribute "CDS_PHYS_NET_NAME" "M_B_DQS_DN<7>"
					( Origin gPackager )
				)
				( attribute "PNN" "M_B_DQS_DN<7>"
					( Origin gPackager )
				)
				( objectStatus "M_B_DQS_DN<7>" )
			)
			( signal "@baseboard_fab2_lib.baseboard_fab2(sch_1):m_b_dqs_dn(8)"
				( attribute "CDS_PHYS_NET_NAME" "M_B_DQS_DN<8>"
					( Origin gPackager )
				)
				( attribute "PNN" "M_B_DQS_DN<8>"
					( Origin gPackager )
				)
				( objectStatus "M_B_DQS_DN<8>" )
			)
			( signal "@baseboard_fab2_lib.baseboard_fab2(sch_1):m_b_dqs_dn(9)"
				( attribute "CDS_PHYS_NET_NAME" "M_B_DQS_DN<9>"
					( Origin gPackager )
				)
				( attribute "PNN" "M_B_DQS_DN<9>"
					( Origin gPackager )
				)
				( objectStatus "M_B_DQS_DN<9>" )
			)
			( signal "@baseboard_fab2_lib.baseboard_fab2(sch_1):m_b_dqs_dn(10)"
				( attribute "CDS_PHYS_NET_NAME" "M_B_DQS_DN<10>"
					( Origin gPackager )
				)
				( attribute "PNN" "M_B_DQS_DN<10>"
					( Origin gPackager )
				)
				( objectStatus "M_B_DQS_DN<10>" )
			)
			( signal "@baseboard_fab2_lib.baseboard_fab2(sch_1):m_b_dqs_dn(11)"
				( attribute "CDS_PHYS_NET_NAME" "M_B_DQS_DN<11>"
					( Origin gPackager )
				)
				( attribute "PNN" "M_B_DQS_DN<11>"
					( Origin gPackager )
				)
				( objectStatus "M_B_DQS_DN<11>" )
			)
			( signal "@baseboard_fab2_lib.baseboard_fab2(sch_1):m_b_dqs_dn(12)"
				( attribute "CDS_PHYS_NET_NAME" "M_B_DQS_DN<12>"
					( Origin gPackager )
				)
				( attribute "PNN" "M_B_DQS_DN<12>"
					( Origin gPackager )
				)
				( objectStatus "M_B_DQS_DN<12>" )
			)
			( signal "@baseboard_fab2_lib.baseboard_fab2(sch_1):m_b_dqs_dn(13)"
				( attribute "CDS_PHYS_NET_NAME" "M_B_DQS_DN<13>"
					( Origin gPackager )
				)
				( attribute "PNN" "M_B_DQS_DN<13>"
					( Origin gPackager )
				)
				( objectStatus "M_B_DQS_DN<13>" )
			)
			( signal "@baseboard_fab2_lib.baseboard_fab2(sch_1):m_b_dqs_dn(14)"
				( attribute "CDS_PHYS_NET_NAME" "M_B_DQS_DN<14>"
					( Origin gPackager )
				)
				( attribute "PNN" "M_B_DQS_DN<14>"
					( Origin gPackager )
				)
				( objectStatus "M_B_DQS_DN<14>" )
			)
			( signal "@baseboard_fab2_lib.baseboard_fab2(sch_1):m_b_dqs_dn(15)"
				( attribute "CDS_PHYS_NET_NAME" "M_B_DQS_DN<15>"
					( Origin gPackager )
				)
				( attribute "PNN" "M_B_DQS_DN<15>"
					( Origin gPackager )
				)
				( objectStatus "M_B_DQS_DN<15>" )
			)
			( signal "@baseboard_fab2_lib.baseboard_fab2(sch_1):m_b_dqs_dn(16)"
				( attribute "CDS_PHYS_NET_NAME" "M_B_DQS_DN<16>"
					( Origin gPackager )
				)
				( attribute "PNN" "M_B_DQS_DN<16>"
					( Origin gPackager )
				)
				( objectStatus "M_B_DQS_DN<16>" )
			)
			( signal "@baseboard_fab2_lib.baseboard_fab2(sch_1):m_b_dqs_dn(17)"
				( attribute "CDS_PHYS_NET_NAME" "M_B_DQS_DN<17>"
					( Origin gPackager )
				)
				( attribute "PNN" "M_B_DQS_DN<17>"
					( Origin gPackager )
				)
				( objectStatus "M_B_DQS_DN<17>" )
			)
			( signal "@baseboard_fab2_lib.baseboard_fab2(sch_1):m_b_dqs_dp(0)"
				( attribute "CDS_PHYS_NET_NAME" "M_B_DQS_DP<0>"
					( Origin gPackager )
				)
				( attribute "PNN" "M_B_DQS_DP<0>"
					( Origin gPackager )
				)
				( objectStatus "M_B_DQS_DP<0>" )
			)
			( signal "@baseboard_fab2_lib.baseboard_fab2(sch_1):m_b_dqs_dp(1)"
				( attribute "CDS_PHYS_NET_NAME" "M_B_DQS_DP<1>"
					( Origin gPackager )
				)
				( attribute "PNN" "M_B_DQS_DP<1>"
					( Origin gPackager )
				)
				( objectStatus "M_B_DQS_DP<1>" )
			)
			( signal "@baseboard_fab2_lib.baseboard_fab2(sch_1):m_b_dqs_dp(2)"
				( attribute "CDS_PHYS_NET_NAME" "M_B_DQS_DP<2>"
					( Origin gPackager )
				)
				( attribute "PNN" "M_B_DQS_DP<2>"
					( Origin gPackager )
				)
				( objectStatus "M_B_DQS_DP<2>" )
			)
			( signal "@baseboard_fab2_lib.baseboard_fab2(sch_1):m_b_dqs_dp(3)"
				( attribute "CDS_PHYS_NET_NAME" "M_B_DQS_DP<3>"
					( Origin gPackager )
				)
				( attribute "PNN" "M_B_DQS_DP<3>"
					( Origin gPackager )
				)
				( objectStatus "M_B_DQS_DP<3>" )
			)
			( signal "@baseboard_fab2_lib.baseboard_fab2(sch_1):m_b_dqs_dp(4)"
				( attribute "CDS_PHYS_NET_NAME" "M_B_DQS_DP<4>"
					( Origin gPackager )
				)
				( attribute "PNN" "M_B_DQS_DP<4>"
					( Origin gPackager )
				)
				( objectStatus "M_B_DQS_DP<4>" )
			)
			( signal "@baseboard_fab2_lib.baseboard_fab2(sch_1):m_b_dqs_dp(5)"
				( attribute "CDS_PHYS_NET_NAME" "M_B_DQS_DP<5>"
					( Origin gPackager )
				)
				( attribute "PNN" "M_B_DQS_DP<5>"
					( Origin gPackager )
				)
				( objectStatus "M_B_DQS_DP<5>" )
			)
			( signal "@baseboard_fab2_lib.baseboard_fab2(sch_1):m_b_dqs_dp(6)"
				( attribute "CDS_PHYS_NET_NAME" "M_B_DQS_DP<6>"
					( Origin gPackager )
				)
				( attribute "PNN" "M_B_DQS_DP<6>"
					( Origin gPackager )
				)
				( objectStatus "M_B_DQS_DP<6>" )
			)
			( signal "@baseboard_fab2_lib.baseboard_fab2(sch_1):m_b_dqs_dp(7)"
				( attribute "CDS_PHYS_NET_NAME" "M_B_DQS_DP<7>"
					( Origin gPackager )
				)
				( attribute "PNN" "M_B_DQS_DP<7>"
					( Origin gPackager )
				)
				( objectStatus "M_B_DQS_DP<7>" )
			)
			( signal "@baseboard_fab2_lib.baseboard_fab2(sch_1):m_b_dqs_dp(8)"
				( attribute "CDS_PHYS_NET_NAME" "M_B_DQS_DP<8>"
					( Origin gPackager )
				)
				( attribute "PNN" "M_B_DQS_DP<8>"
					( Origin gPackager )
				)
				( objectStatus "M_B_DQS_DP<8>" )
			)
			( signal "@baseboard_fab2_lib.baseboard_fab2(sch_1):m_b_dqs_dp(9)"
				( attribute "CDS_PHYS_NET_NAME" "M_B_DQS_DP<9>"
					( Origin gPackager )
				)
				( attribute "PNN" "M_B_DQS_DP<9>"
					( Origin gPackager )
				)
				( objectStatus "M_B_DQS_DP<9>" )
			)
			( signal "@baseboard_fab2_lib.baseboard_fab2(sch_1):m_b_dqs_dp(10)"
				( attribute "CDS_PHYS_NET_NAME" "M_B_DQS_DP<10>"
					( Origin gPackager )
				)
				( attribute "PNN" "M_B_DQS_DP<10>"
					( Origin gPackager )
				)
				( objectStatus "M_B_DQS_DP<10>" )
			)
			( signal "@baseboard_fab2_lib.baseboard_fab2(sch_1):m_b_dqs_dp(11)"
				( attribute "CDS_PHYS_NET_NAME" "M_B_DQS_DP<11>"
					( Origin gPackager )
				)
				( attribute "PNN" "M_B_DQS_DP<11>"
					( Origin gPackager )
				)
				( objectStatus "M_B_DQS_DP<11>" )
			)
			( signal "@baseboard_fab2_lib.baseboard_fab2(sch_1):m_b_dqs_dp(12)"
				( attribute "CDS_PHYS_NET_NAME" "M_B_DQS_DP<12>"
					( Origin gPackager )
				)
				( attribute "PNN" "M_B_DQS_DP<12>"
					( Origin gPackager )
				)
				( objectStatus "M_B_DQS_DP<12>" )
			)
			( signal "@baseboard_fab2_lib.baseboard_fab2(sch_1):m_b_dqs_dp(13)"
				( attribute "CDS_PHYS_NET_NAME" "M_B_DQS_DP<13>"
					( Origin gPackager )
				)
				( attribute "PNN" "M_B_DQS_DP<13>"
					( Origin gPackager )
				)
				( objectStatus "M_B_DQS_DP<13>" )
			)
			( signal "@baseboard_fab2_lib.baseboard_fab2(sch_1):m_b_dqs_dp(14)"
				( attribute "CDS_PHYS_NET_NAME" "M_B_DQS_DP<14>"
					( Origin gPackager )
				)
				( attribute "PNN" "M_B_DQS_DP<14>"
					( Origin gPackager )
				)
				( objectStatus "M_B_DQS_DP<14>" )
			)
			( signal "@baseboard_fab2_lib.baseboard_fab2(sch_1):m_b_dqs_dp(15)"
				( attribute "CDS_PHYS_NET_NAME" "M_B_DQS_DP<15>"
					( Origin gPackager )
				)
				( attribute "PNN" "M_B_DQS_DP<15>"
					( Origin gPackager )
				)
				( objectStatus "M_B_DQS_DP<15>" )
			)
			( signal "@baseboard_fab2_lib.baseboard_fab2(sch_1):m_b_dqs_dp(16)"
				( attribute "CDS_PHYS_NET_NAME" "M_B_DQS_DP<16>"
					( Origin gPackager )
				)
				( attribute "PNN" "M_B_DQS_DP<16>"
					( Origin gPackager )
				)
				( objectStatus "M_B_DQS_DP<16>" )
			)
			( signal "@baseboard_fab2_lib.baseboard_fab2(sch_1):m_b_dqs_dp(17)"
				( attribute "CDS_PHYS_NET_NAME" "M_B_DQS_DP<17>"
					( Origin gPackager )
				)
				( attribute "PNN" "M_B_DQS_DP<17>"
					( Origin gPackager )
				)
				( objectStatus "M_B_DQS_DP<17>" )
			)
			( signal "@baseboard_fab2_lib.baseboard_fab2(sch_1):m_b_ecc(0)"
				( attribute "CDS_PHYS_NET_NAME" "M_B_ECC<0>"
					( Origin gPackager )
				)
				( attribute "PNN" "M_B_ECC<0>"
					( Origin gPackager )
				)
				( objectStatus "M_B_ECC<0>" )
			)
			( signal "@baseboard_fab2_lib.baseboard_fab2(sch_1):m_b_ecc(1)"
				( attribute "CDS_PHYS_NET_NAME" "M_B_ECC<1>"
					( Origin gPackager )
				)
				( attribute "PNN" "M_B_ECC<1>"
					( Origin gPackager )
				)
				( objectStatus "M_B_ECC<1>" )
			)
			( signal "@baseboard_fab2_lib.baseboard_fab2(sch_1):m_b_ecc(2)"
				( attribute "CDS_PHYS_NET_NAME" "M_B_ECC<2>"
					( Origin gPackager )
				)
				( attribute "PNN" "M_B_ECC<2>"
					( Origin gPackager )
				)
				( objectStatus "M_B_ECC<2>" )
			)
			( signal "@baseboard_fab2_lib.baseboard_fab2(sch_1):m_b_ecc(3)"
				( attribute "CDS_PHYS_NET_NAME" "M_B_ECC<3>"
					( Origin gPackager )
				)
				( attribute "PNN" "M_B_ECC<3>"
					( Origin gPackager )
				)
				( objectStatus "M_B_ECC<3>" )
			)
			( signal "@baseboard_fab2_lib.baseboard_fab2(sch_1):m_b_ecc(4)"
				( attribute "CDS_PHYS_NET_NAME" "M_B_ECC<4>"
					( Origin gPackager )
				)
				( attribute "PNN" "M_B_ECC<4>"
					( Origin gPackager )
				)
				( objectStatus "M_B_ECC<4>" )
			)
			( signal "@baseboard_fab2_lib.baseboard_fab2(sch_1):m_b_ecc(5)"
				( attribute "CDS_PHYS_NET_NAME" "M_B_ECC<5>"
					( Origin gPackager )
				)
				( attribute "PNN" "M_B_ECC<5>"
					( Origin gPackager )
				)
				( objectStatus "M_B_ECC<5>" )
			)
			( signal "@baseboard_fab2_lib.baseboard_fab2(sch_1):m_b_ecc(6)"
				( attribute "CDS_PHYS_NET_NAME" "M_B_ECC<6>"
					( Origin gPackager )
				)
				( attribute "PNN" "M_B_ECC<6>"
					( Origin gPackager )
				)
				( objectStatus "M_B_ECC<6>" )
			)
			( signal "@baseboard_fab2_lib.baseboard_fab2(sch_1):m_b_ecc(7)"
				( attribute "CDS_PHYS_NET_NAME" "M_B_ECC<7>"
					( Origin gPackager )
				)
				( attribute "PNN" "M_B_ECC<7>"
					( Origin gPackager )
				)
				( objectStatus "M_B_ECC<7>" )
			)
			( signal "@baseboard_fab2_lib.baseboard_fab2(sch_1):m_b_ma(0)"
				( attribute "CDS_PHYS_NET_NAME" "M_B_MA<0>"
					( Origin gPackager )
				)
				( attribute "PNN" "M_B_MA<0>"
					( Origin gPackager )
				)
				( objectStatus "M_B_MA<0>" )
			)
			( signal "@baseboard_fab2_lib.baseboard_fab2(sch_1):m_b_ma(1)"
				( attribute "CDS_PHYS_NET_NAME" "M_B_MA<1>"
					( Origin gPackager )
				)
				( attribute "PNN" "M_B_MA<1>"
					( Origin gPackager )
				)
				( objectStatus "M_B_MA<1>" )
			)
			( signal "@baseboard_fab2_lib.baseboard_fab2(sch_1):m_b_ma(2)"
				( attribute "CDS_PHYS_NET_NAME" "M_B_MA<2>"
					( Origin gPackager )
				)
				( attribute "PNN" "M_B_MA<2>"
					( Origin gPackager )
				)
				( objectStatus "M_B_MA<2>" )
			)
			( signal "@baseboard_fab2_lib.baseboard_fab2(sch_1):m_b_ma(3)"
				( attribute "CDS_PHYS_NET_NAME" "M_B_MA<3>"
					( Origin gPackager )
				)
				( attribute "PNN" "M_B_MA<3>"
					( Origin gPackager )
				)
				( objectStatus "M_B_MA<3>" )
			)
			( signal "@baseboard_fab2_lib.baseboard_fab2(sch_1):m_b_ma(4)"
				( attribute "CDS_PHYS_NET_NAME" "M_B_MA<4>"
					( Origin gPackager )
				)
				( attribute "PNN" "M_B_MA<4>"
					( Origin gPackager )
				)
				( objectStatus "M_B_MA<4>" )
			)
			( signal "@baseboard_fab2_lib.baseboard_fab2(sch_1):m_b_ma(5)"
				( attribute "CDS_PHYS_NET_NAME" "M_B_MA<5>"
					( Origin gPackager )
				)
				( attribute "PNN" "M_B_MA<5>"
					( Origin gPackager )
				)
				( objectStatus "M_B_MA<5>" )
			)
			( signal "@baseboard_fab2_lib.baseboard_fab2(sch_1):m_b_ma(6)"
				( attribute "CDS_PHYS_NET_NAME" "M_B_MA<6>"
					( Origin gPackager )
				)
				( attribute "PNN" "M_B_MA<6>"
					( Origin gPackager )
				)
				( objectStatus "M_B_MA<6>" )
			)
			( signal "@baseboard_fab2_lib.baseboard_fab2(sch_1):m_b_ma(7)"
				( attribute "CDS_PHYS_NET_NAME" "M_B_MA<7>"
					( Origin gPackager )
				)
				( attribute "PNN" "M_B_MA<7>"
					( Origin gPackager )
				)
				( objectStatus "M_B_MA<7>" )
			)
			( signal "@baseboard_fab2_lib.baseboard_fab2(sch_1):m_b_ma(8)"
				( attribute "CDS_PHYS_NET_NAME" "M_B_MA<8>"
					( Origin gPackager )
				)
				( attribute "PNN" "M_B_MA<8>"
					( Origin gPackager )
				)
				( objectStatus "M_B_MA<8>" )
			)
			( signal "@baseboard_fab2_lib.baseboard_fab2(sch_1):m_b_ma(9)"
				( attribute "CDS_PHYS_NET_NAME" "M_B_MA<9>"
					( Origin gPackager )
				)
				( attribute "PNN" "M_B_MA<9>"
					( Origin gPackager )
				)
				( objectStatus "M_B_MA<9>" )
			)
			( signal "@baseboard_fab2_lib.baseboard_fab2(sch_1):m_b_ma(10)"
				( attribute "CDS_PHYS_NET_NAME" "M_B_MA<10>"
					( Origin gPackager )
				)
				( attribute "PNN" "M_B_MA<10>"
					( Origin gPackager )
				)
				( objectStatus "M_B_MA<10>" )
			)
			( signal "@baseboard_fab2_lib.baseboard_fab2(sch_1):m_b_ma(11)"
				( attribute "CDS_PHYS_NET_NAME" "M_B_MA<11>"
					( Origin gPackager )
				)
				( attribute "PNN" "M_B_MA<11>"
					( Origin gPackager )
				)
				( objectStatus "M_B_MA<11>" )
			)
			( signal "@baseboard_fab2_lib.baseboard_fab2(sch_1):m_b_ma(12)"
				( attribute "CDS_PHYS_NET_NAME" "M_B_MA<12>"
					( Origin gPackager )
				)
				( attribute "PNN" "M_B_MA<12>"
					( Origin gPackager )
				)
				( objectStatus "M_B_MA<12>" )
			)
			( signal "@baseboard_fab2_lib.baseboard_fab2(sch_1):m_b_ma(13)"
				( attribute "CDS_PHYS_NET_NAME" "M_B_MA<13>"
					( Origin gPackager )
				)
				( attribute "PNN" "M_B_MA<13>"
					( Origin gPackager )
				)
				( objectStatus "M_B_MA<13>" )
			)
			( signal "@baseboard_fab2_lib.baseboard_fab2(sch_1):m_b_ma(14)"
				( attribute "CDS_PHYS_NET_NAME" "M_B_MA<14>"
					( Origin gPackager )
				)
				( attribute "PNN" "M_B_MA<14>"
					( Origin gPackager )
				)
				( objectStatus "M_B_MA<14>" )
			)
			( signal "@baseboard_fab2_lib.baseboard_fab2(sch_1):m_b_ma(15)"
				( attribute "CDS_PHYS_NET_NAME" "M_B_MA<15>"
					( Origin gPackager )
				)
				( attribute "PNN" "M_B_MA<15>"
					( Origin gPackager )
				)
				( objectStatus "M_B_MA<15>" )
			)
			( signal "@baseboard_fab2_lib.baseboard_fab2(sch_1):m_b_ma(16)"
				( attribute "CDS_PHYS_NET_NAME" "M_B_MA<16>"
					( Origin gPackager )
				)
				( attribute "PNN" "M_B_MA<16>"
					( Origin gPackager )
				)
				( objectStatus "M_B_MA<16>" )
			)
			( signal "@baseboard_fab2_lib.baseboard_fab2(sch_1):m_b_ma(17)"
				( attribute "CDS_PHYS_NET_NAME" "M_B_MA<17>"
					( Origin gPackager )
				)
				( attribute "PNN" "M_B_MA<17>"
					( Origin gPackager )
				)
				( objectStatus "M_B_MA<17>" )
			)
			( signal "@baseboard_fab2_lib.baseboard_fab2(sch_1):m_b_odt(0)"
				( attribute "CDS_PHYS_NET_NAME" "M_B_ODT<0>"
					( Origin gPackager )
				)
				( attribute "PNN" "M_B_ODT<0>"
					( Origin gPackager )
				)
				( objectStatus "M_B_ODT<0>" )
			)
			( signal "@baseboard_fab2_lib.baseboard_fab2(sch_1):m_b_odt(1)"
				( attribute "CDS_PHYS_NET_NAME" "M_B_ODT<1>"
					( Origin gPackager )
				)
				( attribute "PNN" "M_B_ODT<1>"
					( Origin gPackager )
				)
				( objectStatus "M_B_ODT<1>" )
			)
			( signal "@baseboard_fab2_lib.baseboard_fab2(sch_1):m_b_odt(2)"
				( attribute "CDS_PHYS_NET_NAME" "M_B_ODT<2>"
					( Origin gPackager )
				)
				( attribute "PNN" "M_B_ODT<2>"
					( Origin gPackager )
				)
				( objectStatus "M_B_ODT<2>" )
			)
			( signal "@baseboard_fab2_lib.baseboard_fab2(sch_1):m_b_odt(3)"
				( attribute "CDS_PHYS_NET_NAME" "M_B_ODT<3>"
					( Origin gPackager )
				)
				( attribute "PNN" "M_B_ODT<3>"
					( Origin gPackager )
				)
				( objectStatus "M_B_ODT<3>" )
			)
			( signal "@baseboard_fab2_lib.baseboard_fab2(sch_1):m_b_par"
				( attribute "CDS_PHYS_NET_NAME" "M_B_PAR"
					( Origin gPackager )
				)
				( objectStatus "M_B_PAR" )
			)
			( signal "@baseboard_fab2_lib.baseboard_fab2(sch_1):m_c_act_n"
				( attribute "CDS_PHYS_NET_NAME" "M_C_ACT_N"
					( Origin gPackager )
				)
				( objectStatus "M_C_ACT_N" )
			)
			( signal "@baseboard_fab2_lib.baseboard_fab2(sch_1):m_c_alert_n"
				( attribute "CDS_PHYS_NET_NAME" "M_C_ALERT_N"
					( Origin gPackager )
				)
				( objectStatus "M_C_ALERT_N" )
			)
			( signal "@baseboard_fab2_lib.baseboard_fab2(sch_1):m_c_ba(0)"
				( attribute "CDS_PHYS_NET_NAME" "M_C_BA<0>"
					( Origin gPackager )
				)
				( attribute "PNN" "M_C_BA<0>"
					( Origin gPackager )
				)
				( objectStatus "M_C_BA<0>" )
			)
			( signal "@baseboard_fab2_lib.baseboard_fab2(sch_1):m_c_ba(1)"
				( attribute "CDS_PHYS_NET_NAME" "M_C_BA<1>"
					( Origin gPackager )
				)
				( attribute "PNN" "M_C_BA<1>"
					( Origin gPackager )
				)
				( objectStatus "M_C_BA<1>" )
			)
			( signal "@baseboard_fab2_lib.baseboard_fab2(sch_1):m_c_bg(0)"
				( attribute "CDS_PHYS_NET_NAME" "M_C_BG<0>"
					( Origin gPackager )
				)
				( attribute "PNN" "M_C_BG<0>"
					( Origin gPackager )
				)
				( objectStatus "M_C_BG<0>" )
			)
			( signal "@baseboard_fab2_lib.baseboard_fab2(sch_1):m_c_bg(1)"
				( attribute "CDS_PHYS_NET_NAME" "M_C_BG<1>"
					( Origin gPackager )
				)
				( attribute "PNN" "M_C_BG<1>"
					( Origin gPackager )
				)
				( objectStatus "M_C_BG<1>" )
			)
			( signal "@baseboard_fab2_lib.baseboard_fab2(sch_1):m_c_c(2)"
				( attribute "CDS_PHYS_NET_NAME" "M_C_C<2>"
					( Origin gPackager )
				)
				( attribute "PNN" "M_C_C<2>"
					( Origin gPackager )
				)
				( objectStatus "M_C_C<2>" )
			)
			( signal "@baseboard_fab2_lib.baseboard_fab2(sch_1):m_c_cke(0)"
				( attribute "CDS_PHYS_NET_NAME" "M_C_CKE<0>"
					( Origin gPackager )
				)
				( attribute "PNN" "M_C_CKE<0>"
					( Origin gPackager )
				)
				( objectStatus "M_C_CKE<0>" )
			)
			( signal "@baseboard_fab2_lib.baseboard_fab2(sch_1):m_c_cke(1)"
				( attribute "CDS_PHYS_NET_NAME" "M_C_CKE<1>"
					( Origin gPackager )
				)
				( attribute "PNN" "M_C_CKE<1>"
					( Origin gPackager )
				)
				( objectStatus "M_C_CKE<1>" )
			)
			( signal "@baseboard_fab2_lib.baseboard_fab2(sch_1):m_c_cke(2)"
				( attribute "CDS_PHYS_NET_NAME" "M_C_CKE<2>"
					( Origin gPackager )
				)
				( attribute "PNN" "M_C_CKE<2>"
					( Origin gPackager )
				)
				( objectStatus "M_C_CKE<2>" )
			)
			( signal "@baseboard_fab2_lib.baseboard_fab2(sch_1):m_c_cke(3)"
				( attribute "CDS_PHYS_NET_NAME" "M_C_CKE<3>"
					( Origin gPackager )
				)
				( attribute "PNN" "M_C_CKE<3>"
					( Origin gPackager )
				)
				( objectStatus "M_C_CKE<3>" )
			)
			( signal "@baseboard_fab2_lib.baseboard_fab2(sch_1):m_c_clk_dn(0)"
				( attribute "CDS_PHYS_NET_NAME" "M_C_CLK_DN<0>"
					( Origin gPackager )
				)
				( attribute "PNN" "M_C_CLK_DN<0>"
					( Origin gPackager )
				)
				( objectStatus "M_C_CLK_DN<0>" )
			)
			( signal "@baseboard_fab2_lib.baseboard_fab2(sch_1):m_c_clk_dn(1)"
				( attribute "CDS_PHYS_NET_NAME" "M_C_CLK_DN<1>"
					( Origin gPackager )
				)
				( attribute "PNN" "M_C_CLK_DN<1>"
					( Origin gPackager )
				)
				( objectStatus "M_C_CLK_DN<1>" )
			)
			( signal "@baseboard_fab2_lib.baseboard_fab2(sch_1):m_c_clk_dn(2)"
				( attribute "CDS_PHYS_NET_NAME" "M_C_CLK_DN<2>"
					( Origin gPackager )
				)
				( attribute "PNN" "M_C_CLK_DN<2>"
					( Origin gPackager )
				)
				( objectStatus "M_C_CLK_DN<2>" )
			)
			( signal "@baseboard_fab2_lib.baseboard_fab2(sch_1):m_c_clk_dn(3)"
				( attribute "CDS_PHYS_NET_NAME" "M_C_CLK_DN<3>"
					( Origin gPackager )
				)
				( attribute "PNN" "M_C_CLK_DN<3>"
					( Origin gPackager )
				)
				( objectStatus "M_C_CLK_DN<3>" )
			)
			( signal "@baseboard_fab2_lib.baseboard_fab2(sch_1):m_c_clk_dp(0)"
				( attribute "CDS_PHYS_NET_NAME" "M_C_CLK_DP<0>"
					( Origin gPackager )
				)
				( attribute "PNN" "M_C_CLK_DP<0>"
					( Origin gPackager )
				)
				( objectStatus "M_C_CLK_DP<0>" )
			)
			( signal "@baseboard_fab2_lib.baseboard_fab2(sch_1):m_c_clk_dp(1)"
				( attribute "CDS_PHYS_NET_NAME" "M_C_CLK_DP<1>"
					( Origin gPackager )
				)
				( attribute "PNN" "M_C_CLK_DP<1>"
					( Origin gPackager )
				)
				( objectStatus "M_C_CLK_DP<1>" )
			)
			( signal "@baseboard_fab2_lib.baseboard_fab2(sch_1):m_c_clk_dp(2)"
				( attribute "CDS_PHYS_NET_NAME" "M_C_CLK_DP<2>"
					( Origin gPackager )
				)
				( attribute "PNN" "M_C_CLK_DP<2>"
					( Origin gPackager )
				)
				( objectStatus "M_C_CLK_DP<2>" )
			)
			( signal "@baseboard_fab2_lib.baseboard_fab2(sch_1):m_c_clk_dp(3)"
				( attribute "CDS_PHYS_NET_NAME" "M_C_CLK_DP<3>"
					( Origin gPackager )
				)
				( attribute "PNN" "M_C_CLK_DP<3>"
					( Origin gPackager )
				)
				( objectStatus "M_C_CLK_DP<3>" )
			)
			( signal "@baseboard_fab2_lib.baseboard_fab2(sch_1):m_c_cs_n(0)"
				( attribute "CDS_PHYS_NET_NAME" "M_C_CS_N<0>"
					( Origin gPackager )
				)
				( attribute "PNN" "M_C_CS_N<0>"
					( Origin gPackager )
				)
				( objectStatus "M_C_CS_N<0>" )
			)
			( signal "@baseboard_fab2_lib.baseboard_fab2(sch_1):m_c_cs_n(1)"
				( attribute "CDS_PHYS_NET_NAME" "M_C_CS_N<1>"
					( Origin gPackager )
				)
				( attribute "PNN" "M_C_CS_N<1>"
					( Origin gPackager )
				)
				( objectStatus "M_C_CS_N<1>" )
			)
			( signal "@baseboard_fab2_lib.baseboard_fab2(sch_1):m_c_cs_n(2)"
				( attribute "CDS_PHYS_NET_NAME" "M_C_CS_N<2>"
					( Origin gPackager )
				)
				( attribute "PNN" "M_C_CS_N<2>"
					( Origin gPackager )
				)
				( objectStatus "M_C_CS_N<2>" )
			)
			( signal "@baseboard_fab2_lib.baseboard_fab2(sch_1):m_c_cs_n(3)"
				( attribute "CDS_PHYS_NET_NAME" "M_C_CS_N<3>"
					( Origin gPackager )
				)
				( attribute "PNN" "M_C_CS_N<3>"
					( Origin gPackager )
				)
				( objectStatus "M_C_CS_N<3>" )
			)
			( signal "@baseboard_fab2_lib.baseboard_fab2(sch_1):m_c_cs_n(4)"
				( attribute "CDS_PHYS_NET_NAME" "M_C_CS_N<4>"
					( Origin gPackager )
				)
				( attribute "PNN" "M_C_CS_N<4>"
					( Origin gPackager )
				)
				( objectStatus "M_C_CS_N<4>" )
			)
			( signal "@baseboard_fab2_lib.baseboard_fab2(sch_1):m_c_cs_n(5)"
				( attribute "CDS_PHYS_NET_NAME" "M_C_CS_N<5>"
					( Origin gPackager )
				)
				( attribute "PNN" "M_C_CS_N<5>"
					( Origin gPackager )
				)
				( objectStatus "M_C_CS_N<5>" )
			)
			( signal "@baseboard_fab2_lib.baseboard_fab2(sch_1):m_c_cs_n(6)"
				( attribute "CDS_PHYS_NET_NAME" "M_C_CS_N<6>"
					( Origin gPackager )
				)
				( attribute "PNN" "M_C_CS_N<6>"
					( Origin gPackager )
				)
				( objectStatus "M_C_CS_N<6>" )
			)
			( signal "@baseboard_fab2_lib.baseboard_fab2(sch_1):m_c_cs_n(7)"
				( attribute "CDS_PHYS_NET_NAME" "M_C_CS_N<7>"
					( Origin gPackager )
				)
				( attribute "PNN" "M_C_CS_N<7>"
					( Origin gPackager )
				)
				( objectStatus "M_C_CS_N<7>" )
			)
			( signal "@baseboard_fab2_lib.baseboard_fab2(sch_1):m_c_dq(0)"
				( attribute "CDS_PHYS_NET_NAME" "M_C_DQ<0>"
					( Origin gPackager )
				)
				( attribute "PNN" "M_C_DQ<0>"
					( Origin gPackager )
				)
				( objectStatus "M_C_DQ<0>" )
			)
			( signal "@baseboard_fab2_lib.baseboard_fab2(sch_1):m_c_dq(1)"
				( attribute "CDS_PHYS_NET_NAME" "M_C_DQ<1>"
					( Origin gPackager )
				)
				( attribute "PNN" "M_C_DQ<1>"
					( Origin gPackager )
				)
				( objectStatus "M_C_DQ<1>" )
			)
			( signal "@baseboard_fab2_lib.baseboard_fab2(sch_1):m_c_dq(2)"
				( attribute "CDS_PHYS_NET_NAME" "M_C_DQ<2>"
					( Origin gPackager )
				)
				( attribute "PNN" "M_C_DQ<2>"
					( Origin gPackager )
				)
				( objectStatus "M_C_DQ<2>" )
			)
			( signal "@baseboard_fab2_lib.baseboard_fab2(sch_1):m_c_dq(3)"
				( attribute "CDS_PHYS_NET_NAME" "M_C_DQ<3>"
					( Origin gPackager )
				)
				( attribute "PNN" "M_C_DQ<3>"
					( Origin gPackager )
				)
				( objectStatus "M_C_DQ<3>" )
			)
			( signal "@baseboard_fab2_lib.baseboard_fab2(sch_1):m_c_dq(4)"
				( attribute "CDS_PHYS_NET_NAME" "M_C_DQ<4>"
					( Origin gPackager )
				)
				( attribute "PNN" "M_C_DQ<4>"
					( Origin gPackager )
				)
				( objectStatus "M_C_DQ<4>" )
			)
			( signal "@baseboard_fab2_lib.baseboard_fab2(sch_1):m_c_dq(5)"
				( attribute "CDS_PHYS_NET_NAME" "M_C_DQ<5>"
					( Origin gPackager )
				)
				( attribute "PNN" "M_C_DQ<5>"
					( Origin gPackager )
				)
				( objectStatus "M_C_DQ<5>" )
			)
			( signal "@baseboard_fab2_lib.baseboard_fab2(sch_1):m_c_dq(6)"
				( attribute "CDS_PHYS_NET_NAME" "M_C_DQ<6>"
					( Origin gPackager )
				)
				( attribute "PNN" "M_C_DQ<6>"
					( Origin gPackager )
				)
				( objectStatus "M_C_DQ<6>" )
			)
			( signal "@baseboard_fab2_lib.baseboard_fab2(sch_1):m_c_dq(7)"
				( attribute "CDS_PHYS_NET_NAME" "M_C_DQ<7>"
					( Origin gPackager )
				)
				( attribute "PNN" "M_C_DQ<7>"
					( Origin gPackager )
				)
				( objectStatus "M_C_DQ<7>" )
			)
			( signal "@baseboard_fab2_lib.baseboard_fab2(sch_1):m_c_dq(8)"
				( attribute "CDS_PHYS_NET_NAME" "M_C_DQ<8>"
					( Origin gPackager )
				)
				( attribute "PNN" "M_C_DQ<8>"
					( Origin gPackager )
				)
				( objectStatus "M_C_DQ<8>" )
			)
			( signal "@baseboard_fab2_lib.baseboard_fab2(sch_1):m_c_dq(9)"
				( attribute "CDS_PHYS_NET_NAME" "M_C_DQ<9>"
					( Origin gPackager )
				)
				( attribute "PNN" "M_C_DQ<9>"
					( Origin gPackager )
				)
				( objectStatus "M_C_DQ<9>" )
			)
			( signal "@baseboard_fab2_lib.baseboard_fab2(sch_1):m_c_dq(10)"
				( attribute "CDS_PHYS_NET_NAME" "M_C_DQ<10>"
					( Origin gPackager )
				)
				( attribute "PNN" "M_C_DQ<10>"
					( Origin gPackager )
				)
				( objectStatus "M_C_DQ<10>" )
			)
			( signal "@baseboard_fab2_lib.baseboard_fab2(sch_1):m_c_dq(11)"
				( attribute "CDS_PHYS_NET_NAME" "M_C_DQ<11>"
					( Origin gPackager )
				)
				( attribute "PNN" "M_C_DQ<11>"
					( Origin gPackager )
				)
				( objectStatus "M_C_DQ<11>" )
			)
			( signal "@baseboard_fab2_lib.baseboard_fab2(sch_1):m_c_dq(12)"
				( attribute "CDS_PHYS_NET_NAME" "M_C_DQ<12>"
					( Origin gPackager )
				)
				( attribute "PNN" "M_C_DQ<12>"
					( Origin gPackager )
				)
				( objectStatus "M_C_DQ<12>" )
			)
			( signal "@baseboard_fab2_lib.baseboard_fab2(sch_1):m_c_dq(13)"
				( attribute "CDS_PHYS_NET_NAME" "M_C_DQ<13>"
					( Origin gPackager )
				)
				( attribute "PNN" "M_C_DQ<13>"
					( Origin gPackager )
				)
				( objectStatus "M_C_DQ<13>" )
			)
			( signal "@baseboard_fab2_lib.baseboard_fab2(sch_1):m_c_dq(14)"
				( attribute "CDS_PHYS_NET_NAME" "M_C_DQ<14>"
					( Origin gPackager )
				)
				( attribute "PNN" "M_C_DQ<14>"
					( Origin gPackager )
				)
				( objectStatus "M_C_DQ<14>" )
			)
			( signal "@baseboard_fab2_lib.baseboard_fab2(sch_1):m_c_dq(15)"
				( attribute "CDS_PHYS_NET_NAME" "M_C_DQ<15>"
					( Origin gPackager )
				)
				( attribute "PNN" "M_C_DQ<15>"
					( Origin gPackager )
				)
				( objectStatus "M_C_DQ<15>" )
			)
			( signal "@baseboard_fab2_lib.baseboard_fab2(sch_1):m_c_dq(16)"
				( attribute "CDS_PHYS_NET_NAME" "M_C_DQ<16>"
					( Origin gPackager )
				)
				( attribute "PNN" "M_C_DQ<16>"
					( Origin gPackager )
				)
				( objectStatus "M_C_DQ<16>" )
			)
			( signal "@baseboard_fab2_lib.baseboard_fab2(sch_1):m_c_dq(17)"
				( attribute "CDS_PHYS_NET_NAME" "M_C_DQ<17>"
					( Origin gPackager )
				)
				( attribute "PNN" "M_C_DQ<17>"
					( Origin gPackager )
				)
				( objectStatus "M_C_DQ<17>" )
			)
			( signal "@baseboard_fab2_lib.baseboard_fab2(sch_1):m_c_dq(18)"
				( attribute "CDS_PHYS_NET_NAME" "M_C_DQ<18>"
					( Origin gPackager )
				)
				( attribute "PNN" "M_C_DQ<18>"
					( Origin gPackager )
				)
				( objectStatus "M_C_DQ<18>" )
			)
			( signal "@baseboard_fab2_lib.baseboard_fab2(sch_1):m_c_dq(19)"
				( attribute "CDS_PHYS_NET_NAME" "M_C_DQ<19>"
					( Origin gPackager )
				)
				( attribute "PNN" "M_C_DQ<19>"
					( Origin gPackager )
				)
				( objectStatus "M_C_DQ<19>" )
			)
			( signal "@baseboard_fab2_lib.baseboard_fab2(sch_1):m_c_dq(20)"
				( attribute "CDS_PHYS_NET_NAME" "M_C_DQ<20>"
					( Origin gPackager )
				)
				( attribute "PNN" "M_C_DQ<20>"
					( Origin gPackager )
				)
				( objectStatus "M_C_DQ<20>" )
			)
			( signal "@baseboard_fab2_lib.baseboard_fab2(sch_1):m_c_dq(21)"
				( attribute "CDS_PHYS_NET_NAME" "M_C_DQ<21>"
					( Origin gPackager )
				)
				( attribute "PNN" "M_C_DQ<21>"
					( Origin gPackager )
				)
				( objectStatus "M_C_DQ<21>" )
			)
			( signal "@baseboard_fab2_lib.baseboard_fab2(sch_1):m_c_dq(22)"
				( attribute "CDS_PHYS_NET_NAME" "M_C_DQ<22>"
					( Origin gPackager )
				)
				( attribute "PNN" "M_C_DQ<22>"
					( Origin gPackager )
				)
				( objectStatus "M_C_DQ<22>" )
			)
			( signal "@baseboard_fab2_lib.baseboard_fab2(sch_1):m_c_dq(23)"
				( attribute "CDS_PHYS_NET_NAME" "M_C_DQ<23>"
					( Origin gPackager )
				)
				( attribute "PNN" "M_C_DQ<23>"
					( Origin gPackager )
				)
				( objectStatus "M_C_DQ<23>" )
			)
			( signal "@baseboard_fab2_lib.baseboard_fab2(sch_1):m_c_dq(24)"
				( attribute "CDS_PHYS_NET_NAME" "M_C_DQ<24>"
					( Origin gPackager )
				)
				( attribute "PNN" "M_C_DQ<24>"
					( Origin gPackager )
				)
				( objectStatus "M_C_DQ<24>" )
			)
			( signal "@baseboard_fab2_lib.baseboard_fab2(sch_1):m_c_dq(25)"
				( attribute "CDS_PHYS_NET_NAME" "M_C_DQ<25>"
					( Origin gPackager )
				)
				( attribute "PNN" "M_C_DQ<25>"
					( Origin gPackager )
				)
				( objectStatus "M_C_DQ<25>" )
			)
			( signal "@baseboard_fab2_lib.baseboard_fab2(sch_1):m_c_dq(26)"
				( attribute "CDS_PHYS_NET_NAME" "M_C_DQ<26>"
					( Origin gPackager )
				)
				( attribute "PNN" "M_C_DQ<26>"
					( Origin gPackager )
				)
				( objectStatus "M_C_DQ<26>" )
			)
			( signal "@baseboard_fab2_lib.baseboard_fab2(sch_1):m_c_dq(27)"
				( attribute "CDS_PHYS_NET_NAME" "M_C_DQ<27>"
					( Origin gPackager )
				)
				( attribute "PNN" "M_C_DQ<27>"
					( Origin gPackager )
				)
				( objectStatus "M_C_DQ<27>" )
			)
			( signal "@baseboard_fab2_lib.baseboard_fab2(sch_1):m_c_dq(28)"
				( attribute "CDS_PHYS_NET_NAME" "M_C_DQ<28>"
					( Origin gPackager )
				)
				( attribute "PNN" "M_C_DQ<28>"
					( Origin gPackager )
				)
				( objectStatus "M_C_DQ<28>" )
			)
			( signal "@baseboard_fab2_lib.baseboard_fab2(sch_1):m_c_dq(29)"
				( attribute "CDS_PHYS_NET_NAME" "M_C_DQ<29>"
					( Origin gPackager )
				)
				( attribute "PNN" "M_C_DQ<29>"
					( Origin gPackager )
				)
				( objectStatus "M_C_DQ<29>" )
			)
			( signal "@baseboard_fab2_lib.baseboard_fab2(sch_1):m_c_dq(30)"
				( attribute "CDS_PHYS_NET_NAME" "M_C_DQ<30>"
					( Origin gPackager )
				)
				( attribute "PNN" "M_C_DQ<30>"
					( Origin gPackager )
				)
				( objectStatus "M_C_DQ<30>" )
			)
			( signal "@baseboard_fab2_lib.baseboard_fab2(sch_1):m_c_dq(31)"
				( attribute "CDS_PHYS_NET_NAME" "M_C_DQ<31>"
					( Origin gPackager )
				)
				( attribute "PNN" "M_C_DQ<31>"
					( Origin gPackager )
				)
				( objectStatus "M_C_DQ<31>" )
			)
			( signal "@baseboard_fab2_lib.baseboard_fab2(sch_1):m_c_dq(32)"
				( attribute "CDS_PHYS_NET_NAME" "M_C_DQ<32>"
					( Origin gPackager )
				)
				( attribute "PNN" "M_C_DQ<32>"
					( Origin gPackager )
				)
				( objectStatus "M_C_DQ<32>" )
			)
			( signal "@baseboard_fab2_lib.baseboard_fab2(sch_1):m_c_dq(33)"
				( attribute "CDS_PHYS_NET_NAME" "M_C_DQ<33>"
					( Origin gPackager )
				)
				( attribute "PNN" "M_C_DQ<33>"
					( Origin gPackager )
				)
				( objectStatus "M_C_DQ<33>" )
			)
			( signal "@baseboard_fab2_lib.baseboard_fab2(sch_1):m_c_dq(34)"
				( attribute "CDS_PHYS_NET_NAME" "M_C_DQ<34>"
					( Origin gPackager )
				)
				( attribute "PNN" "M_C_DQ<34>"
					( Origin gPackager )
				)
				( objectStatus "M_C_DQ<34>" )
			)
			( signal "@baseboard_fab2_lib.baseboard_fab2(sch_1):m_c_dq(35)"
				( attribute "CDS_PHYS_NET_NAME" "M_C_DQ<35>"
					( Origin gPackager )
				)
				( attribute "PNN" "M_C_DQ<35>"
					( Origin gPackager )
				)
				( objectStatus "M_C_DQ<35>" )
			)
			( signal "@baseboard_fab2_lib.baseboard_fab2(sch_1):m_c_dq(36)"
				( attribute "CDS_PHYS_NET_NAME" "M_C_DQ<36>"
					( Origin gPackager )
				)
				( attribute "PNN" "M_C_DQ<36>"
					( Origin gPackager )
				)
				( objectStatus "M_C_DQ<36>" )
			)
			( signal "@baseboard_fab2_lib.baseboard_fab2(sch_1):m_c_dq(37)"
				( attribute "CDS_PHYS_NET_NAME" "M_C_DQ<37>"
					( Origin gPackager )
				)
				( attribute "PNN" "M_C_DQ<37>"
					( Origin gPackager )
				)
				( objectStatus "M_C_DQ<37>" )
			)
			( signal "@baseboard_fab2_lib.baseboard_fab2(sch_1):m_c_dq(38)"
				( attribute "CDS_PHYS_NET_NAME" "M_C_DQ<38>"
					( Origin gPackager )
				)
				( attribute "PNN" "M_C_DQ<38>"
					( Origin gPackager )
				)
				( objectStatus "M_C_DQ<38>" )
			)
			( signal "@baseboard_fab2_lib.baseboard_fab2(sch_1):m_c_dq(39)"
				( attribute "CDS_PHYS_NET_NAME" "M_C_DQ<39>"
					( Origin gPackager )
				)
				( attribute "PNN" "M_C_DQ<39>"
					( Origin gPackager )
				)
				( objectStatus "M_C_DQ<39>" )
			)
			( signal "@baseboard_fab2_lib.baseboard_fab2(sch_1):m_c_dq(40)"
				( attribute "CDS_PHYS_NET_NAME" "M_C_DQ<40>"
					( Origin gPackager )
				)
				( attribute "PNN" "M_C_DQ<40>"
					( Origin gPackager )
				)
				( objectStatus "M_C_DQ<40>" )
			)
			( signal "@baseboard_fab2_lib.baseboard_fab2(sch_1):m_c_dq(41)"
				( attribute "CDS_PHYS_NET_NAME" "M_C_DQ<41>"
					( Origin gPackager )
				)
				( attribute "PNN" "M_C_DQ<41>"
					( Origin gPackager )
				)
				( objectStatus "M_C_DQ<41>" )
			)
			( signal "@baseboard_fab2_lib.baseboard_fab2(sch_1):m_c_dq(42)"
				( attribute "CDS_PHYS_NET_NAME" "M_C_DQ<42>"
					( Origin gPackager )
				)
				( attribute "PNN" "M_C_DQ<42>"
					( Origin gPackager )
				)
				( objectStatus "M_C_DQ<42>" )
			)
			( signal "@baseboard_fab2_lib.baseboard_fab2(sch_1):m_c_dq(43)"
				( attribute "CDS_PHYS_NET_NAME" "M_C_DQ<43>"
					( Origin gPackager )
				)
				( attribute "PNN" "M_C_DQ<43>"
					( Origin gPackager )
				)
				( objectStatus "M_C_DQ<43>" )
			)
			( signal "@baseboard_fab2_lib.baseboard_fab2(sch_1):m_c_dq(44)"
				( attribute "CDS_PHYS_NET_NAME" "M_C_DQ<44>"
					( Origin gPackager )
				)
				( attribute "PNN" "M_C_DQ<44>"
					( Origin gPackager )
				)
				( objectStatus "M_C_DQ<44>" )
			)
			( signal "@baseboard_fab2_lib.baseboard_fab2(sch_1):m_c_dq(45)"
				( attribute "CDS_PHYS_NET_NAME" "M_C_DQ<45>"
					( Origin gPackager )
				)
				( attribute "PNN" "M_C_DQ<45>"
					( Origin gPackager )
				)
				( objectStatus "M_C_DQ<45>" )
			)
			( signal "@baseboard_fab2_lib.baseboard_fab2(sch_1):m_c_dq(46)"
				( attribute "CDS_PHYS_NET_NAME" "M_C_DQ<46>"
					( Origin gPackager )
				)
				( attribute "PNN" "M_C_DQ<46>"
					( Origin gPackager )
				)
				( objectStatus "M_C_DQ<46>" )
			)
			( signal "@baseboard_fab2_lib.baseboard_fab2(sch_1):m_c_dq(47)"
				( attribute "CDS_PHYS_NET_NAME" "M_C_DQ<47>"
					( Origin gPackager )
				)
				( attribute "PNN" "M_C_DQ<47>"
					( Origin gPackager )
				)
				( objectStatus "M_C_DQ<47>" )
			)
			( signal "@baseboard_fab2_lib.baseboard_fab2(sch_1):m_c_dq(48)"
				( attribute "CDS_PHYS_NET_NAME" "M_C_DQ<48>"
					( Origin gPackager )
				)
				( attribute "PNN" "M_C_DQ<48>"
					( Origin gPackager )
				)
				( objectStatus "M_C_DQ<48>" )
			)
			( signal "@baseboard_fab2_lib.baseboard_fab2(sch_1):m_c_dq(49)"
				( attribute "CDS_PHYS_NET_NAME" "M_C_DQ<49>"
					( Origin gPackager )
				)
				( attribute "PNN" "M_C_DQ<49>"
					( Origin gPackager )
				)
				( objectStatus "M_C_DQ<49>" )
			)
			( signal "@baseboard_fab2_lib.baseboard_fab2(sch_1):m_c_dq(50)"
				( attribute "CDS_PHYS_NET_NAME" "M_C_DQ<50>"
					( Origin gPackager )
				)
				( attribute "PNN" "M_C_DQ<50>"
					( Origin gPackager )
				)
				( objectStatus "M_C_DQ<50>" )
			)
			( signal "@baseboard_fab2_lib.baseboard_fab2(sch_1):m_c_dq(51)"
				( attribute "CDS_PHYS_NET_NAME" "M_C_DQ<51>"
					( Origin gPackager )
				)
				( attribute "PNN" "M_C_DQ<51>"
					( Origin gPackager )
				)
				( objectStatus "M_C_DQ<51>" )
			)
			( signal "@baseboard_fab2_lib.baseboard_fab2(sch_1):m_c_dq(52)"
				( attribute "CDS_PHYS_NET_NAME" "M_C_DQ<52>"
					( Origin gPackager )
				)
				( attribute "PNN" "M_C_DQ<52>"
					( Origin gPackager )
				)
				( objectStatus "M_C_DQ<52>" )
			)
			( signal "@baseboard_fab2_lib.baseboard_fab2(sch_1):m_c_dq(53)"
				( attribute "CDS_PHYS_NET_NAME" "M_C_DQ<53>"
					( Origin gPackager )
				)
				( attribute "PNN" "M_C_DQ<53>"
					( Origin gPackager )
				)
				( objectStatus "M_C_DQ<53>" )
			)
			( signal "@baseboard_fab2_lib.baseboard_fab2(sch_1):m_c_dq(54)"
				( attribute "CDS_PHYS_NET_NAME" "M_C_DQ<54>"
					( Origin gPackager )
				)
				( attribute "PNN" "M_C_DQ<54>"
					( Origin gPackager )
				)
				( objectStatus "M_C_DQ<54>" )
			)
			( signal "@baseboard_fab2_lib.baseboard_fab2(sch_1):m_c_dq(55)"
				( attribute "CDS_PHYS_NET_NAME" "M_C_DQ<55>"
					( Origin gPackager )
				)
				( attribute "PNN" "M_C_DQ<55>"
					( Origin gPackager )
				)
				( objectStatus "M_C_DQ<55>" )
			)
			( signal "@baseboard_fab2_lib.baseboard_fab2(sch_1):m_c_dq(56)"
				( attribute "CDS_PHYS_NET_NAME" "M_C_DQ<56>"
					( Origin gPackager )
				)
				( attribute "PNN" "M_C_DQ<56>"
					( Origin gPackager )
				)
				( objectStatus "M_C_DQ<56>" )
			)
			( signal "@baseboard_fab2_lib.baseboard_fab2(sch_1):m_c_dq(57)"
				( attribute "CDS_PHYS_NET_NAME" "M_C_DQ<57>"
					( Origin gPackager )
				)
				( attribute "PNN" "M_C_DQ<57>"
					( Origin gPackager )
				)
				( objectStatus "M_C_DQ<57>" )
			)
			( signal "@baseboard_fab2_lib.baseboard_fab2(sch_1):m_c_dq(58)"
				( attribute "CDS_PHYS_NET_NAME" "M_C_DQ<58>"
					( Origin gPackager )
				)
				( attribute "PNN" "M_C_DQ<58>"
					( Origin gPackager )
				)
				( objectStatus "M_C_DQ<58>" )
			)
			( signal "@baseboard_fab2_lib.baseboard_fab2(sch_1):m_c_dq(59)"
				( attribute "CDS_PHYS_NET_NAME" "M_C_DQ<59>"
					( Origin gPackager )
				)
				( attribute "PNN" "M_C_DQ<59>"
					( Origin gPackager )
				)
				( objectStatus "M_C_DQ<59>" )
			)
			( signal "@baseboard_fab2_lib.baseboard_fab2(sch_1):m_c_dq(60)"
				( attribute "CDS_PHYS_NET_NAME" "M_C_DQ<60>"
					( Origin gPackager )
				)
				( attribute "PNN" "M_C_DQ<60>"
					( Origin gPackager )
				)
				( objectStatus "M_C_DQ<60>" )
			)
			( signal "@baseboard_fab2_lib.baseboard_fab2(sch_1):m_c_dq(61)"
				( attribute "CDS_PHYS_NET_NAME" "M_C_DQ<61>"
					( Origin gPackager )
				)
				( attribute "PNN" "M_C_DQ<61>"
					( Origin gPackager )
				)
				( objectStatus "M_C_DQ<61>" )
			)
			( signal "@baseboard_fab2_lib.baseboard_fab2(sch_1):m_c_dq(62)"
				( attribute "CDS_PHYS_NET_NAME" "M_C_DQ<62>"
					( Origin gPackager )
				)
				( attribute "PNN" "M_C_DQ<62>"
					( Origin gPackager )
				)
				( objectStatus "M_C_DQ<62>" )
			)
			( signal "@baseboard_fab2_lib.baseboard_fab2(sch_1):m_c_dq(63)"
				( attribute "CDS_PHYS_NET_NAME" "M_C_DQ<63>"
					( Origin gPackager )
				)
				( attribute "PNN" "M_C_DQ<63>"
					( Origin gPackager )
				)
				( objectStatus "M_C_DQ<63>" )
			)
			( signal "@baseboard_fab2_lib.baseboard_fab2(sch_1):m_c_dqs_dn(0)"
				( attribute "CDS_PHYS_NET_NAME" "M_C_DQS_DN<0>"
					( Origin gPackager )
				)
				( attribute "PNN" "M_C_DQS_DN<0>"
					( Origin gPackager )
				)
				( objectStatus "M_C_DQS_DN<0>" )
			)
			( signal "@baseboard_fab2_lib.baseboard_fab2(sch_1):m_c_dqs_dn(1)"
				( attribute "CDS_PHYS_NET_NAME" "M_C_DQS_DN<1>"
					( Origin gPackager )
				)
				( attribute "PNN" "M_C_DQS_DN<1>"
					( Origin gPackager )
				)
				( objectStatus "M_C_DQS_DN<1>" )
			)
			( signal "@baseboard_fab2_lib.baseboard_fab2(sch_1):m_c_dqs_dn(2)"
				( attribute "CDS_PHYS_NET_NAME" "M_C_DQS_DN<2>"
					( Origin gPackager )
				)
				( attribute "PNN" "M_C_DQS_DN<2>"
					( Origin gPackager )
				)
				( objectStatus "M_C_DQS_DN<2>" )
			)
			( signal "@baseboard_fab2_lib.baseboard_fab2(sch_1):m_c_dqs_dn(3)"
				( attribute "CDS_PHYS_NET_NAME" "M_C_DQS_DN<3>"
					( Origin gPackager )
				)
				( attribute "PNN" "M_C_DQS_DN<3>"
					( Origin gPackager )
				)
				( objectStatus "M_C_DQS_DN<3>" )
			)
			( signal "@baseboard_fab2_lib.baseboard_fab2(sch_1):m_c_dqs_dn(4)"
				( attribute "CDS_PHYS_NET_NAME" "M_C_DQS_DN<4>"
					( Origin gPackager )
				)
				( attribute "PNN" "M_C_DQS_DN<4>"
					( Origin gPackager )
				)
				( objectStatus "M_C_DQS_DN<4>" )
			)
			( signal "@baseboard_fab2_lib.baseboard_fab2(sch_1):m_c_dqs_dn(5)"
				( attribute "CDS_PHYS_NET_NAME" "M_C_DQS_DN<5>"
					( Origin gPackager )
				)
				( attribute "PNN" "M_C_DQS_DN<5>"
					( Origin gPackager )
				)
				( objectStatus "M_C_DQS_DN<5>" )
			)
			( signal "@baseboard_fab2_lib.baseboard_fab2(sch_1):m_c_dqs_dn(6)"
				( attribute "CDS_PHYS_NET_NAME" "M_C_DQS_DN<6>"
					( Origin gPackager )
				)
				( attribute "PNN" "M_C_DQS_DN<6>"
					( Origin gPackager )
				)
				( objectStatus "M_C_DQS_DN<6>" )
			)
			( signal "@baseboard_fab2_lib.baseboard_fab2(sch_1):m_c_dqs_dn(7)"
				( attribute "CDS_PHYS_NET_NAME" "M_C_DQS_DN<7>"
					( Origin gPackager )
				)
				( attribute "PNN" "M_C_DQS_DN<7>"
					( Origin gPackager )
				)
				( objectStatus "M_C_DQS_DN<7>" )
			)
			( signal "@baseboard_fab2_lib.baseboard_fab2(sch_1):m_c_dqs_dn(8)"
				( attribute "CDS_PHYS_NET_NAME" "M_C_DQS_DN<8>"
					( Origin gPackager )
				)
				( attribute "PNN" "M_C_DQS_DN<8>"
					( Origin gPackager )
				)
				( objectStatus "M_C_DQS_DN<8>" )
			)
			( signal "@baseboard_fab2_lib.baseboard_fab2(sch_1):m_c_dqs_dn(9)"
				( attribute "CDS_PHYS_NET_NAME" "M_C_DQS_DN<9>"
					( Origin gPackager )
				)
				( attribute "PNN" "M_C_DQS_DN<9>"
					( Origin gPackager )
				)
				( objectStatus "M_C_DQS_DN<9>" )
			)
			( signal "@baseboard_fab2_lib.baseboard_fab2(sch_1):m_c_dqs_dn(10)"
				( attribute "CDS_PHYS_NET_NAME" "M_C_DQS_DN<10>"
					( Origin gPackager )
				)
				( attribute "PNN" "M_C_DQS_DN<10>"
					( Origin gPackager )
				)
				( objectStatus "M_C_DQS_DN<10>" )
			)
			( signal "@baseboard_fab2_lib.baseboard_fab2(sch_1):m_c_dqs_dn(11)"
				( attribute "CDS_PHYS_NET_NAME" "M_C_DQS_DN<11>"
					( Origin gPackager )
				)
				( attribute "PNN" "M_C_DQS_DN<11>"
					( Origin gPackager )
				)
				( objectStatus "M_C_DQS_DN<11>" )
			)
			( signal "@baseboard_fab2_lib.baseboard_fab2(sch_1):m_c_dqs_dn(12)"
				( attribute "CDS_PHYS_NET_NAME" "M_C_DQS_DN<12>"
					( Origin gPackager )
				)
				( attribute "PNN" "M_C_DQS_DN<12>"
					( Origin gPackager )
				)
				( objectStatus "M_C_DQS_DN<12>" )
			)
			( signal "@baseboard_fab2_lib.baseboard_fab2(sch_1):m_c_dqs_dn(13)"
				( attribute "CDS_PHYS_NET_NAME" "M_C_DQS_DN<13>"
					( Origin gPackager )
				)
				( attribute "PNN" "M_C_DQS_DN<13>"
					( Origin gPackager )
				)
				( objectStatus "M_C_DQS_DN<13>" )
			)
			( signal "@baseboard_fab2_lib.baseboard_fab2(sch_1):m_c_dqs_dn(14)"
				( attribute "CDS_PHYS_NET_NAME" "M_C_DQS_DN<14>"
					( Origin gPackager )
				)
				( attribute "PNN" "M_C_DQS_DN<14>"
					( Origin gPackager )
				)
				( objectStatus "M_C_DQS_DN<14>" )
			)
			( signal "@baseboard_fab2_lib.baseboard_fab2(sch_1):m_c_dqs_dn(15)"
				( attribute "CDS_PHYS_NET_NAME" "M_C_DQS_DN<15>"
					( Origin gPackager )
				)
				( attribute "PNN" "M_C_DQS_DN<15>"
					( Origin gPackager )
				)
				( objectStatus "M_C_DQS_DN<15>" )
			)
			( signal "@baseboard_fab2_lib.baseboard_fab2(sch_1):m_c_dqs_dn(16)"
				( attribute "CDS_PHYS_NET_NAME" "M_C_DQS_DN<16>"
					( Origin gPackager )
				)
				( attribute "PNN" "M_C_DQS_DN<16>"
					( Origin gPackager )
				)
				( objectStatus "M_C_DQS_DN<16>" )
			)
			( signal "@baseboard_fab2_lib.baseboard_fab2(sch_1):m_c_dqs_dn(17)"
				( attribute "CDS_PHYS_NET_NAME" "M_C_DQS_DN<17>"
					( Origin gPackager )
				)
				( attribute "PNN" "M_C_DQS_DN<17>"
					( Origin gPackager )
				)
				( objectStatus "M_C_DQS_DN<17>" )
			)
			( signal "@baseboard_fab2_lib.baseboard_fab2(sch_1):m_c_dqs_dp(0)"
				( attribute "CDS_PHYS_NET_NAME" "M_C_DQS_DP<0>"
					( Origin gPackager )
				)
				( attribute "PNN" "M_C_DQS_DP<0>"
					( Origin gPackager )
				)
				( objectStatus "M_C_DQS_DP<0>" )
			)
			( signal "@baseboard_fab2_lib.baseboard_fab2(sch_1):m_c_dqs_dp(1)"
				( attribute "CDS_PHYS_NET_NAME" "M_C_DQS_DP<1>"
					( Origin gPackager )
				)
				( attribute "PNN" "M_C_DQS_DP<1>"
					( Origin gPackager )
				)
				( objectStatus "M_C_DQS_DP<1>" )
			)
			( signal "@baseboard_fab2_lib.baseboard_fab2(sch_1):m_c_dqs_dp(2)"
				( attribute "CDS_PHYS_NET_NAME" "M_C_DQS_DP<2>"
					( Origin gPackager )
				)
				( attribute "PNN" "M_C_DQS_DP<2>"
					( Origin gPackager )
				)
				( objectStatus "M_C_DQS_DP<2>" )
			)
			( signal "@baseboard_fab2_lib.baseboard_fab2(sch_1):m_c_dqs_dp(3)"
				( attribute "CDS_PHYS_NET_NAME" "M_C_DQS_DP<3>"
					( Origin gPackager )
				)
				( attribute "PNN" "M_C_DQS_DP<3>"
					( Origin gPackager )
				)
				( objectStatus "M_C_DQS_DP<3>" )
			)
			( signal "@baseboard_fab2_lib.baseboard_fab2(sch_1):m_c_dqs_dp(4)"
				( attribute "CDS_PHYS_NET_NAME" "M_C_DQS_DP<4>"
					( Origin gPackager )
				)
				( attribute "PNN" "M_C_DQS_DP<4>"
					( Origin gPackager )
				)
				( objectStatus "M_C_DQS_DP<4>" )
			)
			( signal "@baseboard_fab2_lib.baseboard_fab2(sch_1):m_c_dqs_dp(5)"
				( attribute "CDS_PHYS_NET_NAME" "M_C_DQS_DP<5>"
					( Origin gPackager )
				)
				( attribute "PNN" "M_C_DQS_DP<5>"
					( Origin gPackager )
				)
				( objectStatus "M_C_DQS_DP<5>" )
			)
			( signal "@baseboard_fab2_lib.baseboard_fab2(sch_1):m_c_dqs_dp(6)"
				( attribute "CDS_PHYS_NET_NAME" "M_C_DQS_DP<6>"
					( Origin gPackager )
				)
				( attribute "PNN" "M_C_DQS_DP<6>"
					( Origin gPackager )
				)
				( objectStatus "M_C_DQS_DP<6>" )
			)
			( signal "@baseboard_fab2_lib.baseboard_fab2(sch_1):m_c_dqs_dp(7)"
				( attribute "CDS_PHYS_NET_NAME" "M_C_DQS_DP<7>"
					( Origin gPackager )
				)
				( attribute "PNN" "M_C_DQS_DP<7>"
					( Origin gPackager )
				)
				( objectStatus "M_C_DQS_DP<7>" )
			)
			( signal "@baseboard_fab2_lib.baseboard_fab2(sch_1):m_c_dqs_dp(8)"
				( attribute "CDS_PHYS_NET_NAME" "M_C_DQS_DP<8>"
					( Origin gPackager )
				)
				( attribute "PNN" "M_C_DQS_DP<8>"
					( Origin gPackager )
				)
				( objectStatus "M_C_DQS_DP<8>" )
			)
			( signal "@baseboard_fab2_lib.baseboard_fab2(sch_1):m_c_dqs_dp(9)"
				( attribute "CDS_PHYS_NET_NAME" "M_C_DQS_DP<9>"
					( Origin gPackager )
				)
				( attribute "PNN" "M_C_DQS_DP<9>"
					( Origin gPackager )
				)
				( objectStatus "M_C_DQS_DP<9>" )
			)
			( signal "@baseboard_fab2_lib.baseboard_fab2(sch_1):m_c_dqs_dp(10)"
				( attribute "CDS_PHYS_NET_NAME" "M_C_DQS_DP<10>"
					( Origin gPackager )
				)
				( attribute "PNN" "M_C_DQS_DP<10>"
					( Origin gPackager )
				)
				( objectStatus "M_C_DQS_DP<10>" )
			)
			( signal "@baseboard_fab2_lib.baseboard_fab2(sch_1):m_c_dqs_dp(11)"
				( attribute "CDS_PHYS_NET_NAME" "M_C_DQS_DP<11>"
					( Origin gPackager )
				)
				( attribute "PNN" "M_C_DQS_DP<11>"
					( Origin gPackager )
				)
				( objectStatus "M_C_DQS_DP<11>" )
			)
			( signal "@baseboard_fab2_lib.baseboard_fab2(sch_1):m_c_dqs_dp(12)"
				( attribute "CDS_PHYS_NET_NAME" "M_C_DQS_DP<12>"
					( Origin gPackager )
				)
				( attribute "PNN" "M_C_DQS_DP<12>"
					( Origin gPackager )
				)
				( objectStatus "M_C_DQS_DP<12>" )
			)
			( signal "@baseboard_fab2_lib.baseboard_fab2(sch_1):m_c_dqs_dp(13)"
				( attribute "CDS_PHYS_NET_NAME" "M_C_DQS_DP<13>"
					( Origin gPackager )
				)
				( attribute "PNN" "M_C_DQS_DP<13>"
					( Origin gPackager )
				)
				( objectStatus "M_C_DQS_DP<13>" )
			)
			( signal "@baseboard_fab2_lib.baseboard_fab2(sch_1):m_c_dqs_dp(14)"
				( attribute "CDS_PHYS_NET_NAME" "M_C_DQS_DP<14>"
					( Origin gPackager )
				)
				( attribute "PNN" "M_C_DQS_DP<14>"
					( Origin gPackager )
				)
				( objectStatus "M_C_DQS_DP<14>" )
			)
			( signal "@baseboard_fab2_lib.baseboard_fab2(sch_1):m_c_dqs_dp(15)"
				( attribute "CDS_PHYS_NET_NAME" "M_C_DQS_DP<15>"
					( Origin gPackager )
				)
				( attribute "PNN" "M_C_DQS_DP<15>"
					( Origin gPackager )
				)
				( objectStatus "M_C_DQS_DP<15>" )
			)
			( signal "@baseboard_fab2_lib.baseboard_fab2(sch_1):m_c_dqs_dp(16)"
				( attribute "CDS_PHYS_NET_NAME" "M_C_DQS_DP<16>"
					( Origin gPackager )
				)
				( attribute "PNN" "M_C_DQS_DP<16>"
					( Origin gPackager )
				)
				( objectStatus "M_C_DQS_DP<16>" )
			)
			( signal "@baseboard_fab2_lib.baseboard_fab2(sch_1):m_c_dqs_dp(17)"
				( attribute "CDS_PHYS_NET_NAME" "M_C_DQS_DP<17>"
					( Origin gPackager )
				)
				( attribute "PNN" "M_C_DQS_DP<17>"
					( Origin gPackager )
				)
				( objectStatus "M_C_DQS_DP<17>" )
			)
			( signal "@baseboard_fab2_lib.baseboard_fab2(sch_1):m_c_ecc(0)"
				( attribute "CDS_PHYS_NET_NAME" "M_C_ECC<0>"
					( Origin gPackager )
				)
				( attribute "PNN" "M_C_ECC<0>"
					( Origin gPackager )
				)
				( objectStatus "M_C_ECC<0>" )
			)
			( signal "@baseboard_fab2_lib.baseboard_fab2(sch_1):m_c_ecc(1)"
				( attribute "CDS_PHYS_NET_NAME" "M_C_ECC<1>"
					( Origin gPackager )
				)
				( attribute "PNN" "M_C_ECC<1>"
					( Origin gPackager )
				)
				( objectStatus "M_C_ECC<1>" )
			)
			( signal "@baseboard_fab2_lib.baseboard_fab2(sch_1):m_c_ecc(2)"
				( attribute "CDS_PHYS_NET_NAME" "M_C_ECC<2>"
					( Origin gPackager )
				)
				( attribute "PNN" "M_C_ECC<2>"
					( Origin gPackager )
				)
				( objectStatus "M_C_ECC<2>" )
			)
			( signal "@baseboard_fab2_lib.baseboard_fab2(sch_1):m_c_ecc(3)"
				( attribute "CDS_PHYS_NET_NAME" "M_C_ECC<3>"
					( Origin gPackager )
				)
				( attribute "PNN" "M_C_ECC<3>"
					( Origin gPackager )
				)
				( objectStatus "M_C_ECC<3>" )
			)
			( signal "@baseboard_fab2_lib.baseboard_fab2(sch_1):m_c_ecc(4)"
				( attribute "CDS_PHYS_NET_NAME" "M_C_ECC<4>"
					( Origin gPackager )
				)
				( attribute "PNN" "M_C_ECC<4>"
					( Origin gPackager )
				)
				( objectStatus "M_C_ECC<4>" )
			)
			( signal "@baseboard_fab2_lib.baseboard_fab2(sch_1):m_c_ecc(5)"
				( attribute "CDS_PHYS_NET_NAME" "M_C_ECC<5>"
					( Origin gPackager )
				)
				( attribute "PNN" "M_C_ECC<5>"
					( Origin gPackager )
				)
				( objectStatus "M_C_ECC<5>" )
			)
			( signal "@baseboard_fab2_lib.baseboard_fab2(sch_1):m_c_ecc(6)"
				( attribute "CDS_PHYS_NET_NAME" "M_C_ECC<6>"
					( Origin gPackager )
				)
				( attribute "PNN" "M_C_ECC<6>"
					( Origin gPackager )
				)
				( objectStatus "M_C_ECC<6>" )
			)
			( signal "@baseboard_fab2_lib.baseboard_fab2(sch_1):m_c_ecc(7)"
				( attribute "CDS_PHYS_NET_NAME" "M_C_ECC<7>"
					( Origin gPackager )
				)
				( attribute "PNN" "M_C_ECC<7>"
					( Origin gPackager )
				)
				( objectStatus "M_C_ECC<7>" )
			)
			( signal "@baseboard_fab2_lib.baseboard_fab2(sch_1):m_c_ma(0)"
				( attribute "CDS_PHYS_NET_NAME" "M_C_MA<0>"
					( Origin gPackager )
				)
				( attribute "PNN" "M_C_MA<0>"
					( Origin gPackager )
				)
				( objectStatus "M_C_MA<0>" )
			)
			( signal "@baseboard_fab2_lib.baseboard_fab2(sch_1):m_c_ma(1)"
				( attribute "CDS_PHYS_NET_NAME" "M_C_MA<1>"
					( Origin gPackager )
				)
				( attribute "PNN" "M_C_MA<1>"
					( Origin gPackager )
				)
				( objectStatus "M_C_MA<1>" )
			)
			( signal "@baseboard_fab2_lib.baseboard_fab2(sch_1):m_c_ma(2)"
				( attribute "CDS_PHYS_NET_NAME" "M_C_MA<2>"
					( Origin gPackager )
				)
				( attribute "PNN" "M_C_MA<2>"
					( Origin gPackager )
				)
				( objectStatus "M_C_MA<2>" )
			)
			( signal "@baseboard_fab2_lib.baseboard_fab2(sch_1):m_c_ma(3)"
				( attribute "CDS_PHYS_NET_NAME" "M_C_MA<3>"
					( Origin gPackager )
				)
				( attribute "PNN" "M_C_MA<3>"
					( Origin gPackager )
				)
				( objectStatus "M_C_MA<3>" )
			)
			( signal "@baseboard_fab2_lib.baseboard_fab2(sch_1):m_c_ma(4)"
				( attribute "CDS_PHYS_NET_NAME" "M_C_MA<4>"
					( Origin gPackager )
				)
				( attribute "PNN" "M_C_MA<4>"
					( Origin gPackager )
				)
				( objectStatus "M_C_MA<4>" )
			)
			( signal "@baseboard_fab2_lib.baseboard_fab2(sch_1):m_c_ma(5)"
				( attribute "CDS_PHYS_NET_NAME" "M_C_MA<5>"
					( Origin gPackager )
				)
				( attribute "PNN" "M_C_MA<5>"
					( Origin gPackager )
				)
				( objectStatus "M_C_MA<5>" )
			)
			( signal "@baseboard_fab2_lib.baseboard_fab2(sch_1):m_c_ma(6)"
				( attribute "CDS_PHYS_NET_NAME" "M_C_MA<6>"
					( Origin gPackager )
				)
				( attribute "PNN" "M_C_MA<6>"
					( Origin gPackager )
				)
				( objectStatus "M_C_MA<6>" )
			)
			( signal "@baseboard_fab2_lib.baseboard_fab2(sch_1):m_c_ma(7)"
				( attribute "CDS_PHYS_NET_NAME" "M_C_MA<7>"
					( Origin gPackager )
				)
				( attribute "PNN" "M_C_MA<7>"
					( Origin gPackager )
				)
				( objectStatus "M_C_MA<7>" )
			)
			( signal "@baseboard_fab2_lib.baseboard_fab2(sch_1):m_c_ma(8)"
				( attribute "CDS_PHYS_NET_NAME" "M_C_MA<8>"
					( Origin gPackager )
				)
				( attribute "PNN" "M_C_MA<8>"
					( Origin gPackager )
				)
				( objectStatus "M_C_MA<8>" )
			)
			( signal "@baseboard_fab2_lib.baseboard_fab2(sch_1):m_c_ma(9)"
				( attribute "CDS_PHYS_NET_NAME" "M_C_MA<9>"
					( Origin gPackager )
				)
				( attribute "PNN" "M_C_MA<9>"
					( Origin gPackager )
				)
				( objectStatus "M_C_MA<9>" )
			)
			( signal "@baseboard_fab2_lib.baseboard_fab2(sch_1):m_c_ma(10)"
				( attribute "CDS_PHYS_NET_NAME" "M_C_MA<10>"
					( Origin gPackager )
				)
				( attribute "PNN" "M_C_MA<10>"
					( Origin gPackager )
				)
				( objectStatus "M_C_MA<10>" )
			)
			( signal "@baseboard_fab2_lib.baseboard_fab2(sch_1):m_c_ma(11)"
				( attribute "CDS_PHYS_NET_NAME" "M_C_MA<11>"
					( Origin gPackager )
				)
				( attribute "PNN" "M_C_MA<11>"
					( Origin gPackager )
				)
				( objectStatus "M_C_MA<11>" )
			)
			( signal "@baseboard_fab2_lib.baseboard_fab2(sch_1):m_c_ma(12)"
				( attribute "CDS_PHYS_NET_NAME" "M_C_MA<12>"
					( Origin gPackager )
				)
				( attribute "PNN" "M_C_MA<12>"
					( Origin gPackager )
				)
				( objectStatus "M_C_MA<12>" )
			)
			( signal "@baseboard_fab2_lib.baseboard_fab2(sch_1):m_c_ma(13)"
				( attribute "CDS_PHYS_NET_NAME" "M_C_MA<13>"
					( Origin gPackager )
				)
				( attribute "PNN" "M_C_MA<13>"
					( Origin gPackager )
				)
				( objectStatus "M_C_MA<13>" )
			)
			( signal "@baseboard_fab2_lib.baseboard_fab2(sch_1):m_c_ma(14)"
				( attribute "CDS_PHYS_NET_NAME" "M_C_MA<14>"
					( Origin gPackager )
				)
				( attribute "PNN" "M_C_MA<14>"
					( Origin gPackager )
				)
				( objectStatus "M_C_MA<14>" )
			)
			( signal "@baseboard_fab2_lib.baseboard_fab2(sch_1):m_c_ma(15)"
				( attribute "CDS_PHYS_NET_NAME" "M_C_MA<15>"
					( Origin gPackager )
				)
				( attribute "PNN" "M_C_MA<15>"
					( Origin gPackager )
				)
				( objectStatus "M_C_MA<15>" )
			)
			( signal "@baseboard_fab2_lib.baseboard_fab2(sch_1):m_c_ma(16)"
				( attribute "CDS_PHYS_NET_NAME" "M_C_MA<16>"
					( Origin gPackager )
				)
				( attribute "PNN" "M_C_MA<16>"
					( Origin gPackager )
				)
				( objectStatus "M_C_MA<16>" )
			)
			( signal "@baseboard_fab2_lib.baseboard_fab2(sch_1):m_c_ma(17)"
				( attribute "CDS_PHYS_NET_NAME" "M_C_MA<17>"
					( Origin gPackager )
				)
				( attribute "PNN" "M_C_MA<17>"
					( Origin gPackager )
				)
				( objectStatus "M_C_MA<17>" )
			)
			( signal "@baseboard_fab2_lib.baseboard_fab2(sch_1):m_c_odt(0)"
				( attribute "CDS_PHYS_NET_NAME" "M_C_ODT<0>"
					( Origin gPackager )
				)
				( attribute "PNN" "M_C_ODT<0>"
					( Origin gPackager )
				)
				( objectStatus "M_C_ODT<0>" )
			)
			( signal "@baseboard_fab2_lib.baseboard_fab2(sch_1):m_c_odt(1)"
				( attribute "CDS_PHYS_NET_NAME" "M_C_ODT<1>"
					( Origin gPackager )
				)
				( attribute "PNN" "M_C_ODT<1>"
					( Origin gPackager )
				)
				( objectStatus "M_C_ODT<1>" )
			)
			( signal "@baseboard_fab2_lib.baseboard_fab2(sch_1):m_c_odt(2)"
				( attribute "CDS_PHYS_NET_NAME" "M_C_ODT<2>"
					( Origin gPackager )
				)
				( attribute "PNN" "M_C_ODT<2>"
					( Origin gPackager )
				)
				( objectStatus "M_C_ODT<2>" )
			)
			( signal "@baseboard_fab2_lib.baseboard_fab2(sch_1):m_c_odt(3)"
				( attribute "CDS_PHYS_NET_NAME" "M_C_ODT<3>"
					( Origin gPackager )
				)
				( attribute "PNN" "M_C_ODT<3>"
					( Origin gPackager )
				)
				( objectStatus "M_C_ODT<3>" )
			)
			( signal "@baseboard_fab2_lib.baseboard_fab2(sch_1):m_c_par"
				( attribute "CDS_PHYS_NET_NAME" "M_C_PAR"
					( Origin gPackager )
				)
				( objectStatus "M_C_PAR" )
			)
			( signal "@baseboard_fab2_lib.baseboard_fab2(sch_1):m_d_act_n"
				( attribute "CDS_PHYS_NET_NAME" "M_D_ACT_N"
					( Origin gPackager )
				)
				( objectStatus "M_D_ACT_N" )
			)
			( signal "@baseboard_fab2_lib.baseboard_fab2(sch_1):m_d_alert_n"
				( attribute "CDS_PHYS_NET_NAME" "M_D_ALERT_N"
					( Origin gPackager )
				)
				( objectStatus "M_D_ALERT_N" )
			)
			( signal "@baseboard_fab2_lib.baseboard_fab2(sch_1):m_d_ba(0)"
				( attribute "CDS_PHYS_NET_NAME" "M_D_BA<0>"
					( Origin gPackager )
				)
				( attribute "PNN" "M_D_BA<0>"
					( Origin gPackager )
				)
				( objectStatus "M_D_BA<0>" )
			)
			( signal "@baseboard_fab2_lib.baseboard_fab2(sch_1):m_d_ba(1)"
				( attribute "CDS_PHYS_NET_NAME" "M_D_BA<1>"
					( Origin gPackager )
				)
				( attribute "PNN" "M_D_BA<1>"
					( Origin gPackager )
				)
				( objectStatus "M_D_BA<1>" )
			)
			( signal "@baseboard_fab2_lib.baseboard_fab2(sch_1):m_d_bg(0)"
				( attribute "CDS_PHYS_NET_NAME" "M_D_BG<0>"
					( Origin gPackager )
				)
				( attribute "PNN" "M_D_BG<0>"
					( Origin gPackager )
				)
				( objectStatus "M_D_BG<0>" )
			)
			( signal "@baseboard_fab2_lib.baseboard_fab2(sch_1):m_d_bg(1)"
				( attribute "CDS_PHYS_NET_NAME" "M_D_BG<1>"
					( Origin gPackager )
				)
				( attribute "PNN" "M_D_BG<1>"
					( Origin gPackager )
				)
				( objectStatus "M_D_BG<1>" )
			)
			( signal "@baseboard_fab2_lib.baseboard_fab2(sch_1):m_d_c(2)"
				( attribute "CDS_PHYS_NET_NAME" "M_D_C<2>"
					( Origin gPackager )
				)
				( attribute "PNN" "M_D_C<2>"
					( Origin gPackager )
				)
				( objectStatus "M_D_C<2>" )
			)
			( signal "@baseboard_fab2_lib.baseboard_fab2(sch_1):m_d_cke(0)"
				( attribute "CDS_PHYS_NET_NAME" "M_D_CKE<0>"
					( Origin gPackager )
				)
				( attribute "PNN" "M_D_CKE<0>"
					( Origin gPackager )
				)
				( objectStatus "M_D_CKE<0>" )
			)
			( signal "@baseboard_fab2_lib.baseboard_fab2(sch_1):m_d_cke(1)"
				( attribute "CDS_PHYS_NET_NAME" "M_D_CKE<1>"
					( Origin gPackager )
				)
				( attribute "PNN" "M_D_CKE<1>"
					( Origin gPackager )
				)
				( objectStatus "M_D_CKE<1>" )
			)
			( signal "@baseboard_fab2_lib.baseboard_fab2(sch_1):m_d_cke(2)"
				( attribute "CDS_PHYS_NET_NAME" "M_D_CKE<2>"
					( Origin gPackager )
				)
				( attribute "PNN" "M_D_CKE<2>"
					( Origin gPackager )
				)
				( objectStatus "M_D_CKE<2>" )
			)
			( signal "@baseboard_fab2_lib.baseboard_fab2(sch_1):m_d_cke(3)"
				( attribute "CDS_PHYS_NET_NAME" "M_D_CKE<3>"
					( Origin gPackager )
				)
				( attribute "PNN" "M_D_CKE<3>"
					( Origin gPackager )
				)
				( objectStatus "M_D_CKE<3>" )
			)
			( signal "@baseboard_fab2_lib.baseboard_fab2(sch_1):m_d_clk_dn(0)"
				( attribute "CDS_PHYS_NET_NAME" "M_D_CLK_DN<0>"
					( Origin gPackager )
				)
				( attribute "PNN" "M_D_CLK_DN<0>"
					( Origin gPackager )
				)
				( objectStatus "M_D_CLK_DN<0>" )
			)
			( signal "@baseboard_fab2_lib.baseboard_fab2(sch_1):m_d_clk_dn(1)"
				( attribute "CDS_PHYS_NET_NAME" "M_D_CLK_DN<1>"
					( Origin gPackager )
				)
				( attribute "PNN" "M_D_CLK_DN<1>"
					( Origin gPackager )
				)
				( objectStatus "M_D_CLK_DN<1>" )
			)
			( signal "@baseboard_fab2_lib.baseboard_fab2(sch_1):m_d_clk_dn(2)"
				( attribute "CDS_PHYS_NET_NAME" "M_D_CLK_DN<2>"
					( Origin gPackager )
				)
				( attribute "PNN" "M_D_CLK_DN<2>"
					( Origin gPackager )
				)
				( objectStatus "M_D_CLK_DN<2>" )
			)
			( signal "@baseboard_fab2_lib.baseboard_fab2(sch_1):m_d_clk_dn(3)"
				( attribute "CDS_PHYS_NET_NAME" "M_D_CLK_DN<3>"
					( Origin gPackager )
				)
				( attribute "PNN" "M_D_CLK_DN<3>"
					( Origin gPackager )
				)
				( objectStatus "M_D_CLK_DN<3>" )
			)
			( signal "@baseboard_fab2_lib.baseboard_fab2(sch_1):m_d_clk_dp(0)"
				( attribute "CDS_PHYS_NET_NAME" "M_D_CLK_DP<0>"
					( Origin gPackager )
				)
				( attribute "PNN" "M_D_CLK_DP<0>"
					( Origin gPackager )
				)
				( objectStatus "M_D_CLK_DP<0>" )
			)
			( signal "@baseboard_fab2_lib.baseboard_fab2(sch_1):m_d_clk_dp(1)"
				( attribute "CDS_PHYS_NET_NAME" "M_D_CLK_DP<1>"
					( Origin gPackager )
				)
				( attribute "PNN" "M_D_CLK_DP<1>"
					( Origin gPackager )
				)
				( objectStatus "M_D_CLK_DP<1>" )
			)
			( signal "@baseboard_fab2_lib.baseboard_fab2(sch_1):m_d_clk_dp(2)"
				( attribute "CDS_PHYS_NET_NAME" "M_D_CLK_DP<2>"
					( Origin gPackager )
				)
				( attribute "PNN" "M_D_CLK_DP<2>"
					( Origin gPackager )
				)
				( objectStatus "M_D_CLK_DP<2>" )
			)
			( signal "@baseboard_fab2_lib.baseboard_fab2(sch_1):m_d_clk_dp(3)"
				( attribute "CDS_PHYS_NET_NAME" "M_D_CLK_DP<3>"
					( Origin gPackager )
				)
				( attribute "PNN" "M_D_CLK_DP<3>"
					( Origin gPackager )
				)
				( objectStatus "M_D_CLK_DP<3>" )
			)
			( signal "@baseboard_fab2_lib.baseboard_fab2(sch_1):m_d_cs_n(0)"
				( attribute "CDS_PHYS_NET_NAME" "M_D_CS_N<0>"
					( Origin gPackager )
				)
				( attribute "PNN" "M_D_CS_N<0>"
					( Origin gPackager )
				)
				( objectStatus "M_D_CS_N<0>" )
			)
			( signal "@baseboard_fab2_lib.baseboard_fab2(sch_1):m_d_cs_n(1)"
				( attribute "CDS_PHYS_NET_NAME" "M_D_CS_N<1>"
					( Origin gPackager )
				)
				( attribute "PNN" "M_D_CS_N<1>"
					( Origin gPackager )
				)
				( objectStatus "M_D_CS_N<1>" )
			)
			( signal "@baseboard_fab2_lib.baseboard_fab2(sch_1):m_d_cs_n(2)"
				( attribute "CDS_PHYS_NET_NAME" "M_D_CS_N<2>"
					( Origin gPackager )
				)
				( attribute "PNN" "M_D_CS_N<2>"
					( Origin gPackager )
				)
				( objectStatus "M_D_CS_N<2>" )
			)
			( signal "@baseboard_fab2_lib.baseboard_fab2(sch_1):m_d_cs_n(3)"
				( attribute "CDS_PHYS_NET_NAME" "M_D_CS_N<3>"
					( Origin gPackager )
				)
				( attribute "PNN" "M_D_CS_N<3>"
					( Origin gPackager )
				)
				( objectStatus "M_D_CS_N<3>" )
			)
			( signal "@baseboard_fab2_lib.baseboard_fab2(sch_1):m_d_cs_n(4)"
				( attribute "CDS_PHYS_NET_NAME" "M_D_CS_N<4>"
					( Origin gPackager )
				)
				( attribute "PNN" "M_D_CS_N<4>"
					( Origin gPackager )
				)
				( objectStatus "M_D_CS_N<4>" )
			)
			( signal "@baseboard_fab2_lib.baseboard_fab2(sch_1):m_d_cs_n(5)"
				( attribute "CDS_PHYS_NET_NAME" "M_D_CS_N<5>"
					( Origin gPackager )
				)
				( attribute "PNN" "M_D_CS_N<5>"
					( Origin gPackager )
				)
				( objectStatus "M_D_CS_N<5>" )
			)
			( signal "@baseboard_fab2_lib.baseboard_fab2(sch_1):m_d_cs_n(6)"
				( attribute "CDS_PHYS_NET_NAME" "M_D_CS_N<6>"
					( Origin gPackager )
				)
				( attribute "PNN" "M_D_CS_N<6>"
					( Origin gPackager )
				)
				( objectStatus "M_D_CS_N<6>" )
			)
			( signal "@baseboard_fab2_lib.baseboard_fab2(sch_1):m_d_cs_n(7)"
				( attribute "CDS_PHYS_NET_NAME" "M_D_CS_N<7>"
					( Origin gPackager )
				)
				( attribute "PNN" "M_D_CS_N<7>"
					( Origin gPackager )
				)
				( objectStatus "M_D_CS_N<7>" )
			)
			( signal "@baseboard_fab2_lib.baseboard_fab2(sch_1):m_d_dq(0)"
				( attribute "CDS_PHYS_NET_NAME" "M_D_DQ<0>"
					( Origin gPackager )
				)
				( attribute "PNN" "M_D_DQ<0>"
					( Origin gPackager )
				)
				( objectStatus "M_D_DQ<0>" )
			)
			( signal "@baseboard_fab2_lib.baseboard_fab2(sch_1):m_d_dq(1)"
				( attribute "CDS_PHYS_NET_NAME" "M_D_DQ<1>"
					( Origin gPackager )
				)
				( attribute "PNN" "M_D_DQ<1>"
					( Origin gPackager )
				)
				( objectStatus "M_D_DQ<1>" )
			)
			( signal "@baseboard_fab2_lib.baseboard_fab2(sch_1):m_d_dq(2)"
				( attribute "CDS_PHYS_NET_NAME" "M_D_DQ<2>"
					( Origin gPackager )
				)
				( attribute "PNN" "M_D_DQ<2>"
					( Origin gPackager )
				)
				( objectStatus "M_D_DQ<2>" )
			)
			( signal "@baseboard_fab2_lib.baseboard_fab2(sch_1):m_d_dq(3)"
				( attribute "CDS_PHYS_NET_NAME" "M_D_DQ<3>"
					( Origin gPackager )
				)
				( attribute "PNN" "M_D_DQ<3>"
					( Origin gPackager )
				)
				( objectStatus "M_D_DQ<3>" )
			)
			( signal "@baseboard_fab2_lib.baseboard_fab2(sch_1):m_d_dq(4)"
				( attribute "CDS_PHYS_NET_NAME" "M_D_DQ<4>"
					( Origin gPackager )
				)
				( attribute "PNN" "M_D_DQ<4>"
					( Origin gPackager )
				)
				( objectStatus "M_D_DQ<4>" )
			)
			( signal "@baseboard_fab2_lib.baseboard_fab2(sch_1):m_d_dq(5)"
				( attribute "CDS_PHYS_NET_NAME" "M_D_DQ<5>"
					( Origin gPackager )
				)
				( attribute "PNN" "M_D_DQ<5>"
					( Origin gPackager )
				)
				( objectStatus "M_D_DQ<5>" )
			)
			( signal "@baseboard_fab2_lib.baseboard_fab2(sch_1):m_d_dq(6)"
				( attribute "CDS_PHYS_NET_NAME" "M_D_DQ<6>"
					( Origin gPackager )
				)
				( attribute "PNN" "M_D_DQ<6>"
					( Origin gPackager )
				)
				( objectStatus "M_D_DQ<6>" )
			)
			( signal "@baseboard_fab2_lib.baseboard_fab2(sch_1):m_d_dq(7)"
				( attribute "CDS_PHYS_NET_NAME" "M_D_DQ<7>"
					( Origin gPackager )
				)
				( attribute "PNN" "M_D_DQ<7>"
					( Origin gPackager )
				)
				( objectStatus "M_D_DQ<7>" )
			)
			( signal "@baseboard_fab2_lib.baseboard_fab2(sch_1):m_d_dq(8)"
				( attribute "CDS_PHYS_NET_NAME" "M_D_DQ<8>"
					( Origin gPackager )
				)
				( attribute "PNN" "M_D_DQ<8>"
					( Origin gPackager )
				)
				( objectStatus "M_D_DQ<8>" )
			)
			( signal "@baseboard_fab2_lib.baseboard_fab2(sch_1):m_d_dq(9)"
				( attribute "CDS_PHYS_NET_NAME" "M_D_DQ<9>"
					( Origin gPackager )
				)
				( attribute "PNN" "M_D_DQ<9>"
					( Origin gPackager )
				)
				( objectStatus "M_D_DQ<9>" )
			)
			( signal "@baseboard_fab2_lib.baseboard_fab2(sch_1):m_d_dq(10)"
				( attribute "CDS_PHYS_NET_NAME" "M_D_DQ<10>"
					( Origin gPackager )
				)
				( attribute "PNN" "M_D_DQ<10>"
					( Origin gPackager )
				)
				( objectStatus "M_D_DQ<10>" )
			)
			( signal "@baseboard_fab2_lib.baseboard_fab2(sch_1):m_d_dq(11)"
				( attribute "CDS_PHYS_NET_NAME" "M_D_DQ<11>"
					( Origin gPackager )
				)
				( attribute "PNN" "M_D_DQ<11>"
					( Origin gPackager )
				)
				( objectStatus "M_D_DQ<11>" )
			)
			( signal "@baseboard_fab2_lib.baseboard_fab2(sch_1):m_d_dq(12)"
				( attribute "CDS_PHYS_NET_NAME" "M_D_DQ<12>"
					( Origin gPackager )
				)
				( attribute "PNN" "M_D_DQ<12>"
					( Origin gPackager )
				)
				( objectStatus "M_D_DQ<12>" )
			)
			( signal "@baseboard_fab2_lib.baseboard_fab2(sch_1):m_d_dq(13)"
				( attribute "CDS_PHYS_NET_NAME" "M_D_DQ<13>"
					( Origin gPackager )
				)
				( attribute "PNN" "M_D_DQ<13>"
					( Origin gPackager )
				)
				( objectStatus "M_D_DQ<13>" )
			)
			( signal "@baseboard_fab2_lib.baseboard_fab2(sch_1):m_d_dq(14)"
				( attribute "CDS_PHYS_NET_NAME" "M_D_DQ<14>"
					( Origin gPackager )
				)
				( attribute "PNN" "M_D_DQ<14>"
					( Origin gPackager )
				)
				( objectStatus "M_D_DQ<14>" )
			)
			( signal "@baseboard_fab2_lib.baseboard_fab2(sch_1):m_d_dq(15)"
				( attribute "CDS_PHYS_NET_NAME" "M_D_DQ<15>"
					( Origin gPackager )
				)
				( attribute "PNN" "M_D_DQ<15>"
					( Origin gPackager )
				)
				( objectStatus "M_D_DQ<15>" )
			)
			( signal "@baseboard_fab2_lib.baseboard_fab2(sch_1):m_d_dq(16)"
				( attribute "CDS_PHYS_NET_NAME" "M_D_DQ<16>"
					( Origin gPackager )
				)
				( attribute "PNN" "M_D_DQ<16>"
					( Origin gPackager )
				)
				( objectStatus "M_D_DQ<16>" )
			)
			( signal "@baseboard_fab2_lib.baseboard_fab2(sch_1):m_d_dq(17)"
				( attribute "CDS_PHYS_NET_NAME" "M_D_DQ<17>"
					( Origin gPackager )
				)
				( attribute "PNN" "M_D_DQ<17>"
					( Origin gPackager )
				)
				( objectStatus "M_D_DQ<17>" )
			)
			( signal "@baseboard_fab2_lib.baseboard_fab2(sch_1):m_d_dq(18)"
				( attribute "CDS_PHYS_NET_NAME" "M_D_DQ<18>"
					( Origin gPackager )
				)
				( attribute "PNN" "M_D_DQ<18>"
					( Origin gPackager )
				)
				( objectStatus "M_D_DQ<18>" )
			)
			( signal "@baseboard_fab2_lib.baseboard_fab2(sch_1):m_d_dq(19)"
				( attribute "CDS_PHYS_NET_NAME" "M_D_DQ<19>"
					( Origin gPackager )
				)
				( attribute "PNN" "M_D_DQ<19>"
					( Origin gPackager )
				)
				( objectStatus "M_D_DQ<19>" )
			)
			( signal "@baseboard_fab2_lib.baseboard_fab2(sch_1):m_d_dq(20)"
				( attribute "CDS_PHYS_NET_NAME" "M_D_DQ<20>"
					( Origin gPackager )
				)
				( attribute "PNN" "M_D_DQ<20>"
					( Origin gPackager )
				)
				( objectStatus "M_D_DQ<20>" )
			)
			( signal "@baseboard_fab2_lib.baseboard_fab2(sch_1):m_d_dq(21)"
				( attribute "CDS_PHYS_NET_NAME" "M_D_DQ<21>"
					( Origin gPackager )
				)
				( attribute "PNN" "M_D_DQ<21>"
					( Origin gPackager )
				)
				( objectStatus "M_D_DQ<21>" )
			)
			( signal "@baseboard_fab2_lib.baseboard_fab2(sch_1):m_d_dq(22)"
				( attribute "CDS_PHYS_NET_NAME" "M_D_DQ<22>"
					( Origin gPackager )
				)
				( attribute "PNN" "M_D_DQ<22>"
					( Origin gPackager )
				)
				( objectStatus "M_D_DQ<22>" )
			)
			( signal "@baseboard_fab2_lib.baseboard_fab2(sch_1):m_d_dq(23)"
				( attribute "CDS_PHYS_NET_NAME" "M_D_DQ<23>"
					( Origin gPackager )
				)
				( attribute "PNN" "M_D_DQ<23>"
					( Origin gPackager )
				)
				( objectStatus "M_D_DQ<23>" )
			)
			( signal "@baseboard_fab2_lib.baseboard_fab2(sch_1):m_d_dq(24)"
				( attribute "CDS_PHYS_NET_NAME" "M_D_DQ<24>"
					( Origin gPackager )
				)
				( attribute "PNN" "M_D_DQ<24>"
					( Origin gPackager )
				)
				( objectStatus "M_D_DQ<24>" )
			)
			( signal "@baseboard_fab2_lib.baseboard_fab2(sch_1):m_d_dq(25)"
				( attribute "CDS_PHYS_NET_NAME" "M_D_DQ<25>"
					( Origin gPackager )
				)
				( attribute "PNN" "M_D_DQ<25>"
					( Origin gPackager )
				)
				( objectStatus "M_D_DQ<25>" )
			)
			( signal "@baseboard_fab2_lib.baseboard_fab2(sch_1):m_d_dq(26)"
				( attribute "CDS_PHYS_NET_NAME" "M_D_DQ<26>"
					( Origin gPackager )
				)
				( attribute "PNN" "M_D_DQ<26>"
					( Origin gPackager )
				)
				( objectStatus "M_D_DQ<26>" )
			)
			( signal "@baseboard_fab2_lib.baseboard_fab2(sch_1):m_d_dq(27)"
				( attribute "CDS_PHYS_NET_NAME" "M_D_DQ<27>"
					( Origin gPackager )
				)
				( attribute "PNN" "M_D_DQ<27>"
					( Origin gPackager )
				)
				( objectStatus "M_D_DQ<27>" )
			)
			( signal "@baseboard_fab2_lib.baseboard_fab2(sch_1):m_d_dq(28)"
				( attribute "CDS_PHYS_NET_NAME" "M_D_DQ<28>"
					( Origin gPackager )
				)
				( attribute "PNN" "M_D_DQ<28>"
					( Origin gPackager )
				)
				( objectStatus "M_D_DQ<28>" )
			)
			( signal "@baseboard_fab2_lib.baseboard_fab2(sch_1):m_d_dq(29)"
				( attribute "CDS_PHYS_NET_NAME" "M_D_DQ<29>"
					( Origin gPackager )
				)
				( attribute "PNN" "M_D_DQ<29>"
					( Origin gPackager )
				)
				( objectStatus "M_D_DQ<29>" )
			)
			( signal "@baseboard_fab2_lib.baseboard_fab2(sch_1):m_d_dq(30)"
				( attribute "CDS_PHYS_NET_NAME" "M_D_DQ<30>"
					( Origin gPackager )
				)
				( attribute "PNN" "M_D_DQ<30>"
					( Origin gPackager )
				)
				( objectStatus "M_D_DQ<30>" )
			)
			( signal "@baseboard_fab2_lib.baseboard_fab2(sch_1):m_d_dq(31)"
				( attribute "CDS_PHYS_NET_NAME" "M_D_DQ<31>"
					( Origin gPackager )
				)
				( attribute "PNN" "M_D_DQ<31>"
					( Origin gPackager )
				)
				( objectStatus "M_D_DQ<31>" )
			)
			( signal "@baseboard_fab2_lib.baseboard_fab2(sch_1):m_d_dq(32)"
				( attribute "CDS_PHYS_NET_NAME" "M_D_DQ<32>"
					( Origin gPackager )
				)
				( attribute "PNN" "M_D_DQ<32>"
					( Origin gPackager )
				)
				( objectStatus "M_D_DQ<32>" )
			)
			( signal "@baseboard_fab2_lib.baseboard_fab2(sch_1):m_d_dq(33)"
				( attribute "CDS_PHYS_NET_NAME" "M_D_DQ<33>"
					( Origin gPackager )
				)
				( attribute "PNN" "M_D_DQ<33>"
					( Origin gPackager )
				)
				( objectStatus "M_D_DQ<33>" )
			)
			( signal "@baseboard_fab2_lib.baseboard_fab2(sch_1):m_d_dq(34)"
				( attribute "CDS_PHYS_NET_NAME" "M_D_DQ<34>"
					( Origin gPackager )
				)
				( attribute "PNN" "M_D_DQ<34>"
					( Origin gPackager )
				)
				( objectStatus "M_D_DQ<34>" )
			)
			( signal "@baseboard_fab2_lib.baseboard_fab2(sch_1):m_d_dq(35)"
				( attribute "CDS_PHYS_NET_NAME" "M_D_DQ<35>"
					( Origin gPackager )
				)
				( attribute "PNN" "M_D_DQ<35>"
					( Origin gPackager )
				)
				( objectStatus "M_D_DQ<35>" )
			)
			( signal "@baseboard_fab2_lib.baseboard_fab2(sch_1):m_d_dq(36)"
				( attribute "CDS_PHYS_NET_NAME" "M_D_DQ<36>"
					( Origin gPackager )
				)
				( attribute "PNN" "M_D_DQ<36>"
					( Origin gPackager )
				)
				( objectStatus "M_D_DQ<36>" )
			)
			( signal "@baseboard_fab2_lib.baseboard_fab2(sch_1):m_d_dq(37)"
				( attribute "CDS_PHYS_NET_NAME" "M_D_DQ<37>"
					( Origin gPackager )
				)
				( attribute "PNN" "M_D_DQ<37>"
					( Origin gPackager )
				)
				( objectStatus "M_D_DQ<37>" )
			)
			( signal "@baseboard_fab2_lib.baseboard_fab2(sch_1):m_d_dq(38)"
				( attribute "CDS_PHYS_NET_NAME" "M_D_DQ<38>"
					( Origin gPackager )
				)
				( attribute "PNN" "M_D_DQ<38>"
					( Origin gPackager )
				)
				( objectStatus "M_D_DQ<38>" )
			)
			( signal "@baseboard_fab2_lib.baseboard_fab2(sch_1):m_d_dq(39)"
				( attribute "CDS_PHYS_NET_NAME" "M_D_DQ<39>"
					( Origin gPackager )
				)
				( attribute "PNN" "M_D_DQ<39>"
					( Origin gPackager )
				)
				( objectStatus "M_D_DQ<39>" )
			)
			( signal "@baseboard_fab2_lib.baseboard_fab2(sch_1):m_d_dq(40)"
				( attribute "CDS_PHYS_NET_NAME" "M_D_DQ<40>"
					( Origin gPackager )
				)
				( attribute "PNN" "M_D_DQ<40>"
					( Origin gPackager )
				)
				( objectStatus "M_D_DQ<40>" )
			)
			( signal "@baseboard_fab2_lib.baseboard_fab2(sch_1):m_d_dq(41)"
				( attribute "CDS_PHYS_NET_NAME" "M_D_DQ<41>"
					( Origin gPackager )
				)
				( attribute "PNN" "M_D_DQ<41>"
					( Origin gPackager )
				)
				( objectStatus "M_D_DQ<41>" )
			)
			( signal "@baseboard_fab2_lib.baseboard_fab2(sch_1):m_d_dq(42)"
				( attribute "CDS_PHYS_NET_NAME" "M_D_DQ<42>"
					( Origin gPackager )
				)
				( attribute "PNN" "M_D_DQ<42>"
					( Origin gPackager )
				)
				( objectStatus "M_D_DQ<42>" )
			)
			( signal "@baseboard_fab2_lib.baseboard_fab2(sch_1):m_d_dq(43)"
				( attribute "CDS_PHYS_NET_NAME" "M_D_DQ<43>"
					( Origin gPackager )
				)
				( attribute "PNN" "M_D_DQ<43>"
					( Origin gPackager )
				)
				( objectStatus "M_D_DQ<43>" )
			)
			( signal "@baseboard_fab2_lib.baseboard_fab2(sch_1):m_d_dq(44)"
				( attribute "CDS_PHYS_NET_NAME" "M_D_DQ<44>"
					( Origin gPackager )
				)
				( attribute "PNN" "M_D_DQ<44>"
					( Origin gPackager )
				)
				( objectStatus "M_D_DQ<44>" )
			)
			( signal "@baseboard_fab2_lib.baseboard_fab2(sch_1):m_d_dq(45)"
				( attribute "CDS_PHYS_NET_NAME" "M_D_DQ<45>"
					( Origin gPackager )
				)
				( attribute "PNN" "M_D_DQ<45>"
					( Origin gPackager )
				)
				( objectStatus "M_D_DQ<45>" )
			)
			( signal "@baseboard_fab2_lib.baseboard_fab2(sch_1):m_d_dq(46)"
				( attribute "CDS_PHYS_NET_NAME" "M_D_DQ<46>"
					( Origin gPackager )
				)
				( attribute "PNN" "M_D_DQ<46>"
					( Origin gPackager )
				)
				( objectStatus "M_D_DQ<46>" )
			)
			( signal "@baseboard_fab2_lib.baseboard_fab2(sch_1):m_d_dq(47)"
				( attribute "CDS_PHYS_NET_NAME" "M_D_DQ<47>"
					( Origin gPackager )
				)
				( attribute "PNN" "M_D_DQ<47>"
					( Origin gPackager )
				)
				( objectStatus "M_D_DQ<47>" )
			)
			( signal "@baseboard_fab2_lib.baseboard_fab2(sch_1):m_d_dq(48)"
				( attribute "CDS_PHYS_NET_NAME" "M_D_DQ<48>"
					( Origin gPackager )
				)
				( attribute "PNN" "M_D_DQ<48>"
					( Origin gPackager )
				)
				( objectStatus "M_D_DQ<48>" )
			)
			( signal "@baseboard_fab2_lib.baseboard_fab2(sch_1):m_d_dq(49)"
				( attribute "CDS_PHYS_NET_NAME" "M_D_DQ<49>"
					( Origin gPackager )
				)
				( attribute "PNN" "M_D_DQ<49>"
					( Origin gPackager )
				)
				( objectStatus "M_D_DQ<49>" )
			)
			( signal "@baseboard_fab2_lib.baseboard_fab2(sch_1):m_d_dq(50)"
				( attribute "CDS_PHYS_NET_NAME" "M_D_DQ<50>"
					( Origin gPackager )
				)
				( attribute "PNN" "M_D_DQ<50>"
					( Origin gPackager )
				)
				( objectStatus "M_D_DQ<50>" )
			)
			( signal "@baseboard_fab2_lib.baseboard_fab2(sch_1):m_d_dq(51)"
				( attribute "CDS_PHYS_NET_NAME" "M_D_DQ<51>"
					( Origin gPackager )
				)
				( attribute "PNN" "M_D_DQ<51>"
					( Origin gPackager )
				)
				( objectStatus "M_D_DQ<51>" )
			)
			( signal "@baseboard_fab2_lib.baseboard_fab2(sch_1):m_d_dq(52)"
				( attribute "CDS_PHYS_NET_NAME" "M_D_DQ<52>"
					( Origin gPackager )
				)
				( attribute "PNN" "M_D_DQ<52>"
					( Origin gPackager )
				)
				( objectStatus "M_D_DQ<52>" )
			)
			( signal "@baseboard_fab2_lib.baseboard_fab2(sch_1):m_d_dq(53)"
				( attribute "CDS_PHYS_NET_NAME" "M_D_DQ<53>"
					( Origin gPackager )
				)
				( attribute "PNN" "M_D_DQ<53>"
					( Origin gPackager )
				)
				( objectStatus "M_D_DQ<53>" )
			)
			( signal "@baseboard_fab2_lib.baseboard_fab2(sch_1):m_d_dq(54)"
				( attribute "CDS_PHYS_NET_NAME" "M_D_DQ<54>"
					( Origin gPackager )
				)
				( attribute "PNN" "M_D_DQ<54>"
					( Origin gPackager )
				)
				( objectStatus "M_D_DQ<54>" )
			)
			( signal "@baseboard_fab2_lib.baseboard_fab2(sch_1):m_d_dq(55)"
				( attribute "CDS_PHYS_NET_NAME" "M_D_DQ<55>"
					( Origin gPackager )
				)
				( attribute "PNN" "M_D_DQ<55>"
					( Origin gPackager )
				)
				( objectStatus "M_D_DQ<55>" )
			)
			( signal "@baseboard_fab2_lib.baseboard_fab2(sch_1):m_d_dq(56)"
				( attribute "CDS_PHYS_NET_NAME" "M_D_DQ<56>"
					( Origin gPackager )
				)
				( attribute "PNN" "M_D_DQ<56>"
					( Origin gPackager )
				)
				( objectStatus "M_D_DQ<56>" )
			)
			( signal "@baseboard_fab2_lib.baseboard_fab2(sch_1):m_d_dq(57)"
				( attribute "CDS_PHYS_NET_NAME" "M_D_DQ<57>"
					( Origin gPackager )
				)
				( attribute "PNN" "M_D_DQ<57>"
					( Origin gPackager )
				)
				( objectStatus "M_D_DQ<57>" )
			)
			( signal "@baseboard_fab2_lib.baseboard_fab2(sch_1):m_d_dq(58)"
				( attribute "CDS_PHYS_NET_NAME" "M_D_DQ<58>"
					( Origin gPackager )
				)
				( attribute "PNN" "M_D_DQ<58>"
					( Origin gPackager )
				)
				( objectStatus "M_D_DQ<58>" )
			)
			( signal "@baseboard_fab2_lib.baseboard_fab2(sch_1):m_d_dq(59)"
				( attribute "CDS_PHYS_NET_NAME" "M_D_DQ<59>"
					( Origin gPackager )
				)
				( attribute "PNN" "M_D_DQ<59>"
					( Origin gPackager )
				)
				( objectStatus "M_D_DQ<59>" )
			)
			( signal "@baseboard_fab2_lib.baseboard_fab2(sch_1):m_d_dq(60)"
				( attribute "CDS_PHYS_NET_NAME" "M_D_DQ<60>"
					( Origin gPackager )
				)
				( attribute "PNN" "M_D_DQ<60>"
					( Origin gPackager )
				)
				( objectStatus "M_D_DQ<60>" )
			)
			( signal "@baseboard_fab2_lib.baseboard_fab2(sch_1):m_d_dq(61)"
				( attribute "CDS_PHYS_NET_NAME" "M_D_DQ<61>"
					( Origin gPackager )
				)
				( attribute "PNN" "M_D_DQ<61>"
					( Origin gPackager )
				)
				( objectStatus "M_D_DQ<61>" )
			)
			( signal "@baseboard_fab2_lib.baseboard_fab2(sch_1):m_d_dq(62)"
				( attribute "CDS_PHYS_NET_NAME" "M_D_DQ<62>"
					( Origin gPackager )
				)
				( attribute "PNN" "M_D_DQ<62>"
					( Origin gPackager )
				)
				( objectStatus "M_D_DQ<62>" )
			)
			( signal "@baseboard_fab2_lib.baseboard_fab2(sch_1):m_d_dq(63)"
				( attribute "CDS_PHYS_NET_NAME" "M_D_DQ<63>"
					( Origin gPackager )
				)
				( attribute "PNN" "M_D_DQ<63>"
					( Origin gPackager )
				)
				( objectStatus "M_D_DQ<63>" )
			)
			( signal "@baseboard_fab2_lib.baseboard_fab2(sch_1):m_d_dqs_dn(0)"
				( attribute "CDS_PHYS_NET_NAME" "M_D_DQS_DN<0>"
					( Origin gPackager )
				)
				( attribute "PNN" "M_D_DQS_DN<0>"
					( Origin gPackager )
				)
				( objectStatus "M_D_DQS_DN<0>" )
			)
			( signal "@baseboard_fab2_lib.baseboard_fab2(sch_1):m_d_dqs_dn(1)"
				( attribute "CDS_PHYS_NET_NAME" "M_D_DQS_DN<1>"
					( Origin gPackager )
				)
				( attribute "PNN" "M_D_DQS_DN<1>"
					( Origin gPackager )
				)
				( objectStatus "M_D_DQS_DN<1>" )
			)
			( signal "@baseboard_fab2_lib.baseboard_fab2(sch_1):m_d_dqs_dn(2)"
				( attribute "CDS_PHYS_NET_NAME" "M_D_DQS_DN<2>"
					( Origin gPackager )
				)
				( attribute "PNN" "M_D_DQS_DN<2>"
					( Origin gPackager )
				)
				( objectStatus "M_D_DQS_DN<2>" )
			)
			( signal "@baseboard_fab2_lib.baseboard_fab2(sch_1):m_d_dqs_dn(3)"
				( attribute "CDS_PHYS_NET_NAME" "M_D_DQS_DN<3>"
					( Origin gPackager )
				)
				( attribute "PNN" "M_D_DQS_DN<3>"
					( Origin gPackager )
				)
				( objectStatus "M_D_DQS_DN<3>" )
			)
			( signal "@baseboard_fab2_lib.baseboard_fab2(sch_1):m_d_dqs_dn(4)"
				( attribute "CDS_PHYS_NET_NAME" "M_D_DQS_DN<4>"
					( Origin gPackager )
				)
				( attribute "PNN" "M_D_DQS_DN<4>"
					( Origin gPackager )
				)
				( objectStatus "M_D_DQS_DN<4>" )
			)
			( signal "@baseboard_fab2_lib.baseboard_fab2(sch_1):m_d_dqs_dn(5)"
				( attribute "CDS_PHYS_NET_NAME" "M_D_DQS_DN<5>"
					( Origin gPackager )
				)
				( attribute "PNN" "M_D_DQS_DN<5>"
					( Origin gPackager )
				)
				( objectStatus "M_D_DQS_DN<5>" )
			)
			( signal "@baseboard_fab2_lib.baseboard_fab2(sch_1):m_d_dqs_dn(6)"
				( attribute "CDS_PHYS_NET_NAME" "M_D_DQS_DN<6>"
					( Origin gPackager )
				)
				( attribute "PNN" "M_D_DQS_DN<6>"
					( Origin gPackager )
				)
				( objectStatus "M_D_DQS_DN<6>" )
			)
			( signal "@baseboard_fab2_lib.baseboard_fab2(sch_1):m_d_dqs_dn(7)"
				( attribute "CDS_PHYS_NET_NAME" "M_D_DQS_DN<7>"
					( Origin gPackager )
				)
				( attribute "PNN" "M_D_DQS_DN<7>"
					( Origin gPackager )
				)
				( objectStatus "M_D_DQS_DN<7>" )
			)
			( signal "@baseboard_fab2_lib.baseboard_fab2(sch_1):m_d_dqs_dn(8)"
				( attribute "CDS_PHYS_NET_NAME" "M_D_DQS_DN<8>"
					( Origin gPackager )
				)
				( attribute "PNN" "M_D_DQS_DN<8>"
					( Origin gPackager )
				)
				( objectStatus "M_D_DQS_DN<8>" )
			)
			( signal "@baseboard_fab2_lib.baseboard_fab2(sch_1):m_d_dqs_dn(9)"
				( attribute "CDS_PHYS_NET_NAME" "M_D_DQS_DN<9>"
					( Origin gPackager )
				)
				( attribute "PNN" "M_D_DQS_DN<9>"
					( Origin gPackager )
				)
				( objectStatus "M_D_DQS_DN<9>" )
			)
			( signal "@baseboard_fab2_lib.baseboard_fab2(sch_1):m_d_dqs_dn(10)"
				( attribute "CDS_PHYS_NET_NAME" "M_D_DQS_DN<10>"
					( Origin gPackager )
				)
				( attribute "PNN" "M_D_DQS_DN<10>"
					( Origin gPackager )
				)
				( objectStatus "M_D_DQS_DN<10>" )
			)
			( signal "@baseboard_fab2_lib.baseboard_fab2(sch_1):m_d_dqs_dn(11)"
				( attribute "CDS_PHYS_NET_NAME" "M_D_DQS_DN<11>"
					( Origin gPackager )
				)
				( attribute "PNN" "M_D_DQS_DN<11>"
					( Origin gPackager )
				)
				( objectStatus "M_D_DQS_DN<11>" )
			)
			( signal "@baseboard_fab2_lib.baseboard_fab2(sch_1):m_d_dqs_dn(12)"
				( attribute "CDS_PHYS_NET_NAME" "M_D_DQS_DN<12>"
					( Origin gPackager )
				)
				( attribute "PNN" "M_D_DQS_DN<12>"
					( Origin gPackager )
				)
				( objectStatus "M_D_DQS_DN<12>" )
			)
			( signal "@baseboard_fab2_lib.baseboard_fab2(sch_1):m_d_dqs_dn(13)"
				( attribute "CDS_PHYS_NET_NAME" "M_D_DQS_DN<13>"
					( Origin gPackager )
				)
				( attribute "PNN" "M_D_DQS_DN<13>"
					( Origin gPackager )
				)
				( objectStatus "M_D_DQS_DN<13>" )
			)
			( signal "@baseboard_fab2_lib.baseboard_fab2(sch_1):m_d_dqs_dn(14)"
				( attribute "CDS_PHYS_NET_NAME" "M_D_DQS_DN<14>"
					( Origin gPackager )
				)
				( attribute "PNN" "M_D_DQS_DN<14>"
					( Origin gPackager )
				)
				( objectStatus "M_D_DQS_DN<14>" )
			)
			( signal "@baseboard_fab2_lib.baseboard_fab2(sch_1):m_d_dqs_dn(15)"
				( attribute "CDS_PHYS_NET_NAME" "M_D_DQS_DN<15>"
					( Origin gPackager )
				)
				( attribute "PNN" "M_D_DQS_DN<15>"
					( Origin gPackager )
				)
				( objectStatus "M_D_DQS_DN<15>" )
			)
			( signal "@baseboard_fab2_lib.baseboard_fab2(sch_1):m_d_dqs_dn(16)"
				( attribute "CDS_PHYS_NET_NAME" "M_D_DQS_DN<16>"
					( Origin gPackager )
				)
				( attribute "PNN" "M_D_DQS_DN<16>"
					( Origin gPackager )
				)
				( objectStatus "M_D_DQS_DN<16>" )
			)
			( signal "@baseboard_fab2_lib.baseboard_fab2(sch_1):m_d_dqs_dn(17)"
				( attribute "CDS_PHYS_NET_NAME" "M_D_DQS_DN<17>"
					( Origin gPackager )
				)
				( attribute "PNN" "M_D_DQS_DN<17>"
					( Origin gPackager )
				)
				( objectStatus "M_D_DQS_DN<17>" )
			)
			( signal "@baseboard_fab2_lib.baseboard_fab2(sch_1):m_d_dqs_dp(0)"
				( attribute "CDS_PHYS_NET_NAME" "M_D_DQS_DP<0>"
					( Origin gPackager )
				)
				( attribute "PNN" "M_D_DQS_DP<0>"
					( Origin gPackager )
				)
				( objectStatus "M_D_DQS_DP<0>" )
			)
			( signal "@baseboard_fab2_lib.baseboard_fab2(sch_1):m_d_dqs_dp(1)"
				( attribute "CDS_PHYS_NET_NAME" "M_D_DQS_DP<1>"
					( Origin gPackager )
				)
				( attribute "PNN" "M_D_DQS_DP<1>"
					( Origin gPackager )
				)
				( objectStatus "M_D_DQS_DP<1>" )
			)
			( signal "@baseboard_fab2_lib.baseboard_fab2(sch_1):m_d_dqs_dp(2)"
				( attribute "CDS_PHYS_NET_NAME" "M_D_DQS_DP<2>"
					( Origin gPackager )
				)
				( attribute "PNN" "M_D_DQS_DP<2>"
					( Origin gPackager )
				)
				( objectStatus "M_D_DQS_DP<2>" )
			)
			( signal "@baseboard_fab2_lib.baseboard_fab2(sch_1):m_d_dqs_dp(3)"
				( attribute "CDS_PHYS_NET_NAME" "M_D_DQS_DP<3>"
					( Origin gPackager )
				)
				( attribute "PNN" "M_D_DQS_DP<3>"
					( Origin gPackager )
				)
				( objectStatus "M_D_DQS_DP<3>" )
			)
			( signal "@baseboard_fab2_lib.baseboard_fab2(sch_1):m_d_dqs_dp(4)"
				( attribute "CDS_PHYS_NET_NAME" "M_D_DQS_DP<4>"
					( Origin gPackager )
				)
				( attribute "PNN" "M_D_DQS_DP<4>"
					( Origin gPackager )
				)
				( objectStatus "M_D_DQS_DP<4>" )
			)
			( signal "@baseboard_fab2_lib.baseboard_fab2(sch_1):m_d_dqs_dp(5)"
				( attribute "CDS_PHYS_NET_NAME" "M_D_DQS_DP<5>"
					( Origin gPackager )
				)
				( attribute "PNN" "M_D_DQS_DP<5>"
					( Origin gPackager )
				)
				( objectStatus "M_D_DQS_DP<5>" )
			)
			( signal "@baseboard_fab2_lib.baseboard_fab2(sch_1):m_d_dqs_dp(6)"
				( attribute "CDS_PHYS_NET_NAME" "M_D_DQS_DP<6>"
					( Origin gPackager )
				)
				( attribute "PNN" "M_D_DQS_DP<6>"
					( Origin gPackager )
				)
				( objectStatus "M_D_DQS_DP<6>" )
			)
			( signal "@baseboard_fab2_lib.baseboard_fab2(sch_1):m_d_dqs_dp(7)"
				( attribute "CDS_PHYS_NET_NAME" "M_D_DQS_DP<7>"
					( Origin gPackager )
				)
				( attribute "PNN" "M_D_DQS_DP<7>"
					( Origin gPackager )
				)
				( objectStatus "M_D_DQS_DP<7>" )
			)
			( signal "@baseboard_fab2_lib.baseboard_fab2(sch_1):m_d_dqs_dp(8)"
				( attribute "CDS_PHYS_NET_NAME" "M_D_DQS_DP<8>"
					( Origin gPackager )
				)
				( attribute "PNN" "M_D_DQS_DP<8>"
					( Origin gPackager )
				)
				( objectStatus "M_D_DQS_DP<8>" )
			)
			( signal "@baseboard_fab2_lib.baseboard_fab2(sch_1):m_d_dqs_dp(9)"
				( attribute "CDS_PHYS_NET_NAME" "M_D_DQS_DP<9>"
					( Origin gPackager )
				)
				( attribute "PNN" "M_D_DQS_DP<9>"
					( Origin gPackager )
				)
				( objectStatus "M_D_DQS_DP<9>" )
			)
			( signal "@baseboard_fab2_lib.baseboard_fab2(sch_1):m_d_dqs_dp(10)"
				( attribute "CDS_PHYS_NET_NAME" "M_D_DQS_DP<10>"
					( Origin gPackager )
				)
				( attribute "PNN" "M_D_DQS_DP<10>"
					( Origin gPackager )
				)
				( objectStatus "M_D_DQS_DP<10>" )
			)
			( signal "@baseboard_fab2_lib.baseboard_fab2(sch_1):m_d_dqs_dp(11)"
				( attribute "CDS_PHYS_NET_NAME" "M_D_DQS_DP<11>"
					( Origin gPackager )
				)
				( attribute "PNN" "M_D_DQS_DP<11>"
					( Origin gPackager )
				)
				( objectStatus "M_D_DQS_DP<11>" )
			)
			( signal "@baseboard_fab2_lib.baseboard_fab2(sch_1):m_d_dqs_dp(12)"
				( attribute "CDS_PHYS_NET_NAME" "M_D_DQS_DP<12>"
					( Origin gPackager )
				)
				( attribute "PNN" "M_D_DQS_DP<12>"
					( Origin gPackager )
				)
				( objectStatus "M_D_DQS_DP<12>" )
			)
			( signal "@baseboard_fab2_lib.baseboard_fab2(sch_1):m_d_dqs_dp(13)"
				( attribute "CDS_PHYS_NET_NAME" "M_D_DQS_DP<13>"
					( Origin gPackager )
				)
				( attribute "PNN" "M_D_DQS_DP<13>"
					( Origin gPackager )
				)
				( objectStatus "M_D_DQS_DP<13>" )
			)
			( signal "@baseboard_fab2_lib.baseboard_fab2(sch_1):m_d_dqs_dp(14)"
				( attribute "CDS_PHYS_NET_NAME" "M_D_DQS_DP<14>"
					( Origin gPackager )
				)
				( attribute "PNN" "M_D_DQS_DP<14>"
					( Origin gPackager )
				)
				( objectStatus "M_D_DQS_DP<14>" )
			)
			( signal "@baseboard_fab2_lib.baseboard_fab2(sch_1):m_d_dqs_dp(15)"
				( attribute "CDS_PHYS_NET_NAME" "M_D_DQS_DP<15>"
					( Origin gPackager )
				)
				( attribute "PNN" "M_D_DQS_DP<15>"
					( Origin gPackager )
				)
				( objectStatus "M_D_DQS_DP<15>" )
			)
			( signal "@baseboard_fab2_lib.baseboard_fab2(sch_1):m_d_dqs_dp(16)"
				( attribute "CDS_PHYS_NET_NAME" "M_D_DQS_DP<16>"
					( Origin gPackager )
				)
				( attribute "PNN" "M_D_DQS_DP<16>"
					( Origin gPackager )
				)
				( objectStatus "M_D_DQS_DP<16>" )
			)
			( signal "@baseboard_fab2_lib.baseboard_fab2(sch_1):m_d_dqs_dp(17)"
				( attribute "CDS_PHYS_NET_NAME" "M_D_DQS_DP<17>"
					( Origin gPackager )
				)
				( attribute "PNN" "M_D_DQS_DP<17>"
					( Origin gPackager )
				)
				( objectStatus "M_D_DQS_DP<17>" )
			)
			( signal "@baseboard_fab2_lib.baseboard_fab2(sch_1):m_d_ecc(0)"
				( attribute "CDS_PHYS_NET_NAME" "M_D_ECC<0>"
					( Origin gPackager )
				)
				( attribute "PNN" "M_D_ECC<0>"
					( Origin gPackager )
				)
				( objectStatus "M_D_ECC<0>" )
			)
			( signal "@baseboard_fab2_lib.baseboard_fab2(sch_1):m_d_ecc(1)"
				( attribute "CDS_PHYS_NET_NAME" "M_D_ECC<1>"
					( Origin gPackager )
				)
				( attribute "PNN" "M_D_ECC<1>"
					( Origin gPackager )
				)
				( objectStatus "M_D_ECC<1>" )
			)
			( signal "@baseboard_fab2_lib.baseboard_fab2(sch_1):m_d_ecc(2)"
				( attribute "CDS_PHYS_NET_NAME" "M_D_ECC<2>"
					( Origin gPackager )
				)
				( attribute "PNN" "M_D_ECC<2>"
					( Origin gPackager )
				)
				( objectStatus "M_D_ECC<2>" )
			)
			( signal "@baseboard_fab2_lib.baseboard_fab2(sch_1):m_d_ecc(3)"
				( attribute "CDS_PHYS_NET_NAME" "M_D_ECC<3>"
					( Origin gPackager )
				)
				( attribute "PNN" "M_D_ECC<3>"
					( Origin gPackager )
				)
				( objectStatus "M_D_ECC<3>" )
			)
			( signal "@baseboard_fab2_lib.baseboard_fab2(sch_1):m_d_ecc(4)"
				( attribute "CDS_PHYS_NET_NAME" "M_D_ECC<4>"
					( Origin gPackager )
				)
				( attribute "PNN" "M_D_ECC<4>"
					( Origin gPackager )
				)
				( objectStatus "M_D_ECC<4>" )
			)
			( signal "@baseboard_fab2_lib.baseboard_fab2(sch_1):m_d_ecc(5)"
				( attribute "CDS_PHYS_NET_NAME" "M_D_ECC<5>"
					( Origin gPackager )
				)
				( attribute "PNN" "M_D_ECC<5>"
					( Origin gPackager )
				)
				( objectStatus "M_D_ECC<5>" )
			)
			( signal "@baseboard_fab2_lib.baseboard_fab2(sch_1):m_d_ecc(6)"
				( attribute "CDS_PHYS_NET_NAME" "M_D_ECC<6>"
					( Origin gPackager )
				)
				( attribute "PNN" "M_D_ECC<6>"
					( Origin gPackager )
				)
				( objectStatus "M_D_ECC<6>" )
			)
			( signal "@baseboard_fab2_lib.baseboard_fab2(sch_1):m_d_ecc(7)"
				( attribute "CDS_PHYS_NET_NAME" "M_D_ECC<7>"
					( Origin gPackager )
				)
				( attribute "PNN" "M_D_ECC<7>"
					( Origin gPackager )
				)
				( objectStatus "M_D_ECC<7>" )
			)
			( signal "@baseboard_fab2_lib.baseboard_fab2(sch_1):m_d_ma(0)"
				( attribute "CDS_PHYS_NET_NAME" "M_D_MA<0>"
					( Origin gPackager )
				)
				( attribute "PNN" "M_D_MA<0>"
					( Origin gPackager )
				)
				( objectStatus "M_D_MA<0>" )
			)
			( signal "@baseboard_fab2_lib.baseboard_fab2(sch_1):m_d_ma(1)"
				( attribute "CDS_PHYS_NET_NAME" "M_D_MA<1>"
					( Origin gPackager )
				)
				( attribute "PNN" "M_D_MA<1>"
					( Origin gPackager )
				)
				( objectStatus "M_D_MA<1>" )
			)
			( signal "@baseboard_fab2_lib.baseboard_fab2(sch_1):m_d_ma(2)"
				( attribute "CDS_PHYS_NET_NAME" "M_D_MA<2>"
					( Origin gPackager )
				)
				( attribute "PNN" "M_D_MA<2>"
					( Origin gPackager )
				)
				( objectStatus "M_D_MA<2>" )
			)
			( signal "@baseboard_fab2_lib.baseboard_fab2(sch_1):m_d_ma(3)"
				( attribute "CDS_PHYS_NET_NAME" "M_D_MA<3>"
					( Origin gPackager )
				)
				( attribute "PNN" "M_D_MA<3>"
					( Origin gPackager )
				)
				( objectStatus "M_D_MA<3>" )
			)
			( signal "@baseboard_fab2_lib.baseboard_fab2(sch_1):m_d_ma(4)"
				( attribute "CDS_PHYS_NET_NAME" "M_D_MA<4>"
					( Origin gPackager )
				)
				( attribute "PNN" "M_D_MA<4>"
					( Origin gPackager )
				)
				( objectStatus "M_D_MA<4>" )
			)
			( signal "@baseboard_fab2_lib.baseboard_fab2(sch_1):m_d_ma(5)"
				( attribute "CDS_PHYS_NET_NAME" "M_D_MA<5>"
					( Origin gPackager )
				)
				( attribute "PNN" "M_D_MA<5>"
					( Origin gPackager )
				)
				( objectStatus "M_D_MA<5>" )
			)
			( signal "@baseboard_fab2_lib.baseboard_fab2(sch_1):m_d_ma(6)"
				( attribute "CDS_PHYS_NET_NAME" "M_D_MA<6>"
					( Origin gPackager )
				)
				( attribute "PNN" "M_D_MA<6>"
					( Origin gPackager )
				)
				( objectStatus "M_D_MA<6>" )
			)
			( signal "@baseboard_fab2_lib.baseboard_fab2(sch_1):m_d_ma(7)"
				( attribute "CDS_PHYS_NET_NAME" "M_D_MA<7>"
					( Origin gPackager )
				)
				( attribute "PNN" "M_D_MA<7>"
					( Origin gPackager )
				)
				( objectStatus "M_D_MA<7>" )
			)
			( signal "@baseboard_fab2_lib.baseboard_fab2(sch_1):m_d_ma(8)"
				( attribute "CDS_PHYS_NET_NAME" "M_D_MA<8>"
					( Origin gPackager )
				)
				( attribute "PNN" "M_D_MA<8>"
					( Origin gPackager )
				)
				( objectStatus "M_D_MA<8>" )
			)
			( signal "@baseboard_fab2_lib.baseboard_fab2(sch_1):m_d_ma(9)"
				( attribute "CDS_PHYS_NET_NAME" "M_D_MA<9>"
					( Origin gPackager )
				)
				( attribute "PNN" "M_D_MA<9>"
					( Origin gPackager )
				)
				( objectStatus "M_D_MA<9>" )
			)
			( signal "@baseboard_fab2_lib.baseboard_fab2(sch_1):m_d_ma(10)"
				( attribute "CDS_PHYS_NET_NAME" "M_D_MA<10>"
					( Origin gPackager )
				)
				( attribute "PNN" "M_D_MA<10>"
					( Origin gPackager )
				)
				( objectStatus "M_D_MA<10>" )
			)
			( signal "@baseboard_fab2_lib.baseboard_fab2(sch_1):m_d_ma(11)"
				( attribute "CDS_PHYS_NET_NAME" "M_D_MA<11>"
					( Origin gPackager )
				)
				( attribute "PNN" "M_D_MA<11>"
					( Origin gPackager )
				)
				( objectStatus "M_D_MA<11>" )
			)
			( signal "@baseboard_fab2_lib.baseboard_fab2(sch_1):m_d_ma(12)"
				( attribute "CDS_PHYS_NET_NAME" "M_D_MA<12>"
					( Origin gPackager )
				)
				( attribute "PNN" "M_D_MA<12>"
					( Origin gPackager )
				)
				( objectStatus "M_D_MA<12>" )
			)
			( signal "@baseboard_fab2_lib.baseboard_fab2(sch_1):m_d_ma(13)"
				( attribute "CDS_PHYS_NET_NAME" "M_D_MA<13>"
					( Origin gPackager )
				)
				( attribute "PNN" "M_D_MA<13>"
					( Origin gPackager )
				)
				( objectStatus "M_D_MA<13>" )
			)
			( signal "@baseboard_fab2_lib.baseboard_fab2(sch_1):m_d_ma(14)"
				( attribute "CDS_PHYS_NET_NAME" "M_D_MA<14>"
					( Origin gPackager )
				)
				( attribute "PNN" "M_D_MA<14>"
					( Origin gPackager )
				)
				( objectStatus "M_D_MA<14>" )
			)
			( signal "@baseboard_fab2_lib.baseboard_fab2(sch_1):m_d_ma(15)"
				( attribute "CDS_PHYS_NET_NAME" "M_D_MA<15>"
					( Origin gPackager )
				)
				( attribute "PNN" "M_D_MA<15>"
					( Origin gPackager )
				)
				( objectStatus "M_D_MA<15>" )
			)
			( signal "@baseboard_fab2_lib.baseboard_fab2(sch_1):m_d_ma(16)"
				( attribute "CDS_PHYS_NET_NAME" "M_D_MA<16>"
					( Origin gPackager )
				)
				( attribute "PNN" "M_D_MA<16>"
					( Origin gPackager )
				)
				( objectStatus "M_D_MA<16>" )
			)
			( signal "@baseboard_fab2_lib.baseboard_fab2(sch_1):m_d_ma(17)"
				( attribute "CDS_PHYS_NET_NAME" "M_D_MA<17>"
					( Origin gPackager )
				)
				( attribute "PNN" "M_D_MA<17>"
					( Origin gPackager )
				)
				( objectStatus "M_D_MA<17>" )
			)
			( signal "@baseboard_fab2_lib.baseboard_fab2(sch_1):m_d_odt(0)"
				( attribute "CDS_PHYS_NET_NAME" "M_D_ODT<0>"
					( Origin gPackager )
				)
				( attribute "PNN" "M_D_ODT<0>"
					( Origin gPackager )
				)
				( objectStatus "M_D_ODT<0>" )
			)
			( signal "@baseboard_fab2_lib.baseboard_fab2(sch_1):m_d_odt(1)"
				( attribute "CDS_PHYS_NET_NAME" "M_D_ODT<1>"
					( Origin gPackager )
				)
				( attribute "PNN" "M_D_ODT<1>"
					( Origin gPackager )
				)
				( objectStatus "M_D_ODT<1>" )
			)
			( signal "@baseboard_fab2_lib.baseboard_fab2(sch_1):m_d_odt(2)"
				( attribute "CDS_PHYS_NET_NAME" "M_D_ODT<2>"
					( Origin gPackager )
				)
				( attribute "PNN" "M_D_ODT<2>"
					( Origin gPackager )
				)
				( objectStatus "M_D_ODT<2>" )
			)
			( signal "@baseboard_fab2_lib.baseboard_fab2(sch_1):m_d_odt(3)"
				( attribute "CDS_PHYS_NET_NAME" "M_D_ODT<3>"
					( Origin gPackager )
				)
				( attribute "PNN" "M_D_ODT<3>"
					( Origin gPackager )
				)
				( objectStatus "M_D_ODT<3>" )
			)
			( signal "@baseboard_fab2_lib.baseboard_fab2(sch_1):m_d_par"
				( attribute "CDS_PHYS_NET_NAME" "M_D_PAR"
					( Origin gPackager )
				)
				( objectStatus "M_D_PAR" )
			)
			( signal "@baseboard_fab2_lib.baseboard_fab2(sch_1):m_e_act_n"
				( attribute "CDS_PHYS_NET_NAME" "M_E_ACT_N"
					( Origin gPackager )
				)
				( objectStatus "M_E_ACT_N" )
			)
			( signal "@baseboard_fab2_lib.baseboard_fab2(sch_1):m_e_alert_n"
				( attribute "CDS_PHYS_NET_NAME" "M_E_ALERT_N"
					( Origin gPackager )
				)
				( objectStatus "M_E_ALERT_N" )
			)
			( signal "@baseboard_fab2_lib.baseboard_fab2(sch_1):m_e_ba(0)"
				( attribute "CDS_PHYS_NET_NAME" "M_E_BA<0>"
					( Origin gPackager )
				)
				( attribute "PNN" "M_E_BA<0>"
					( Origin gPackager )
				)
				( objectStatus "M_E_BA<0>" )
			)
			( signal "@baseboard_fab2_lib.baseboard_fab2(sch_1):m_e_ba(1)"
				( attribute "CDS_PHYS_NET_NAME" "M_E_BA<1>"
					( Origin gPackager )
				)
				( attribute "PNN" "M_E_BA<1>"
					( Origin gPackager )
				)
				( objectStatus "M_E_BA<1>" )
			)
			( signal "@baseboard_fab2_lib.baseboard_fab2(sch_1):m_e_bg(0)"
				( attribute "CDS_PHYS_NET_NAME" "M_E_BG<0>"
					( Origin gPackager )
				)
				( attribute "PNN" "M_E_BG<0>"
					( Origin gPackager )
				)
				( objectStatus "M_E_BG<0>" )
			)
			( signal "@baseboard_fab2_lib.baseboard_fab2(sch_1):m_e_bg(1)"
				( attribute "CDS_PHYS_NET_NAME" "M_E_BG<1>"
					( Origin gPackager )
				)
				( attribute "PNN" "M_E_BG<1>"
					( Origin gPackager )
				)
				( objectStatus "M_E_BG<1>" )
			)
			( signal "@baseboard_fab2_lib.baseboard_fab2(sch_1):m_e_c(2)"
				( attribute "CDS_PHYS_NET_NAME" "M_E_C<2>"
					( Origin gPackager )
				)
				( attribute "PNN" "M_E_C<2>"
					( Origin gPackager )
				)
				( objectStatus "M_E_C<2>" )
			)
			( signal "@baseboard_fab2_lib.baseboard_fab2(sch_1):m_e_cke(0)"
				( attribute "CDS_PHYS_NET_NAME" "M_E_CKE<0>"
					( Origin gPackager )
				)
				( attribute "PNN" "M_E_CKE<0>"
					( Origin gPackager )
				)
				( objectStatus "M_E_CKE<0>" )
			)
			( signal "@baseboard_fab2_lib.baseboard_fab2(sch_1):m_e_cke(1)"
				( attribute "CDS_PHYS_NET_NAME" "M_E_CKE<1>"
					( Origin gPackager )
				)
				( attribute "PNN" "M_E_CKE<1>"
					( Origin gPackager )
				)
				( objectStatus "M_E_CKE<1>" )
			)
			( signal "@baseboard_fab2_lib.baseboard_fab2(sch_1):m_e_cke(2)"
				( attribute "CDS_PHYS_NET_NAME" "M_E_CKE<2>"
					( Origin gPackager )
				)
				( attribute "PNN" "M_E_CKE<2>"
					( Origin gPackager )
				)
				( objectStatus "M_E_CKE<2>" )
			)
			( signal "@baseboard_fab2_lib.baseboard_fab2(sch_1):m_e_cke(3)"
				( attribute "CDS_PHYS_NET_NAME" "M_E_CKE<3>"
					( Origin gPackager )
				)
				( attribute "PNN" "M_E_CKE<3>"
					( Origin gPackager )
				)
				( objectStatus "M_E_CKE<3>" )
			)
			( signal "@baseboard_fab2_lib.baseboard_fab2(sch_1):m_e_clk_dn(0)"
				( attribute "CDS_PHYS_NET_NAME" "M_E_CLK_DN<0>"
					( Origin gPackager )
				)
				( attribute "PNN" "M_E_CLK_DN<0>"
					( Origin gPackager )
				)
				( objectStatus "M_E_CLK_DN<0>" )
			)
			( signal "@baseboard_fab2_lib.baseboard_fab2(sch_1):m_e_clk_dn(1)"
				( attribute "CDS_PHYS_NET_NAME" "M_E_CLK_DN<1>"
					( Origin gPackager )
				)
				( attribute "PNN" "M_E_CLK_DN<1>"
					( Origin gPackager )
				)
				( objectStatus "M_E_CLK_DN<1>" )
			)
			( signal "@baseboard_fab2_lib.baseboard_fab2(sch_1):m_e_clk_dn(2)"
				( attribute "CDS_PHYS_NET_NAME" "M_E_CLK_DN<2>"
					( Origin gPackager )
				)
				( attribute "PNN" "M_E_CLK_DN<2>"
					( Origin gPackager )
				)
				( objectStatus "M_E_CLK_DN<2>" )
			)
			( signal "@baseboard_fab2_lib.baseboard_fab2(sch_1):m_e_clk_dn(3)"
				( attribute "CDS_PHYS_NET_NAME" "M_E_CLK_DN<3>"
					( Origin gPackager )
				)
				( attribute "PNN" "M_E_CLK_DN<3>"
					( Origin gPackager )
				)
				( objectStatus "M_E_CLK_DN<3>" )
			)
			( signal "@baseboard_fab2_lib.baseboard_fab2(sch_1):m_e_clk_dp(0)"
				( attribute "CDS_PHYS_NET_NAME" "M_E_CLK_DP<0>"
					( Origin gPackager )
				)
				( attribute "PNN" "M_E_CLK_DP<0>"
					( Origin gPackager )
				)
				( objectStatus "M_E_CLK_DP<0>" )
			)
			( signal "@baseboard_fab2_lib.baseboard_fab2(sch_1):m_e_clk_dp(1)"
				( attribute "CDS_PHYS_NET_NAME" "M_E_CLK_DP<1>"
					( Origin gPackager )
				)
				( attribute "PNN" "M_E_CLK_DP<1>"
					( Origin gPackager )
				)
				( objectStatus "M_E_CLK_DP<1>" )
			)
			( signal "@baseboard_fab2_lib.baseboard_fab2(sch_1):m_e_clk_dp(2)"
				( attribute "CDS_PHYS_NET_NAME" "M_E_CLK_DP<2>"
					( Origin gPackager )
				)
				( attribute "PNN" "M_E_CLK_DP<2>"
					( Origin gPackager )
				)
				( objectStatus "M_E_CLK_DP<2>" )
			)
			( signal "@baseboard_fab2_lib.baseboard_fab2(sch_1):m_e_clk_dp(3)"
				( attribute "CDS_PHYS_NET_NAME" "M_E_CLK_DP<3>"
					( Origin gPackager )
				)
				( attribute "PNN" "M_E_CLK_DP<3>"
					( Origin gPackager )
				)
				( objectStatus "M_E_CLK_DP<3>" )
			)
			( signal "@baseboard_fab2_lib.baseboard_fab2(sch_1):m_e_cs_n(0)"
				( attribute "CDS_PHYS_NET_NAME" "M_E_CS_N<0>"
					( Origin gPackager )
				)
				( attribute "PNN" "M_E_CS_N<0>"
					( Origin gPackager )
				)
				( objectStatus "M_E_CS_N<0>" )
			)
			( signal "@baseboard_fab2_lib.baseboard_fab2(sch_1):m_e_cs_n(1)"
				( attribute "CDS_PHYS_NET_NAME" "M_E_CS_N<1>"
					( Origin gPackager )
				)
				( attribute "PNN" "M_E_CS_N<1>"
					( Origin gPackager )
				)
				( objectStatus "M_E_CS_N<1>" )
			)
			( signal "@baseboard_fab2_lib.baseboard_fab2(sch_1):m_e_cs_n(2)"
				( attribute "CDS_PHYS_NET_NAME" "M_E_CS_N<2>"
					( Origin gPackager )
				)
				( attribute "PNN" "M_E_CS_N<2>"
					( Origin gPackager )
				)
				( objectStatus "M_E_CS_N<2>" )
			)
			( signal "@baseboard_fab2_lib.baseboard_fab2(sch_1):m_e_cs_n(3)"
				( attribute "CDS_PHYS_NET_NAME" "M_E_CS_N<3>"
					( Origin gPackager )
				)
				( attribute "PNN" "M_E_CS_N<3>"
					( Origin gPackager )
				)
				( objectStatus "M_E_CS_N<3>" )
			)
			( signal "@baseboard_fab2_lib.baseboard_fab2(sch_1):m_e_cs_n(4)"
				( attribute "CDS_PHYS_NET_NAME" "M_E_CS_N<4>"
					( Origin gPackager )
				)
				( attribute "PNN" "M_E_CS_N<4>"
					( Origin gPackager )
				)
				( objectStatus "M_E_CS_N<4>" )
			)
			( signal "@baseboard_fab2_lib.baseboard_fab2(sch_1):m_e_cs_n(5)"
				( attribute "CDS_PHYS_NET_NAME" "M_E_CS_N<5>"
					( Origin gPackager )
				)
				( attribute "PNN" "M_E_CS_N<5>"
					( Origin gPackager )
				)
				( objectStatus "M_E_CS_N<5>" )
			)
			( signal "@baseboard_fab2_lib.baseboard_fab2(sch_1):m_e_cs_n(6)"
				( attribute "CDS_PHYS_NET_NAME" "M_E_CS_N<6>"
					( Origin gPackager )
				)
				( attribute "PNN" "M_E_CS_N<6>"
					( Origin gPackager )
				)
				( objectStatus "M_E_CS_N<6>" )
			)
			( signal "@baseboard_fab2_lib.baseboard_fab2(sch_1):m_e_cs_n(7)"
				( attribute "CDS_PHYS_NET_NAME" "M_E_CS_N<7>"
					( Origin gPackager )
				)
				( attribute "PNN" "M_E_CS_N<7>"
					( Origin gPackager )
				)
				( objectStatus "M_E_CS_N<7>" )
			)
			( signal "@baseboard_fab2_lib.baseboard_fab2(sch_1):m_e_dq(0)"
				( attribute "CDS_PHYS_NET_NAME" "M_E_DQ<0>"
					( Origin gPackager )
				)
				( attribute "PNN" "M_E_DQ<0>"
					( Origin gPackager )
				)
				( objectStatus "M_E_DQ<0>" )
			)
			( signal "@baseboard_fab2_lib.baseboard_fab2(sch_1):m_e_dq(1)"
				( attribute "CDS_PHYS_NET_NAME" "M_E_DQ<1>"
					( Origin gPackager )
				)
				( attribute "PNN" "M_E_DQ<1>"
					( Origin gPackager )
				)
				( objectStatus "M_E_DQ<1>" )
			)
			( signal "@baseboard_fab2_lib.baseboard_fab2(sch_1):m_e_dq(2)"
				( attribute "CDS_PHYS_NET_NAME" "M_E_DQ<2>"
					( Origin gPackager )
				)
				( attribute "PNN" "M_E_DQ<2>"
					( Origin gPackager )
				)
				( objectStatus "M_E_DQ<2>" )
			)
			( signal "@baseboard_fab2_lib.baseboard_fab2(sch_1):m_e_dq(3)"
				( attribute "CDS_PHYS_NET_NAME" "M_E_DQ<3>"
					( Origin gPackager )
				)
				( attribute "PNN" "M_E_DQ<3>"
					( Origin gPackager )
				)
				( objectStatus "M_E_DQ<3>" )
			)
			( signal "@baseboard_fab2_lib.baseboard_fab2(sch_1):m_e_dq(4)"
				( attribute "CDS_PHYS_NET_NAME" "M_E_DQ<4>"
					( Origin gPackager )
				)
				( attribute "PNN" "M_E_DQ<4>"
					( Origin gPackager )
				)
				( objectStatus "M_E_DQ<4>" )
			)
			( signal "@baseboard_fab2_lib.baseboard_fab2(sch_1):m_e_dq(5)"
				( attribute "CDS_PHYS_NET_NAME" "M_E_DQ<5>"
					( Origin gPackager )
				)
				( attribute "PNN" "M_E_DQ<5>"
					( Origin gPackager )
				)
				( objectStatus "M_E_DQ<5>" )
			)
			( signal "@baseboard_fab2_lib.baseboard_fab2(sch_1):m_e_dq(6)"
				( attribute "CDS_PHYS_NET_NAME" "M_E_DQ<6>"
					( Origin gPackager )
				)
				( attribute "PNN" "M_E_DQ<6>"
					( Origin gPackager )
				)
				( objectStatus "M_E_DQ<6>" )
			)
			( signal "@baseboard_fab2_lib.baseboard_fab2(sch_1):m_e_dq(7)"
				( attribute "CDS_PHYS_NET_NAME" "M_E_DQ<7>"
					( Origin gPackager )
				)
				( attribute "PNN" "M_E_DQ<7>"
					( Origin gPackager )
				)
				( objectStatus "M_E_DQ<7>" )
			)
			( signal "@baseboard_fab2_lib.baseboard_fab2(sch_1):m_e_dq(8)"
				( attribute "CDS_PHYS_NET_NAME" "M_E_DQ<8>"
					( Origin gPackager )
				)
				( attribute "PNN" "M_E_DQ<8>"
					( Origin gPackager )
				)
				( objectStatus "M_E_DQ<8>" )
			)
			( signal "@baseboard_fab2_lib.baseboard_fab2(sch_1):m_e_dq(9)"
				( attribute "CDS_PHYS_NET_NAME" "M_E_DQ<9>"
					( Origin gPackager )
				)
				( attribute "PNN" "M_E_DQ<9>"
					( Origin gPackager )
				)
				( objectStatus "M_E_DQ<9>" )
			)
			( signal "@baseboard_fab2_lib.baseboard_fab2(sch_1):m_e_dq(10)"
				( attribute "CDS_PHYS_NET_NAME" "M_E_DQ<10>"
					( Origin gPackager )
				)
				( attribute "PNN" "M_E_DQ<10>"
					( Origin gPackager )
				)
				( objectStatus "M_E_DQ<10>" )
			)
			( signal "@baseboard_fab2_lib.baseboard_fab2(sch_1):m_e_dq(11)"
				( attribute "CDS_PHYS_NET_NAME" "M_E_DQ<11>"
					( Origin gPackager )
				)
				( attribute "PNN" "M_E_DQ<11>"
					( Origin gPackager )
				)
				( objectStatus "M_E_DQ<11>" )
			)
			( signal "@baseboard_fab2_lib.baseboard_fab2(sch_1):m_e_dq(12)"
				( attribute "CDS_PHYS_NET_NAME" "M_E_DQ<12>"
					( Origin gPackager )
				)
				( attribute "PNN" "M_E_DQ<12>"
					( Origin gPackager )
				)
				( objectStatus "M_E_DQ<12>" )
			)
			( signal "@baseboard_fab2_lib.baseboard_fab2(sch_1):m_e_dq(13)"
				( attribute "CDS_PHYS_NET_NAME" "M_E_DQ<13>"
					( Origin gPackager )
				)
				( attribute "PNN" "M_E_DQ<13>"
					( Origin gPackager )
				)
				( objectStatus "M_E_DQ<13>" )
			)
			( signal "@baseboard_fab2_lib.baseboard_fab2(sch_1):m_e_dq(14)"
				( attribute "CDS_PHYS_NET_NAME" "M_E_DQ<14>"
					( Origin gPackager )
				)
				( attribute "PNN" "M_E_DQ<14>"
					( Origin gPackager )
				)
				( objectStatus "M_E_DQ<14>" )
			)
			( signal "@baseboard_fab2_lib.baseboard_fab2(sch_1):m_e_dq(15)"
				( attribute "CDS_PHYS_NET_NAME" "M_E_DQ<15>"
					( Origin gPackager )
				)
				( attribute "PNN" "M_E_DQ<15>"
					( Origin gPackager )
				)
				( objectStatus "M_E_DQ<15>" )
			)
			( signal "@baseboard_fab2_lib.baseboard_fab2(sch_1):m_e_dq(16)"
				( attribute "CDS_PHYS_NET_NAME" "M_E_DQ<16>"
					( Origin gPackager )
				)
				( attribute "PNN" "M_E_DQ<16>"
					( Origin gPackager )
				)
				( objectStatus "M_E_DQ<16>" )
			)
			( signal "@baseboard_fab2_lib.baseboard_fab2(sch_1):m_e_dq(17)"
				( attribute "CDS_PHYS_NET_NAME" "M_E_DQ<17>"
					( Origin gPackager )
				)
				( attribute "PNN" "M_E_DQ<17>"
					( Origin gPackager )
				)
				( objectStatus "M_E_DQ<17>" )
			)
			( signal "@baseboard_fab2_lib.baseboard_fab2(sch_1):m_e_dq(18)"
				( attribute "CDS_PHYS_NET_NAME" "M_E_DQ<18>"
					( Origin gPackager )
				)
				( attribute "PNN" "M_E_DQ<18>"
					( Origin gPackager )
				)
				( objectStatus "M_E_DQ<18>" )
			)
			( signal "@baseboard_fab2_lib.baseboard_fab2(sch_1):m_e_dq(19)"
				( attribute "CDS_PHYS_NET_NAME" "M_E_DQ<19>"
					( Origin gPackager )
				)
				( attribute "PNN" "M_E_DQ<19>"
					( Origin gPackager )
				)
				( objectStatus "M_E_DQ<19>" )
			)
			( signal "@baseboard_fab2_lib.baseboard_fab2(sch_1):m_e_dq(20)"
				( attribute "CDS_PHYS_NET_NAME" "M_E_DQ<20>"
					( Origin gPackager )
				)
				( attribute "PNN" "M_E_DQ<20>"
					( Origin gPackager )
				)
				( objectStatus "M_E_DQ<20>" )
			)
			( signal "@baseboard_fab2_lib.baseboard_fab2(sch_1):m_e_dq(21)"
				( attribute "CDS_PHYS_NET_NAME" "M_E_DQ<21>"
					( Origin gPackager )
				)
				( attribute "PNN" "M_E_DQ<21>"
					( Origin gPackager )
				)
				( objectStatus "M_E_DQ<21>" )
			)
			( signal "@baseboard_fab2_lib.baseboard_fab2(sch_1):m_e_dq(22)"
				( attribute "CDS_PHYS_NET_NAME" "M_E_DQ<22>"
					( Origin gPackager )
				)
				( attribute "PNN" "M_E_DQ<22>"
					( Origin gPackager )
				)
				( objectStatus "M_E_DQ<22>" )
			)
			( signal "@baseboard_fab2_lib.baseboard_fab2(sch_1):m_e_dq(23)"
				( attribute "CDS_PHYS_NET_NAME" "M_E_DQ<23>"
					( Origin gPackager )
				)
				( attribute "PNN" "M_E_DQ<23>"
					( Origin gPackager )
				)
				( objectStatus "M_E_DQ<23>" )
			)
			( signal "@baseboard_fab2_lib.baseboard_fab2(sch_1):m_e_dq(24)"
				( attribute "CDS_PHYS_NET_NAME" "M_E_DQ<24>"
					( Origin gPackager )
				)
				( attribute "PNN" "M_E_DQ<24>"
					( Origin gPackager )
				)
				( objectStatus "M_E_DQ<24>" )
			)
			( signal "@baseboard_fab2_lib.baseboard_fab2(sch_1):m_e_dq(25)"
				( attribute "CDS_PHYS_NET_NAME" "M_E_DQ<25>"
					( Origin gPackager )
				)
				( attribute "PNN" "M_E_DQ<25>"
					( Origin gPackager )
				)
				( objectStatus "M_E_DQ<25>" )
			)
			( signal "@baseboard_fab2_lib.baseboard_fab2(sch_1):m_e_dq(26)"
				( attribute "CDS_PHYS_NET_NAME" "M_E_DQ<26>"
					( Origin gPackager )
				)
				( attribute "PNN" "M_E_DQ<26>"
					( Origin gPackager )
				)
				( objectStatus "M_E_DQ<26>" )
			)
			( signal "@baseboard_fab2_lib.baseboard_fab2(sch_1):m_e_dq(27)"
				( attribute "CDS_PHYS_NET_NAME" "M_E_DQ<27>"
					( Origin gPackager )
				)
				( attribute "PNN" "M_E_DQ<27>"
					( Origin gPackager )
				)
				( objectStatus "M_E_DQ<27>" )
			)
			( signal "@baseboard_fab2_lib.baseboard_fab2(sch_1):m_e_dq(28)"
				( attribute "CDS_PHYS_NET_NAME" "M_E_DQ<28>"
					( Origin gPackager )
				)
				( attribute "PNN" "M_E_DQ<28>"
					( Origin gPackager )
				)
				( objectStatus "M_E_DQ<28>" )
			)
			( signal "@baseboard_fab2_lib.baseboard_fab2(sch_1):m_e_dq(29)"
				( attribute "CDS_PHYS_NET_NAME" "M_E_DQ<29>"
					( Origin gPackager )
				)
				( attribute "PNN" "M_E_DQ<29>"
					( Origin gPackager )
				)
				( objectStatus "M_E_DQ<29>" )
			)
			( signal "@baseboard_fab2_lib.baseboard_fab2(sch_1):m_e_dq(30)"
				( attribute "CDS_PHYS_NET_NAME" "M_E_DQ<30>"
					( Origin gPackager )
				)
				( attribute "PNN" "M_E_DQ<30>"
					( Origin gPackager )
				)
				( objectStatus "M_E_DQ<30>" )
			)
			( signal "@baseboard_fab2_lib.baseboard_fab2(sch_1):m_e_dq(31)"
				( attribute "CDS_PHYS_NET_NAME" "M_E_DQ<31>"
					( Origin gPackager )
				)
				( attribute "PNN" "M_E_DQ<31>"
					( Origin gPackager )
				)
				( objectStatus "M_E_DQ<31>" )
			)
			( signal "@baseboard_fab2_lib.baseboard_fab2(sch_1):m_e_dq(32)"
				( attribute "CDS_PHYS_NET_NAME" "M_E_DQ<32>"
					( Origin gPackager )
				)
				( attribute "PNN" "M_E_DQ<32>"
					( Origin gPackager )
				)
				( objectStatus "M_E_DQ<32>" )
			)
			( signal "@baseboard_fab2_lib.baseboard_fab2(sch_1):m_e_dq(33)"
				( attribute "CDS_PHYS_NET_NAME" "M_E_DQ<33>"
					( Origin gPackager )
				)
				( attribute "PNN" "M_E_DQ<33>"
					( Origin gPackager )
				)
				( objectStatus "M_E_DQ<33>" )
			)
			( signal "@baseboard_fab2_lib.baseboard_fab2(sch_1):m_e_dq(34)"
				( attribute "CDS_PHYS_NET_NAME" "M_E_DQ<34>"
					( Origin gPackager )
				)
				( attribute "PNN" "M_E_DQ<34>"
					( Origin gPackager )
				)
				( objectStatus "M_E_DQ<34>" )
			)
			( signal "@baseboard_fab2_lib.baseboard_fab2(sch_1):m_e_dq(35)"
				( attribute "CDS_PHYS_NET_NAME" "M_E_DQ<35>"
					( Origin gPackager )
				)
				( attribute "PNN" "M_E_DQ<35>"
					( Origin gPackager )
				)
				( objectStatus "M_E_DQ<35>" )
			)
			( signal "@baseboard_fab2_lib.baseboard_fab2(sch_1):m_e_dq(36)"
				( attribute "CDS_PHYS_NET_NAME" "M_E_DQ<36>"
					( Origin gPackager )
				)
				( attribute "PNN" "M_E_DQ<36>"
					( Origin gPackager )
				)
				( objectStatus "M_E_DQ<36>" )
			)
			( signal "@baseboard_fab2_lib.baseboard_fab2(sch_1):m_e_dq(37)"
				( attribute "CDS_PHYS_NET_NAME" "M_E_DQ<37>"
					( Origin gPackager )
				)
				( attribute "PNN" "M_E_DQ<37>"
					( Origin gPackager )
				)
				( objectStatus "M_E_DQ<37>" )
			)
			( signal "@baseboard_fab2_lib.baseboard_fab2(sch_1):m_e_dq(38)"
				( attribute "CDS_PHYS_NET_NAME" "M_E_DQ<38>"
					( Origin gPackager )
				)
				( attribute "PNN" "M_E_DQ<38>"
					( Origin gPackager )
				)
				( objectStatus "M_E_DQ<38>" )
			)
			( signal "@baseboard_fab2_lib.baseboard_fab2(sch_1):m_e_dq(39)"
				( attribute "CDS_PHYS_NET_NAME" "M_E_DQ<39>"
					( Origin gPackager )
				)
				( attribute "PNN" "M_E_DQ<39>"
					( Origin gPackager )
				)
				( objectStatus "M_E_DQ<39>" )
			)
			( signal "@baseboard_fab2_lib.baseboard_fab2(sch_1):m_e_dq(40)"
				( attribute "CDS_PHYS_NET_NAME" "M_E_DQ<40>"
					( Origin gPackager )
				)
				( attribute "PNN" "M_E_DQ<40>"
					( Origin gPackager )
				)
				( objectStatus "M_E_DQ<40>" )
			)
			( signal "@baseboard_fab2_lib.baseboard_fab2(sch_1):m_e_dq(41)"
				( attribute "CDS_PHYS_NET_NAME" "M_E_DQ<41>"
					( Origin gPackager )
				)
				( attribute "PNN" "M_E_DQ<41>"
					( Origin gPackager )
				)
				( objectStatus "M_E_DQ<41>" )
			)
			( signal "@baseboard_fab2_lib.baseboard_fab2(sch_1):m_e_dq(42)"
				( attribute "CDS_PHYS_NET_NAME" "M_E_DQ<42>"
					( Origin gPackager )
				)
				( attribute "PNN" "M_E_DQ<42>"
					( Origin gPackager )
				)
				( objectStatus "M_E_DQ<42>" )
			)
			( signal "@baseboard_fab2_lib.baseboard_fab2(sch_1):m_e_dq(43)"
				( attribute "CDS_PHYS_NET_NAME" "M_E_DQ<43>"
					( Origin gPackager )
				)
				( attribute "PNN" "M_E_DQ<43>"
					( Origin gPackager )
				)
				( objectStatus "M_E_DQ<43>" )
			)
			( signal "@baseboard_fab2_lib.baseboard_fab2(sch_1):m_e_dq(44)"
				( attribute "CDS_PHYS_NET_NAME" "M_E_DQ<44>"
					( Origin gPackager )
				)
				( attribute "PNN" "M_E_DQ<44>"
					( Origin gPackager )
				)
				( objectStatus "M_E_DQ<44>" )
			)
			( signal "@baseboard_fab2_lib.baseboard_fab2(sch_1):m_e_dq(45)"
				( attribute "CDS_PHYS_NET_NAME" "M_E_DQ<45>"
					( Origin gPackager )
				)
				( attribute "PNN" "M_E_DQ<45>"
					( Origin gPackager )
				)
				( objectStatus "M_E_DQ<45>" )
			)
			( signal "@baseboard_fab2_lib.baseboard_fab2(sch_1):m_e_dq(46)"
				( attribute "CDS_PHYS_NET_NAME" "M_E_DQ<46>"
					( Origin gPackager )
				)
				( attribute "PNN" "M_E_DQ<46>"
					( Origin gPackager )
				)
				( objectStatus "M_E_DQ<46>" )
			)
			( signal "@baseboard_fab2_lib.baseboard_fab2(sch_1):m_e_dq(47)"
				( attribute "CDS_PHYS_NET_NAME" "M_E_DQ<47>"
					( Origin gPackager )
				)
				( attribute "PNN" "M_E_DQ<47>"
					( Origin gPackager )
				)
				( objectStatus "M_E_DQ<47>" )
			)
			( signal "@baseboard_fab2_lib.baseboard_fab2(sch_1):m_e_dq(48)"
				( attribute "CDS_PHYS_NET_NAME" "M_E_DQ<48>"
					( Origin gPackager )
				)
				( attribute "PNN" "M_E_DQ<48>"
					( Origin gPackager )
				)
				( objectStatus "M_E_DQ<48>" )
			)
			( signal "@baseboard_fab2_lib.baseboard_fab2(sch_1):m_e_dq(49)"
				( attribute "CDS_PHYS_NET_NAME" "M_E_DQ<49>"
					( Origin gPackager )
				)
				( attribute "PNN" "M_E_DQ<49>"
					( Origin gPackager )
				)
				( objectStatus "M_E_DQ<49>" )
			)
			( signal "@baseboard_fab2_lib.baseboard_fab2(sch_1):m_e_dq(50)"
				( attribute "CDS_PHYS_NET_NAME" "M_E_DQ<50>"
					( Origin gPackager )
				)
				( attribute "PNN" "M_E_DQ<50>"
					( Origin gPackager )
				)
				( objectStatus "M_E_DQ<50>" )
			)
			( signal "@baseboard_fab2_lib.baseboard_fab2(sch_1):m_e_dq(51)"
				( attribute "CDS_PHYS_NET_NAME" "M_E_DQ<51>"
					( Origin gPackager )
				)
				( attribute "PNN" "M_E_DQ<51>"
					( Origin gPackager )
				)
				( objectStatus "M_E_DQ<51>" )
			)
			( signal "@baseboard_fab2_lib.baseboard_fab2(sch_1):m_e_dq(52)"
				( attribute "CDS_PHYS_NET_NAME" "M_E_DQ<52>"
					( Origin gPackager )
				)
				( attribute "PNN" "M_E_DQ<52>"
					( Origin gPackager )
				)
				( objectStatus "M_E_DQ<52>" )
			)
			( signal "@baseboard_fab2_lib.baseboard_fab2(sch_1):m_e_dq(53)"
				( attribute "CDS_PHYS_NET_NAME" "M_E_DQ<53>"
					( Origin gPackager )
				)
				( attribute "PNN" "M_E_DQ<53>"
					( Origin gPackager )
				)
				( objectStatus "M_E_DQ<53>" )
			)
			( signal "@baseboard_fab2_lib.baseboard_fab2(sch_1):m_e_dq(54)"
				( attribute "CDS_PHYS_NET_NAME" "M_E_DQ<54>"
					( Origin gPackager )
				)
				( attribute "PNN" "M_E_DQ<54>"
					( Origin gPackager )
				)
				( objectStatus "M_E_DQ<54>" )
			)
			( signal "@baseboard_fab2_lib.baseboard_fab2(sch_1):m_e_dq(55)"
				( attribute "CDS_PHYS_NET_NAME" "M_E_DQ<55>"
					( Origin gPackager )
				)
				( attribute "PNN" "M_E_DQ<55>"
					( Origin gPackager )
				)
				( objectStatus "M_E_DQ<55>" )
			)
			( signal "@baseboard_fab2_lib.baseboard_fab2(sch_1):m_e_dq(56)"
				( attribute "CDS_PHYS_NET_NAME" "M_E_DQ<56>"
					( Origin gPackager )
				)
				( attribute "PNN" "M_E_DQ<56>"
					( Origin gPackager )
				)
				( objectStatus "M_E_DQ<56>" )
			)
			( signal "@baseboard_fab2_lib.baseboard_fab2(sch_1):m_e_dq(57)"
				( attribute "CDS_PHYS_NET_NAME" "M_E_DQ<57>"
					( Origin gPackager )
				)
				( attribute "PNN" "M_E_DQ<57>"
					( Origin gPackager )
				)
				( objectStatus "M_E_DQ<57>" )
			)
			( signal "@baseboard_fab2_lib.baseboard_fab2(sch_1):m_e_dq(58)"
				( attribute "CDS_PHYS_NET_NAME" "M_E_DQ<58>"
					( Origin gPackager )
				)
				( attribute "PNN" "M_E_DQ<58>"
					( Origin gPackager )
				)
				( objectStatus "M_E_DQ<58>" )
			)
			( signal "@baseboard_fab2_lib.baseboard_fab2(sch_1):m_e_dq(59)"
				( attribute "CDS_PHYS_NET_NAME" "M_E_DQ<59>"
					( Origin gPackager )
				)
				( attribute "PNN" "M_E_DQ<59>"
					( Origin gPackager )
				)
				( objectStatus "M_E_DQ<59>" )
			)
			( signal "@baseboard_fab2_lib.baseboard_fab2(sch_1):m_e_dq(60)"
				( attribute "CDS_PHYS_NET_NAME" "M_E_DQ<60>"
					( Origin gPackager )
				)
				( attribute "PNN" "M_E_DQ<60>"
					( Origin gPackager )
				)
				( objectStatus "M_E_DQ<60>" )
			)
			( signal "@baseboard_fab2_lib.baseboard_fab2(sch_1):m_e_dq(61)"
				( attribute "CDS_PHYS_NET_NAME" "M_E_DQ<61>"
					( Origin gPackager )
				)
				( attribute "PNN" "M_E_DQ<61>"
					( Origin gPackager )
				)
				( objectStatus "M_E_DQ<61>" )
			)
			( signal "@baseboard_fab2_lib.baseboard_fab2(sch_1):m_e_dq(62)"
				( attribute "CDS_PHYS_NET_NAME" "M_E_DQ<62>"
					( Origin gPackager )
				)
				( attribute "PNN" "M_E_DQ<62>"
					( Origin gPackager )
				)
				( objectStatus "M_E_DQ<62>" )
			)
			( signal "@baseboard_fab2_lib.baseboard_fab2(sch_1):m_e_dq(63)"
				( attribute "CDS_PHYS_NET_NAME" "M_E_DQ<63>"
					( Origin gPackager )
				)
				( attribute "PNN" "M_E_DQ<63>"
					( Origin gPackager )
				)
				( objectStatus "M_E_DQ<63>" )
			)
			( signal "@baseboard_fab2_lib.baseboard_fab2(sch_1):m_e_dqs_dn(0)"
				( attribute "CDS_PHYS_NET_NAME" "M_E_DQS_DN<0>"
					( Origin gPackager )
				)
				( attribute "PNN" "M_E_DQS_DN<0>"
					( Origin gPackager )
				)
				( objectStatus "M_E_DQS_DN<0>" )
			)
			( signal "@baseboard_fab2_lib.baseboard_fab2(sch_1):m_e_dqs_dn(1)"
				( attribute "CDS_PHYS_NET_NAME" "M_E_DQS_DN<1>"
					( Origin gPackager )
				)
				( attribute "PNN" "M_E_DQS_DN<1>"
					( Origin gPackager )
				)
				( objectStatus "M_E_DQS_DN<1>" )
			)
			( signal "@baseboard_fab2_lib.baseboard_fab2(sch_1):m_e_dqs_dn(2)"
				( attribute "CDS_PHYS_NET_NAME" "M_E_DQS_DN<2>"
					( Origin gPackager )
				)
				( attribute "PNN" "M_E_DQS_DN<2>"
					( Origin gPackager )
				)
				( objectStatus "M_E_DQS_DN<2>" )
			)
			( signal "@baseboard_fab2_lib.baseboard_fab2(sch_1):m_e_dqs_dn(3)"
				( attribute "CDS_PHYS_NET_NAME" "M_E_DQS_DN<3>"
					( Origin gPackager )
				)
				( attribute "PNN" "M_E_DQS_DN<3>"
					( Origin gPackager )
				)
				( objectStatus "M_E_DQS_DN<3>" )
			)
			( signal "@baseboard_fab2_lib.baseboard_fab2(sch_1):m_e_dqs_dn(4)"
				( attribute "CDS_PHYS_NET_NAME" "M_E_DQS_DN<4>"
					( Origin gPackager )
				)
				( attribute "PNN" "M_E_DQS_DN<4>"
					( Origin gPackager )
				)
				( objectStatus "M_E_DQS_DN<4>" )
			)
			( signal "@baseboard_fab2_lib.baseboard_fab2(sch_1):m_e_dqs_dn(5)"
				( attribute "CDS_PHYS_NET_NAME" "M_E_DQS_DN<5>"
					( Origin gPackager )
				)
				( attribute "PNN" "M_E_DQS_DN<5>"
					( Origin gPackager )
				)
				( objectStatus "M_E_DQS_DN<5>" )
			)
			( signal "@baseboard_fab2_lib.baseboard_fab2(sch_1):m_e_dqs_dn(6)"
				( attribute "CDS_PHYS_NET_NAME" "M_E_DQS_DN<6>"
					( Origin gPackager )
				)
				( attribute "PNN" "M_E_DQS_DN<6>"
					( Origin gPackager )
				)
				( objectStatus "M_E_DQS_DN<6>" )
			)
			( signal "@baseboard_fab2_lib.baseboard_fab2(sch_1):m_e_dqs_dn(7)"
				( attribute "CDS_PHYS_NET_NAME" "M_E_DQS_DN<7>"
					( Origin gPackager )
				)
				( attribute "PNN" "M_E_DQS_DN<7>"
					( Origin gPackager )
				)
				( objectStatus "M_E_DQS_DN<7>" )
			)
			( signal "@baseboard_fab2_lib.baseboard_fab2(sch_1):m_e_dqs_dn(8)"
				( attribute "CDS_PHYS_NET_NAME" "M_E_DQS_DN<8>"
					( Origin gPackager )
				)
				( attribute "PNN" "M_E_DQS_DN<8>"
					( Origin gPackager )
				)
				( objectStatus "M_E_DQS_DN<8>" )
			)
			( signal "@baseboard_fab2_lib.baseboard_fab2(sch_1):m_e_dqs_dn(9)"
				( attribute "CDS_PHYS_NET_NAME" "M_E_DQS_DN<9>"
					( Origin gPackager )
				)
				( attribute "PNN" "M_E_DQS_DN<9>"
					( Origin gPackager )
				)
				( objectStatus "M_E_DQS_DN<9>" )
			)
			( signal "@baseboard_fab2_lib.baseboard_fab2(sch_1):m_e_dqs_dn(10)"
				( attribute "CDS_PHYS_NET_NAME" "M_E_DQS_DN<10>"
					( Origin gPackager )
				)
				( attribute "PNN" "M_E_DQS_DN<10>"
					( Origin gPackager )
				)
				( objectStatus "M_E_DQS_DN<10>" )
			)
			( signal "@baseboard_fab2_lib.baseboard_fab2(sch_1):m_e_dqs_dn(11)"
				( attribute "CDS_PHYS_NET_NAME" "M_E_DQS_DN<11>"
					( Origin gPackager )
				)
				( attribute "PNN" "M_E_DQS_DN<11>"
					( Origin gPackager )
				)
				( objectStatus "M_E_DQS_DN<11>" )
			)
			( signal "@baseboard_fab2_lib.baseboard_fab2(sch_1):m_e_dqs_dn(12)"
				( attribute "CDS_PHYS_NET_NAME" "M_E_DQS_DN<12>"
					( Origin gPackager )
				)
				( attribute "PNN" "M_E_DQS_DN<12>"
					( Origin gPackager )
				)
				( objectStatus "M_E_DQS_DN<12>" )
			)
			( signal "@baseboard_fab2_lib.baseboard_fab2(sch_1):m_e_dqs_dn(13)"
				( attribute "CDS_PHYS_NET_NAME" "M_E_DQS_DN<13>"
					( Origin gPackager )
				)
				( attribute "PNN" "M_E_DQS_DN<13>"
					( Origin gPackager )
				)
				( objectStatus "M_E_DQS_DN<13>" )
			)
			( signal "@baseboard_fab2_lib.baseboard_fab2(sch_1):m_e_dqs_dn(14)"
				( attribute "CDS_PHYS_NET_NAME" "M_E_DQS_DN<14>"
					( Origin gPackager )
				)
				( attribute "PNN" "M_E_DQS_DN<14>"
					( Origin gPackager )
				)
				( objectStatus "M_E_DQS_DN<14>" )
			)
			( signal "@baseboard_fab2_lib.baseboard_fab2(sch_1):m_e_dqs_dn(15)"
				( attribute "CDS_PHYS_NET_NAME" "M_E_DQS_DN<15>"
					( Origin gPackager )
				)
				( attribute "PNN" "M_E_DQS_DN<15>"
					( Origin gPackager )
				)
				( objectStatus "M_E_DQS_DN<15>" )
			)
			( signal "@baseboard_fab2_lib.baseboard_fab2(sch_1):m_e_dqs_dn(16)"
				( attribute "CDS_PHYS_NET_NAME" "M_E_DQS_DN<16>"
					( Origin gPackager )
				)
				( attribute "PNN" "M_E_DQS_DN<16>"
					( Origin gPackager )
				)
				( objectStatus "M_E_DQS_DN<16>" )
			)
			( signal "@baseboard_fab2_lib.baseboard_fab2(sch_1):m_e_dqs_dn(17)"
				( attribute "CDS_PHYS_NET_NAME" "M_E_DQS_DN<17>"
					( Origin gPackager )
				)
				( attribute "PNN" "M_E_DQS_DN<17>"
					( Origin gPackager )
				)
				( objectStatus "M_E_DQS_DN<17>" )
			)
			( signal "@baseboard_fab2_lib.baseboard_fab2(sch_1):m_e_dqs_dp(0)"
				( attribute "CDS_PHYS_NET_NAME" "M_E_DQS_DP<0>"
					( Origin gPackager )
				)
				( attribute "PNN" "M_E_DQS_DP<0>"
					( Origin gPackager )
				)
				( objectStatus "M_E_DQS_DP<0>" )
			)
			( signal "@baseboard_fab2_lib.baseboard_fab2(sch_1):m_e_dqs_dp(1)"
				( attribute "CDS_PHYS_NET_NAME" "M_E_DQS_DP<1>"
					( Origin gPackager )
				)
				( attribute "PNN" "M_E_DQS_DP<1>"
					( Origin gPackager )
				)
				( objectStatus "M_E_DQS_DP<1>" )
			)
			( signal "@baseboard_fab2_lib.baseboard_fab2(sch_1):m_e_dqs_dp(2)"
				( attribute "CDS_PHYS_NET_NAME" "M_E_DQS_DP<2>"
					( Origin gPackager )
				)
				( attribute "PNN" "M_E_DQS_DP<2>"
					( Origin gPackager )
				)
				( objectStatus "M_E_DQS_DP<2>" )
			)
			( signal "@baseboard_fab2_lib.baseboard_fab2(sch_1):m_e_dqs_dp(3)"
				( attribute "CDS_PHYS_NET_NAME" "M_E_DQS_DP<3>"
					( Origin gPackager )
				)
				( attribute "PNN" "M_E_DQS_DP<3>"
					( Origin gPackager )
				)
				( objectStatus "M_E_DQS_DP<3>" )
			)
			( signal "@baseboard_fab2_lib.baseboard_fab2(sch_1):m_e_dqs_dp(4)"
				( attribute "CDS_PHYS_NET_NAME" "M_E_DQS_DP<4>"
					( Origin gPackager )
				)
				( attribute "PNN" "M_E_DQS_DP<4>"
					( Origin gPackager )
				)
				( objectStatus "M_E_DQS_DP<4>" )
			)
			( signal "@baseboard_fab2_lib.baseboard_fab2(sch_1):m_e_dqs_dp(5)"
				( attribute "CDS_PHYS_NET_NAME" "M_E_DQS_DP<5>"
					( Origin gPackager )
				)
				( attribute "PNN" "M_E_DQS_DP<5>"
					( Origin gPackager )
				)
				( objectStatus "M_E_DQS_DP<5>" )
			)
			( signal "@baseboard_fab2_lib.baseboard_fab2(sch_1):m_e_dqs_dp(6)"
				( attribute "CDS_PHYS_NET_NAME" "M_E_DQS_DP<6>"
					( Origin gPackager )
				)
				( attribute "PNN" "M_E_DQS_DP<6>"
					( Origin gPackager )
				)
				( objectStatus "M_E_DQS_DP<6>" )
			)
			( signal "@baseboard_fab2_lib.baseboard_fab2(sch_1):m_e_dqs_dp(7)"
				( attribute "CDS_PHYS_NET_NAME" "M_E_DQS_DP<7>"
					( Origin gPackager )
				)
				( attribute "PNN" "M_E_DQS_DP<7>"
					( Origin gPackager )
				)
				( objectStatus "M_E_DQS_DP<7>" )
			)
			( signal "@baseboard_fab2_lib.baseboard_fab2(sch_1):m_e_dqs_dp(8)"
				( attribute "CDS_PHYS_NET_NAME" "M_E_DQS_DP<8>"
					( Origin gPackager )
				)
				( attribute "PNN" "M_E_DQS_DP<8>"
					( Origin gPackager )
				)
				( objectStatus "M_E_DQS_DP<8>" )
			)
			( signal "@baseboard_fab2_lib.baseboard_fab2(sch_1):m_e_dqs_dp(9)"
				( attribute "CDS_PHYS_NET_NAME" "M_E_DQS_DP<9>"
					( Origin gPackager )
				)
				( attribute "PNN" "M_E_DQS_DP<9>"
					( Origin gPackager )
				)
				( objectStatus "M_E_DQS_DP<9>" )
			)
			( signal "@baseboard_fab2_lib.baseboard_fab2(sch_1):m_e_dqs_dp(10)"
				( attribute "CDS_PHYS_NET_NAME" "M_E_DQS_DP<10>"
					( Origin gPackager )
				)
				( attribute "PNN" "M_E_DQS_DP<10>"
					( Origin gPackager )
				)
				( objectStatus "M_E_DQS_DP<10>" )
			)
			( signal "@baseboard_fab2_lib.baseboard_fab2(sch_1):m_e_dqs_dp(11)"
				( attribute "CDS_PHYS_NET_NAME" "M_E_DQS_DP<11>"
					( Origin gPackager )
				)
				( attribute "PNN" "M_E_DQS_DP<11>"
					( Origin gPackager )
				)
				( objectStatus "M_E_DQS_DP<11>" )
			)
			( signal "@baseboard_fab2_lib.baseboard_fab2(sch_1):m_e_dqs_dp(12)"
				( attribute "CDS_PHYS_NET_NAME" "M_E_DQS_DP<12>"
					( Origin gPackager )
				)
				( attribute "PNN" "M_E_DQS_DP<12>"
					( Origin gPackager )
				)
				( objectStatus "M_E_DQS_DP<12>" )
			)
			( signal "@baseboard_fab2_lib.baseboard_fab2(sch_1):m_e_dqs_dp(13)"
				( attribute "CDS_PHYS_NET_NAME" "M_E_DQS_DP<13>"
					( Origin gPackager )
				)
				( attribute "PNN" "M_E_DQS_DP<13>"
					( Origin gPackager )
				)
				( objectStatus "M_E_DQS_DP<13>" )
			)
			( signal "@baseboard_fab2_lib.baseboard_fab2(sch_1):m_e_dqs_dp(14)"
				( attribute "CDS_PHYS_NET_NAME" "M_E_DQS_DP<14>"
					( Origin gPackager )
				)
				( attribute "PNN" "M_E_DQS_DP<14>"
					( Origin gPackager )
				)
				( objectStatus "M_E_DQS_DP<14>" )
			)
			( signal "@baseboard_fab2_lib.baseboard_fab2(sch_1):m_e_dqs_dp(15)"
				( attribute "CDS_PHYS_NET_NAME" "M_E_DQS_DP<15>"
					( Origin gPackager )
				)
				( attribute "PNN" "M_E_DQS_DP<15>"
					( Origin gPackager )
				)
				( objectStatus "M_E_DQS_DP<15>" )
			)
			( signal "@baseboard_fab2_lib.baseboard_fab2(sch_1):m_e_dqs_dp(16)"
				( attribute "CDS_PHYS_NET_NAME" "M_E_DQS_DP<16>"
					( Origin gPackager )
				)
				( attribute "PNN" "M_E_DQS_DP<16>"
					( Origin gPackager )
				)
				( objectStatus "M_E_DQS_DP<16>" )
			)
			( signal "@baseboard_fab2_lib.baseboard_fab2(sch_1):m_e_dqs_dp(17)"
				( attribute "CDS_PHYS_NET_NAME" "M_E_DQS_DP<17>"
					( Origin gPackager )
				)
				( attribute "PNN" "M_E_DQS_DP<17>"
					( Origin gPackager )
				)
				( objectStatus "M_E_DQS_DP<17>" )
			)
			( signal "@baseboard_fab2_lib.baseboard_fab2(sch_1):m_e_ecc(0)"
				( attribute "CDS_PHYS_NET_NAME" "M_E_ECC<0>"
					( Origin gPackager )
				)
				( attribute "PNN" "M_E_ECC<0>"
					( Origin gPackager )
				)
				( objectStatus "M_E_ECC<0>" )
			)
			( signal "@baseboard_fab2_lib.baseboard_fab2(sch_1):m_e_ecc(1)"
				( attribute "CDS_PHYS_NET_NAME" "M_E_ECC<1>"
					( Origin gPackager )
				)
				( attribute "PNN" "M_E_ECC<1>"
					( Origin gPackager )
				)
				( objectStatus "M_E_ECC<1>" )
			)
			( signal "@baseboard_fab2_lib.baseboard_fab2(sch_1):m_e_ecc(2)"
				( attribute "CDS_PHYS_NET_NAME" "M_E_ECC<2>"
					( Origin gPackager )
				)
				( attribute "PNN" "M_E_ECC<2>"
					( Origin gPackager )
				)
				( objectStatus "M_E_ECC<2>" )
			)
			( signal "@baseboard_fab2_lib.baseboard_fab2(sch_1):m_e_ecc(3)"
				( attribute "CDS_PHYS_NET_NAME" "M_E_ECC<3>"
					( Origin gPackager )
				)
				( attribute "PNN" "M_E_ECC<3>"
					( Origin gPackager )
				)
				( objectStatus "M_E_ECC<3>" )
			)
			( signal "@baseboard_fab2_lib.baseboard_fab2(sch_1):m_e_ecc(4)"
				( attribute "CDS_PHYS_NET_NAME" "M_E_ECC<4>"
					( Origin gPackager )
				)
				( attribute "PNN" "M_E_ECC<4>"
					( Origin gPackager )
				)
				( objectStatus "M_E_ECC<4>" )
			)
			( signal "@baseboard_fab2_lib.baseboard_fab2(sch_1):m_e_ecc(5)"
				( attribute "CDS_PHYS_NET_NAME" "M_E_ECC<5>"
					( Origin gPackager )
				)
				( attribute "PNN" "M_E_ECC<5>"
					( Origin gPackager )
				)
				( objectStatus "M_E_ECC<5>" )
			)
			( signal "@baseboard_fab2_lib.baseboard_fab2(sch_1):m_e_ecc(6)"
				( attribute "CDS_PHYS_NET_NAME" "M_E_ECC<6>"
					( Origin gPackager )
				)
				( attribute "PNN" "M_E_ECC<6>"
					( Origin gPackager )
				)
				( objectStatus "M_E_ECC<6>" )
			)
			( signal "@baseboard_fab2_lib.baseboard_fab2(sch_1):m_e_ecc(7)"
				( attribute "CDS_PHYS_NET_NAME" "M_E_ECC<7>"
					( Origin gPackager )
				)
				( attribute "PNN" "M_E_ECC<7>"
					( Origin gPackager )
				)
				( objectStatus "M_E_ECC<7>" )
			)
			( signal "@baseboard_fab2_lib.baseboard_fab2(sch_1):m_e_ma(0)"
				( attribute "CDS_PHYS_NET_NAME" "M_E_MA<0>"
					( Origin gPackager )
				)
				( attribute "PNN" "M_E_MA<0>"
					( Origin gPackager )
				)
				( objectStatus "M_E_MA<0>" )
			)
			( signal "@baseboard_fab2_lib.baseboard_fab2(sch_1):m_e_ma(1)"
				( attribute "CDS_PHYS_NET_NAME" "M_E_MA<1>"
					( Origin gPackager )
				)
				( attribute "PNN" "M_E_MA<1>"
					( Origin gPackager )
				)
				( objectStatus "M_E_MA<1>" )
			)
			( signal "@baseboard_fab2_lib.baseboard_fab2(sch_1):m_e_ma(2)"
				( attribute "CDS_PHYS_NET_NAME" "M_E_MA<2>"
					( Origin gPackager )
				)
				( attribute "PNN" "M_E_MA<2>"
					( Origin gPackager )
				)
				( objectStatus "M_E_MA<2>" )
			)
			( signal "@baseboard_fab2_lib.baseboard_fab2(sch_1):m_e_ma(3)"
				( attribute "CDS_PHYS_NET_NAME" "M_E_MA<3>"
					( Origin gPackager )
				)
				( attribute "PNN" "M_E_MA<3>"
					( Origin gPackager )
				)
				( objectStatus "M_E_MA<3>" )
			)
			( signal "@baseboard_fab2_lib.baseboard_fab2(sch_1):m_e_ma(4)"
				( attribute "CDS_PHYS_NET_NAME" "M_E_MA<4>"
					( Origin gPackager )
				)
				( attribute "PNN" "M_E_MA<4>"
					( Origin gPackager )
				)
				( objectStatus "M_E_MA<4>" )
			)
			( signal "@baseboard_fab2_lib.baseboard_fab2(sch_1):m_e_ma(5)"
				( attribute "CDS_PHYS_NET_NAME" "M_E_MA<5>"
					( Origin gPackager )
				)
				( attribute "PNN" "M_E_MA<5>"
					( Origin gPackager )
				)
				( objectStatus "M_E_MA<5>" )
			)
			( signal "@baseboard_fab2_lib.baseboard_fab2(sch_1):m_e_ma(6)"
				( attribute "CDS_PHYS_NET_NAME" "M_E_MA<6>"
					( Origin gPackager )
				)
				( attribute "PNN" "M_E_MA<6>"
					( Origin gPackager )
				)
				( objectStatus "M_E_MA<6>" )
			)
			( signal "@baseboard_fab2_lib.baseboard_fab2(sch_1):m_e_ma(7)"
				( attribute "CDS_PHYS_NET_NAME" "M_E_MA<7>"
					( Origin gPackager )
				)
				( attribute "PNN" "M_E_MA<7>"
					( Origin gPackager )
				)
				( objectStatus "M_E_MA<7>" )
			)
			( signal "@baseboard_fab2_lib.baseboard_fab2(sch_1):m_e_ma(8)"
				( attribute "CDS_PHYS_NET_NAME" "M_E_MA<8>"
					( Origin gPackager )
				)
				( attribute "PNN" "M_E_MA<8>"
					( Origin gPackager )
				)
				( objectStatus "M_E_MA<8>" )
			)
			( signal "@baseboard_fab2_lib.baseboard_fab2(sch_1):m_e_ma(9)"
				( attribute "CDS_PHYS_NET_NAME" "M_E_MA<9>"
					( Origin gPackager )
				)
				( attribute "PNN" "M_E_MA<9>"
					( Origin gPackager )
				)
				( objectStatus "M_E_MA<9>" )
			)
			( signal "@baseboard_fab2_lib.baseboard_fab2(sch_1):m_e_ma(10)"
				( attribute "CDS_PHYS_NET_NAME" "M_E_MA<10>"
					( Origin gPackager )
				)
				( attribute "PNN" "M_E_MA<10>"
					( Origin gPackager )
				)
				( objectStatus "M_E_MA<10>" )
			)
			( signal "@baseboard_fab2_lib.baseboard_fab2(sch_1):m_e_ma(11)"
				( attribute "CDS_PHYS_NET_NAME" "M_E_MA<11>"
					( Origin gPackager )
				)
				( attribute "PNN" "M_E_MA<11>"
					( Origin gPackager )
				)
				( objectStatus "M_E_MA<11>" )
			)
			( signal "@baseboard_fab2_lib.baseboard_fab2(sch_1):m_e_ma(12)"
				( attribute "CDS_PHYS_NET_NAME" "M_E_MA<12>"
					( Origin gPackager )
				)
				( attribute "PNN" "M_E_MA<12>"
					( Origin gPackager )
				)
				( objectStatus "M_E_MA<12>" )
			)
			( signal "@baseboard_fab2_lib.baseboard_fab2(sch_1):m_e_ma(13)"
				( attribute "CDS_PHYS_NET_NAME" "M_E_MA<13>"
					( Origin gPackager )
				)
				( attribute "PNN" "M_E_MA<13>"
					( Origin gPackager )
				)
				( objectStatus "M_E_MA<13>" )
			)
			( signal "@baseboard_fab2_lib.baseboard_fab2(sch_1):m_e_ma(14)"
				( attribute "CDS_PHYS_NET_NAME" "M_E_MA<14>"
					( Origin gPackager )
				)
				( attribute "PNN" "M_E_MA<14>"
					( Origin gPackager )
				)
				( objectStatus "M_E_MA<14>" )
			)
			( signal "@baseboard_fab2_lib.baseboard_fab2(sch_1):m_e_ma(15)"
				( attribute "CDS_PHYS_NET_NAME" "M_E_MA<15>"
					( Origin gPackager )
				)
				( attribute "PNN" "M_E_MA<15>"
					( Origin gPackager )
				)
				( objectStatus "M_E_MA<15>" )
			)
			( signal "@baseboard_fab2_lib.baseboard_fab2(sch_1):m_e_ma(16)"
				( attribute "CDS_PHYS_NET_NAME" "M_E_MA<16>"
					( Origin gPackager )
				)
				( attribute "PNN" "M_E_MA<16>"
					( Origin gPackager )
				)
				( objectStatus "M_E_MA<16>" )
			)
			( signal "@baseboard_fab2_lib.baseboard_fab2(sch_1):m_e_ma(17)"
				( attribute "CDS_PHYS_NET_NAME" "M_E_MA<17>"
					( Origin gPackager )
				)
				( attribute "PNN" "M_E_MA<17>"
					( Origin gPackager )
				)
				( objectStatus "M_E_MA<17>" )
			)
			( signal "@baseboard_fab2_lib.baseboard_fab2(sch_1):m_e_odt(0)"
				( attribute "CDS_PHYS_NET_NAME" "M_E_ODT<0>"
					( Origin gPackager )
				)
				( attribute "PNN" "M_E_ODT<0>"
					( Origin gPackager )
				)
				( objectStatus "M_E_ODT<0>" )
			)
			( signal "@baseboard_fab2_lib.baseboard_fab2(sch_1):m_e_odt(1)"
				( attribute "CDS_PHYS_NET_NAME" "M_E_ODT<1>"
					( Origin gPackager )
				)
				( attribute "PNN" "M_E_ODT<1>"
					( Origin gPackager )
				)
				( objectStatus "M_E_ODT<1>" )
			)
			( signal "@baseboard_fab2_lib.baseboard_fab2(sch_1):m_e_odt(2)"
				( attribute "CDS_PHYS_NET_NAME" "M_E_ODT<2>"
					( Origin gPackager )
				)
				( attribute "PNN" "M_E_ODT<2>"
					( Origin gPackager )
				)
				( objectStatus "M_E_ODT<2>" )
			)
			( signal "@baseboard_fab2_lib.baseboard_fab2(sch_1):m_e_odt(3)"
				( attribute "CDS_PHYS_NET_NAME" "M_E_ODT<3>"
					( Origin gPackager )
				)
				( attribute "PNN" "M_E_ODT<3>"
					( Origin gPackager )
				)
				( objectStatus "M_E_ODT<3>" )
			)
			( signal "@baseboard_fab2_lib.baseboard_fab2(sch_1):m_e_par"
				( attribute "CDS_PHYS_NET_NAME" "M_E_PAR"
					( Origin gPackager )
				)
				( objectStatus "M_E_PAR" )
			)
			( signal "@baseboard_fab2_lib.baseboard_fab2(sch_1):m_f_act_n"
				( attribute "CDS_PHYS_NET_NAME" "M_F_ACT_N"
					( Origin gPackager )
				)
				( objectStatus "M_F_ACT_N" )
			)
			( signal "@baseboard_fab2_lib.baseboard_fab2(sch_1):m_f_alert_n"
				( attribute "CDS_PHYS_NET_NAME" "M_F_ALERT_N"
					( Origin gPackager )
				)
				( objectStatus "M_F_ALERT_N" )
			)
			( signal "@baseboard_fab2_lib.baseboard_fab2(sch_1):m_f_ba(0)"
				( attribute "CDS_PHYS_NET_NAME" "M_F_BA<0>"
					( Origin gPackager )
				)
				( attribute "PNN" "M_F_BA<0>"
					( Origin gPackager )
				)
				( objectStatus "M_F_BA<0>" )
			)
			( signal "@baseboard_fab2_lib.baseboard_fab2(sch_1):m_f_ba(1)"
				( attribute "CDS_PHYS_NET_NAME" "M_F_BA<1>"
					( Origin gPackager )
				)
				( attribute "PNN" "M_F_BA<1>"
					( Origin gPackager )
				)
				( objectStatus "M_F_BA<1>" )
			)
			( signal "@baseboard_fab2_lib.baseboard_fab2(sch_1):m_f_bg(0)"
				( attribute "CDS_PHYS_NET_NAME" "M_F_BG<0>"
					( Origin gPackager )
				)
				( attribute "PNN" "M_F_BG<0>"
					( Origin gPackager )
				)
				( objectStatus "M_F_BG<0>" )
			)
			( signal "@baseboard_fab2_lib.baseboard_fab2(sch_1):m_f_bg(1)"
				( attribute "CDS_PHYS_NET_NAME" "M_F_BG<1>"
					( Origin gPackager )
				)
				( attribute "PNN" "M_F_BG<1>"
					( Origin gPackager )
				)
				( objectStatus "M_F_BG<1>" )
			)
			( signal "@baseboard_fab2_lib.baseboard_fab2(sch_1):m_f_c(2)"
				( attribute "CDS_PHYS_NET_NAME" "M_F_C<2>"
					( Origin gPackager )
				)
				( attribute "PNN" "M_F_C<2>"
					( Origin gPackager )
				)
				( objectStatus "M_F_C<2>" )
			)
			( signal "@baseboard_fab2_lib.baseboard_fab2(sch_1):m_f_cke(0)"
				( attribute "CDS_PHYS_NET_NAME" "M_F_CKE<0>"
					( Origin gPackager )
				)
				( attribute "PNN" "M_F_CKE<0>"
					( Origin gPackager )
				)
				( objectStatus "M_F_CKE<0>" )
			)
			( signal "@baseboard_fab2_lib.baseboard_fab2(sch_1):m_f_cke(1)"
				( attribute "CDS_PHYS_NET_NAME" "M_F_CKE<1>"
					( Origin gPackager )
				)
				( attribute "PNN" "M_F_CKE<1>"
					( Origin gPackager )
				)
				( objectStatus "M_F_CKE<1>" )
			)
			( signal "@baseboard_fab2_lib.baseboard_fab2(sch_1):m_f_cke(2)"
				( attribute "CDS_PHYS_NET_NAME" "M_F_CKE<2>"
					( Origin gPackager )
				)
				( attribute "PNN" "M_F_CKE<2>"
					( Origin gPackager )
				)
				( objectStatus "M_F_CKE<2>" )
			)
			( signal "@baseboard_fab2_lib.baseboard_fab2(sch_1):m_f_cke(3)"
				( attribute "CDS_PHYS_NET_NAME" "M_F_CKE<3>"
					( Origin gPackager )
				)
				( attribute "PNN" "M_F_CKE<3>"
					( Origin gPackager )
				)
				( objectStatus "M_F_CKE<3>" )
			)
			( signal "@baseboard_fab2_lib.baseboard_fab2(sch_1):m_f_clk_dn(0)"
				( attribute "CDS_PHYS_NET_NAME" "M_F_CLK_DN<0>"
					( Origin gPackager )
				)
				( attribute "PNN" "M_F_CLK_DN<0>"
					( Origin gPackager )
				)
				( objectStatus "M_F_CLK_DN<0>" )
			)
			( signal "@baseboard_fab2_lib.baseboard_fab2(sch_1):m_f_clk_dn(1)"
				( attribute "CDS_PHYS_NET_NAME" "M_F_CLK_DN<1>"
					( Origin gPackager )
				)
				( attribute "PNN" "M_F_CLK_DN<1>"
					( Origin gPackager )
				)
				( objectStatus "M_F_CLK_DN<1>" )
			)
			( signal "@baseboard_fab2_lib.baseboard_fab2(sch_1):m_f_clk_dn(2)"
				( attribute "CDS_PHYS_NET_NAME" "M_F_CLK_DN<2>"
					( Origin gPackager )
				)
				( attribute "PNN" "M_F_CLK_DN<2>"
					( Origin gPackager )
				)
				( objectStatus "M_F_CLK_DN<2>" )
			)
			( signal "@baseboard_fab2_lib.baseboard_fab2(sch_1):m_f_clk_dn(3)"
				( attribute "CDS_PHYS_NET_NAME" "M_F_CLK_DN<3>"
					( Origin gPackager )
				)
				( attribute "PNN" "M_F_CLK_DN<3>"
					( Origin gPackager )
				)
				( objectStatus "M_F_CLK_DN<3>" )
			)
			( signal "@baseboard_fab2_lib.baseboard_fab2(sch_1):m_f_clk_dp(0)"
				( attribute "CDS_PHYS_NET_NAME" "M_F_CLK_DP<0>"
					( Origin gPackager )
				)
				( attribute "PNN" "M_F_CLK_DP<0>"
					( Origin gPackager )
				)
				( objectStatus "M_F_CLK_DP<0>" )
			)
			( signal "@baseboard_fab2_lib.baseboard_fab2(sch_1):m_f_clk_dp(1)"
				( attribute "CDS_PHYS_NET_NAME" "M_F_CLK_DP<1>"
					( Origin gPackager )
				)
				( attribute "PNN" "M_F_CLK_DP<1>"
					( Origin gPackager )
				)
				( objectStatus "M_F_CLK_DP<1>" )
			)
			( signal "@baseboard_fab2_lib.baseboard_fab2(sch_1):m_f_clk_dp(2)"
				( attribute "CDS_PHYS_NET_NAME" "M_F_CLK_DP<2>"
					( Origin gPackager )
				)
				( attribute "PNN" "M_F_CLK_DP<2>"
					( Origin gPackager )
				)
				( objectStatus "M_F_CLK_DP<2>" )
			)
			( signal "@baseboard_fab2_lib.baseboard_fab2(sch_1):m_f_clk_dp(3)"
				( attribute "CDS_PHYS_NET_NAME" "M_F_CLK_DP<3>"
					( Origin gPackager )
				)
				( attribute "PNN" "M_F_CLK_DP<3>"
					( Origin gPackager )
				)
				( objectStatus "M_F_CLK_DP<3>" )
			)
			( signal "@baseboard_fab2_lib.baseboard_fab2(sch_1):m_f_cs_n(0)"
				( attribute "CDS_PHYS_NET_NAME" "M_F_CS_N<0>"
					( Origin gPackager )
				)
				( attribute "PNN" "M_F_CS_N<0>"
					( Origin gPackager )
				)
				( objectStatus "M_F_CS_N<0>" )
			)
			( signal "@baseboard_fab2_lib.baseboard_fab2(sch_1):m_f_cs_n(1)"
				( attribute "CDS_PHYS_NET_NAME" "M_F_CS_N<1>"
					( Origin gPackager )
				)
				( attribute "PNN" "M_F_CS_N<1>"
					( Origin gPackager )
				)
				( objectStatus "M_F_CS_N<1>" )
			)
			( signal "@baseboard_fab2_lib.baseboard_fab2(sch_1):m_f_cs_n(2)"
				( attribute "CDS_PHYS_NET_NAME" "M_F_CS_N<2>"
					( Origin gPackager )
				)
				( attribute "PNN" "M_F_CS_N<2>"
					( Origin gPackager )
				)
				( objectStatus "M_F_CS_N<2>" )
			)
			( signal "@baseboard_fab2_lib.baseboard_fab2(sch_1):m_f_cs_n(3)"
				( attribute "CDS_PHYS_NET_NAME" "M_F_CS_N<3>"
					( Origin gPackager )
				)
				( attribute "PNN" "M_F_CS_N<3>"
					( Origin gPackager )
				)
				( objectStatus "M_F_CS_N<3>" )
			)
			( signal "@baseboard_fab2_lib.baseboard_fab2(sch_1):m_f_cs_n(4)"
				( attribute "CDS_PHYS_NET_NAME" "M_F_CS_N<4>"
					( Origin gPackager )
				)
				( attribute "PNN" "M_F_CS_N<4>"
					( Origin gPackager )
				)
				( objectStatus "M_F_CS_N<4>" )
			)
			( signal "@baseboard_fab2_lib.baseboard_fab2(sch_1):m_f_cs_n(5)"
				( attribute "CDS_PHYS_NET_NAME" "M_F_CS_N<5>"
					( Origin gPackager )
				)
				( attribute "PNN" "M_F_CS_N<5>"
					( Origin gPackager )
				)
				( objectStatus "M_F_CS_N<5>" )
			)
			( signal "@baseboard_fab2_lib.baseboard_fab2(sch_1):m_f_cs_n(6)"
				( attribute "CDS_PHYS_NET_NAME" "M_F_CS_N<6>"
					( Origin gPackager )
				)
				( attribute "PNN" "M_F_CS_N<6>"
					( Origin gPackager )
				)
				( objectStatus "M_F_CS_N<6>" )
			)
			( signal "@baseboard_fab2_lib.baseboard_fab2(sch_1):m_f_cs_n(7)"
				( attribute "CDS_PHYS_NET_NAME" "M_F_CS_N<7>"
					( Origin gPackager )
				)
				( attribute "PNN" "M_F_CS_N<7>"
					( Origin gPackager )
				)
				( objectStatus "M_F_CS_N<7>" )
			)
			( signal "@baseboard_fab2_lib.baseboard_fab2(sch_1):m_f_dq(0)"
				( attribute "CDS_PHYS_NET_NAME" "M_F_DQ<0>"
					( Origin gPackager )
				)
				( attribute "PNN" "M_F_DQ<0>"
					( Origin gPackager )
				)
				( objectStatus "M_F_DQ<0>" )
			)
			( signal "@baseboard_fab2_lib.baseboard_fab2(sch_1):m_f_dq(1)"
				( attribute "CDS_PHYS_NET_NAME" "M_F_DQ<1>"
					( Origin gPackager )
				)
				( attribute "PNN" "M_F_DQ<1>"
					( Origin gPackager )
				)
				( objectStatus "M_F_DQ<1>" )
			)
			( signal "@baseboard_fab2_lib.baseboard_fab2(sch_1):m_f_dq(2)"
				( attribute "CDS_PHYS_NET_NAME" "M_F_DQ<2>"
					( Origin gPackager )
				)
				( attribute "PNN" "M_F_DQ<2>"
					( Origin gPackager )
				)
				( objectStatus "M_F_DQ<2>" )
			)
			( signal "@baseboard_fab2_lib.baseboard_fab2(sch_1):m_f_dq(3)"
				( attribute "CDS_PHYS_NET_NAME" "M_F_DQ<3>"
					( Origin gPackager )
				)
				( attribute "PNN" "M_F_DQ<3>"
					( Origin gPackager )
				)
				( objectStatus "M_F_DQ<3>" )
			)
			( signal "@baseboard_fab2_lib.baseboard_fab2(sch_1):m_f_dq(4)"
				( attribute "CDS_PHYS_NET_NAME" "M_F_DQ<4>"
					( Origin gPackager )
				)
				( attribute "PNN" "M_F_DQ<4>"
					( Origin gPackager )
				)
				( objectStatus "M_F_DQ<4>" )
			)
			( signal "@baseboard_fab2_lib.baseboard_fab2(sch_1):m_f_dq(5)"
				( attribute "CDS_PHYS_NET_NAME" "M_F_DQ<5>"
					( Origin gPackager )
				)
				( attribute "PNN" "M_F_DQ<5>"
					( Origin gPackager )
				)
				( objectStatus "M_F_DQ<5>" )
			)
			( signal "@baseboard_fab2_lib.baseboard_fab2(sch_1):m_f_dq(6)"
				( attribute "CDS_PHYS_NET_NAME" "M_F_DQ<6>"
					( Origin gPackager )
				)
				( attribute "PNN" "M_F_DQ<6>"
					( Origin gPackager )
				)
				( objectStatus "M_F_DQ<6>" )
			)
			( signal "@baseboard_fab2_lib.baseboard_fab2(sch_1):m_f_dq(7)"
				( attribute "CDS_PHYS_NET_NAME" "M_F_DQ<7>"
					( Origin gPackager )
				)
				( attribute "PNN" "M_F_DQ<7>"
					( Origin gPackager )
				)
				( objectStatus "M_F_DQ<7>" )
			)
			( signal "@baseboard_fab2_lib.baseboard_fab2(sch_1):m_f_dq(8)"
				( attribute "CDS_PHYS_NET_NAME" "M_F_DQ<8>"
					( Origin gPackager )
				)
				( attribute "PNN" "M_F_DQ<8>"
					( Origin gPackager )
				)
				( objectStatus "M_F_DQ<8>" )
			)
			( signal "@baseboard_fab2_lib.baseboard_fab2(sch_1):m_f_dq(9)"
				( attribute "CDS_PHYS_NET_NAME" "M_F_DQ<9>"
					( Origin gPackager )
				)
				( attribute "PNN" "M_F_DQ<9>"
					( Origin gPackager )
				)
				( objectStatus "M_F_DQ<9>" )
			)
			( signal "@baseboard_fab2_lib.baseboard_fab2(sch_1):m_f_dq(10)"
				( attribute "CDS_PHYS_NET_NAME" "M_F_DQ<10>"
					( Origin gPackager )
				)
				( attribute "PNN" "M_F_DQ<10>"
					( Origin gPackager )
				)
				( objectStatus "M_F_DQ<10>" )
			)
			( signal "@baseboard_fab2_lib.baseboard_fab2(sch_1):m_f_dq(11)"
				( attribute "CDS_PHYS_NET_NAME" "M_F_DQ<11>"
					( Origin gPackager )
				)
				( attribute "PNN" "M_F_DQ<11>"
					( Origin gPackager )
				)
				( objectStatus "M_F_DQ<11>" )
			)
			( signal "@baseboard_fab2_lib.baseboard_fab2(sch_1):m_f_dq(12)"
				( attribute "CDS_PHYS_NET_NAME" "M_F_DQ<12>"
					( Origin gPackager )
				)
				( attribute "PNN" "M_F_DQ<12>"
					( Origin gPackager )
				)
				( objectStatus "M_F_DQ<12>" )
			)
			( signal "@baseboard_fab2_lib.baseboard_fab2(sch_1):m_f_dq(13)"
				( attribute "CDS_PHYS_NET_NAME" "M_F_DQ<13>"
					( Origin gPackager )
				)
				( attribute "PNN" "M_F_DQ<13>"
					( Origin gPackager )
				)
				( objectStatus "M_F_DQ<13>" )
			)
			( signal "@baseboard_fab2_lib.baseboard_fab2(sch_1):m_f_dq(14)"
				( attribute "CDS_PHYS_NET_NAME" "M_F_DQ<14>"
					( Origin gPackager )
				)
				( attribute "PNN" "M_F_DQ<14>"
					( Origin gPackager )
				)
				( objectStatus "M_F_DQ<14>" )
			)
			( signal "@baseboard_fab2_lib.baseboard_fab2(sch_1):m_f_dq(15)"
				( attribute "CDS_PHYS_NET_NAME" "M_F_DQ<15>"
					( Origin gPackager )
				)
				( attribute "PNN" "M_F_DQ<15>"
					( Origin gPackager )
				)
				( objectStatus "M_F_DQ<15>" )
			)
			( signal "@baseboard_fab2_lib.baseboard_fab2(sch_1):m_f_dq(16)"
				( attribute "CDS_PHYS_NET_NAME" "M_F_DQ<16>"
					( Origin gPackager )
				)
				( attribute "PNN" "M_F_DQ<16>"
					( Origin gPackager )
				)
				( objectStatus "M_F_DQ<16>" )
			)
			( signal "@baseboard_fab2_lib.baseboard_fab2(sch_1):m_f_dq(17)"
				( attribute "CDS_PHYS_NET_NAME" "M_F_DQ<17>"
					( Origin gPackager )
				)
				( attribute "PNN" "M_F_DQ<17>"
					( Origin gPackager )
				)
				( objectStatus "M_F_DQ<17>" )
			)
			( signal "@baseboard_fab2_lib.baseboard_fab2(sch_1):m_f_dq(18)"
				( attribute "CDS_PHYS_NET_NAME" "M_F_DQ<18>"
					( Origin gPackager )
				)
				( attribute "PNN" "M_F_DQ<18>"
					( Origin gPackager )
				)
				( objectStatus "M_F_DQ<18>" )
			)
			( signal "@baseboard_fab2_lib.baseboard_fab2(sch_1):m_f_dq(19)"
				( attribute "CDS_PHYS_NET_NAME" "M_F_DQ<19>"
					( Origin gPackager )
				)
				( attribute "PNN" "M_F_DQ<19>"
					( Origin gPackager )
				)
				( objectStatus "M_F_DQ<19>" )
			)
			( signal "@baseboard_fab2_lib.baseboard_fab2(sch_1):m_f_dq(20)"
				( attribute "CDS_PHYS_NET_NAME" "M_F_DQ<20>"
					( Origin gPackager )
				)
				( attribute "PNN" "M_F_DQ<20>"
					( Origin gPackager )
				)
				( objectStatus "M_F_DQ<20>" )
			)
			( signal "@baseboard_fab2_lib.baseboard_fab2(sch_1):m_f_dq(21)"
				( attribute "CDS_PHYS_NET_NAME" "M_F_DQ<21>"
					( Origin gPackager )
				)
				( attribute "PNN" "M_F_DQ<21>"
					( Origin gPackager )
				)
				( objectStatus "M_F_DQ<21>" )
			)
			( signal "@baseboard_fab2_lib.baseboard_fab2(sch_1):m_f_dq(22)"
				( attribute "CDS_PHYS_NET_NAME" "M_F_DQ<22>"
					( Origin gPackager )
				)
				( attribute "PNN" "M_F_DQ<22>"
					( Origin gPackager )
				)
				( objectStatus "M_F_DQ<22>" )
			)
			( signal "@baseboard_fab2_lib.baseboard_fab2(sch_1):m_f_dq(23)"
				( attribute "CDS_PHYS_NET_NAME" "M_F_DQ<23>"
					( Origin gPackager )
				)
				( attribute "PNN" "M_F_DQ<23>"
					( Origin gPackager )
				)
				( objectStatus "M_F_DQ<23>" )
			)
			( signal "@baseboard_fab2_lib.baseboard_fab2(sch_1):m_f_dq(24)"
				( attribute "CDS_PHYS_NET_NAME" "M_F_DQ<24>"
					( Origin gPackager )
				)
				( attribute "PNN" "M_F_DQ<24>"
					( Origin gPackager )
				)
				( objectStatus "M_F_DQ<24>" )
			)
			( signal "@baseboard_fab2_lib.baseboard_fab2(sch_1):m_f_dq(25)"
				( attribute "CDS_PHYS_NET_NAME" "M_F_DQ<25>"
					( Origin gPackager )
				)
				( attribute "PNN" "M_F_DQ<25>"
					( Origin gPackager )
				)
				( objectStatus "M_F_DQ<25>" )
			)
			( signal "@baseboard_fab2_lib.baseboard_fab2(sch_1):m_f_dq(26)"
				( attribute "CDS_PHYS_NET_NAME" "M_F_DQ<26>"
					( Origin gPackager )
				)
				( attribute "PNN" "M_F_DQ<26>"
					( Origin gPackager )
				)
				( objectStatus "M_F_DQ<26>" )
			)
			( signal "@baseboard_fab2_lib.baseboard_fab2(sch_1):m_f_dq(27)"
				( attribute "CDS_PHYS_NET_NAME" "M_F_DQ<27>"
					( Origin gPackager )
				)
				( attribute "PNN" "M_F_DQ<27>"
					( Origin gPackager )
				)
				( objectStatus "M_F_DQ<27>" )
			)
			( signal "@baseboard_fab2_lib.baseboard_fab2(sch_1):m_f_dq(28)"
				( attribute "CDS_PHYS_NET_NAME" "M_F_DQ<28>"
					( Origin gPackager )
				)
				( attribute "PNN" "M_F_DQ<28>"
					( Origin gPackager )
				)
				( objectStatus "M_F_DQ<28>" )
			)
			( signal "@baseboard_fab2_lib.baseboard_fab2(sch_1):m_f_dq(29)"
				( attribute "CDS_PHYS_NET_NAME" "M_F_DQ<29>"
					( Origin gPackager )
				)
				( attribute "PNN" "M_F_DQ<29>"
					( Origin gPackager )
				)
				( objectStatus "M_F_DQ<29>" )
			)
			( signal "@baseboard_fab2_lib.baseboard_fab2(sch_1):m_f_dq(30)"
				( attribute "CDS_PHYS_NET_NAME" "M_F_DQ<30>"
					( Origin gPackager )
				)
				( attribute "PNN" "M_F_DQ<30>"
					( Origin gPackager )
				)
				( objectStatus "M_F_DQ<30>" )
			)
			( signal "@baseboard_fab2_lib.baseboard_fab2(sch_1):m_f_dq(31)"
				( attribute "CDS_PHYS_NET_NAME" "M_F_DQ<31>"
					( Origin gPackager )
				)
				( attribute "PNN" "M_F_DQ<31>"
					( Origin gPackager )
				)
				( objectStatus "M_F_DQ<31>" )
			)
			( signal "@baseboard_fab2_lib.baseboard_fab2(sch_1):m_f_dq(32)"
				( attribute "CDS_PHYS_NET_NAME" "M_F_DQ<32>"
					( Origin gPackager )
				)
				( attribute "PNN" "M_F_DQ<32>"
					( Origin gPackager )
				)
				( objectStatus "M_F_DQ<32>" )
			)
			( signal "@baseboard_fab2_lib.baseboard_fab2(sch_1):m_f_dq(33)"
				( attribute "CDS_PHYS_NET_NAME" "M_F_DQ<33>"
					( Origin gPackager )
				)
				( attribute "PNN" "M_F_DQ<33>"
					( Origin gPackager )
				)
				( objectStatus "M_F_DQ<33>" )
			)
			( signal "@baseboard_fab2_lib.baseboard_fab2(sch_1):m_f_dq(34)"
				( attribute "CDS_PHYS_NET_NAME" "M_F_DQ<34>"
					( Origin gPackager )
				)
				( attribute "PNN" "M_F_DQ<34>"
					( Origin gPackager )
				)
				( objectStatus "M_F_DQ<34>" )
			)
			( signal "@baseboard_fab2_lib.baseboard_fab2(sch_1):m_f_dq(35)"
				( attribute "CDS_PHYS_NET_NAME" "M_F_DQ<35>"
					( Origin gPackager )
				)
				( attribute "PNN" "M_F_DQ<35>"
					( Origin gPackager )
				)
				( objectStatus "M_F_DQ<35>" )
			)
			( signal "@baseboard_fab2_lib.baseboard_fab2(sch_1):m_f_dq(36)"
				( attribute "CDS_PHYS_NET_NAME" "M_F_DQ<36>"
					( Origin gPackager )
				)
				( attribute "PNN" "M_F_DQ<36>"
					( Origin gPackager )
				)
				( objectStatus "M_F_DQ<36>" )
			)
			( signal "@baseboard_fab2_lib.baseboard_fab2(sch_1):m_f_dq(37)"
				( attribute "CDS_PHYS_NET_NAME" "M_F_DQ<37>"
					( Origin gPackager )
				)
				( attribute "PNN" "M_F_DQ<37>"
					( Origin gPackager )
				)
				( objectStatus "M_F_DQ<37>" )
			)
			( signal "@baseboard_fab2_lib.baseboard_fab2(sch_1):m_f_dq(38)"
				( attribute "CDS_PHYS_NET_NAME" "M_F_DQ<38>"
					( Origin gPackager )
				)
				( attribute "PNN" "M_F_DQ<38>"
					( Origin gPackager )
				)
				( objectStatus "M_F_DQ<38>" )
			)
			( signal "@baseboard_fab2_lib.baseboard_fab2(sch_1):m_f_dq(39)"
				( attribute "CDS_PHYS_NET_NAME" "M_F_DQ<39>"
					( Origin gPackager )
				)
				( attribute "PNN" "M_F_DQ<39>"
					( Origin gPackager )
				)
				( objectStatus "M_F_DQ<39>" )
			)
			( signal "@baseboard_fab2_lib.baseboard_fab2(sch_1):m_f_dq(40)"
				( attribute "CDS_PHYS_NET_NAME" "M_F_DQ<40>"
					( Origin gPackager )
				)
				( attribute "PNN" "M_F_DQ<40>"
					( Origin gPackager )
				)
				( objectStatus "M_F_DQ<40>" )
			)
			( signal "@baseboard_fab2_lib.baseboard_fab2(sch_1):m_f_dq(41)"
				( attribute "CDS_PHYS_NET_NAME" "M_F_DQ<41>"
					( Origin gPackager )
				)
				( attribute "PNN" "M_F_DQ<41>"
					( Origin gPackager )
				)
				( objectStatus "M_F_DQ<41>" )
			)
			( signal "@baseboard_fab2_lib.baseboard_fab2(sch_1):m_f_dq(42)"
				( attribute "CDS_PHYS_NET_NAME" "M_F_DQ<42>"
					( Origin gPackager )
				)
				( attribute "PNN" "M_F_DQ<42>"
					( Origin gPackager )
				)
				( objectStatus "M_F_DQ<42>" )
			)
			( signal "@baseboard_fab2_lib.baseboard_fab2(sch_1):m_f_dq(43)"
				( attribute "CDS_PHYS_NET_NAME" "M_F_DQ<43>"
					( Origin gPackager )
				)
				( attribute "PNN" "M_F_DQ<43>"
					( Origin gPackager )
				)
				( objectStatus "M_F_DQ<43>" )
			)
			( signal "@baseboard_fab2_lib.baseboard_fab2(sch_1):m_f_dq(44)"
				( attribute "CDS_PHYS_NET_NAME" "M_F_DQ<44>"
					( Origin gPackager )
				)
				( attribute "PNN" "M_F_DQ<44>"
					( Origin gPackager )
				)
				( objectStatus "M_F_DQ<44>" )
			)
			( signal "@baseboard_fab2_lib.baseboard_fab2(sch_1):m_f_dq(45)"
				( attribute "CDS_PHYS_NET_NAME" "M_F_DQ<45>"
					( Origin gPackager )
				)
				( attribute "PNN" "M_F_DQ<45>"
					( Origin gPackager )
				)
				( objectStatus "M_F_DQ<45>" )
			)
			( signal "@baseboard_fab2_lib.baseboard_fab2(sch_1):m_f_dq(46)"
				( attribute "CDS_PHYS_NET_NAME" "M_F_DQ<46>"
					( Origin gPackager )
				)
				( attribute "PNN" "M_F_DQ<46>"
					( Origin gPackager )
				)
				( objectStatus "M_F_DQ<46>" )
			)
			( signal "@baseboard_fab2_lib.baseboard_fab2(sch_1):m_f_dq(47)"
				( attribute "CDS_PHYS_NET_NAME" "M_F_DQ<47>"
					( Origin gPackager )
				)
				( attribute "PNN" "M_F_DQ<47>"
					( Origin gPackager )
				)
				( objectStatus "M_F_DQ<47>" )
			)
			( signal "@baseboard_fab2_lib.baseboard_fab2(sch_1):m_f_dq(48)"
				( attribute "CDS_PHYS_NET_NAME" "M_F_DQ<48>"
					( Origin gPackager )
				)
				( attribute "PNN" "M_F_DQ<48>"
					( Origin gPackager )
				)
				( objectStatus "M_F_DQ<48>" )
			)
			( signal "@baseboard_fab2_lib.baseboard_fab2(sch_1):m_f_dq(49)"
				( attribute "CDS_PHYS_NET_NAME" "M_F_DQ<49>"
					( Origin gPackager )
				)
				( attribute "PNN" "M_F_DQ<49>"
					( Origin gPackager )
				)
				( objectStatus "M_F_DQ<49>" )
			)
			( signal "@baseboard_fab2_lib.baseboard_fab2(sch_1):m_f_dq(50)"
				( attribute "CDS_PHYS_NET_NAME" "M_F_DQ<50>"
					( Origin gPackager )
				)
				( attribute "PNN" "M_F_DQ<50>"
					( Origin gPackager )
				)
				( objectStatus "M_F_DQ<50>" )
			)
			( signal "@baseboard_fab2_lib.baseboard_fab2(sch_1):m_f_dq(51)"
				( attribute "CDS_PHYS_NET_NAME" "M_F_DQ<51>"
					( Origin gPackager )
				)
				( attribute "PNN" "M_F_DQ<51>"
					( Origin gPackager )
				)
				( objectStatus "M_F_DQ<51>" )
			)
			( signal "@baseboard_fab2_lib.baseboard_fab2(sch_1):m_f_dq(52)"
				( attribute "CDS_PHYS_NET_NAME" "M_F_DQ<52>"
					( Origin gPackager )
				)
				( attribute "PNN" "M_F_DQ<52>"
					( Origin gPackager )
				)
				( objectStatus "M_F_DQ<52>" )
			)
			( signal "@baseboard_fab2_lib.baseboard_fab2(sch_1):m_f_dq(53)"
				( attribute "CDS_PHYS_NET_NAME" "M_F_DQ<53>"
					( Origin gPackager )
				)
				( attribute "PNN" "M_F_DQ<53>"
					( Origin gPackager )
				)
				( objectStatus "M_F_DQ<53>" )
			)
			( signal "@baseboard_fab2_lib.baseboard_fab2(sch_1):m_f_dq(54)"
				( attribute "CDS_PHYS_NET_NAME" "M_F_DQ<54>"
					( Origin gPackager )
				)
				( attribute "PNN" "M_F_DQ<54>"
					( Origin gPackager )
				)
				( objectStatus "M_F_DQ<54>" )
			)
			( signal "@baseboard_fab2_lib.baseboard_fab2(sch_1):m_f_dq(55)"
				( attribute "CDS_PHYS_NET_NAME" "M_F_DQ<55>"
					( Origin gPackager )
				)
				( attribute "PNN" "M_F_DQ<55>"
					( Origin gPackager )
				)
				( objectStatus "M_F_DQ<55>" )
			)
			( signal "@baseboard_fab2_lib.baseboard_fab2(sch_1):m_f_dq(56)"
				( attribute "CDS_PHYS_NET_NAME" "M_F_DQ<56>"
					( Origin gPackager )
				)
				( attribute "PNN" "M_F_DQ<56>"
					( Origin gPackager )
				)
				( objectStatus "M_F_DQ<56>" )
			)
			( signal "@baseboard_fab2_lib.baseboard_fab2(sch_1):m_f_dq(57)"
				( attribute "CDS_PHYS_NET_NAME" "M_F_DQ<57>"
					( Origin gPackager )
				)
				( attribute "PNN" "M_F_DQ<57>"
					( Origin gPackager )
				)
				( objectStatus "M_F_DQ<57>" )
			)
			( signal "@baseboard_fab2_lib.baseboard_fab2(sch_1):m_f_dq(58)"
				( attribute "CDS_PHYS_NET_NAME" "M_F_DQ<58>"
					( Origin gPackager )
				)
				( attribute "PNN" "M_F_DQ<58>"
					( Origin gPackager )
				)
				( objectStatus "M_F_DQ<58>" )
			)
			( signal "@baseboard_fab2_lib.baseboard_fab2(sch_1):m_f_dq(59)"
				( attribute "CDS_PHYS_NET_NAME" "M_F_DQ<59>"
					( Origin gPackager )
				)
				( attribute "PNN" "M_F_DQ<59>"
					( Origin gPackager )
				)
				( objectStatus "M_F_DQ<59>" )
			)
			( signal "@baseboard_fab2_lib.baseboard_fab2(sch_1):m_f_dq(60)"
				( attribute "CDS_PHYS_NET_NAME" "M_F_DQ<60>"
					( Origin gPackager )
				)
				( attribute "PNN" "M_F_DQ<60>"
					( Origin gPackager )
				)
				( objectStatus "M_F_DQ<60>" )
			)
			( signal "@baseboard_fab2_lib.baseboard_fab2(sch_1):m_f_dq(61)"
				( attribute "CDS_PHYS_NET_NAME" "M_F_DQ<61>"
					( Origin gPackager )
				)
				( attribute "PNN" "M_F_DQ<61>"
					( Origin gPackager )
				)
				( objectStatus "M_F_DQ<61>" )
			)
			( signal "@baseboard_fab2_lib.baseboard_fab2(sch_1):m_f_dq(62)"
				( attribute "CDS_PHYS_NET_NAME" "M_F_DQ<62>"
					( Origin gPackager )
				)
				( attribute "PNN" "M_F_DQ<62>"
					( Origin gPackager )
				)
				( objectStatus "M_F_DQ<62>" )
			)
			( signal "@baseboard_fab2_lib.baseboard_fab2(sch_1):m_f_dq(63)"
				( attribute "CDS_PHYS_NET_NAME" "M_F_DQ<63>"
					( Origin gPackager )
				)
				( attribute "PNN" "M_F_DQ<63>"
					( Origin gPackager )
				)
				( objectStatus "M_F_DQ<63>" )
			)
			( signal "@baseboard_fab2_lib.baseboard_fab2(sch_1):m_f_dqs_dn(0)"
				( attribute "CDS_PHYS_NET_NAME" "M_F_DQS_DN<0>"
					( Origin gPackager )
				)
				( attribute "PNN" "M_F_DQS_DN<0>"
					( Origin gPackager )
				)
				( objectStatus "M_F_DQS_DN<0>" )
			)
			( signal "@baseboard_fab2_lib.baseboard_fab2(sch_1):m_f_dqs_dn(1)"
				( attribute "CDS_PHYS_NET_NAME" "M_F_DQS_DN<1>"
					( Origin gPackager )
				)
				( attribute "PNN" "M_F_DQS_DN<1>"
					( Origin gPackager )
				)
				( objectStatus "M_F_DQS_DN<1>" )
			)
			( signal "@baseboard_fab2_lib.baseboard_fab2(sch_1):m_f_dqs_dn(2)"
				( attribute "CDS_PHYS_NET_NAME" "M_F_DQS_DN<2>"
					( Origin gPackager )
				)
				( attribute "PNN" "M_F_DQS_DN<2>"
					( Origin gPackager )
				)
				( objectStatus "M_F_DQS_DN<2>" )
			)
			( signal "@baseboard_fab2_lib.baseboard_fab2(sch_1):m_f_dqs_dn(3)"
				( attribute "CDS_PHYS_NET_NAME" "M_F_DQS_DN<3>"
					( Origin gPackager )
				)
				( attribute "PNN" "M_F_DQS_DN<3>"
					( Origin gPackager )
				)
				( objectStatus "M_F_DQS_DN<3>" )
			)
			( signal "@baseboard_fab2_lib.baseboard_fab2(sch_1):m_f_dqs_dn(4)"
				( attribute "CDS_PHYS_NET_NAME" "M_F_DQS_DN<4>"
					( Origin gPackager )
				)
				( attribute "PNN" "M_F_DQS_DN<4>"
					( Origin gPackager )
				)
				( objectStatus "M_F_DQS_DN<4>" )
			)
			( signal "@baseboard_fab2_lib.baseboard_fab2(sch_1):m_f_dqs_dn(5)"
				( attribute "CDS_PHYS_NET_NAME" "M_F_DQS_DN<5>"
					( Origin gPackager )
				)
				( attribute "PNN" "M_F_DQS_DN<5>"
					( Origin gPackager )
				)
				( objectStatus "M_F_DQS_DN<5>" )
			)
			( signal "@baseboard_fab2_lib.baseboard_fab2(sch_1):m_f_dqs_dn(6)"
				( attribute "CDS_PHYS_NET_NAME" "M_F_DQS_DN<6>"
					( Origin gPackager )
				)
				( attribute "PNN" "M_F_DQS_DN<6>"
					( Origin gPackager )
				)
				( objectStatus "M_F_DQS_DN<6>" )
			)
			( signal "@baseboard_fab2_lib.baseboard_fab2(sch_1):m_f_dqs_dn(7)"
				( attribute "CDS_PHYS_NET_NAME" "M_F_DQS_DN<7>"
					( Origin gPackager )
				)
				( attribute "PNN" "M_F_DQS_DN<7>"
					( Origin gPackager )
				)
				( objectStatus "M_F_DQS_DN<7>" )
			)
			( signal "@baseboard_fab2_lib.baseboard_fab2(sch_1):m_f_dqs_dn(8)"
				( attribute "CDS_PHYS_NET_NAME" "M_F_DQS_DN<8>"
					( Origin gPackager )
				)
				( attribute "PNN" "M_F_DQS_DN<8>"
					( Origin gPackager )
				)
				( objectStatus "M_F_DQS_DN<8>" )
			)
			( signal "@baseboard_fab2_lib.baseboard_fab2(sch_1):m_f_dqs_dn(9)"
				( attribute "CDS_PHYS_NET_NAME" "M_F_DQS_DN<9>"
					( Origin gPackager )
				)
				( attribute "PNN" "M_F_DQS_DN<9>"
					( Origin gPackager )
				)
				( objectStatus "M_F_DQS_DN<9>" )
			)
			( signal "@baseboard_fab2_lib.baseboard_fab2(sch_1):m_f_dqs_dn(10)"
				( attribute "CDS_PHYS_NET_NAME" "M_F_DQS_DN<10>"
					( Origin gPackager )
				)
				( attribute "PNN" "M_F_DQS_DN<10>"
					( Origin gPackager )
				)
				( objectStatus "M_F_DQS_DN<10>" )
			)
			( signal "@baseboard_fab2_lib.baseboard_fab2(sch_1):m_f_dqs_dn(11)"
				( attribute "CDS_PHYS_NET_NAME" "M_F_DQS_DN<11>"
					( Origin gPackager )
				)
				( attribute "PNN" "M_F_DQS_DN<11>"
					( Origin gPackager )
				)
				( objectStatus "M_F_DQS_DN<11>" )
			)
			( signal "@baseboard_fab2_lib.baseboard_fab2(sch_1):m_f_dqs_dn(12)"
				( attribute "CDS_PHYS_NET_NAME" "M_F_DQS_DN<12>"
					( Origin gPackager )
				)
				( attribute "PNN" "M_F_DQS_DN<12>"
					( Origin gPackager )
				)
				( objectStatus "M_F_DQS_DN<12>" )
			)
			( signal "@baseboard_fab2_lib.baseboard_fab2(sch_1):m_f_dqs_dn(13)"
				( attribute "CDS_PHYS_NET_NAME" "M_F_DQS_DN<13>"
					( Origin gPackager )
				)
				( attribute "PNN" "M_F_DQS_DN<13>"
					( Origin gPackager )
				)
				( objectStatus "M_F_DQS_DN<13>" )
			)
			( signal "@baseboard_fab2_lib.baseboard_fab2(sch_1):m_f_dqs_dn(14)"
				( attribute "CDS_PHYS_NET_NAME" "M_F_DQS_DN<14>"
					( Origin gPackager )
				)
				( attribute "PNN" "M_F_DQS_DN<14>"
					( Origin gPackager )
				)
				( objectStatus "M_F_DQS_DN<14>" )
			)
			( signal "@baseboard_fab2_lib.baseboard_fab2(sch_1):m_f_dqs_dn(15)"
				( attribute "CDS_PHYS_NET_NAME" "M_F_DQS_DN<15>"
					( Origin gPackager )
				)
				( attribute "PNN" "M_F_DQS_DN<15>"
					( Origin gPackager )
				)
				( objectStatus "M_F_DQS_DN<15>" )
			)
			( signal "@baseboard_fab2_lib.baseboard_fab2(sch_1):m_f_dqs_dn(16)"
				( attribute "CDS_PHYS_NET_NAME" "M_F_DQS_DN<16>"
					( Origin gPackager )
				)
				( attribute "PNN" "M_F_DQS_DN<16>"
					( Origin gPackager )
				)
				( objectStatus "M_F_DQS_DN<16>" )
			)
			( signal "@baseboard_fab2_lib.baseboard_fab2(sch_1):m_f_dqs_dn(17)"
				( attribute "CDS_PHYS_NET_NAME" "M_F_DQS_DN<17>"
					( Origin gPackager )
				)
				( attribute "PNN" "M_F_DQS_DN<17>"
					( Origin gPackager )
				)
				( objectStatus "M_F_DQS_DN<17>" )
			)
			( signal "@baseboard_fab2_lib.baseboard_fab2(sch_1):m_f_dqs_dp(0)"
				( attribute "CDS_PHYS_NET_NAME" "M_F_DQS_DP<0>"
					( Origin gPackager )
				)
				( attribute "PNN" "M_F_DQS_DP<0>"
					( Origin gPackager )
				)
				( objectStatus "M_F_DQS_DP<0>" )
			)
			( signal "@baseboard_fab2_lib.baseboard_fab2(sch_1):m_f_dqs_dp(1)"
				( attribute "CDS_PHYS_NET_NAME" "M_F_DQS_DP<1>"
					( Origin gPackager )
				)
				( attribute "PNN" "M_F_DQS_DP<1>"
					( Origin gPackager )
				)
				( objectStatus "M_F_DQS_DP<1>" )
			)
			( signal "@baseboard_fab2_lib.baseboard_fab2(sch_1):m_f_dqs_dp(2)"
				( attribute "CDS_PHYS_NET_NAME" "M_F_DQS_DP<2>"
					( Origin gPackager )
				)
				( attribute "PNN" "M_F_DQS_DP<2>"
					( Origin gPackager )
				)
				( objectStatus "M_F_DQS_DP<2>" )
			)
			( signal "@baseboard_fab2_lib.baseboard_fab2(sch_1):m_f_dqs_dp(3)"
				( attribute "CDS_PHYS_NET_NAME" "M_F_DQS_DP<3>"
					( Origin gPackager )
				)
				( attribute "PNN" "M_F_DQS_DP<3>"
					( Origin gPackager )
				)
				( objectStatus "M_F_DQS_DP<3>" )
			)
			( signal "@baseboard_fab2_lib.baseboard_fab2(sch_1):m_f_dqs_dp(4)"
				( attribute "CDS_PHYS_NET_NAME" "M_F_DQS_DP<4>"
					( Origin gPackager )
				)
				( attribute "PNN" "M_F_DQS_DP<4>"
					( Origin gPackager )
				)
				( objectStatus "M_F_DQS_DP<4>" )
			)
			( signal "@baseboard_fab2_lib.baseboard_fab2(sch_1):m_f_dqs_dp(5)"
				( attribute "CDS_PHYS_NET_NAME" "M_F_DQS_DP<5>"
					( Origin gPackager )
				)
				( attribute "PNN" "M_F_DQS_DP<5>"
					( Origin gPackager )
				)
				( objectStatus "M_F_DQS_DP<5>" )
			)
			( signal "@baseboard_fab2_lib.baseboard_fab2(sch_1):m_f_dqs_dp(6)"
				( attribute "CDS_PHYS_NET_NAME" "M_F_DQS_DP<6>"
					( Origin gPackager )
				)
				( attribute "PNN" "M_F_DQS_DP<6>"
					( Origin gPackager )
				)
				( objectStatus "M_F_DQS_DP<6>" )
			)
			( signal "@baseboard_fab2_lib.baseboard_fab2(sch_1):m_f_dqs_dp(7)"
				( attribute "CDS_PHYS_NET_NAME" "M_F_DQS_DP<7>"
					( Origin gPackager )
				)
				( attribute "PNN" "M_F_DQS_DP<7>"
					( Origin gPackager )
				)
				( objectStatus "M_F_DQS_DP<7>" )
			)
			( signal "@baseboard_fab2_lib.baseboard_fab2(sch_1):m_f_dqs_dp(8)"
				( attribute "CDS_PHYS_NET_NAME" "M_F_DQS_DP<8>"
					( Origin gPackager )
				)
				( attribute "PNN" "M_F_DQS_DP<8>"
					( Origin gPackager )
				)
				( objectStatus "M_F_DQS_DP<8>" )
			)
			( signal "@baseboard_fab2_lib.baseboard_fab2(sch_1):m_f_dqs_dp(9)"
				( attribute "CDS_PHYS_NET_NAME" "M_F_DQS_DP<9>"
					( Origin gPackager )
				)
				( attribute "PNN" "M_F_DQS_DP<9>"
					( Origin gPackager )
				)
				( objectStatus "M_F_DQS_DP<9>" )
			)
			( signal "@baseboard_fab2_lib.baseboard_fab2(sch_1):m_f_dqs_dp(10)"
				( attribute "CDS_PHYS_NET_NAME" "M_F_DQS_DP<10>"
					( Origin gPackager )
				)
				( attribute "PNN" "M_F_DQS_DP<10>"
					( Origin gPackager )
				)
				( objectStatus "M_F_DQS_DP<10>" )
			)
			( signal "@baseboard_fab2_lib.baseboard_fab2(sch_1):m_f_dqs_dp(11)"
				( attribute "CDS_PHYS_NET_NAME" "M_F_DQS_DP<11>"
					( Origin gPackager )
				)
				( attribute "PNN" "M_F_DQS_DP<11>"
					( Origin gPackager )
				)
				( objectStatus "M_F_DQS_DP<11>" )
			)
			( signal "@baseboard_fab2_lib.baseboard_fab2(sch_1):m_f_dqs_dp(12)"
				( attribute "CDS_PHYS_NET_NAME" "M_F_DQS_DP<12>"
					( Origin gPackager )
				)
				( attribute "PNN" "M_F_DQS_DP<12>"
					( Origin gPackager )
				)
				( objectStatus "M_F_DQS_DP<12>" )
			)
			( signal "@baseboard_fab2_lib.baseboard_fab2(sch_1):m_f_dqs_dp(13)"
				( attribute "CDS_PHYS_NET_NAME" "M_F_DQS_DP<13>"
					( Origin gPackager )
				)
				( attribute "PNN" "M_F_DQS_DP<13>"
					( Origin gPackager )
				)
				( objectStatus "M_F_DQS_DP<13>" )
			)
			( signal "@baseboard_fab2_lib.baseboard_fab2(sch_1):m_f_dqs_dp(14)"
				( attribute "CDS_PHYS_NET_NAME" "M_F_DQS_DP<14>"
					( Origin gPackager )
				)
				( attribute "PNN" "M_F_DQS_DP<14>"
					( Origin gPackager )
				)
				( objectStatus "M_F_DQS_DP<14>" )
			)
			( signal "@baseboard_fab2_lib.baseboard_fab2(sch_1):m_f_dqs_dp(15)"
				( attribute "CDS_PHYS_NET_NAME" "M_F_DQS_DP<15>"
					( Origin gPackager )
				)
				( attribute "PNN" "M_F_DQS_DP<15>"
					( Origin gPackager )
				)
				( objectStatus "M_F_DQS_DP<15>" )
			)
			( signal "@baseboard_fab2_lib.baseboard_fab2(sch_1):m_f_dqs_dp(16)"
				( attribute "CDS_PHYS_NET_NAME" "M_F_DQS_DP<16>"
					( Origin gPackager )
				)
				( attribute "PNN" "M_F_DQS_DP<16>"
					( Origin gPackager )
				)
				( objectStatus "M_F_DQS_DP<16>" )
			)
			( signal "@baseboard_fab2_lib.baseboard_fab2(sch_1):m_f_dqs_dp(17)"
				( attribute "CDS_PHYS_NET_NAME" "M_F_DQS_DP<17>"
					( Origin gPackager )
				)
				( attribute "PNN" "M_F_DQS_DP<17>"
					( Origin gPackager )
				)
				( objectStatus "M_F_DQS_DP<17>" )
			)
			( signal "@baseboard_fab2_lib.baseboard_fab2(sch_1):m_f_ecc(0)"
				( attribute "CDS_PHYS_NET_NAME" "M_F_ECC<0>"
					( Origin gPackager )
				)
				( attribute "PNN" "M_F_ECC<0>"
					( Origin gPackager )
				)
				( objectStatus "M_F_ECC<0>" )
			)
			( signal "@baseboard_fab2_lib.baseboard_fab2(sch_1):m_f_ecc(1)"
				( attribute "CDS_PHYS_NET_NAME" "M_F_ECC<1>"
					( Origin gPackager )
				)
				( attribute "PNN" "M_F_ECC<1>"
					( Origin gPackager )
				)
				( objectStatus "M_F_ECC<1>" )
			)
			( signal "@baseboard_fab2_lib.baseboard_fab2(sch_1):m_f_ecc(2)"
				( attribute "CDS_PHYS_NET_NAME" "M_F_ECC<2>"
					( Origin gPackager )
				)
				( attribute "PNN" "M_F_ECC<2>"
					( Origin gPackager )
				)
				( objectStatus "M_F_ECC<2>" )
			)
			( signal "@baseboard_fab2_lib.baseboard_fab2(sch_1):m_f_ecc(3)"
				( attribute "CDS_PHYS_NET_NAME" "M_F_ECC<3>"
					( Origin gPackager )
				)
				( attribute "PNN" "M_F_ECC<3>"
					( Origin gPackager )
				)
				( objectStatus "M_F_ECC<3>" )
			)
			( signal "@baseboard_fab2_lib.baseboard_fab2(sch_1):m_f_ecc(4)"
				( attribute "CDS_PHYS_NET_NAME" "M_F_ECC<4>"
					( Origin gPackager )
				)
				( attribute "PNN" "M_F_ECC<4>"
					( Origin gPackager )
				)
				( objectStatus "M_F_ECC<4>" )
			)
			( signal "@baseboard_fab2_lib.baseboard_fab2(sch_1):m_f_ecc(5)"
				( attribute "CDS_PHYS_NET_NAME" "M_F_ECC<5>"
					( Origin gPackager )
				)
				( attribute "PNN" "M_F_ECC<5>"
					( Origin gPackager )
				)
				( objectStatus "M_F_ECC<5>" )
			)
			( signal "@baseboard_fab2_lib.baseboard_fab2(sch_1):m_f_ecc(6)"
				( attribute "CDS_PHYS_NET_NAME" "M_F_ECC<6>"
					( Origin gPackager )
				)
				( attribute "PNN" "M_F_ECC<6>"
					( Origin gPackager )
				)
				( objectStatus "M_F_ECC<6>" )
			)
			( signal "@baseboard_fab2_lib.baseboard_fab2(sch_1):m_f_ecc(7)"
				( attribute "CDS_PHYS_NET_NAME" "M_F_ECC<7>"
					( Origin gPackager )
				)
				( attribute "PNN" "M_F_ECC<7>"
					( Origin gPackager )
				)
				( objectStatus "M_F_ECC<7>" )
			)
			( signal "@baseboard_fab2_lib.baseboard_fab2(sch_1):m_f_ma(0)"
				( attribute "CDS_PHYS_NET_NAME" "M_F_MA<0>"
					( Origin gPackager )
				)
				( attribute "PNN" "M_F_MA<0>"
					( Origin gPackager )
				)
				( objectStatus "M_F_MA<0>" )
			)
			( signal "@baseboard_fab2_lib.baseboard_fab2(sch_1):m_f_ma(1)"
				( attribute "CDS_PHYS_NET_NAME" "M_F_MA<1>"
					( Origin gPackager )
				)
				( attribute "PNN" "M_F_MA<1>"
					( Origin gPackager )
				)
				( objectStatus "M_F_MA<1>" )
			)
			( signal "@baseboard_fab2_lib.baseboard_fab2(sch_1):m_f_ma(2)"
				( attribute "CDS_PHYS_NET_NAME" "M_F_MA<2>"
					( Origin gPackager )
				)
				( attribute "PNN" "M_F_MA<2>"
					( Origin gPackager )
				)
				( objectStatus "M_F_MA<2>" )
			)
			( signal "@baseboard_fab2_lib.baseboard_fab2(sch_1):m_f_ma(3)"
				( attribute "CDS_PHYS_NET_NAME" "M_F_MA<3>"
					( Origin gPackager )
				)
				( attribute "PNN" "M_F_MA<3>"
					( Origin gPackager )
				)
				( objectStatus "M_F_MA<3>" )
			)
			( signal "@baseboard_fab2_lib.baseboard_fab2(sch_1):m_f_ma(4)"
				( attribute "CDS_PHYS_NET_NAME" "M_F_MA<4>"
					( Origin gPackager )
				)
				( attribute "PNN" "M_F_MA<4>"
					( Origin gPackager )
				)
				( objectStatus "M_F_MA<4>" )
			)
			( signal "@baseboard_fab2_lib.baseboard_fab2(sch_1):m_f_ma(5)"
				( attribute "CDS_PHYS_NET_NAME" "M_F_MA<5>"
					( Origin gPackager )
				)
				( attribute "PNN" "M_F_MA<5>"
					( Origin gPackager )
				)
				( objectStatus "M_F_MA<5>" )
			)
			( signal "@baseboard_fab2_lib.baseboard_fab2(sch_1):m_f_ma(6)"
				( attribute "CDS_PHYS_NET_NAME" "M_F_MA<6>"
					( Origin gPackager )
				)
				( attribute "PNN" "M_F_MA<6>"
					( Origin gPackager )
				)
				( objectStatus "M_F_MA<6>" )
			)
			( signal "@baseboard_fab2_lib.baseboard_fab2(sch_1):m_f_ma(7)"
				( attribute "CDS_PHYS_NET_NAME" "M_F_MA<7>"
					( Origin gPackager )
				)
				( attribute "PNN" "M_F_MA<7>"
					( Origin gPackager )
				)
				( objectStatus "M_F_MA<7>" )
			)
			( signal "@baseboard_fab2_lib.baseboard_fab2(sch_1):m_f_ma(8)"
				( attribute "CDS_PHYS_NET_NAME" "M_F_MA<8>"
					( Origin gPackager )
				)
				( attribute "PNN" "M_F_MA<8>"
					( Origin gPackager )
				)
				( objectStatus "M_F_MA<8>" )
			)
			( signal "@baseboard_fab2_lib.baseboard_fab2(sch_1):m_f_ma(9)"
				( attribute "CDS_PHYS_NET_NAME" "M_F_MA<9>"
					( Origin gPackager )
				)
				( attribute "PNN" "M_F_MA<9>"
					( Origin gPackager )
				)
				( objectStatus "M_F_MA<9>" )
			)
			( signal "@baseboard_fab2_lib.baseboard_fab2(sch_1):m_f_ma(10)"
				( attribute "CDS_PHYS_NET_NAME" "M_F_MA<10>"
					( Origin gPackager )
				)
				( attribute "PNN" "M_F_MA<10>"
					( Origin gPackager )
				)
				( objectStatus "M_F_MA<10>" )
			)
			( signal "@baseboard_fab2_lib.baseboard_fab2(sch_1):m_f_ma(11)"
				( attribute "CDS_PHYS_NET_NAME" "M_F_MA<11>"
					( Origin gPackager )
				)
				( attribute "PNN" "M_F_MA<11>"
					( Origin gPackager )
				)
				( objectStatus "M_F_MA<11>" )
			)
			( signal "@baseboard_fab2_lib.baseboard_fab2(sch_1):m_f_ma(12)"
				( attribute "CDS_PHYS_NET_NAME" "M_F_MA<12>"
					( Origin gPackager )
				)
				( attribute "PNN" "M_F_MA<12>"
					( Origin gPackager )
				)
				( objectStatus "M_F_MA<12>" )
			)
			( signal "@baseboard_fab2_lib.baseboard_fab2(sch_1):m_f_ma(13)"
				( attribute "CDS_PHYS_NET_NAME" "M_F_MA<13>"
					( Origin gPackager )
				)
				( attribute "PNN" "M_F_MA<13>"
					( Origin gPackager )
				)
				( objectStatus "M_F_MA<13>" )
			)
			( signal "@baseboard_fab2_lib.baseboard_fab2(sch_1):m_f_ma(14)"
				( attribute "CDS_PHYS_NET_NAME" "M_F_MA<14>"
					( Origin gPackager )
				)
				( attribute "PNN" "M_F_MA<14>"
					( Origin gPackager )
				)
				( objectStatus "M_F_MA<14>" )
			)
			( signal "@baseboard_fab2_lib.baseboard_fab2(sch_1):m_f_ma(15)"
				( attribute "CDS_PHYS_NET_NAME" "M_F_MA<15>"
					( Origin gPackager )
				)
				( attribute "PNN" "M_F_MA<15>"
					( Origin gPackager )
				)
				( objectStatus "M_F_MA<15>" )
			)
			( signal "@baseboard_fab2_lib.baseboard_fab2(sch_1):m_f_ma(16)"
				( attribute "CDS_PHYS_NET_NAME" "M_F_MA<16>"
					( Origin gPackager )
				)
				( attribute "PNN" "M_F_MA<16>"
					( Origin gPackager )
				)
				( objectStatus "M_F_MA<16>" )
			)
			( signal "@baseboard_fab2_lib.baseboard_fab2(sch_1):m_f_ma(17)"
				( attribute "CDS_PHYS_NET_NAME" "M_F_MA<17>"
					( Origin gPackager )
				)
				( attribute "PNN" "M_F_MA<17>"
					( Origin gPackager )
				)
				( objectStatus "M_F_MA<17>" )
			)
			( signal "@baseboard_fab2_lib.baseboard_fab2(sch_1):m_f_odt(0)"
				( attribute "CDS_PHYS_NET_NAME" "M_F_ODT<0>"
					( Origin gPackager )
				)
				( attribute "PNN" "M_F_ODT<0>"
					( Origin gPackager )
				)
				( objectStatus "M_F_ODT<0>" )
			)
			( signal "@baseboard_fab2_lib.baseboard_fab2(sch_1):m_f_odt(1)"
				( attribute "CDS_PHYS_NET_NAME" "M_F_ODT<1>"
					( Origin gPackager )
				)
				( attribute "PNN" "M_F_ODT<1>"
					( Origin gPackager )
				)
				( objectStatus "M_F_ODT<1>" )
			)
			( signal "@baseboard_fab2_lib.baseboard_fab2(sch_1):m_f_odt(2)"
				( attribute "CDS_PHYS_NET_NAME" "M_F_ODT<2>"
					( Origin gPackager )
				)
				( attribute "PNN" "M_F_ODT<2>"
					( Origin gPackager )
				)
				( objectStatus "M_F_ODT<2>" )
			)
			( signal "@baseboard_fab2_lib.baseboard_fab2(sch_1):m_f_odt(3)"
				( attribute "CDS_PHYS_NET_NAME" "M_F_ODT<3>"
					( Origin gPackager )
				)
				( attribute "PNN" "M_F_ODT<3>"
					( Origin gPackager )
				)
				( objectStatus "M_F_ODT<3>" )
			)
			( signal "@baseboard_fab2_lib.baseboard_fab2(sch_1):m_f_par"
				( attribute "CDS_PHYS_NET_NAME" "M_F_PAR"
					( Origin gPackager )
				)
				( objectStatus "M_F_PAR" )
			)
			( signal "@baseboard_fab2_lib.baseboard_fab2(sch_1):clk_100m_cpu0_pe_refclk_dn"
				( attribute "CDS_PHYS_NET_NAME" "CLK_100M_CPU0_PE_REFCLK_DN"
					( Origin gPackager )
				)
				( objectStatus "CLK_100M_CPU0_PE_REFCLK_DN" )
			)
			( signal "@baseboard_fab2_lib.baseboard_fab2(sch_1):clk_100m_cpu0_pe_refclk_dp"
				( attribute "CDS_PHYS_NET_NAME" "CLK_100M_CPU0_PE_REFCLK_DP"
					( Origin gPackager )
				)
				( objectStatus "CLK_100M_CPU0_PE_REFCLK_DP" )
			)
			( signal "@baseboard_fab2_lib.baseboard_fab2(sch_1):clk_156m_osc_cpu0_hfi_dn"
				( attribute "CDS_PHYS_NET_NAME" "CLK_156M_OSC_CPU0_HFI_DN"
					( Origin gPackager )
				)
				( objectStatus "CLK_156M_OSC_CPU0_HFI_DN" )
			)
			( signal "@baseboard_fab2_lib.baseboard_fab2(sch_1):clk_156m_osc_cpu0_hfi_dp"
				( attribute "CDS_PHYS_NET_NAME" "CLK_156M_OSC_CPU0_HFI_DP"
					( Origin gPackager )
				)
				( objectStatus "CLK_156M_OSC_CPU0_HFI_DP" )
			)
			( signal "@baseboard_fab2_lib.baseboard_fab2(sch_1):dmi_cpu0_pch_rx_c_dn(0)"
				( attribute "CDS_PHYS_NET_NAME" "DMI_CPU0_PCH_RX_C_DN<0>"
					( Origin gPackager )
				)
				( attribute "PNN" "DMI_CPU0_PCH_RX_C_DN<0>"
					( Origin gPackager )
				)
				( objectStatus "DMI_CPU0_PCH_RX_C_DN<0>" )
			)
			( signal "@baseboard_fab2_lib.baseboard_fab2(sch_1):dmi_cpu0_pch_rx_c_dn(1)"
				( attribute "CDS_PHYS_NET_NAME" "DMI_CPU0_PCH_RX_C_DN<1>"
					( Origin gPackager )
				)
				( attribute "PNN" "DMI_CPU0_PCH_RX_C_DN<1>"
					( Origin gPackager )
				)
				( objectStatus "DMI_CPU0_PCH_RX_C_DN<1>" )
			)
			( signal "@baseboard_fab2_lib.baseboard_fab2(sch_1):dmi_cpu0_pch_rx_c_dn(2)"
				( attribute "CDS_PHYS_NET_NAME" "DMI_CPU0_PCH_RX_C_DN<2>"
					( Origin gPackager )
				)
				( attribute "PNN" "DMI_CPU0_PCH_RX_C_DN<2>"
					( Origin gPackager )
				)
				( objectStatus "DMI_CPU0_PCH_RX_C_DN<2>" )
			)
			( signal "@baseboard_fab2_lib.baseboard_fab2(sch_1):dmi_cpu0_pch_rx_c_dn(3)"
				( attribute "CDS_PHYS_NET_NAME" "DMI_CPU0_PCH_RX_C_DN<3>"
					( Origin gPackager )
				)
				( attribute "PNN" "DMI_CPU0_PCH_RX_C_DN<3>"
					( Origin gPackager )
				)
				( objectStatus "DMI_CPU0_PCH_RX_C_DN<3>" )
			)
			( signal "@baseboard_fab2_lib.baseboard_fab2(sch_1):dmi_cpu0_pch_rx_c_dp(0)"
				( attribute "CDS_PHYS_NET_NAME" "DMI_CPU0_PCH_RX_C_DP<0>"
					( Origin gPackager )
				)
				( attribute "PNN" "DMI_CPU0_PCH_RX_C_DP<0>"
					( Origin gPackager )
				)
				( objectStatus "DMI_CPU0_PCH_RX_C_DP<0>" )
			)
			( signal "@baseboard_fab2_lib.baseboard_fab2(sch_1):dmi_cpu0_pch_rx_c_dp(1)"
				( attribute "CDS_PHYS_NET_NAME" "DMI_CPU0_PCH_RX_C_DP<1>"
					( Origin gPackager )
				)
				( attribute "PNN" "DMI_CPU0_PCH_RX_C_DP<1>"
					( Origin gPackager )
				)
				( objectStatus "DMI_CPU0_PCH_RX_C_DP<1>" )
			)
			( signal "@baseboard_fab2_lib.baseboard_fab2(sch_1):dmi_cpu0_pch_rx_c_dp(2)"
				( attribute "CDS_PHYS_NET_NAME" "DMI_CPU0_PCH_RX_C_DP<2>"
					( Origin gPackager )
				)
				( attribute "PNN" "DMI_CPU0_PCH_RX_C_DP<2>"
					( Origin gPackager )
				)
				( objectStatus "DMI_CPU0_PCH_RX_C_DP<2>" )
			)
			( signal "@baseboard_fab2_lib.baseboard_fab2(sch_1):dmi_cpu0_pch_rx_c_dp(3)"
				( attribute "CDS_PHYS_NET_NAME" "DMI_CPU0_PCH_RX_C_DP<3>"
					( Origin gPackager )
				)
				( attribute "PNN" "DMI_CPU0_PCH_RX_C_DP<3>"
					( Origin gPackager )
				)
				( objectStatus "DMI_CPU0_PCH_RX_C_DP<3>" )
			)
			( signal "@baseboard_fab2_lib.baseboard_fab2(sch_1):dmi_cpu0_pch_tx_dn(0)"
				( attribute "CDS_PHYS_NET_NAME" "DMI_CPU0_PCH_TX_DN<0>"
					( Origin gPackager )
				)
				( attribute "PNN" "DMI_CPU0_PCH_TX_DN<0>"
					( Origin gPackager )
				)
				( objectStatus "DMI_CPU0_PCH_TX_DN<0>" )
			)
			( signal "@baseboard_fab2_lib.baseboard_fab2(sch_1):dmi_cpu0_pch_tx_dn(1)"
				( attribute "CDS_PHYS_NET_NAME" "DMI_CPU0_PCH_TX_DN<1>"
					( Origin gPackager )
				)
				( attribute "PNN" "DMI_CPU0_PCH_TX_DN<1>"
					( Origin gPackager )
				)
				( objectStatus "DMI_CPU0_PCH_TX_DN<1>" )
			)
			( signal "@baseboard_fab2_lib.baseboard_fab2(sch_1):dmi_cpu0_pch_tx_dn(2)"
				( attribute "CDS_PHYS_NET_NAME" "DMI_CPU0_PCH_TX_DN<2>"
					( Origin gPackager )
				)
				( attribute "PNN" "DMI_CPU0_PCH_TX_DN<2>"
					( Origin gPackager )
				)
				( objectStatus "DMI_CPU0_PCH_TX_DN<2>" )
			)
			( signal "@baseboard_fab2_lib.baseboard_fab2(sch_1):dmi_cpu0_pch_tx_dn(3)"
				( attribute "CDS_PHYS_NET_NAME" "DMI_CPU0_PCH_TX_DN<3>"
					( Origin gPackager )
				)
				( attribute "PNN" "DMI_CPU0_PCH_TX_DN<3>"
					( Origin gPackager )
				)
				( objectStatus "DMI_CPU0_PCH_TX_DN<3>" )
			)
			( signal "@baseboard_fab2_lib.baseboard_fab2(sch_1):dmi_cpu0_pch_tx_dp(0)"
				( attribute "CDS_PHYS_NET_NAME" "DMI_CPU0_PCH_TX_DP<0>"
					( Origin gPackager )
				)
				( attribute "PNN" "DMI_CPU0_PCH_TX_DP<0>"
					( Origin gPackager )
				)
				( objectStatus "DMI_CPU0_PCH_TX_DP<0>" )
			)
			( signal "@baseboard_fab2_lib.baseboard_fab2(sch_1):dmi_cpu0_pch_tx_dp(1)"
				( attribute "CDS_PHYS_NET_NAME" "DMI_CPU0_PCH_TX_DP<1>"
					( Origin gPackager )
				)
				( attribute "PNN" "DMI_CPU0_PCH_TX_DP<1>"
					( Origin gPackager )
				)
				( objectStatus "DMI_CPU0_PCH_TX_DP<1>" )
			)
			( signal "@baseboard_fab2_lib.baseboard_fab2(sch_1):dmi_cpu0_pch_tx_dp(2)"
				( attribute "CDS_PHYS_NET_NAME" "DMI_CPU0_PCH_TX_DP<2>"
					( Origin gPackager )
				)
				( attribute "PNN" "DMI_CPU0_PCH_TX_DP<2>"
					( Origin gPackager )
				)
				( objectStatus "DMI_CPU0_PCH_TX_DP<2>" )
			)
			( signal "@baseboard_fab2_lib.baseboard_fab2(sch_1):dmi_cpu0_pch_tx_dp(3)"
				( attribute "CDS_PHYS_NET_NAME" "DMI_CPU0_PCH_TX_DP<3>"
					( Origin gPackager )
				)
				( attribute "PNN" "DMI_CPU0_PCH_TX_DP<3>"
					( Origin gPackager )
				)
				( objectStatus "DMI_CPU0_PCH_TX_DP<3>" )
			)
			( signal "@baseboard_fab2_lib.baseboard_fab2(sch_1):fm_modprst_hfi0_cpu0_lvt2_n"
				( attribute "CDS_PHYS_NET_NAME" "FM_MODPRST_HFI0_CPU0_LVT2_N"
					( Origin gPackager )
				)
				( objectStatus "FM_MODPRST_HFI0_CPU0_LVT2_N" )
			)
			( signal "@baseboard_fab2_lib.baseboard_fab2(sch_1):fm_modprst_hfi1_cpu0_lvt2_n"
				( attribute "CDS_PHYS_NET_NAME" "FM_MODPRST_HFI1_CPU0_LVT2_N"
					( Origin gPackager )
				)
				( objectStatus "FM_MODPRST_HFI1_CPU0_LVT2_N" )
			)
			( signal "@baseboard_fab2_lib.baseboard_fab2(sch_1):irq_hfi0_cpu0_lvt2_n"
				( attribute "CDS_PHYS_NET_NAME" "IRQ_HFI0_CPU0_LVT2_N"
					( Origin gPackager )
				)
				( objectStatus "IRQ_HFI0_CPU0_LVT2_N" )
			)
			( signal "@baseboard_fab2_lib.baseboard_fab2(sch_1):irq_hfi1_cpu0_lvt2_n"
				( attribute "CDS_PHYS_NET_NAME" "IRQ_HFI1_CPU0_LVT2_N"
					( Origin gPackager )
				)
				( objectStatus "IRQ_HFI1_CPU0_LVT2_N" )
			)
			( signal "@baseboard_fab2_lib.baseboard_fab2(sch_1):jtag_mcp_cpu0_tdi"
				( attribute "CDS_PHYS_NET_NAME" "JTAG_MCP_CPU0_TDI"
					( Origin gPackager )
				)
				( objectStatus "JTAG_MCP_CPU0_TDI" )
			)
			( signal "@baseboard_fab2_lib.baseboard_fab2(sch_1):jtag_mcp_cpu0_tdo"
				( attribute "CDS_PHYS_NET_NAME" "JTAG_MCP_CPU0_TDO"
					( Origin gPackager )
				)
				( objectStatus "JTAG_MCP_CPU0_TDO" )
			)
			( signal "@baseboard_fab2_lib.baseboard_fab2(sch_1):jtag_mcp_tck"
				( attribute "CDS_PHYS_NET_NAME" "JTAG_MCP_TCK"
					( Origin gPackager )
				)
				( objectStatus "JTAG_MCP_TCK" )
			)
			( signal "@baseboard_fab2_lib.baseboard_fab2(sch_1):jtag_mcp_tms"
				( attribute "CDS_PHYS_NET_NAME" "JTAG_MCP_TMS"
					( Origin gPackager )
				)
				( objectStatus "JTAG_MCP_TMS" )
			)
			( signal "@baseboard_fab2_lib.baseboard_fab2(sch_1):jtag_mcp_trst_n"
				( attribute "CDS_PHYS_NET_NAME" "JTAG_MCP_TRST_N"
					( Origin gPackager )
				)
				( objectStatus "JTAG_MCP_TRST_N" )
			)
			( signal "@baseboard_fab2_lib.baseboard_fab2(sch_1):led_hfi0_cpu0_n"
				( attribute "CDS_PHYS_NET_NAME" "LED_HFI0_CPU0_N"
					( Origin gPackager )
				)
				( objectStatus "LED_HFI0_CPU0_N" )
			)
			( signal "@baseboard_fab2_lib.baseboard_fab2(sch_1):led_hfi1_cpu0_n"
				( attribute "CDS_PHYS_NET_NAME" "LED_HFI1_CPU0_N"
					( Origin gPackager )
				)
				( objectStatus "LED_HFI1_CPU0_N" )
			)
			( signal "@baseboard_fab2_lib.baseboard_fab2(sch_1):rst_cd_cpu0_por_n"
				( attribute "CDS_PHYS_NET_NAME" "RST_CD_CPU0_POR_N"
					( Origin gPackager )
				)
				( objectStatus "RST_CD_CPU0_POR_N" )
			)
			( signal "@baseboard_fab2_lib.baseboard_fab2(sch_1):rst_hfi0_cpu0_lvt2_n"
				( attribute "CDS_PHYS_NET_NAME" "RST_HFI0_CPU0_LVT2_N"
					( Origin gPackager )
				)
				( objectStatus "RST_HFI0_CPU0_LVT2_N" )
			)
			( signal "@baseboard_fab2_lib.baseboard_fab2(sch_1):rst_hfi1_cpu0_lvt2_n"
				( attribute "CDS_PHYS_NET_NAME" "RST_HFI1_CPU0_LVT2_N"
					( Origin gPackager )
				)
				( objectStatus "RST_HFI1_CPU0_LVT2_N" )
			)
			( signal "@baseboard_fab2_lib.baseboard_fab2(sch_1):smb_hfi0_cpu0_lvc2_scl"
				( attribute "CDS_PHYS_NET_NAME" "SMB_HFI0_CPU0_LVC2_SCL"
					( Origin gPackager )
				)
				( objectStatus "SMB_HFI0_CPU0_LVC2_SCL" )
			)
			( signal "@baseboard_fab2_lib.baseboard_fab2(sch_1):smb_hfi0_cpu0_lvc2_sda"
				( attribute "CDS_PHYS_NET_NAME" "SMB_HFI0_CPU0_LVC2_SDA"
					( Origin gPackager )
				)
				( objectStatus "SMB_HFI0_CPU0_LVC2_SDA" )
			)
			( signal "@baseboard_fab2_lib.baseboard_fab2(sch_1):smb_hfi1_cpu0_lvc2_scl"
				( attribute "CDS_PHYS_NET_NAME" "SMB_HFI1_CPU0_LVC2_SCL"
					( Origin gPackager )
				)
				( objectStatus "SMB_HFI1_CPU0_LVC2_SCL" )
			)
			( signal "@baseboard_fab2_lib.baseboard_fab2(sch_1):smb_hfi1_cpu0_lvc2_sda"
				( attribute "CDS_PHYS_NET_NAME" "SMB_HFI1_CPU0_LVC2_SDA"
					( Origin gPackager )
				)
				( objectStatus "SMB_HFI1_CPU0_LVC2_SDA" )
			)
			( signal "@baseboard_fab2_lib.baseboard_fab2(sch_1):tp_cpu0_rsvd_172"
				( attribute "CDS_PHYS_NET_NAME" "TP_CPU0_RSVD_172"
					( Origin gPackager )
				)
				( objectStatus "TP_CPU0_RSVD_172" )
			)
			( signal "@baseboard_fab2_lib.baseboard_fab2(sch_1):tp_cpu0_rsvd_173"
				( attribute "CDS_PHYS_NET_NAME" "TP_CPU0_RSVD_173"
					( Origin gPackager )
				)
				( objectStatus "TP_CPU0_RSVD_173" )
			)
			( signal "@baseboard_fab2_lib.baseboard_fab2(sch_1):tp_cpu0_rsvd_174"
				( attribute "CDS_PHYS_NET_NAME" "TP_CPU0_RSVD_174"
					( Origin gPackager )
				)
				( objectStatus "TP_CPU0_RSVD_174" )
			)
			( signal "@baseboard_fab2_lib.baseboard_fab2(sch_1):tp_cpu0_rsvd_175"
				( attribute "CDS_PHYS_NET_NAME" "TP_CPU0_RSVD_175"
					( Origin gPackager )
				)
				( objectStatus "TP_CPU0_RSVD_175" )
			)
			( signal "@baseboard_fab2_lib.baseboard_fab2(sch_1):tp_cpu0_rsvd_176"
				( attribute "CDS_PHYS_NET_NAME" "TP_CPU0_RSVD_176"
					( Origin gPackager )
				)
				( objectStatus "TP_CPU0_RSVD_176" )
			)
			( signal "@baseboard_fab2_lib.baseboard_fab2(sch_1):tp_cpu0_rsvd_177"
				( attribute "CDS_PHYS_NET_NAME" "TP_CPU0_RSVD_177"
					( Origin gPackager )
				)
				( objectStatus "TP_CPU0_RSVD_177" )
			)
			( signal "@baseboard_fab2_lib.baseboard_fab2(sch_1):tp_cpu0_rsvd_178"
				( attribute "CDS_PHYS_NET_NAME" "TP_CPU0_RSVD_178"
					( Origin gPackager )
				)
				( objectStatus "TP_CPU0_RSVD_178" )
			)
			( signal "@baseboard_fab2_lib.baseboard_fab2(sch_1):tp_cpu0_rsvd_179"
				( attribute "CDS_PHYS_NET_NAME" "TP_CPU0_RSVD_179"
					( Origin gPackager )
				)
				( objectStatus "TP_CPU0_RSVD_179" )
			)
			( signal "@baseboard_fab2_lib.baseboard_fab2(sch_1):tp_cpu0_rsvd_180"
				( attribute "CDS_PHYS_NET_NAME" "TP_CPU0_RSVD_180"
					( Origin gPackager )
				)
				( objectStatus "TP_CPU0_RSVD_180" )
			)
			( signal "@baseboard_fab2_lib.baseboard_fab2(sch_1):tp_cpu0_rsvd_181"
				( attribute "CDS_PHYS_NET_NAME" "TP_CPU0_RSVD_181"
					( Origin gPackager )
				)
				( objectStatus "TP_CPU0_RSVD_181" )
			)
			( signal "@baseboard_fab2_lib.baseboard_fab2(sch_1):tp_cpu0_rsvd_182"
				( attribute "CDS_PHYS_NET_NAME" "TP_CPU0_RSVD_182"
					( Origin gPackager )
				)
				( objectStatus "TP_CPU0_RSVD_182" )
			)
			( signal "@baseboard_fab2_lib.baseboard_fab2(sch_1):tp_cpu0_rsvd_183"
				( attribute "CDS_PHYS_NET_NAME" "TP_CPU0_RSVD_183"
					( Origin gPackager )
				)
				( objectStatus "TP_CPU0_RSVD_183" )
			)
			( signal "@baseboard_fab2_lib.baseboard_fab2(sch_1):tp_cpu0_rsvd_184"
				( attribute "CDS_PHYS_NET_NAME" "TP_CPU0_RSVD_184"
					( Origin gPackager )
				)
				( objectStatus "TP_CPU0_RSVD_184" )
			)
			( signal "@baseboard_fab2_lib.baseboard_fab2(sch_1):tp_cpu0_rsvd_186"
				( attribute "CDS_PHYS_NET_NAME" "TP_CPU0_RSVD_186"
					( Origin gPackager )
				)
				( objectStatus "TP_CPU0_RSVD_186" )
			)
			( signal "@baseboard_fab2_lib.baseboard_fab2(sch_1):tp_cpu0_rsvd_189"
				( attribute "CDS_PHYS_NET_NAME" "TP_CPU0_RSVD_189"
					( Origin gPackager )
				)
				( objectStatus "TP_CPU0_RSVD_189" )
			)
			( signal "@baseboard_fab2_lib.baseboard_fab2(sch_1):tp_cpu0_rsvd_190"
				( attribute "CDS_PHYS_NET_NAME" "TP_CPU0_RSVD_190"
					( Origin gPackager )
				)
				( objectStatus "TP_CPU0_RSVD_190" )
			)
			( signal "@baseboard_fab2_lib.baseboard_fab2(sch_1):p3e_cpu0_pe1_pch_rxn(8)"
				( attribute "CDS_PHYS_NET_NAME" "P3E_CPU0_PE1_PCH_RXN<8>"
					( Origin gPackager )
				)
				( attribute "PNN" "P3E_CPU0_PE1_PCH_RXN<8>"
					( Origin gPackager )
				)
				( objectStatus "P3E_CPU0_PE1_PCH_RXN<8>" )
			)
			( signal "@baseboard_fab2_lib.baseboard_fab2(sch_1):p3e_cpu0_pe1_pch_rxn(9)"
				( attribute "CDS_PHYS_NET_NAME" "P3E_CPU0_PE1_PCH_RXN<9>"
					( Origin gPackager )
				)
				( attribute "PNN" "P3E_CPU0_PE1_PCH_RXN<9>"
					( Origin gPackager )
				)
				( objectStatus "P3E_CPU0_PE1_PCH_RXN<9>" )
			)
			( signal "@baseboard_fab2_lib.baseboard_fab2(sch_1):p3e_cpu0_pe1_pch_rxn(10)"
				( attribute "CDS_PHYS_NET_NAME" "P3E_CPU0_PE1_PCH_RXN<10>"
					( Origin gPackager )
				)
				( attribute "PNN" "P3E_CPU0_PE1_PCH_RXN<10>"
					( Origin gPackager )
				)
				( objectStatus "P3E_CPU0_PE1_PCH_RXN<10>" )
			)
			( signal "@baseboard_fab2_lib.baseboard_fab2(sch_1):p3e_cpu0_pe1_pch_rxn(11)"
				( attribute "CDS_PHYS_NET_NAME" "P3E_CPU0_PE1_PCH_RXN<11>"
					( Origin gPackager )
				)
				( attribute "PNN" "P3E_CPU0_PE1_PCH_RXN<11>"
					( Origin gPackager )
				)
				( objectStatus "P3E_CPU0_PE1_PCH_RXN<11>" )
			)
			( signal "@baseboard_fab2_lib.baseboard_fab2(sch_1):p3e_cpu0_pe1_pch_rxn(12)"
				( attribute "CDS_PHYS_NET_NAME" "P3E_CPU0_PE1_PCH_RXN<12>"
					( Origin gPackager )
				)
				( attribute "PNN" "P3E_CPU0_PE1_PCH_RXN<12>"
					( Origin gPackager )
				)
				( objectStatus "P3E_CPU0_PE1_PCH_RXN<12>" )
			)
			( signal "@baseboard_fab2_lib.baseboard_fab2(sch_1):p3e_cpu0_pe1_pch_rxn(13)"
				( attribute "CDS_PHYS_NET_NAME" "P3E_CPU0_PE1_PCH_RXN<13>"
					( Origin gPackager )
				)
				( attribute "PNN" "P3E_CPU0_PE1_PCH_RXN<13>"
					( Origin gPackager )
				)
				( objectStatus "P3E_CPU0_PE1_PCH_RXN<13>" )
			)
			( signal "@baseboard_fab2_lib.baseboard_fab2(sch_1):p3e_cpu0_pe1_pch_rxn(14)"
				( attribute "CDS_PHYS_NET_NAME" "P3E_CPU0_PE1_PCH_RXN<14>"
					( Origin gPackager )
				)
				( attribute "PNN" "P3E_CPU0_PE1_PCH_RXN<14>"
					( Origin gPackager )
				)
				( objectStatus "P3E_CPU0_PE1_PCH_RXN<14>" )
			)
			( signal "@baseboard_fab2_lib.baseboard_fab2(sch_1):p3e_cpu0_pe1_pch_rxn(15)"
				( attribute "CDS_PHYS_NET_NAME" "P3E_CPU0_PE1_PCH_RXN<15>"
					( Origin gPackager )
				)
				( attribute "PNN" "P3E_CPU0_PE1_PCH_RXN<15>"
					( Origin gPackager )
				)
				( objectStatus "P3E_CPU0_PE1_PCH_RXN<15>" )
			)
			( signal "@baseboard_fab2_lib.baseboard_fab2(sch_1):p3e_cpu0_pe1_pch_rxp(8)"
				( attribute "CDS_PHYS_NET_NAME" "P3E_CPU0_PE1_PCH_RXP<8>"
					( Origin gPackager )
				)
				( attribute "PNN" "P3E_CPU0_PE1_PCH_RXP<8>"
					( Origin gPackager )
				)
				( objectStatus "P3E_CPU0_PE1_PCH_RXP<8>" )
			)
			( signal "@baseboard_fab2_lib.baseboard_fab2(sch_1):p3e_cpu0_pe1_pch_rxp(9)"
				( attribute "CDS_PHYS_NET_NAME" "P3E_CPU0_PE1_PCH_RXP<9>"
					( Origin gPackager )
				)
				( attribute "PNN" "P3E_CPU0_PE1_PCH_RXP<9>"
					( Origin gPackager )
				)
				( objectStatus "P3E_CPU0_PE1_PCH_RXP<9>" )
			)
			( signal "@baseboard_fab2_lib.baseboard_fab2(sch_1):p3e_cpu0_pe1_pch_rxp(10)"
				( attribute "CDS_PHYS_NET_NAME" "P3E_CPU0_PE1_PCH_RXP<10>"
					( Origin gPackager )
				)
				( attribute "PNN" "P3E_CPU0_PE1_PCH_RXP<10>"
					( Origin gPackager )
				)
				( objectStatus "P3E_CPU0_PE1_PCH_RXP<10>" )
			)
			( signal "@baseboard_fab2_lib.baseboard_fab2(sch_1):p3e_cpu0_pe1_pch_rxp(11)"
				( attribute "CDS_PHYS_NET_NAME" "P3E_CPU0_PE1_PCH_RXP<11>"
					( Origin gPackager )
				)
				( attribute "PNN" "P3E_CPU0_PE1_PCH_RXP<11>"
					( Origin gPackager )
				)
				( objectStatus "P3E_CPU0_PE1_PCH_RXP<11>" )
			)
			( signal "@baseboard_fab2_lib.baseboard_fab2(sch_1):p3e_cpu0_pe1_pch_rxp(12)"
				( attribute "CDS_PHYS_NET_NAME" "P3E_CPU0_PE1_PCH_RXP<12>"
					( Origin gPackager )
				)
				( attribute "PNN" "P3E_CPU0_PE1_PCH_RXP<12>"
					( Origin gPackager )
				)
				( objectStatus "P3E_CPU0_PE1_PCH_RXP<12>" )
			)
			( signal "@baseboard_fab2_lib.baseboard_fab2(sch_1):p3e_cpu0_pe1_pch_rxp(13)"
				( attribute "CDS_PHYS_NET_NAME" "P3E_CPU0_PE1_PCH_RXP<13>"
					( Origin gPackager )
				)
				( attribute "PNN" "P3E_CPU0_PE1_PCH_RXP<13>"
					( Origin gPackager )
				)
				( objectStatus "P3E_CPU0_PE1_PCH_RXP<13>" )
			)
			( signal "@baseboard_fab2_lib.baseboard_fab2(sch_1):p3e_cpu0_pe1_pch_rxp(14)"
				( attribute "CDS_PHYS_NET_NAME" "P3E_CPU0_PE1_PCH_RXP<14>"
					( Origin gPackager )
				)
				( attribute "PNN" "P3E_CPU0_PE1_PCH_RXP<14>"
					( Origin gPackager )
				)
				( objectStatus "P3E_CPU0_PE1_PCH_RXP<14>" )
			)
			( signal "@baseboard_fab2_lib.baseboard_fab2(sch_1):p3e_cpu0_pe1_pch_rxp(15)"
				( attribute "CDS_PHYS_NET_NAME" "P3E_CPU0_PE1_PCH_RXP<15>"
					( Origin gPackager )
				)
				( attribute "PNN" "P3E_CPU0_PE1_PCH_RXP<15>"
					( Origin gPackager )
				)
				( objectStatus "P3E_CPU0_PE1_PCH_RXP<15>" )
			)
			( signal "@baseboard_fab2_lib.baseboard_fab2(sch_1):p3e_cpu0_pe1_pch_txn(8)"
				( attribute "CDS_PHYS_NET_NAME" "P3E_CPU0_PE1_PCH_TXN<8>"
					( Origin gPackager )
				)
				( attribute "PNN" "P3E_CPU0_PE1_PCH_TXN<8>"
					( Origin gPackager )
				)
				( objectStatus "P3E_CPU0_PE1_PCH_TXN<8>" )
			)
			( signal "@baseboard_fab2_lib.baseboard_fab2(sch_1):p3e_cpu0_pe1_pch_txn(9)"
				( attribute "CDS_PHYS_NET_NAME" "P3E_CPU0_PE1_PCH_TXN<9>"
					( Origin gPackager )
				)
				( attribute "PNN" "P3E_CPU0_PE1_PCH_TXN<9>"
					( Origin gPackager )
				)
				( objectStatus "P3E_CPU0_PE1_PCH_TXN<9>" )
			)
			( signal "@baseboard_fab2_lib.baseboard_fab2(sch_1):p3e_cpu0_pe1_pch_txn(10)"
				( attribute "CDS_PHYS_NET_NAME" "P3E_CPU0_PE1_PCH_TXN<10>"
					( Origin gPackager )
				)
				( attribute "PNN" "P3E_CPU0_PE1_PCH_TXN<10>"
					( Origin gPackager )
				)
				( objectStatus "P3E_CPU0_PE1_PCH_TXN<10>" )
			)
			( signal "@baseboard_fab2_lib.baseboard_fab2(sch_1):p3e_cpu0_pe1_pch_txn(11)"
				( attribute "CDS_PHYS_NET_NAME" "P3E_CPU0_PE1_PCH_TXN<11>"
					( Origin gPackager )
				)
				( attribute "PNN" "P3E_CPU0_PE1_PCH_TXN<11>"
					( Origin gPackager )
				)
				( objectStatus "P3E_CPU0_PE1_PCH_TXN<11>" )
			)
			( signal "@baseboard_fab2_lib.baseboard_fab2(sch_1):p3e_cpu0_pe1_pch_txn(12)"
				( attribute "CDS_PHYS_NET_NAME" "P3E_CPU0_PE1_PCH_TXN<12>"
					( Origin gPackager )
				)
				( attribute "PNN" "P3E_CPU0_PE1_PCH_TXN<12>"
					( Origin gPackager )
				)
				( objectStatus "P3E_CPU0_PE1_PCH_TXN<12>" )
			)
			( signal "@baseboard_fab2_lib.baseboard_fab2(sch_1):p3e_cpu0_pe1_pch_txn(13)"
				( attribute "CDS_PHYS_NET_NAME" "P3E_CPU0_PE1_PCH_TXN<13>"
					( Origin gPackager )
				)
				( attribute "PNN" "P3E_CPU0_PE1_PCH_TXN<13>"
					( Origin gPackager )
				)
				( objectStatus "P3E_CPU0_PE1_PCH_TXN<13>" )
			)
			( signal "@baseboard_fab2_lib.baseboard_fab2(sch_1):p3e_cpu0_pe1_pch_txn(14)"
				( attribute "CDS_PHYS_NET_NAME" "P3E_CPU0_PE1_PCH_TXN<14>"
					( Origin gPackager )
				)
				( attribute "PNN" "P3E_CPU0_PE1_PCH_TXN<14>"
					( Origin gPackager )
				)
				( objectStatus "P3E_CPU0_PE1_PCH_TXN<14>" )
			)
			( signal "@baseboard_fab2_lib.baseboard_fab2(sch_1):p3e_cpu0_pe1_pch_txn(15)"
				( attribute "CDS_PHYS_NET_NAME" "P3E_CPU0_PE1_PCH_TXN<15>"
					( Origin gPackager )
				)
				( attribute "PNN" "P3E_CPU0_PE1_PCH_TXN<15>"
					( Origin gPackager )
				)
				( objectStatus "P3E_CPU0_PE1_PCH_TXN<15>" )
			)
			( signal "@baseboard_fab2_lib.baseboard_fab2(sch_1):p3e_cpu0_pe1_pch_txp(8)"
				( attribute "CDS_PHYS_NET_NAME" "P3E_CPU0_PE1_PCH_TXP<8>"
					( Origin gPackager )
				)
				( attribute "PNN" "P3E_CPU0_PE1_PCH_TXP<8>"
					( Origin gPackager )
				)
				( objectStatus "P3E_CPU0_PE1_PCH_TXP<8>" )
			)
			( signal "@baseboard_fab2_lib.baseboard_fab2(sch_1):p3e_cpu0_pe1_pch_txp(9)"
				( attribute "CDS_PHYS_NET_NAME" "P3E_CPU0_PE1_PCH_TXP<9>"
					( Origin gPackager )
				)
				( attribute "PNN" "P3E_CPU0_PE1_PCH_TXP<9>"
					( Origin gPackager )
				)
				( objectStatus "P3E_CPU0_PE1_PCH_TXP<9>" )
			)
			( signal "@baseboard_fab2_lib.baseboard_fab2(sch_1):p3e_cpu0_pe1_pch_txp(10)"
				( attribute "CDS_PHYS_NET_NAME" "P3E_CPU0_PE1_PCH_TXP<10>"
					( Origin gPackager )
				)
				( attribute "PNN" "P3E_CPU0_PE1_PCH_TXP<10>"
					( Origin gPackager )
				)
				( objectStatus "P3E_CPU0_PE1_PCH_TXP<10>" )
			)
			( signal "@baseboard_fab2_lib.baseboard_fab2(sch_1):p3e_cpu0_pe1_pch_txp(11)"
				( attribute "CDS_PHYS_NET_NAME" "P3E_CPU0_PE1_PCH_TXP<11>"
					( Origin gPackager )
				)
				( attribute "PNN" "P3E_CPU0_PE1_PCH_TXP<11>"
					( Origin gPackager )
				)
				( objectStatus "P3E_CPU0_PE1_PCH_TXP<11>" )
			)
			( signal "@baseboard_fab2_lib.baseboard_fab2(sch_1):p3e_cpu0_pe1_pch_txp(12)"
				( attribute "CDS_PHYS_NET_NAME" "P3E_CPU0_PE1_PCH_TXP<12>"
					( Origin gPackager )
				)
				( attribute "PNN" "P3E_CPU0_PE1_PCH_TXP<12>"
					( Origin gPackager )
				)
				( objectStatus "P3E_CPU0_PE1_PCH_TXP<12>" )
			)
			( signal "@baseboard_fab2_lib.baseboard_fab2(sch_1):p3e_cpu0_pe1_pch_txp(13)"
				( attribute "CDS_PHYS_NET_NAME" "P3E_CPU0_PE1_PCH_TXP<13>"
					( Origin gPackager )
				)
				( attribute "PNN" "P3E_CPU0_PE1_PCH_TXP<13>"
					( Origin gPackager )
				)
				( objectStatus "P3E_CPU0_PE1_PCH_TXP<13>" )
			)
			( signal "@baseboard_fab2_lib.baseboard_fab2(sch_1):p3e_cpu0_pe1_pch_txp(14)"
				( attribute "CDS_PHYS_NET_NAME" "P3E_CPU0_PE1_PCH_TXP<14>"
					( Origin gPackager )
				)
				( attribute "PNN" "P3E_CPU0_PE1_PCH_TXP<14>"
					( Origin gPackager )
				)
				( objectStatus "P3E_CPU0_PE1_PCH_TXP<14>" )
			)
			( signal "@baseboard_fab2_lib.baseboard_fab2(sch_1):p3e_cpu0_pe1_pch_txp(15)"
				( attribute "CDS_PHYS_NET_NAME" "P3E_CPU0_PE1_PCH_TXP<15>"
					( Origin gPackager )
				)
				( attribute "PNN" "P3E_CPU0_PE1_PCH_TXP<15>"
					( Origin gPackager )
				)
				( objectStatus "P3E_CPU0_PE1_PCH_TXP<15>" )
			)
			( signal "@baseboard_fab2_lib.baseboard_fab2(sch_1):p3e_cpu0_pe1_ss_rxn(0)"
				( attribute "CDS_PHYS_NET_NAME" "P3E_CPU0_PE1_SS_RXN<0>"
					( Origin gPackager )
				)
				( attribute "PNN" "P3E_CPU0_PE1_SS_RXN<0>"
					( Origin gPackager )
				)
				( objectStatus "P3E_CPU0_PE1_SS_RXN<0>" )
			)
			( signal "@baseboard_fab2_lib.baseboard_fab2(sch_1):p3e_cpu0_pe1_ss_rxn(1)"
				( attribute "CDS_PHYS_NET_NAME" "P3E_CPU0_PE1_SS_RXN<1>"
					( Origin gPackager )
				)
				( attribute "PNN" "P3E_CPU0_PE1_SS_RXN<1>"
					( Origin gPackager )
				)
				( objectStatus "P3E_CPU0_PE1_SS_RXN<1>" )
			)
			( signal "@baseboard_fab2_lib.baseboard_fab2(sch_1):p3e_cpu0_pe1_ss_rxn(2)"
				( attribute "CDS_PHYS_NET_NAME" "P3E_CPU0_PE1_SS_RXN<2>"
					( Origin gPackager )
				)
				( attribute "PNN" "P3E_CPU0_PE1_SS_RXN<2>"
					( Origin gPackager )
				)
				( objectStatus "P3E_CPU0_PE1_SS_RXN<2>" )
			)
			( signal "@baseboard_fab2_lib.baseboard_fab2(sch_1):p3e_cpu0_pe1_ss_rxn(3)"
				( attribute "CDS_PHYS_NET_NAME" "P3E_CPU0_PE1_SS_RXN<3>"
					( Origin gPackager )
				)
				( attribute "PNN" "P3E_CPU0_PE1_SS_RXN<3>"
					( Origin gPackager )
				)
				( objectStatus "P3E_CPU0_PE1_SS_RXN<3>" )
			)
			( signal "@baseboard_fab2_lib.baseboard_fab2(sch_1):p3e_cpu0_pe1_ss_rxn(4)"
				( attribute "CDS_PHYS_NET_NAME" "P3E_CPU0_PE1_SS_RXN<4>"
					( Origin gPackager )
				)
				( attribute "PNN" "P3E_CPU0_PE1_SS_RXN<4>"
					( Origin gPackager )
				)
				( objectStatus "P3E_CPU0_PE1_SS_RXN<4>" )
			)
			( signal "@baseboard_fab2_lib.baseboard_fab2(sch_1):p3e_cpu0_pe1_ss_rxn(5)"
				( attribute "CDS_PHYS_NET_NAME" "P3E_CPU0_PE1_SS_RXN<5>"
					( Origin gPackager )
				)
				( attribute "PNN" "P3E_CPU0_PE1_SS_RXN<5>"
					( Origin gPackager )
				)
				( objectStatus "P3E_CPU0_PE1_SS_RXN<5>" )
			)
			( signal "@baseboard_fab2_lib.baseboard_fab2(sch_1):p3e_cpu0_pe1_ss_rxn(6)"
				( attribute "CDS_PHYS_NET_NAME" "P3E_CPU0_PE1_SS_RXN<6>"
					( Origin gPackager )
				)
				( attribute "PNN" "P3E_CPU0_PE1_SS_RXN<6>"
					( Origin gPackager )
				)
				( objectStatus "P3E_CPU0_PE1_SS_RXN<6>" )
			)
			( signal "@baseboard_fab2_lib.baseboard_fab2(sch_1):p3e_cpu0_pe1_ss_rxn(7)"
				( attribute "CDS_PHYS_NET_NAME" "P3E_CPU0_PE1_SS_RXN<7>"
					( Origin gPackager )
				)
				( attribute "PNN" "P3E_CPU0_PE1_SS_RXN<7>"
					( Origin gPackager )
				)
				( objectStatus "P3E_CPU0_PE1_SS_RXN<7>" )
			)
			( signal "@baseboard_fab2_lib.baseboard_fab2(sch_1):p3e_cpu0_pe1_ss_rxp(0)"
				( attribute "CDS_PHYS_NET_NAME" "P3E_CPU0_PE1_SS_RXP<0>"
					( Origin gPackager )
				)
				( attribute "PNN" "P3E_CPU0_PE1_SS_RXP<0>"
					( Origin gPackager )
				)
				( objectStatus "P3E_CPU0_PE1_SS_RXP<0>" )
			)
			( signal "@baseboard_fab2_lib.baseboard_fab2(sch_1):p3e_cpu0_pe1_ss_rxp(1)"
				( attribute "CDS_PHYS_NET_NAME" "P3E_CPU0_PE1_SS_RXP<1>"
					( Origin gPackager )
				)
				( attribute "PNN" "P3E_CPU0_PE1_SS_RXP<1>"
					( Origin gPackager )
				)
				( objectStatus "P3E_CPU0_PE1_SS_RXP<1>" )
			)
			( signal "@baseboard_fab2_lib.baseboard_fab2(sch_1):p3e_cpu0_pe1_ss_rxp(2)"
				( attribute "CDS_PHYS_NET_NAME" "P3E_CPU0_PE1_SS_RXP<2>"
					( Origin gPackager )
				)
				( attribute "PNN" "P3E_CPU0_PE1_SS_RXP<2>"
					( Origin gPackager )
				)
				( objectStatus "P3E_CPU0_PE1_SS_RXP<2>" )
			)
			( signal "@baseboard_fab2_lib.baseboard_fab2(sch_1):p3e_cpu0_pe1_ss_rxp(3)"
				( attribute "CDS_PHYS_NET_NAME" "P3E_CPU0_PE1_SS_RXP<3>"
					( Origin gPackager )
				)
				( attribute "PNN" "P3E_CPU0_PE1_SS_RXP<3>"
					( Origin gPackager )
				)
				( objectStatus "P3E_CPU0_PE1_SS_RXP<3>" )
			)
			( signal "@baseboard_fab2_lib.baseboard_fab2(sch_1):p3e_cpu0_pe1_ss_rxp(4)"
				( attribute "CDS_PHYS_NET_NAME" "P3E_CPU0_PE1_SS_RXP<4>"
					( Origin gPackager )
				)
				( attribute "PNN" "P3E_CPU0_PE1_SS_RXP<4>"
					( Origin gPackager )
				)
				( objectStatus "P3E_CPU0_PE1_SS_RXP<4>" )
			)
			( signal "@baseboard_fab2_lib.baseboard_fab2(sch_1):p3e_cpu0_pe1_ss_rxp(5)"
				( attribute "CDS_PHYS_NET_NAME" "P3E_CPU0_PE1_SS_RXP<5>"
					( Origin gPackager )
				)
				( attribute "PNN" "P3E_CPU0_PE1_SS_RXP<5>"
					( Origin gPackager )
				)
				( objectStatus "P3E_CPU0_PE1_SS_RXP<5>" )
			)
			( signal "@baseboard_fab2_lib.baseboard_fab2(sch_1):p3e_cpu0_pe1_ss_rxp(6)"
				( attribute "CDS_PHYS_NET_NAME" "P3E_CPU0_PE1_SS_RXP<6>"
					( Origin gPackager )
				)
				( attribute "PNN" "P3E_CPU0_PE1_SS_RXP<6>"
					( Origin gPackager )
				)
				( objectStatus "P3E_CPU0_PE1_SS_RXP<6>" )
			)
			( signal "@baseboard_fab2_lib.baseboard_fab2(sch_1):p3e_cpu0_pe1_ss_rxp(7)"
				( attribute "CDS_PHYS_NET_NAME" "P3E_CPU0_PE1_SS_RXP<7>"
					( Origin gPackager )
				)
				( attribute "PNN" "P3E_CPU0_PE1_SS_RXP<7>"
					( Origin gPackager )
				)
				( objectStatus "P3E_CPU0_PE1_SS_RXP<7>" )
			)
			( signal "@baseboard_fab2_lib.baseboard_fab2(sch_1):p3e_cpu0_pe1_ss_txn(0)"
				( attribute "CDS_PHYS_NET_NAME" "P3E_CPU0_PE1_SS_TXN<0>"
					( Origin gPackager )
				)
				( attribute "PNN" "P3E_CPU0_PE1_SS_TXN<0>"
					( Origin gPackager )
				)
				( objectStatus "P3E_CPU0_PE1_SS_TXN<0>" )
			)
			( signal "@baseboard_fab2_lib.baseboard_fab2(sch_1):p3e_cpu0_pe1_ss_txn(1)"
				( attribute "CDS_PHYS_NET_NAME" "P3E_CPU0_PE1_SS_TXN<1>"
					( Origin gPackager )
				)
				( attribute "PNN" "P3E_CPU0_PE1_SS_TXN<1>"
					( Origin gPackager )
				)
				( objectStatus "P3E_CPU0_PE1_SS_TXN<1>" )
			)
			( signal "@baseboard_fab2_lib.baseboard_fab2(sch_1):p3e_cpu0_pe1_ss_txn(2)"
				( attribute "CDS_PHYS_NET_NAME" "P3E_CPU0_PE1_SS_TXN<2>"
					( Origin gPackager )
				)
				( attribute "PNN" "P3E_CPU0_PE1_SS_TXN<2>"
					( Origin gPackager )
				)
				( objectStatus "P3E_CPU0_PE1_SS_TXN<2>" )
			)
			( signal "@baseboard_fab2_lib.baseboard_fab2(sch_1):p3e_cpu0_pe1_ss_txn(3)"
				( attribute "CDS_PHYS_NET_NAME" "P3E_CPU0_PE1_SS_TXN<3>"
					( Origin gPackager )
				)
				( attribute "PNN" "P3E_CPU0_PE1_SS_TXN<3>"
					( Origin gPackager )
				)
				( objectStatus "P3E_CPU0_PE1_SS_TXN<3>" )
			)
			( signal "@baseboard_fab2_lib.baseboard_fab2(sch_1):p3e_cpu0_pe1_ss_txn(4)"
				( attribute "CDS_PHYS_NET_NAME" "P3E_CPU0_PE1_SS_TXN<4>"
					( Origin gPackager )
				)
				( attribute "PNN" "P3E_CPU0_PE1_SS_TXN<4>"
					( Origin gPackager )
				)
				( objectStatus "P3E_CPU0_PE1_SS_TXN<4>" )
			)
			( signal "@baseboard_fab2_lib.baseboard_fab2(sch_1):p3e_cpu0_pe1_ss_txn(5)"
				( attribute "CDS_PHYS_NET_NAME" "P3E_CPU0_PE1_SS_TXN<5>"
					( Origin gPackager )
				)
				( attribute "PNN" "P3E_CPU0_PE1_SS_TXN<5>"
					( Origin gPackager )
				)
				( objectStatus "P3E_CPU0_PE1_SS_TXN<5>" )
			)
			( signal "@baseboard_fab2_lib.baseboard_fab2(sch_1):p3e_cpu0_pe1_ss_txn(6)"
				( attribute "CDS_PHYS_NET_NAME" "P3E_CPU0_PE1_SS_TXN<6>"
					( Origin gPackager )
				)
				( attribute "PNN" "P3E_CPU0_PE1_SS_TXN<6>"
					( Origin gPackager )
				)
				( objectStatus "P3E_CPU0_PE1_SS_TXN<6>" )
			)
			( signal "@baseboard_fab2_lib.baseboard_fab2(sch_1):p3e_cpu0_pe1_ss_txn(7)"
				( attribute "CDS_PHYS_NET_NAME" "P3E_CPU0_PE1_SS_TXN<7>"
					( Origin gPackager )
				)
				( attribute "PNN" "P3E_CPU0_PE1_SS_TXN<7>"
					( Origin gPackager )
				)
				( objectStatus "P3E_CPU0_PE1_SS_TXN<7>" )
			)
			( signal "@baseboard_fab2_lib.baseboard_fab2(sch_1):p3e_cpu0_pe1_ss_txp(0)"
				( attribute "CDS_PHYS_NET_NAME" "P3E_CPU0_PE1_SS_TXP<0>"
					( Origin gPackager )
				)
				( attribute "PNN" "P3E_CPU0_PE1_SS_TXP<0>"
					( Origin gPackager )
				)
				( objectStatus "P3E_CPU0_PE1_SS_TXP<0>" )
			)
			( signal "@baseboard_fab2_lib.baseboard_fab2(sch_1):p3e_cpu0_pe1_ss_txp(1)"
				( attribute "CDS_PHYS_NET_NAME" "P3E_CPU0_PE1_SS_TXP<1>"
					( Origin gPackager )
				)
				( attribute "PNN" "P3E_CPU0_PE1_SS_TXP<1>"
					( Origin gPackager )
				)
				( objectStatus "P3E_CPU0_PE1_SS_TXP<1>" )
			)
			( signal "@baseboard_fab2_lib.baseboard_fab2(sch_1):p3e_cpu0_pe1_ss_txp(2)"
				( attribute "CDS_PHYS_NET_NAME" "P3E_CPU0_PE1_SS_TXP<2>"
					( Origin gPackager )
				)
				( attribute "PNN" "P3E_CPU0_PE1_SS_TXP<2>"
					( Origin gPackager )
				)
				( objectStatus "P3E_CPU0_PE1_SS_TXP<2>" )
			)
			( signal "@baseboard_fab2_lib.baseboard_fab2(sch_1):p3e_cpu0_pe1_ss_txp(3)"
				( attribute "CDS_PHYS_NET_NAME" "P3E_CPU0_PE1_SS_TXP<3>"
					( Origin gPackager )
				)
				( attribute "PNN" "P3E_CPU0_PE1_SS_TXP<3>"
					( Origin gPackager )
				)
				( objectStatus "P3E_CPU0_PE1_SS_TXP<3>" )
			)
			( signal "@baseboard_fab2_lib.baseboard_fab2(sch_1):p3e_cpu0_pe1_ss_txp(4)"
				( attribute "CDS_PHYS_NET_NAME" "P3E_CPU0_PE1_SS_TXP<4>"
					( Origin gPackager )
				)
				( attribute "PNN" "P3E_CPU0_PE1_SS_TXP<4>"
					( Origin gPackager )
				)
				( objectStatus "P3E_CPU0_PE1_SS_TXP<4>" )
			)
			( signal "@baseboard_fab2_lib.baseboard_fab2(sch_1):p3e_cpu0_pe1_ss_txp(5)"
				( attribute "CDS_PHYS_NET_NAME" "P3E_CPU0_PE1_SS_TXP<5>"
					( Origin gPackager )
				)
				( attribute "PNN" "P3E_CPU0_PE1_SS_TXP<5>"
					( Origin gPackager )
				)
				( objectStatus "P3E_CPU0_PE1_SS_TXP<5>" )
			)
			( signal "@baseboard_fab2_lib.baseboard_fab2(sch_1):p3e_cpu0_pe1_ss_txp(6)"
				( attribute "CDS_PHYS_NET_NAME" "P3E_CPU0_PE1_SS_TXP<6>"
					( Origin gPackager )
				)
				( attribute "PNN" "P3E_CPU0_PE1_SS_TXP<6>"
					( Origin gPackager )
				)
				( objectStatus "P3E_CPU0_PE1_SS_TXP<6>" )
			)
			( signal "@baseboard_fab2_lib.baseboard_fab2(sch_1):p3e_cpu0_pe1_ss_txp(7)"
				( attribute "CDS_PHYS_NET_NAME" "P3E_CPU0_PE1_SS_TXP<7>"
					( Origin gPackager )
				)
				( attribute "PNN" "P3E_CPU0_PE1_SS_TXP<7>"
					( Origin gPackager )
				)
				( objectStatus "P3E_CPU0_PE1_SS_TXP<7>" )
			)
			( signal "@baseboard_fab2_lib.baseboard_fab2(sch_1):p3e_cpu0_pe2_ss_rxn(0)"
				( attribute "CDS_PHYS_NET_NAME" "P3E_CPU0_PE2_SS_RXN<0>"
					( Origin gPackager )
				)
				( attribute "PNN" "P3E_CPU0_PE2_SS_RXN<0>"
					( Origin gPackager )
				)
				( objectStatus "P3E_CPU0_PE2_SS_RXN<0>" )
			)
			( signal "@baseboard_fab2_lib.baseboard_fab2(sch_1):p3e_cpu0_pe2_ss_rxn(1)"
				( attribute "CDS_PHYS_NET_NAME" "P3E_CPU0_PE2_SS_RXN<1>"
					( Origin gPackager )
				)
				( attribute "PNN" "P3E_CPU0_PE2_SS_RXN<1>"
					( Origin gPackager )
				)
				( objectStatus "P3E_CPU0_PE2_SS_RXN<1>" )
			)
			( signal "@baseboard_fab2_lib.baseboard_fab2(sch_1):p3e_cpu0_pe2_ss_rxn(2)"
				( attribute "CDS_PHYS_NET_NAME" "P3E_CPU0_PE2_SS_RXN<2>"
					( Origin gPackager )
				)
				( attribute "PNN" "P3E_CPU0_PE2_SS_RXN<2>"
					( Origin gPackager )
				)
				( objectStatus "P3E_CPU0_PE2_SS_RXN<2>" )
			)
			( signal "@baseboard_fab2_lib.baseboard_fab2(sch_1):p3e_cpu0_pe2_ss_rxn(3)"
				( attribute "CDS_PHYS_NET_NAME" "P3E_CPU0_PE2_SS_RXN<3>"
					( Origin gPackager )
				)
				( attribute "PNN" "P3E_CPU0_PE2_SS_RXN<3>"
					( Origin gPackager )
				)
				( objectStatus "P3E_CPU0_PE2_SS_RXN<3>" )
			)
			( signal "@baseboard_fab2_lib.baseboard_fab2(sch_1):p3e_cpu0_pe2_ss_rxn(4)"
				( attribute "CDS_PHYS_NET_NAME" "P3E_CPU0_PE2_SS_RXN<4>"
					( Origin gPackager )
				)
				( attribute "PNN" "P3E_CPU0_PE2_SS_RXN<4>"
					( Origin gPackager )
				)
				( objectStatus "P3E_CPU0_PE2_SS_RXN<4>" )
			)
			( signal "@baseboard_fab2_lib.baseboard_fab2(sch_1):p3e_cpu0_pe2_ss_rxn(5)"
				( attribute "CDS_PHYS_NET_NAME" "P3E_CPU0_PE2_SS_RXN<5>"
					( Origin gPackager )
				)
				( attribute "PNN" "P3E_CPU0_PE2_SS_RXN<5>"
					( Origin gPackager )
				)
				( objectStatus "P3E_CPU0_PE2_SS_RXN<5>" )
			)
			( signal "@baseboard_fab2_lib.baseboard_fab2(sch_1):p3e_cpu0_pe2_ss_rxn(6)"
				( attribute "CDS_PHYS_NET_NAME" "P3E_CPU0_PE2_SS_RXN<6>"
					( Origin gPackager )
				)
				( attribute "PNN" "P3E_CPU0_PE2_SS_RXN<6>"
					( Origin gPackager )
				)
				( objectStatus "P3E_CPU0_PE2_SS_RXN<6>" )
			)
			( signal "@baseboard_fab2_lib.baseboard_fab2(sch_1):p3e_cpu0_pe2_ss_rxn(7)"
				( attribute "CDS_PHYS_NET_NAME" "P3E_CPU0_PE2_SS_RXN<7>"
					( Origin gPackager )
				)
				( attribute "PNN" "P3E_CPU0_PE2_SS_RXN<7>"
					( Origin gPackager )
				)
				( objectStatus "P3E_CPU0_PE2_SS_RXN<7>" )
			)
			( signal "@baseboard_fab2_lib.baseboard_fab2(sch_1):p3e_cpu0_pe2_ss_rxn(8)"
				( alias ( signalRef "@baseboard_fab2_lib.baseboard_fab2(sch_1):page245_p3e_cpu0_pe2_ss_rxn(8)") )
				( attribute "CDS_PHYS_NET_NAME" "P3E_CPU0_PE2_SS_RXN<8>"
					( Origin gPackager )
				)
				( attribute "PNN" "P3E_CPU0_PE2_SS_RXN<8>"
					( Origin gPackager )
				)
				( objectStatus "P3E_CPU0_PE2_SS_RXN<8>" )
			)
			( signal "@baseboard_fab2_lib.baseboard_fab2(sch_1):page245_p3e_cpu0_pe2_ss_rxn(8)"
				( attribute "CDS_PHYS_NET_NAME" "P3E_CPU0_PE2_SS_RXN<8>"
					( Origin gPackager )
				)
				( objectFlag fObjectAlias )
				( objectStatus "page245_p3e_cpu0_pe2_ss_rxn<8>" )
			)
			( signal "@baseboard_fab2_lib.baseboard_fab2(sch_1):p3e_cpu0_pe2_ss_rxn(9)"
				( alias ( signalRef "@baseboard_fab2_lib.baseboard_fab2(sch_1):page245_p3e_cpu0_pe2_ss_rxn(9)") )
				( attribute "CDS_PHYS_NET_NAME" "P3E_CPU0_PE2_SS_RXN<9>"
					( Origin gPackager )
				)
				( attribute "PNN" "P3E_CPU0_PE2_SS_RXN<9>"
					( Origin gPackager )
				)
				( objectStatus "P3E_CPU0_PE2_SS_RXN<9>" )
			)
			( signal "@baseboard_fab2_lib.baseboard_fab2(sch_1):page245_p3e_cpu0_pe2_ss_rxn(9)"
				( objectFlag fObjectAlias )
				( objectStatus "page245_p3e_cpu0_pe2_ss_rxn<9>" )
			)
			( signal "@baseboard_fab2_lib.baseboard_fab2(sch_1):p3e_cpu0_pe2_ss_rxn(10)"
				( alias ( signalRef "@baseboard_fab2_lib.baseboard_fab2(sch_1):page245_p3e_cpu0_pe2_ss_rxn(10)") )
				( attribute "CDS_PHYS_NET_NAME" "P3E_CPU0_PE2_SS_RXN<10>"
					( Origin gPackager )
				)
				( attribute "PNN" "P3E_CPU0_PE2_SS_RXN<10>"
					( Origin gPackager )
				)
				( objectStatus "P3E_CPU0_PE2_SS_RXN<10>" )
			)
			( signal "@baseboard_fab2_lib.baseboard_fab2(sch_1):page245_p3e_cpu0_pe2_ss_rxn(10)"
				( objectFlag fObjectAlias )
				( objectStatus "page245_p3e_cpu0_pe2_ss_rxn<10>" )
			)
			( signal "@baseboard_fab2_lib.baseboard_fab2(sch_1):p3e_cpu0_pe2_ss_rxn(11)"
				( alias ( signalRef "@baseboard_fab2_lib.baseboard_fab2(sch_1):page245_p3e_cpu0_pe2_ss_rxn(11)") )
				( attribute "CDS_PHYS_NET_NAME" "P3E_CPU0_PE2_SS_RXN<11>"
					( Origin gPackager )
				)
				( attribute "PNN" "P3E_CPU0_PE2_SS_RXN<11>"
					( Origin gPackager )
				)
				( objectStatus "P3E_CPU0_PE2_SS_RXN<11>" )
			)
			( signal "@baseboard_fab2_lib.baseboard_fab2(sch_1):page245_p3e_cpu0_pe2_ss_rxn(11)"
				( objectFlag fObjectAlias )
				( objectStatus "page245_p3e_cpu0_pe2_ss_rxn<11>" )
			)
			( signal "@baseboard_fab2_lib.baseboard_fab2(sch_1):p3e_cpu0_pe2_ss_rxn(12)"
				( alias ( signalRef "@baseboard_fab2_lib.baseboard_fab2(sch_1):page245_p3e_cpu0_pe2_ss_rxn(12)") )
				( attribute "CDS_PHYS_NET_NAME" "P3E_CPU0_PE2_SS_RXN<12>"
					( Origin gPackager )
				)
				( attribute "PNN" "P3E_CPU0_PE2_SS_RXN<12>"
					( Origin gPackager )
				)
				( objectStatus "P3E_CPU0_PE2_SS_RXN<12>" )
			)
			( signal "@baseboard_fab2_lib.baseboard_fab2(sch_1):page245_p3e_cpu0_pe2_ss_rxn(12)"
				( objectFlag fObjectAlias )
				( objectStatus "page245_p3e_cpu0_pe2_ss_rxn<12>" )
			)
			( signal "@baseboard_fab2_lib.baseboard_fab2(sch_1):p3e_cpu0_pe2_ss_rxn(13)"
				( alias ( signalRef "@baseboard_fab2_lib.baseboard_fab2(sch_1):page245_p3e_cpu0_pe2_ss_rxn(13)") )
				( attribute "CDS_PHYS_NET_NAME" "P3E_CPU0_PE2_SS_RXN<13>"
					( Origin gPackager )
				)
				( attribute "PNN" "P3E_CPU0_PE2_SS_RXN<13>"
					( Origin gPackager )
				)
				( objectStatus "P3E_CPU0_PE2_SS_RXN<13>" )
			)
			( signal "@baseboard_fab2_lib.baseboard_fab2(sch_1):page245_p3e_cpu0_pe2_ss_rxn(13)"
				( objectFlag fObjectAlias )
				( objectStatus "page245_p3e_cpu0_pe2_ss_rxn<13>" )
			)
			( signal "@baseboard_fab2_lib.baseboard_fab2(sch_1):p3e_cpu0_pe2_ss_rxn(14)"
				( alias ( signalRef "@baseboard_fab2_lib.baseboard_fab2(sch_1):page245_p3e_cpu0_pe2_ss_rxn(14)") )
				( attribute "CDS_PHYS_NET_NAME" "P3E_CPU0_PE2_SS_RXN<14>"
					( Origin gPackager )
				)
				( attribute "PNN" "P3E_CPU0_PE2_SS_RXN<14>"
					( Origin gPackager )
				)
				( objectStatus "P3E_CPU0_PE2_SS_RXN<14>" )
			)
			( signal "@baseboard_fab2_lib.baseboard_fab2(sch_1):page245_p3e_cpu0_pe2_ss_rxn(14)"
				( objectFlag fObjectAlias )
				( objectStatus "page245_p3e_cpu0_pe2_ss_rxn<14>" )
			)
			( signal "@baseboard_fab2_lib.baseboard_fab2(sch_1):p3e_cpu0_pe2_ss_rxn(15)"
				( alias ( signalRef "@baseboard_fab2_lib.baseboard_fab2(sch_1):page245_p3e_cpu0_pe2_ss_rxn(15)") )
				( attribute "CDS_PHYS_NET_NAME" "P3E_CPU0_PE2_SS_RXN<15>"
					( Origin gPackager )
				)
				( attribute "PNN" "P3E_CPU0_PE2_SS_RXN<15>"
					( Origin gPackager )
				)
				( objectStatus "P3E_CPU0_PE2_SS_RXN<15>" )
			)
			( signal "@baseboard_fab2_lib.baseboard_fab2(sch_1):page245_p3e_cpu0_pe2_ss_rxn(15)"
				( objectFlag fObjectAlias )
				( objectStatus "page245_p3e_cpu0_pe2_ss_rxn<15>" )
			)
			( signal "@baseboard_fab2_lib.baseboard_fab2(sch_1):p3e_cpu0_pe2_ss_rxp(0)"
				( attribute "CDS_PHYS_NET_NAME" "P3E_CPU0_PE2_SS_RXP<0>"
					( Origin gPackager )
				)
				( attribute "PNN" "P3E_CPU0_PE2_SS_RXP<0>"
					( Origin gPackager )
				)
				( objectStatus "P3E_CPU0_PE2_SS_RXP<0>" )
			)
			( signal "@baseboard_fab2_lib.baseboard_fab2(sch_1):p3e_cpu0_pe2_ss_rxp(1)"
				( attribute "CDS_PHYS_NET_NAME" "P3E_CPU0_PE2_SS_RXP<1>"
					( Origin gPackager )
				)
				( attribute "PNN" "P3E_CPU0_PE2_SS_RXP<1>"
					( Origin gPackager )
				)
				( objectStatus "P3E_CPU0_PE2_SS_RXP<1>" )
			)
			( signal "@baseboard_fab2_lib.baseboard_fab2(sch_1):p3e_cpu0_pe2_ss_rxp(2)"
				( attribute "CDS_PHYS_NET_NAME" "P3E_CPU0_PE2_SS_RXP<2>"
					( Origin gPackager )
				)
				( attribute "PNN" "P3E_CPU0_PE2_SS_RXP<2>"
					( Origin gPackager )
				)
				( objectStatus "P3E_CPU0_PE2_SS_RXP<2>" )
			)
			( signal "@baseboard_fab2_lib.baseboard_fab2(sch_1):p3e_cpu0_pe2_ss_rxp(3)"
				( attribute "CDS_PHYS_NET_NAME" "P3E_CPU0_PE2_SS_RXP<3>"
					( Origin gPackager )
				)
				( attribute "PNN" "P3E_CPU0_PE2_SS_RXP<3>"
					( Origin gPackager )
				)
				( objectStatus "P3E_CPU0_PE2_SS_RXP<3>" )
			)
			( signal "@baseboard_fab2_lib.baseboard_fab2(sch_1):p3e_cpu0_pe2_ss_rxp(4)"
				( attribute "CDS_PHYS_NET_NAME" "P3E_CPU0_PE2_SS_RXP<4>"
					( Origin gPackager )
				)
				( attribute "PNN" "P3E_CPU0_PE2_SS_RXP<4>"
					( Origin gPackager )
				)
				( objectStatus "P3E_CPU0_PE2_SS_RXP<4>" )
			)
			( signal "@baseboard_fab2_lib.baseboard_fab2(sch_1):p3e_cpu0_pe2_ss_rxp(5)"
				( attribute "CDS_PHYS_NET_NAME" "P3E_CPU0_PE2_SS_RXP<5>"
					( Origin gPackager )
				)
				( attribute "PNN" "P3E_CPU0_PE2_SS_RXP<5>"
					( Origin gPackager )
				)
				( objectStatus "P3E_CPU0_PE2_SS_RXP<5>" )
			)
			( signal "@baseboard_fab2_lib.baseboard_fab2(sch_1):p3e_cpu0_pe2_ss_rxp(6)"
				( attribute "CDS_PHYS_NET_NAME" "P3E_CPU0_PE2_SS_RXP<6>"
					( Origin gPackager )
				)
				( attribute "PNN" "P3E_CPU0_PE2_SS_RXP<6>"
					( Origin gPackager )
				)
				( objectStatus "P3E_CPU0_PE2_SS_RXP<6>" )
			)
			( signal "@baseboard_fab2_lib.baseboard_fab2(sch_1):p3e_cpu0_pe2_ss_rxp(7)"
				( attribute "CDS_PHYS_NET_NAME" "P3E_CPU0_PE2_SS_RXP<7>"
					( Origin gPackager )
				)
				( attribute "PNN" "P3E_CPU0_PE2_SS_RXP<7>"
					( Origin gPackager )
				)
				( objectStatus "P3E_CPU0_PE2_SS_RXP<7>" )
			)
			( signal "@baseboard_fab2_lib.baseboard_fab2(sch_1):p3e_cpu0_pe2_ss_rxp(8)"
				( alias ( signalRef "@baseboard_fab2_lib.baseboard_fab2(sch_1):page245_p3e_cpu0_pe2_ss_rxp(8)") )
				( attribute "CDS_PHYS_NET_NAME" "P3E_CPU0_PE2_SS_RXP<8>"
					( Origin gPackager )
				)
				( attribute "PNN" "P3E_CPU0_PE2_SS_RXP<8>"
					( Origin gPackager )
				)
				( objectStatus "P3E_CPU0_PE2_SS_RXP<8>" )
			)
			( signal "@baseboard_fab2_lib.baseboard_fab2(sch_1):page245_p3e_cpu0_pe2_ss_rxp(8)"
				( attribute "CDS_PHYS_NET_NAME" "P3E_CPU0_PE2_SS_RXP<8>"
					( Origin gPackager )
				)
				( objectFlag fObjectAlias )
				( objectStatus "page245_p3e_cpu0_pe2_ss_rxp<8>" )
			)
			( signal "@baseboard_fab2_lib.baseboard_fab2(sch_1):p3e_cpu0_pe2_ss_rxp(9)"
				( alias ( signalRef "@baseboard_fab2_lib.baseboard_fab2(sch_1):page245_p3e_cpu0_pe2_ss_rxp(9)") )
				( attribute "CDS_PHYS_NET_NAME" "P3E_CPU0_PE2_SS_RXP<9>"
					( Origin gPackager )
				)
				( attribute "PNN" "P3E_CPU0_PE2_SS_RXP<9>"
					( Origin gPackager )
				)
				( objectStatus "P3E_CPU0_PE2_SS_RXP<9>" )
			)
			( signal "@baseboard_fab2_lib.baseboard_fab2(sch_1):page245_p3e_cpu0_pe2_ss_rxp(9)"
				( objectFlag fObjectAlias )
				( objectStatus "page245_p3e_cpu0_pe2_ss_rxp<9>" )
			)
			( signal "@baseboard_fab2_lib.baseboard_fab2(sch_1):p3e_cpu0_pe2_ss_rxp(10)"
				( alias ( signalRef "@baseboard_fab2_lib.baseboard_fab2(sch_1):page245_p3e_cpu0_pe2_ss_rxp(10)") )
				( attribute "CDS_PHYS_NET_NAME" "P3E_CPU0_PE2_SS_RXP<10>"
					( Origin gPackager )
				)
				( attribute "PNN" "P3E_CPU0_PE2_SS_RXP<10>"
					( Origin gPackager )
				)
				( objectStatus "P3E_CPU0_PE2_SS_RXP<10>" )
			)
			( signal "@baseboard_fab2_lib.baseboard_fab2(sch_1):page245_p3e_cpu0_pe2_ss_rxp(10)"
				( objectFlag fObjectAlias )
				( objectStatus "page245_p3e_cpu0_pe2_ss_rxp<10>" )
			)
			( signal "@baseboard_fab2_lib.baseboard_fab2(sch_1):p3e_cpu0_pe2_ss_rxp(11)"
				( alias ( signalRef "@baseboard_fab2_lib.baseboard_fab2(sch_1):page245_p3e_cpu0_pe2_ss_rxp(11)") )
				( attribute "CDS_PHYS_NET_NAME" "P3E_CPU0_PE2_SS_RXP<11>"
					( Origin gPackager )
				)
				( attribute "PNN" "P3E_CPU0_PE2_SS_RXP<11>"
					( Origin gPackager )
				)
				( objectStatus "P3E_CPU0_PE2_SS_RXP<11>" )
			)
			( signal "@baseboard_fab2_lib.baseboard_fab2(sch_1):page245_p3e_cpu0_pe2_ss_rxp(11)"
				( objectFlag fObjectAlias )
				( objectStatus "page245_p3e_cpu0_pe2_ss_rxp<11>" )
			)
			( signal "@baseboard_fab2_lib.baseboard_fab2(sch_1):p3e_cpu0_pe2_ss_rxp(12)"
				( alias ( signalRef "@baseboard_fab2_lib.baseboard_fab2(sch_1):page245_p3e_cpu0_pe2_ss_rxp(12)") )
				( attribute "CDS_PHYS_NET_NAME" "P3E_CPU0_PE2_SS_RXP<12>"
					( Origin gPackager )
				)
				( attribute "PNN" "P3E_CPU0_PE2_SS_RXP<12>"
					( Origin gPackager )
				)
				( objectStatus "P3E_CPU0_PE2_SS_RXP<12>" )
			)
			( signal "@baseboard_fab2_lib.baseboard_fab2(sch_1):page245_p3e_cpu0_pe2_ss_rxp(12)"
				( objectFlag fObjectAlias )
				( objectStatus "page245_p3e_cpu0_pe2_ss_rxp<12>" )
			)
			( signal "@baseboard_fab2_lib.baseboard_fab2(sch_1):p3e_cpu0_pe2_ss_rxp(13)"
				( alias ( signalRef "@baseboard_fab2_lib.baseboard_fab2(sch_1):page245_p3e_cpu0_pe2_ss_rxp(13)") )
				( attribute "CDS_PHYS_NET_NAME" "P3E_CPU0_PE2_SS_RXP<13>"
					( Origin gPackager )
				)
				( attribute "PNN" "P3E_CPU0_PE2_SS_RXP<13>"
					( Origin gPackager )
				)
				( objectStatus "P3E_CPU0_PE2_SS_RXP<13>" )
			)
			( signal "@baseboard_fab2_lib.baseboard_fab2(sch_1):page245_p3e_cpu0_pe2_ss_rxp(13)"
				( objectFlag fObjectAlias )
				( objectStatus "page245_p3e_cpu0_pe2_ss_rxp<13>" )
			)
			( signal "@baseboard_fab2_lib.baseboard_fab2(sch_1):p3e_cpu0_pe2_ss_rxp(14)"
				( alias ( signalRef "@baseboard_fab2_lib.baseboard_fab2(sch_1):page245_p3e_cpu0_pe2_ss_rxp(14)") )
				( attribute "CDS_PHYS_NET_NAME" "P3E_CPU0_PE2_SS_RXP<14>"
					( Origin gPackager )
				)
				( attribute "PNN" "P3E_CPU0_PE2_SS_RXP<14>"
					( Origin gPackager )
				)
				( objectStatus "P3E_CPU0_PE2_SS_RXP<14>" )
			)
			( signal "@baseboard_fab2_lib.baseboard_fab2(sch_1):page245_p3e_cpu0_pe2_ss_rxp(14)"
				( objectFlag fObjectAlias )
				( objectStatus "page245_p3e_cpu0_pe2_ss_rxp<14>" )
			)
			( signal "@baseboard_fab2_lib.baseboard_fab2(sch_1):p3e_cpu0_pe2_ss_rxp(15)"
				( alias ( signalRef "@baseboard_fab2_lib.baseboard_fab2(sch_1):page245_p3e_cpu0_pe2_ss_rxp(15)") )
				( attribute "CDS_PHYS_NET_NAME" "P3E_CPU0_PE2_SS_RXP<15>"
					( Origin gPackager )
				)
				( attribute "PNN" "P3E_CPU0_PE2_SS_RXP<15>"
					( Origin gPackager )
				)
				( objectStatus "P3E_CPU0_PE2_SS_RXP<15>" )
			)
			( signal "@baseboard_fab2_lib.baseboard_fab2(sch_1):page245_p3e_cpu0_pe2_ss_rxp(15)"
				( objectFlag fObjectAlias )
				( objectStatus "page245_p3e_cpu0_pe2_ss_rxp<15>" )
			)
			( signal "@baseboard_fab2_lib.baseboard_fab2(sch_1):p3e_cpu0_pe2_ss_txn(0)"
				( attribute "CDS_PHYS_NET_NAME" "P3E_CPU0_PE2_SS_TXN<0>"
					( Origin gPackager )
				)
				( attribute "PNN" "P3E_CPU0_PE2_SS_TXN<0>"
					( Origin gPackager )
				)
				( objectStatus "P3E_CPU0_PE2_SS_TXN<0>" )
			)
			( signal "@baseboard_fab2_lib.baseboard_fab2(sch_1):p3e_cpu0_pe2_ss_txn(1)"
				( attribute "CDS_PHYS_NET_NAME" "P3E_CPU0_PE2_SS_TXN<1>"
					( Origin gPackager )
				)
				( attribute "PNN" "P3E_CPU0_PE2_SS_TXN<1>"
					( Origin gPackager )
				)
				( objectStatus "P3E_CPU0_PE2_SS_TXN<1>" )
			)
			( signal "@baseboard_fab2_lib.baseboard_fab2(sch_1):p3e_cpu0_pe2_ss_txn(2)"
				( attribute "CDS_PHYS_NET_NAME" "P3E_CPU0_PE2_SS_TXN<2>"
					( Origin gPackager )
				)
				( attribute "PNN" "P3E_CPU0_PE2_SS_TXN<2>"
					( Origin gPackager )
				)
				( objectStatus "P3E_CPU0_PE2_SS_TXN<2>" )
			)
			( signal "@baseboard_fab2_lib.baseboard_fab2(sch_1):p3e_cpu0_pe2_ss_txn(3)"
				( attribute "CDS_PHYS_NET_NAME" "P3E_CPU0_PE2_SS_TXN<3>"
					( Origin gPackager )
				)
				( attribute "PNN" "P3E_CPU0_PE2_SS_TXN<3>"
					( Origin gPackager )
				)
				( objectStatus "P3E_CPU0_PE2_SS_TXN<3>" )
			)
			( signal "@baseboard_fab2_lib.baseboard_fab2(sch_1):p3e_cpu0_pe2_ss_txn(4)"
				( attribute "CDS_PHYS_NET_NAME" "P3E_CPU0_PE2_SS_TXN<4>"
					( Origin gPackager )
				)
				( attribute "PNN" "P3E_CPU0_PE2_SS_TXN<4>"
					( Origin gPackager )
				)
				( objectStatus "P3E_CPU0_PE2_SS_TXN<4>" )
			)
			( signal "@baseboard_fab2_lib.baseboard_fab2(sch_1):p3e_cpu0_pe2_ss_txn(5)"
				( attribute "CDS_PHYS_NET_NAME" "P3E_CPU0_PE2_SS_TXN<5>"
					( Origin gPackager )
				)
				( attribute "PNN" "P3E_CPU0_PE2_SS_TXN<5>"
					( Origin gPackager )
				)
				( objectStatus "P3E_CPU0_PE2_SS_TXN<5>" )
			)
			( signal "@baseboard_fab2_lib.baseboard_fab2(sch_1):p3e_cpu0_pe2_ss_txn(6)"
				( attribute "CDS_PHYS_NET_NAME" "P3E_CPU0_PE2_SS_TXN<6>"
					( Origin gPackager )
				)
				( attribute "PNN" "P3E_CPU0_PE2_SS_TXN<6>"
					( Origin gPackager )
				)
				( objectStatus "P3E_CPU0_PE2_SS_TXN<6>" )
			)
			( signal "@baseboard_fab2_lib.baseboard_fab2(sch_1):p3e_cpu0_pe2_ss_txn(7)"
				( attribute "CDS_PHYS_NET_NAME" "P3E_CPU0_PE2_SS_TXN<7>"
					( Origin gPackager )
				)
				( attribute "PNN" "P3E_CPU0_PE2_SS_TXN<7>"
					( Origin gPackager )
				)
				( objectStatus "P3E_CPU0_PE2_SS_TXN<7>" )
			)
			( signal "@baseboard_fab2_lib.baseboard_fab2(sch_1):p3e_cpu0_pe2_ss_txn(8)"
				( attribute "CDS_PHYS_NET_NAME" "P3E_CPU0_PE2_SS_TXN<8>"
					( Origin gPackager )
				)
				( attribute "PNN" "P3E_CPU0_PE2_SS_TXN<8>"
					( Origin gPackager )
				)
				( objectStatus "P3E_CPU0_PE2_SS_TXN<8>" )
			)
			( signal "@baseboard_fab2_lib.baseboard_fab2(sch_1):p3e_cpu0_pe2_ss_txn(9)"
				( attribute "CDS_PHYS_NET_NAME" "P3E_CPU0_PE2_SS_TXN<9>"
					( Origin gPackager )
				)
				( attribute "PNN" "P3E_CPU0_PE2_SS_TXN<9>"
					( Origin gPackager )
				)
				( objectStatus "P3E_CPU0_PE2_SS_TXN<9>" )
			)
			( signal "@baseboard_fab2_lib.baseboard_fab2(sch_1):p3e_cpu0_pe2_ss_txn(10)"
				( attribute "CDS_PHYS_NET_NAME" "P3E_CPU0_PE2_SS_TXN<10>"
					( Origin gPackager )
				)
				( attribute "PNN" "P3E_CPU0_PE2_SS_TXN<10>"
					( Origin gPackager )
				)
				( objectStatus "P3E_CPU0_PE2_SS_TXN<10>" )
			)
			( signal "@baseboard_fab2_lib.baseboard_fab2(sch_1):p3e_cpu0_pe2_ss_txn(11)"
				( attribute "CDS_PHYS_NET_NAME" "P3E_CPU0_PE2_SS_TXN<11>"
					( Origin gPackager )
				)
				( attribute "PNN" "P3E_CPU0_PE2_SS_TXN<11>"
					( Origin gPackager )
				)
				( objectStatus "P3E_CPU0_PE2_SS_TXN<11>" )
			)
			( signal "@baseboard_fab2_lib.baseboard_fab2(sch_1):p3e_cpu0_pe2_ss_txn(12)"
				( attribute "CDS_PHYS_NET_NAME" "P3E_CPU0_PE2_SS_TXN<12>"
					( Origin gPackager )
				)
				( attribute "PNN" "P3E_CPU0_PE2_SS_TXN<12>"
					( Origin gPackager )
				)
				( objectStatus "P3E_CPU0_PE2_SS_TXN<12>" )
			)
			( signal "@baseboard_fab2_lib.baseboard_fab2(sch_1):p3e_cpu0_pe2_ss_txn(13)"
				( attribute "CDS_PHYS_NET_NAME" "P3E_CPU0_PE2_SS_TXN<13>"
					( Origin gPackager )
				)
				( attribute "PNN" "P3E_CPU0_PE2_SS_TXN<13>"
					( Origin gPackager )
				)
				( objectStatus "P3E_CPU0_PE2_SS_TXN<13>" )
			)
			( signal "@baseboard_fab2_lib.baseboard_fab2(sch_1):p3e_cpu0_pe2_ss_txn(14)"
				( attribute "CDS_PHYS_NET_NAME" "P3E_CPU0_PE2_SS_TXN<14>"
					( Origin gPackager )
				)
				( attribute "PNN" "P3E_CPU0_PE2_SS_TXN<14>"
					( Origin gPackager )
				)
				( objectStatus "P3E_CPU0_PE2_SS_TXN<14>" )
			)
			( signal "@baseboard_fab2_lib.baseboard_fab2(sch_1):p3e_cpu0_pe2_ss_txn(15)"
				( attribute "CDS_PHYS_NET_NAME" "P3E_CPU0_PE2_SS_TXN<15>"
					( Origin gPackager )
				)
				( attribute "PNN" "P3E_CPU0_PE2_SS_TXN<15>"
					( Origin gPackager )
				)
				( objectStatus "P3E_CPU0_PE2_SS_TXN<15>" )
			)
			( signal "@baseboard_fab2_lib.baseboard_fab2(sch_1):p3e_cpu0_pe2_ss_txp(0)"
				( attribute "CDS_PHYS_NET_NAME" "P3E_CPU0_PE2_SS_TXP<0>"
					( Origin gPackager )
				)
				( attribute "PNN" "P3E_CPU0_PE2_SS_TXP<0>"
					( Origin gPackager )
				)
				( objectStatus "P3E_CPU0_PE2_SS_TXP<0>" )
			)
			( signal "@baseboard_fab2_lib.baseboard_fab2(sch_1):p3e_cpu0_pe2_ss_txp(1)"
				( attribute "CDS_PHYS_NET_NAME" "P3E_CPU0_PE2_SS_TXP<1>"
					( Origin gPackager )
				)
				( attribute "PNN" "P3E_CPU0_PE2_SS_TXP<1>"
					( Origin gPackager )
				)
				( objectStatus "P3E_CPU0_PE2_SS_TXP<1>" )
			)
			( signal "@baseboard_fab2_lib.baseboard_fab2(sch_1):p3e_cpu0_pe2_ss_txp(2)"
				( attribute "CDS_PHYS_NET_NAME" "P3E_CPU0_PE2_SS_TXP<2>"
					( Origin gPackager )
				)
				( attribute "PNN" "P3E_CPU0_PE2_SS_TXP<2>"
					( Origin gPackager )
				)
				( objectStatus "P3E_CPU0_PE2_SS_TXP<2>" )
			)
			( signal "@baseboard_fab2_lib.baseboard_fab2(sch_1):p3e_cpu0_pe2_ss_txp(3)"
				( attribute "CDS_PHYS_NET_NAME" "P3E_CPU0_PE2_SS_TXP<3>"
					( Origin gPackager )
				)
				( attribute "PNN" "P3E_CPU0_PE2_SS_TXP<3>"
					( Origin gPackager )
				)
				( objectStatus "P3E_CPU0_PE2_SS_TXP<3>" )
			)
			( signal "@baseboard_fab2_lib.baseboard_fab2(sch_1):p3e_cpu0_pe2_ss_txp(4)"
				( attribute "CDS_PHYS_NET_NAME" "P3E_CPU0_PE2_SS_TXP<4>"
					( Origin gPackager )
				)
				( attribute "PNN" "P3E_CPU0_PE2_SS_TXP<4>"
					( Origin gPackager )
				)
				( objectStatus "P3E_CPU0_PE2_SS_TXP<4>" )
			)
			( signal "@baseboard_fab2_lib.baseboard_fab2(sch_1):p3e_cpu0_pe2_ss_txp(5)"
				( attribute "CDS_PHYS_NET_NAME" "P3E_CPU0_PE2_SS_TXP<5>"
					( Origin gPackager )
				)
				( attribute "PNN" "P3E_CPU0_PE2_SS_TXP<5>"
					( Origin gPackager )
				)
				( objectStatus "P3E_CPU0_PE2_SS_TXP<5>" )
			)
			( signal "@baseboard_fab2_lib.baseboard_fab2(sch_1):p3e_cpu0_pe2_ss_txp(6)"
				( attribute "CDS_PHYS_NET_NAME" "P3E_CPU0_PE2_SS_TXP<6>"
					( Origin gPackager )
				)
				( attribute "PNN" "P3E_CPU0_PE2_SS_TXP<6>"
					( Origin gPackager )
				)
				( objectStatus "P3E_CPU0_PE2_SS_TXP<6>" )
			)
			( signal "@baseboard_fab2_lib.baseboard_fab2(sch_1):p3e_cpu0_pe2_ss_txp(7)"
				( attribute "CDS_PHYS_NET_NAME" "P3E_CPU0_PE2_SS_TXP<7>"
					( Origin gPackager )
				)
				( attribute "PNN" "P3E_CPU0_PE2_SS_TXP<7>"
					( Origin gPackager )
				)
				( objectStatus "P3E_CPU0_PE2_SS_TXP<7>" )
			)
			( signal "@baseboard_fab2_lib.baseboard_fab2(sch_1):p3e_cpu0_pe2_ss_txp(8)"
				( attribute "CDS_PHYS_NET_NAME" "P3E_CPU0_PE2_SS_TXP<8>"
					( Origin gPackager )
				)
				( attribute "PNN" "P3E_CPU0_PE2_SS_TXP<8>"
					( Origin gPackager )
				)
				( objectStatus "P3E_CPU0_PE2_SS_TXP<8>" )
			)
			( signal "@baseboard_fab2_lib.baseboard_fab2(sch_1):p3e_cpu0_pe2_ss_txp(9)"
				( attribute "CDS_PHYS_NET_NAME" "P3E_CPU0_PE2_SS_TXP<9>"
					( Origin gPackager )
				)
				( attribute "PNN" "P3E_CPU0_PE2_SS_TXP<9>"
					( Origin gPackager )
				)
				( objectStatus "P3E_CPU0_PE2_SS_TXP<9>" )
			)
			( signal "@baseboard_fab2_lib.baseboard_fab2(sch_1):p3e_cpu0_pe2_ss_txp(10)"
				( attribute "CDS_PHYS_NET_NAME" "P3E_CPU0_PE2_SS_TXP<10>"
					( Origin gPackager )
				)
				( attribute "PNN" "P3E_CPU0_PE2_SS_TXP<10>"
					( Origin gPackager )
				)
				( objectStatus "P3E_CPU0_PE2_SS_TXP<10>" )
			)
			( signal "@baseboard_fab2_lib.baseboard_fab2(sch_1):p3e_cpu0_pe2_ss_txp(11)"
				( attribute "CDS_PHYS_NET_NAME" "P3E_CPU0_PE2_SS_TXP<11>"
					( Origin gPackager )
				)
				( attribute "PNN" "P3E_CPU0_PE2_SS_TXP<11>"
					( Origin gPackager )
				)
				( objectStatus "P3E_CPU0_PE2_SS_TXP<11>" )
			)
			( signal "@baseboard_fab2_lib.baseboard_fab2(sch_1):p3e_cpu0_pe2_ss_txp(12)"
				( attribute "CDS_PHYS_NET_NAME" "P3E_CPU0_PE2_SS_TXP<12>"
					( Origin gPackager )
				)
				( attribute "PNN" "P3E_CPU0_PE2_SS_TXP<12>"
					( Origin gPackager )
				)
				( objectStatus "P3E_CPU0_PE2_SS_TXP<12>" )
			)
			( signal "@baseboard_fab2_lib.baseboard_fab2(sch_1):p3e_cpu0_pe2_ss_txp(13)"
				( attribute "CDS_PHYS_NET_NAME" "P3E_CPU0_PE2_SS_TXP<13>"
					( Origin gPackager )
				)
				( attribute "PNN" "P3E_CPU0_PE2_SS_TXP<13>"
					( Origin gPackager )
				)
				( objectStatus "P3E_CPU0_PE2_SS_TXP<13>" )
			)
			( signal "@baseboard_fab2_lib.baseboard_fab2(sch_1):p3e_cpu0_pe2_ss_txp(14)"
				( attribute "CDS_PHYS_NET_NAME" "P3E_CPU0_PE2_SS_TXP<14>"
					( Origin gPackager )
				)
				( attribute "PNN" "P3E_CPU0_PE2_SS_TXP<14>"
					( Origin gPackager )
				)
				( objectStatus "P3E_CPU0_PE2_SS_TXP<14>" )
			)
			( signal "@baseboard_fab2_lib.baseboard_fab2(sch_1):p3e_cpu0_pe2_ss_txp(15)"
				( attribute "CDS_PHYS_NET_NAME" "P3E_CPU0_PE2_SS_TXP<15>"
					( Origin gPackager )
				)
				( attribute "PNN" "P3E_CPU0_PE2_SS_TXP<15>"
					( Origin gPackager )
				)
				( objectStatus "P3E_CPU0_PE2_SS_TXP<15>" )
			)
			( signal "@baseboard_fab2_lib.baseboard_fab2(sch_1):p3e_cpu0_pe3_ocp_rxn(0)"
				( attribute "CDS_PHYS_NET_NAME" "P3E_CPU0_PE3_OCP_RXN<0>"
					( Origin gPackager )
				)
				( attribute "PNN" "P3E_CPU0_PE3_OCP_RXN<0>"
					( Origin gPackager )
				)
				( objectStatus "P3E_CPU0_PE3_OCP_RXN<0>" )
			)
			( signal "@baseboard_fab2_lib.baseboard_fab2(sch_1):p3e_cpu0_pe3_ocp_rxn(1)"
				( attribute "CDS_PHYS_NET_NAME" "P3E_CPU0_PE3_OCP_RXN<1>"
					( Origin gPackager )
				)
				( attribute "PNN" "P3E_CPU0_PE3_OCP_RXN<1>"
					( Origin gPackager )
				)
				( objectStatus "P3E_CPU0_PE3_OCP_RXN<1>" )
			)
			( signal "@baseboard_fab2_lib.baseboard_fab2(sch_1):p3e_cpu0_pe3_ocp_rxn(2)"
				( attribute "CDS_PHYS_NET_NAME" "P3E_CPU0_PE3_OCP_RXN<2>"
					( Origin gPackager )
				)
				( attribute "PNN" "P3E_CPU0_PE3_OCP_RXN<2>"
					( Origin gPackager )
				)
				( objectStatus "P3E_CPU0_PE3_OCP_RXN<2>" )
			)
			( signal "@baseboard_fab2_lib.baseboard_fab2(sch_1):p3e_cpu0_pe3_ocp_rxn(3)"
				( attribute "CDS_PHYS_NET_NAME" "P3E_CPU0_PE3_OCP_RXN<3>"
					( Origin gPackager )
				)
				( attribute "PNN" "P3E_CPU0_PE3_OCP_RXN<3>"
					( Origin gPackager )
				)
				( objectStatus "P3E_CPU0_PE3_OCP_RXN<3>" )
			)
			( signal "@baseboard_fab2_lib.baseboard_fab2(sch_1):p3e_cpu0_pe3_ocp_rxn(4)"
				( attribute "CDS_PHYS_NET_NAME" "P3E_CPU0_PE3_OCP_RXN<4>"
					( Origin gPackager )
				)
				( attribute "PNN" "P3E_CPU0_PE3_OCP_RXN<4>"
					( Origin gPackager )
				)
				( objectStatus "P3E_CPU0_PE3_OCP_RXN<4>" )
			)
			( signal "@baseboard_fab2_lib.baseboard_fab2(sch_1):p3e_cpu0_pe3_ocp_rxn(5)"
				( attribute "CDS_PHYS_NET_NAME" "P3E_CPU0_PE3_OCP_RXN<5>"
					( Origin gPackager )
				)
				( attribute "PNN" "P3E_CPU0_PE3_OCP_RXN<5>"
					( Origin gPackager )
				)
				( objectStatus "P3E_CPU0_PE3_OCP_RXN<5>" )
			)
			( signal "@baseboard_fab2_lib.baseboard_fab2(sch_1):p3e_cpu0_pe3_ocp_rxn(6)"
				( attribute "CDS_PHYS_NET_NAME" "P3E_CPU0_PE3_OCP_RXN<6>"
					( Origin gPackager )
				)
				( attribute "PNN" "P3E_CPU0_PE3_OCP_RXN<6>"
					( Origin gPackager )
				)
				( objectStatus "P3E_CPU0_PE3_OCP_RXN<6>" )
			)
			( signal "@baseboard_fab2_lib.baseboard_fab2(sch_1):p3e_cpu0_pe3_ocp_rxn(7)"
				( attribute "CDS_PHYS_NET_NAME" "P3E_CPU0_PE3_OCP_RXN<7>"
					( Origin gPackager )
				)
				( attribute "PNN" "P3E_CPU0_PE3_OCP_RXN<7>"
					( Origin gPackager )
				)
				( objectStatus "P3E_CPU0_PE3_OCP_RXN<7>" )
			)
			( signal "@baseboard_fab2_lib.baseboard_fab2(sch_1):p3e_cpu0_pe3_ocp_rxn(8)"
				( attribute "CDS_PHYS_NET_NAME" "P3E_CPU0_PE3_OCP_RXN<8>"
					( Origin gPackager )
				)
				( attribute "PNN" "P3E_CPU0_PE3_OCP_RXN<8>"
					( Origin gPackager )
				)
				( objectStatus "P3E_CPU0_PE3_OCP_RXN<8>" )
			)
			( signal "@baseboard_fab2_lib.baseboard_fab2(sch_1):p3e_cpu0_pe3_ocp_rxn(9)"
				( attribute "CDS_PHYS_NET_NAME" "P3E_CPU0_PE3_OCP_RXN<9>"
					( Origin gPackager )
				)
				( attribute "PNN" "P3E_CPU0_PE3_OCP_RXN<9>"
					( Origin gPackager )
				)
				( objectStatus "P3E_CPU0_PE3_OCP_RXN<9>" )
			)
			( signal "@baseboard_fab2_lib.baseboard_fab2(sch_1):p3e_cpu0_pe3_ocp_rxn(10)"
				( attribute "CDS_PHYS_NET_NAME" "P3E_CPU0_PE3_OCP_RXN<10>"
					( Origin gPackager )
				)
				( attribute "PNN" "P3E_CPU0_PE3_OCP_RXN<10>"
					( Origin gPackager )
				)
				( objectStatus "P3E_CPU0_PE3_OCP_RXN<10>" )
			)
			( signal "@baseboard_fab2_lib.baseboard_fab2(sch_1):p3e_cpu0_pe3_ocp_rxn(11)"
				( attribute "CDS_PHYS_NET_NAME" "P3E_CPU0_PE3_OCP_RXN<11>"
					( Origin gPackager )
				)
				( attribute "PNN" "P3E_CPU0_PE3_OCP_RXN<11>"
					( Origin gPackager )
				)
				( objectStatus "P3E_CPU0_PE3_OCP_RXN<11>" )
			)
			( signal "@baseboard_fab2_lib.baseboard_fab2(sch_1):p3e_cpu0_pe3_ocp_rxn(12)"
				( attribute "CDS_PHYS_NET_NAME" "P3E_CPU0_PE3_OCP_RXN<12>"
					( Origin gPackager )
				)
				( attribute "PNN" "P3E_CPU0_PE3_OCP_RXN<12>"
					( Origin gPackager )
				)
				( objectStatus "P3E_CPU0_PE3_OCP_RXN<12>" )
			)
			( signal "@baseboard_fab2_lib.baseboard_fab2(sch_1):p3e_cpu0_pe3_ocp_rxn(13)"
				( attribute "CDS_PHYS_NET_NAME" "P3E_CPU0_PE3_OCP_RXN<13>"
					( Origin gPackager )
				)
				( attribute "PNN" "P3E_CPU0_PE3_OCP_RXN<13>"
					( Origin gPackager )
				)
				( objectStatus "P3E_CPU0_PE3_OCP_RXN<13>" )
			)
			( signal "@baseboard_fab2_lib.baseboard_fab2(sch_1):p3e_cpu0_pe3_ocp_rxn(14)"
				( attribute "CDS_PHYS_NET_NAME" "P3E_CPU0_PE3_OCP_RXN<14>"
					( Origin gPackager )
				)
				( attribute "PNN" "P3E_CPU0_PE3_OCP_RXN<14>"
					( Origin gPackager )
				)
				( objectStatus "P3E_CPU0_PE3_OCP_RXN<14>" )
			)
			( signal "@baseboard_fab2_lib.baseboard_fab2(sch_1):p3e_cpu0_pe3_ocp_rxn(15)"
				( attribute "CDS_PHYS_NET_NAME" "P3E_CPU0_PE3_OCP_RXN<15>"
					( Origin gPackager )
				)
				( attribute "PNN" "P3E_CPU0_PE3_OCP_RXN<15>"
					( Origin gPackager )
				)
				( objectStatus "P3E_CPU0_PE3_OCP_RXN<15>" )
			)
			( signal "@baseboard_fab2_lib.baseboard_fab2(sch_1):p3e_cpu0_pe3_ocp_rxp(0)"
				( attribute "CDS_PHYS_NET_NAME" "P3E_CPU0_PE3_OCP_RXP<0>"
					( Origin gPackager )
				)
				( attribute "PNN" "P3E_CPU0_PE3_OCP_RXP<0>"
					( Origin gPackager )
				)
				( objectStatus "P3E_CPU0_PE3_OCP_RXP<0>" )
			)
			( signal "@baseboard_fab2_lib.baseboard_fab2(sch_1):p3e_cpu0_pe3_ocp_rxp(1)"
				( attribute "CDS_PHYS_NET_NAME" "P3E_CPU0_PE3_OCP_RXP<1>"
					( Origin gPackager )
				)
				( attribute "PNN" "P3E_CPU0_PE3_OCP_RXP<1>"
					( Origin gPackager )
				)
				( objectStatus "P3E_CPU0_PE3_OCP_RXP<1>" )
			)
			( signal "@baseboard_fab2_lib.baseboard_fab2(sch_1):p3e_cpu0_pe3_ocp_rxp(2)"
				( attribute "CDS_PHYS_NET_NAME" "P3E_CPU0_PE3_OCP_RXP<2>"
					( Origin gPackager )
				)
				( attribute "PNN" "P3E_CPU0_PE3_OCP_RXP<2>"
					( Origin gPackager )
				)
				( objectStatus "P3E_CPU0_PE3_OCP_RXP<2>" )
			)
			( signal "@baseboard_fab2_lib.baseboard_fab2(sch_1):p3e_cpu0_pe3_ocp_rxp(3)"
				( attribute "CDS_PHYS_NET_NAME" "P3E_CPU0_PE3_OCP_RXP<3>"
					( Origin gPackager )
				)
				( attribute "PNN" "P3E_CPU0_PE3_OCP_RXP<3>"
					( Origin gPackager )
				)
				( objectStatus "P3E_CPU0_PE3_OCP_RXP<3>" )
			)
			( signal "@baseboard_fab2_lib.baseboard_fab2(sch_1):p3e_cpu0_pe3_ocp_rxp(4)"
				( attribute "CDS_PHYS_NET_NAME" "P3E_CPU0_PE3_OCP_RXP<4>"
					( Origin gPackager )
				)
				( attribute "PNN" "P3E_CPU0_PE3_OCP_RXP<4>"
					( Origin gPackager )
				)
				( objectStatus "P3E_CPU0_PE3_OCP_RXP<4>" )
			)
			( signal "@baseboard_fab2_lib.baseboard_fab2(sch_1):p3e_cpu0_pe3_ocp_rxp(5)"
				( attribute "CDS_PHYS_NET_NAME" "P3E_CPU0_PE3_OCP_RXP<5>"
					( Origin gPackager )
				)
				( attribute "PNN" "P3E_CPU0_PE3_OCP_RXP<5>"
					( Origin gPackager )
				)
				( objectStatus "P3E_CPU0_PE3_OCP_RXP<5>" )
			)
			( signal "@baseboard_fab2_lib.baseboard_fab2(sch_1):p3e_cpu0_pe3_ocp_rxp(6)"
				( attribute "CDS_PHYS_NET_NAME" "P3E_CPU0_PE3_OCP_RXP<6>"
					( Origin gPackager )
				)
				( attribute "PNN" "P3E_CPU0_PE3_OCP_RXP<6>"
					( Origin gPackager )
				)
				( objectStatus "P3E_CPU0_PE3_OCP_RXP<6>" )
			)
			( signal "@baseboard_fab2_lib.baseboard_fab2(sch_1):p3e_cpu0_pe3_ocp_rxp(7)"
				( attribute "CDS_PHYS_NET_NAME" "P3E_CPU0_PE3_OCP_RXP<7>"
					( Origin gPackager )
				)
				( attribute "PNN" "P3E_CPU0_PE3_OCP_RXP<7>"
					( Origin gPackager )
				)
				( objectStatus "P3E_CPU0_PE3_OCP_RXP<7>" )
			)
			( signal "@baseboard_fab2_lib.baseboard_fab2(sch_1):p3e_cpu0_pe3_ocp_rxp(8)"
				( attribute "CDS_PHYS_NET_NAME" "P3E_CPU0_PE3_OCP_RXP<8>"
					( Origin gPackager )
				)
				( attribute "PNN" "P3E_CPU0_PE3_OCP_RXP<8>"
					( Origin gPackager )
				)
				( objectStatus "P3E_CPU0_PE3_OCP_RXP<8>" )
			)
			( signal "@baseboard_fab2_lib.baseboard_fab2(sch_1):p3e_cpu0_pe3_ocp_rxp(9)"
				( attribute "CDS_PHYS_NET_NAME" "P3E_CPU0_PE3_OCP_RXP<9>"
					( Origin gPackager )
				)
				( attribute "PNN" "P3E_CPU0_PE3_OCP_RXP<9>"
					( Origin gPackager )
				)
				( objectStatus "P3E_CPU0_PE3_OCP_RXP<9>" )
			)
			( signal "@baseboard_fab2_lib.baseboard_fab2(sch_1):p3e_cpu0_pe3_ocp_rxp(10)"
				( attribute "CDS_PHYS_NET_NAME" "P3E_CPU0_PE3_OCP_RXP<10>"
					( Origin gPackager )
				)
				( attribute "PNN" "P3E_CPU0_PE3_OCP_RXP<10>"
					( Origin gPackager )
				)
				( objectStatus "P3E_CPU0_PE3_OCP_RXP<10>" )
			)
			( signal "@baseboard_fab2_lib.baseboard_fab2(sch_1):p3e_cpu0_pe3_ocp_rxp(11)"
				( attribute "CDS_PHYS_NET_NAME" "P3E_CPU0_PE3_OCP_RXP<11>"
					( Origin gPackager )
				)
				( attribute "PNN" "P3E_CPU0_PE3_OCP_RXP<11>"
					( Origin gPackager )
				)
				( objectStatus "P3E_CPU0_PE3_OCP_RXP<11>" )
			)
			( signal "@baseboard_fab2_lib.baseboard_fab2(sch_1):p3e_cpu0_pe3_ocp_rxp(12)"
				( attribute "CDS_PHYS_NET_NAME" "P3E_CPU0_PE3_OCP_RXP<12>"
					( Origin gPackager )
				)
				( attribute "PNN" "P3E_CPU0_PE3_OCP_RXP<12>"
					( Origin gPackager )
				)
				( objectStatus "P3E_CPU0_PE3_OCP_RXP<12>" )
			)
			( signal "@baseboard_fab2_lib.baseboard_fab2(sch_1):p3e_cpu0_pe3_ocp_rxp(13)"
				( attribute "CDS_PHYS_NET_NAME" "P3E_CPU0_PE3_OCP_RXP<13>"
					( Origin gPackager )
				)
				( attribute "PNN" "P3E_CPU0_PE3_OCP_RXP<13>"
					( Origin gPackager )
				)
				( objectStatus "P3E_CPU0_PE3_OCP_RXP<13>" )
			)
			( signal "@baseboard_fab2_lib.baseboard_fab2(sch_1):p3e_cpu0_pe3_ocp_rxp(14)"
				( attribute "CDS_PHYS_NET_NAME" "P3E_CPU0_PE3_OCP_RXP<14>"
					( Origin gPackager )
				)
				( attribute "PNN" "P3E_CPU0_PE3_OCP_RXP<14>"
					( Origin gPackager )
				)
				( objectStatus "P3E_CPU0_PE3_OCP_RXP<14>" )
			)
			( signal "@baseboard_fab2_lib.baseboard_fab2(sch_1):p3e_cpu0_pe3_ocp_rxp(15)"
				( attribute "CDS_PHYS_NET_NAME" "P3E_CPU0_PE3_OCP_RXP<15>"
					( Origin gPackager )
				)
				( attribute "PNN" "P3E_CPU0_PE3_OCP_RXP<15>"
					( Origin gPackager )
				)
				( objectStatus "P3E_CPU0_PE3_OCP_RXP<15>" )
			)
			( signal "@baseboard_fab2_lib.baseboard_fab2(sch_1):p3e_cpu0_pe3_ocp_txn(0)"
				( attribute "CDS_PHYS_NET_NAME" "P3E_CPU0_PE3_OCP_TXN<0>"
					( Origin gPackager )
				)
				( attribute "PNN" "P3E_CPU0_PE3_OCP_TXN<0>"
					( Origin gPackager )
				)
				( objectStatus "P3E_CPU0_PE3_OCP_TXN<0>" )
			)
			( signal "@baseboard_fab2_lib.baseboard_fab2(sch_1):p3e_cpu0_pe3_ocp_txn(1)"
				( attribute "CDS_PHYS_NET_NAME" "P3E_CPU0_PE3_OCP_TXN<1>"
					( Origin gPackager )
				)
				( attribute "PNN" "P3E_CPU0_PE3_OCP_TXN<1>"
					( Origin gPackager )
				)
				( objectStatus "P3E_CPU0_PE3_OCP_TXN<1>" )
			)
			( signal "@baseboard_fab2_lib.baseboard_fab2(sch_1):p3e_cpu0_pe3_ocp_txn(2)"
				( attribute "CDS_PHYS_NET_NAME" "P3E_CPU0_PE3_OCP_TXN<2>"
					( Origin gPackager )
				)
				( attribute "PNN" "P3E_CPU0_PE3_OCP_TXN<2>"
					( Origin gPackager )
				)
				( objectStatus "P3E_CPU0_PE3_OCP_TXN<2>" )
			)
			( signal "@baseboard_fab2_lib.baseboard_fab2(sch_1):p3e_cpu0_pe3_ocp_txn(3)"
				( attribute "CDS_PHYS_NET_NAME" "P3E_CPU0_PE3_OCP_TXN<3>"
					( Origin gPackager )
				)
				( attribute "PNN" "P3E_CPU0_PE3_OCP_TXN<3>"
					( Origin gPackager )
				)
				( objectStatus "P3E_CPU0_PE3_OCP_TXN<3>" )
			)
			( signal "@baseboard_fab2_lib.baseboard_fab2(sch_1):p3e_cpu0_pe3_ocp_txn(4)"
				( attribute "CDS_PHYS_NET_NAME" "P3E_CPU0_PE3_OCP_TXN<4>"
					( Origin gPackager )
				)
				( attribute "PNN" "P3E_CPU0_PE3_OCP_TXN<4>"
					( Origin gPackager )
				)
				( objectStatus "P3E_CPU0_PE3_OCP_TXN<4>" )
			)
			( signal "@baseboard_fab2_lib.baseboard_fab2(sch_1):p3e_cpu0_pe3_ocp_txn(5)"
				( attribute "CDS_PHYS_NET_NAME" "P3E_CPU0_PE3_OCP_TXN<5>"
					( Origin gPackager )
				)
				( attribute "PNN" "P3E_CPU0_PE3_OCP_TXN<5>"
					( Origin gPackager )
				)
				( objectStatus "P3E_CPU0_PE3_OCP_TXN<5>" )
			)
			( signal "@baseboard_fab2_lib.baseboard_fab2(sch_1):p3e_cpu0_pe3_ocp_txn(6)"
				( attribute "CDS_PHYS_NET_NAME" "P3E_CPU0_PE3_OCP_TXN<6>"
					( Origin gPackager )
				)
				( attribute "PNN" "P3E_CPU0_PE3_OCP_TXN<6>"
					( Origin gPackager )
				)
				( objectStatus "P3E_CPU0_PE3_OCP_TXN<6>" )
			)
			( signal "@baseboard_fab2_lib.baseboard_fab2(sch_1):p3e_cpu0_pe3_ocp_txn(7)"
				( attribute "CDS_PHYS_NET_NAME" "P3E_CPU0_PE3_OCP_TXN<7>"
					( Origin gPackager )
				)
				( attribute "PNN" "P3E_CPU0_PE3_OCP_TXN<7>"
					( Origin gPackager )
				)
				( objectStatus "P3E_CPU0_PE3_OCP_TXN<7>" )
			)
			( signal "@baseboard_fab2_lib.baseboard_fab2(sch_1):p3e_cpu0_pe3_ocp_txn(8)"
				( attribute "CDS_PHYS_NET_NAME" "P3E_CPU0_PE3_OCP_TXN<8>"
					( Origin gPackager )
				)
				( attribute "PNN" "P3E_CPU0_PE3_OCP_TXN<8>"
					( Origin gPackager )
				)
				( objectStatus "P3E_CPU0_PE3_OCP_TXN<8>" )
			)
			( signal "@baseboard_fab2_lib.baseboard_fab2(sch_1):p3e_cpu0_pe3_ocp_txn(9)"
				( attribute "CDS_PHYS_NET_NAME" "P3E_CPU0_PE3_OCP_TXN<9>"
					( Origin gPackager )
				)
				( attribute "PNN" "P3E_CPU0_PE3_OCP_TXN<9>"
					( Origin gPackager )
				)
				( objectStatus "P3E_CPU0_PE3_OCP_TXN<9>" )
			)
			( signal "@baseboard_fab2_lib.baseboard_fab2(sch_1):p3e_cpu0_pe3_ocp_txn(10)"
				( attribute "CDS_PHYS_NET_NAME" "P3E_CPU0_PE3_OCP_TXN<10>"
					( Origin gPackager )
				)
				( attribute "PNN" "P3E_CPU0_PE3_OCP_TXN<10>"
					( Origin gPackager )
				)
				( objectStatus "P3E_CPU0_PE3_OCP_TXN<10>" )
			)
			( signal "@baseboard_fab2_lib.baseboard_fab2(sch_1):p3e_cpu0_pe3_ocp_txn(11)"
				( attribute "CDS_PHYS_NET_NAME" "P3E_CPU0_PE3_OCP_TXN<11>"
					( Origin gPackager )
				)
				( attribute "PNN" "P3E_CPU0_PE3_OCP_TXN<11>"
					( Origin gPackager )
				)
				( objectStatus "P3E_CPU0_PE3_OCP_TXN<11>" )
			)
			( signal "@baseboard_fab2_lib.baseboard_fab2(sch_1):p3e_cpu0_pe3_ocp_txn(12)"
				( attribute "CDS_PHYS_NET_NAME" "P3E_CPU0_PE3_OCP_TXN<12>"
					( Origin gPackager )
				)
				( attribute "PNN" "P3E_CPU0_PE3_OCP_TXN<12>"
					( Origin gPackager )
				)
				( objectStatus "P3E_CPU0_PE3_OCP_TXN<12>" )
			)
			( signal "@baseboard_fab2_lib.baseboard_fab2(sch_1):p3e_cpu0_pe3_ocp_txn(13)"
				( attribute "CDS_PHYS_NET_NAME" "P3E_CPU0_PE3_OCP_TXN<13>"
					( Origin gPackager )
				)
				( attribute "PNN" "P3E_CPU0_PE3_OCP_TXN<13>"
					( Origin gPackager )
				)
				( objectStatus "P3E_CPU0_PE3_OCP_TXN<13>" )
			)
			( signal "@baseboard_fab2_lib.baseboard_fab2(sch_1):p3e_cpu0_pe3_ocp_txn(14)"
				( attribute "CDS_PHYS_NET_NAME" "P3E_CPU0_PE3_OCP_TXN<14>"
					( Origin gPackager )
				)
				( attribute "PNN" "P3E_CPU0_PE3_OCP_TXN<14>"
					( Origin gPackager )
				)
				( objectStatus "P3E_CPU0_PE3_OCP_TXN<14>" )
			)
			( signal "@baseboard_fab2_lib.baseboard_fab2(sch_1):p3e_cpu0_pe3_ocp_txn(15)"
				( attribute "CDS_PHYS_NET_NAME" "P3E_CPU0_PE3_OCP_TXN<15>"
					( Origin gPackager )
				)
				( attribute "PNN" "P3E_CPU0_PE3_OCP_TXN<15>"
					( Origin gPackager )
				)
				( objectStatus "P3E_CPU0_PE3_OCP_TXN<15>" )
			)
			( signal "@baseboard_fab2_lib.baseboard_fab2(sch_1):p3e_cpu0_pe3_ocp_txp(0)"
				( attribute "CDS_PHYS_NET_NAME" "P3E_CPU0_PE3_OCP_TXP<0>"
					( Origin gPackager )
				)
				( attribute "PNN" "P3E_CPU0_PE3_OCP_TXP<0>"
					( Origin gPackager )
				)
				( objectStatus "P3E_CPU0_PE3_OCP_TXP<0>" )
			)
			( signal "@baseboard_fab2_lib.baseboard_fab2(sch_1):p3e_cpu0_pe3_ocp_txp(1)"
				( attribute "CDS_PHYS_NET_NAME" "P3E_CPU0_PE3_OCP_TXP<1>"
					( Origin gPackager )
				)
				( attribute "PNN" "P3E_CPU0_PE3_OCP_TXP<1>"
					( Origin gPackager )
				)
				( objectStatus "P3E_CPU0_PE3_OCP_TXP<1>" )
			)
			( signal "@baseboard_fab2_lib.baseboard_fab2(sch_1):p3e_cpu0_pe3_ocp_txp(2)"
				( attribute "CDS_PHYS_NET_NAME" "P3E_CPU0_PE3_OCP_TXP<2>"
					( Origin gPackager )
				)
				( attribute "PNN" "P3E_CPU0_PE3_OCP_TXP<2>"
					( Origin gPackager )
				)
				( objectStatus "P3E_CPU0_PE3_OCP_TXP<2>" )
			)
			( signal "@baseboard_fab2_lib.baseboard_fab2(sch_1):p3e_cpu0_pe3_ocp_txp(3)"
				( attribute "CDS_PHYS_NET_NAME" "P3E_CPU0_PE3_OCP_TXP<3>"
					( Origin gPackager )
				)
				( attribute "PNN" "P3E_CPU0_PE3_OCP_TXP<3>"
					( Origin gPackager )
				)
				( objectStatus "P3E_CPU0_PE3_OCP_TXP<3>" )
			)
			( signal "@baseboard_fab2_lib.baseboard_fab2(sch_1):p3e_cpu0_pe3_ocp_txp(4)"
				( attribute "CDS_PHYS_NET_NAME" "P3E_CPU0_PE3_OCP_TXP<4>"
					( Origin gPackager )
				)
				( attribute "PNN" "P3E_CPU0_PE3_OCP_TXP<4>"
					( Origin gPackager )
				)
				( objectStatus "P3E_CPU0_PE3_OCP_TXP<4>" )
			)
			( signal "@baseboard_fab2_lib.baseboard_fab2(sch_1):p3e_cpu0_pe3_ocp_txp(5)"
				( attribute "CDS_PHYS_NET_NAME" "P3E_CPU0_PE3_OCP_TXP<5>"
					( Origin gPackager )
				)
				( attribute "PNN" "P3E_CPU0_PE3_OCP_TXP<5>"
					( Origin gPackager )
				)
				( objectStatus "P3E_CPU0_PE3_OCP_TXP<5>" )
			)
			( signal "@baseboard_fab2_lib.baseboard_fab2(sch_1):p3e_cpu0_pe3_ocp_txp(6)"
				( attribute "CDS_PHYS_NET_NAME" "P3E_CPU0_PE3_OCP_TXP<6>"
					( Origin gPackager )
				)
				( attribute "PNN" "P3E_CPU0_PE3_OCP_TXP<6>"
					( Origin gPackager )
				)
				( objectStatus "P3E_CPU0_PE3_OCP_TXP<6>" )
			)
			( signal "@baseboard_fab2_lib.baseboard_fab2(sch_1):p3e_cpu0_pe3_ocp_txp(7)"
				( attribute "CDS_PHYS_NET_NAME" "P3E_CPU0_PE3_OCP_TXP<7>"
					( Origin gPackager )
				)
				( attribute "PNN" "P3E_CPU0_PE3_OCP_TXP<7>"
					( Origin gPackager )
				)
				( objectStatus "P3E_CPU0_PE3_OCP_TXP<7>" )
			)
			( signal "@baseboard_fab2_lib.baseboard_fab2(sch_1):p3e_cpu0_pe3_ocp_txp(8)"
				( attribute "CDS_PHYS_NET_NAME" "P3E_CPU0_PE3_OCP_TXP<8>"
					( Origin gPackager )
				)
				( attribute "PNN" "P3E_CPU0_PE3_OCP_TXP<8>"
					( Origin gPackager )
				)
				( objectStatus "P3E_CPU0_PE3_OCP_TXP<8>" )
			)
			( signal "@baseboard_fab2_lib.baseboard_fab2(sch_1):p3e_cpu0_pe3_ocp_txp(9)"
				( attribute "CDS_PHYS_NET_NAME" "P3E_CPU0_PE3_OCP_TXP<9>"
					( Origin gPackager )
				)
				( attribute "PNN" "P3E_CPU0_PE3_OCP_TXP<9>"
					( Origin gPackager )
				)
				( objectStatus "P3E_CPU0_PE3_OCP_TXP<9>" )
			)
			( signal "@baseboard_fab2_lib.baseboard_fab2(sch_1):p3e_cpu0_pe3_ocp_txp(10)"
				( attribute "CDS_PHYS_NET_NAME" "P3E_CPU0_PE3_OCP_TXP<10>"
					( Origin gPackager )
				)
				( attribute "PNN" "P3E_CPU0_PE3_OCP_TXP<10>"
					( Origin gPackager )
				)
				( objectStatus "P3E_CPU0_PE3_OCP_TXP<10>" )
			)
			( signal "@baseboard_fab2_lib.baseboard_fab2(sch_1):p3e_cpu0_pe3_ocp_txp(11)"
				( attribute "CDS_PHYS_NET_NAME" "P3E_CPU0_PE3_OCP_TXP<11>"
					( Origin gPackager )
				)
				( attribute "PNN" "P3E_CPU0_PE3_OCP_TXP<11>"
					( Origin gPackager )
				)
				( objectStatus "P3E_CPU0_PE3_OCP_TXP<11>" )
			)
			( signal "@baseboard_fab2_lib.baseboard_fab2(sch_1):p3e_cpu0_pe3_ocp_txp(12)"
				( attribute "CDS_PHYS_NET_NAME" "P3E_CPU0_PE3_OCP_TXP<12>"
					( Origin gPackager )
				)
				( attribute "PNN" "P3E_CPU0_PE3_OCP_TXP<12>"
					( Origin gPackager )
				)
				( objectStatus "P3E_CPU0_PE3_OCP_TXP<12>" )
			)
			( signal "@baseboard_fab2_lib.baseboard_fab2(sch_1):p3e_cpu0_pe3_ocp_txp(13)"
				( attribute "CDS_PHYS_NET_NAME" "P3E_CPU0_PE3_OCP_TXP<13>"
					( Origin gPackager )
				)
				( attribute "PNN" "P3E_CPU0_PE3_OCP_TXP<13>"
					( Origin gPackager )
				)
				( objectStatus "P3E_CPU0_PE3_OCP_TXP<13>" )
			)
			( signal "@baseboard_fab2_lib.baseboard_fab2(sch_1):p3e_cpu0_pe3_ocp_txp(14)"
				( attribute "CDS_PHYS_NET_NAME" "P3E_CPU0_PE3_OCP_TXP<14>"
					( Origin gPackager )
				)
				( attribute "PNN" "P3E_CPU0_PE3_OCP_TXP<14>"
					( Origin gPackager )
				)
				( objectStatus "P3E_CPU0_PE3_OCP_TXP<14>" )
			)
			( signal "@baseboard_fab2_lib.baseboard_fab2(sch_1):p3e_cpu0_pe3_ocp_txp(15)"
				( attribute "CDS_PHYS_NET_NAME" "P3E_CPU0_PE3_OCP_TXP<15>"
					( Origin gPackager )
				)
				( attribute "PNN" "P3E_CPU0_PE3_OCP_TXP<15>"
					( Origin gPackager )
				)
				( objectStatus "P3E_CPU0_PE3_OCP_TXP<15>" )
			)
			( signal "@baseboard_fab2_lib.baseboard_fab2(sch_1):upi_cpu0_cpu1_p0p0_dn(0)"
				( attribute "CDS_PHYS_NET_NAME" "UPI_CPU0_CPU1_P0P0_DN<0>"
					( Origin gPackager )
				)
				( attribute "PNN" "UPI_CPU0_CPU1_P0P0_DN<0>"
					( Origin gPackager )
				)
				( objectStatus "UPI_CPU0_CPU1_P0P0_DN<0>" )
			)
			( signal "@baseboard_fab2_lib.baseboard_fab2(sch_1):upi_cpu0_cpu1_p0p0_dn(1)"
				( attribute "CDS_PHYS_NET_NAME" "UPI_CPU0_CPU1_P0P0_DN<1>"
					( Origin gPackager )
				)
				( attribute "PNN" "UPI_CPU0_CPU1_P0P0_DN<1>"
					( Origin gPackager )
				)
				( objectStatus "UPI_CPU0_CPU1_P0P0_DN<1>" )
			)
			( signal "@baseboard_fab2_lib.baseboard_fab2(sch_1):upi_cpu0_cpu1_p0p0_dn(2)"
				( attribute "CDS_PHYS_NET_NAME" "UPI_CPU0_CPU1_P0P0_DN<2>"
					( Origin gPackager )
				)
				( attribute "PNN" "UPI_CPU0_CPU1_P0P0_DN<2>"
					( Origin gPackager )
				)
				( objectStatus "UPI_CPU0_CPU1_P0P0_DN<2>" )
			)
			( signal "@baseboard_fab2_lib.baseboard_fab2(sch_1):upi_cpu0_cpu1_p0p0_dn(3)"
				( attribute "CDS_PHYS_NET_NAME" "UPI_CPU0_CPU1_P0P0_DN<3>"
					( Origin gPackager )
				)
				( attribute "PNN" "UPI_CPU0_CPU1_P0P0_DN<3>"
					( Origin gPackager )
				)
				( objectStatus "UPI_CPU0_CPU1_P0P0_DN<3>" )
			)
			( signal "@baseboard_fab2_lib.baseboard_fab2(sch_1):upi_cpu0_cpu1_p0p0_dn(4)"
				( attribute "CDS_PHYS_NET_NAME" "UPI_CPU0_CPU1_P0P0_DN<4>"
					( Origin gPackager )
				)
				( attribute "PNN" "UPI_CPU0_CPU1_P0P0_DN<4>"
					( Origin gPackager )
				)
				( objectStatus "UPI_CPU0_CPU1_P0P0_DN<4>" )
			)
			( signal "@baseboard_fab2_lib.baseboard_fab2(sch_1):upi_cpu0_cpu1_p0p0_dn(5)"
				( attribute "CDS_PHYS_NET_NAME" "UPI_CPU0_CPU1_P0P0_DN<5>"
					( Origin gPackager )
				)
				( attribute "PNN" "UPI_CPU0_CPU1_P0P0_DN<5>"
					( Origin gPackager )
				)
				( objectStatus "UPI_CPU0_CPU1_P0P0_DN<5>" )
			)
			( signal "@baseboard_fab2_lib.baseboard_fab2(sch_1):upi_cpu0_cpu1_p0p0_dn(6)"
				( attribute "CDS_PHYS_NET_NAME" "UPI_CPU0_CPU1_P0P0_DN<6>"
					( Origin gPackager )
				)
				( attribute "PNN" "UPI_CPU0_CPU1_P0P0_DN<6>"
					( Origin gPackager )
				)
				( objectStatus "UPI_CPU0_CPU1_P0P0_DN<6>" )
			)
			( signal "@baseboard_fab2_lib.baseboard_fab2(sch_1):upi_cpu0_cpu1_p0p0_dn(7)"
				( attribute "CDS_PHYS_NET_NAME" "UPI_CPU0_CPU1_P0P0_DN<7>"
					( Origin gPackager )
				)
				( attribute "PNN" "UPI_CPU0_CPU1_P0P0_DN<7>"
					( Origin gPackager )
				)
				( objectStatus "UPI_CPU0_CPU1_P0P0_DN<7>" )
			)
			( signal "@baseboard_fab2_lib.baseboard_fab2(sch_1):upi_cpu0_cpu1_p0p0_dn(8)"
				( attribute "CDS_PHYS_NET_NAME" "UPI_CPU0_CPU1_P0P0_DN<8>"
					( Origin gPackager )
				)
				( attribute "PNN" "UPI_CPU0_CPU1_P0P0_DN<8>"
					( Origin gPackager )
				)
				( objectStatus "UPI_CPU0_CPU1_P0P0_DN<8>" )
			)
			( signal "@baseboard_fab2_lib.baseboard_fab2(sch_1):upi_cpu0_cpu1_p0p0_dn(9)"
				( attribute "CDS_PHYS_NET_NAME" "UPI_CPU0_CPU1_P0P0_DN<9>"
					( Origin gPackager )
				)
				( attribute "PNN" "UPI_CPU0_CPU1_P0P0_DN<9>"
					( Origin gPackager )
				)
				( objectStatus "UPI_CPU0_CPU1_P0P0_DN<9>" )
			)
			( signal "@baseboard_fab2_lib.baseboard_fab2(sch_1):upi_cpu0_cpu1_p0p0_dn(10)"
				( attribute "CDS_PHYS_NET_NAME" "UPI_CPU0_CPU1_P0P0_DN<10>"
					( Origin gPackager )
				)
				( attribute "PNN" "UPI_CPU0_CPU1_P0P0_DN<10>"
					( Origin gPackager )
				)
				( objectStatus "UPI_CPU0_CPU1_P0P0_DN<10>" )
			)
			( signal "@baseboard_fab2_lib.baseboard_fab2(sch_1):upi_cpu0_cpu1_p0p0_dn(11)"
				( attribute "CDS_PHYS_NET_NAME" "UPI_CPU0_CPU1_P0P0_DN<11>"
					( Origin gPackager )
				)
				( attribute "PNN" "UPI_CPU0_CPU1_P0P0_DN<11>"
					( Origin gPackager )
				)
				( objectStatus "UPI_CPU0_CPU1_P0P0_DN<11>" )
			)
			( signal "@baseboard_fab2_lib.baseboard_fab2(sch_1):upi_cpu0_cpu1_p0p0_dn(12)"
				( attribute "CDS_PHYS_NET_NAME" "UPI_CPU0_CPU1_P0P0_DN<12>"
					( Origin gPackager )
				)
				( attribute "PNN" "UPI_CPU0_CPU1_P0P0_DN<12>"
					( Origin gPackager )
				)
				( objectStatus "UPI_CPU0_CPU1_P0P0_DN<12>" )
			)
			( signal "@baseboard_fab2_lib.baseboard_fab2(sch_1):upi_cpu0_cpu1_p0p0_dn(13)"
				( attribute "CDS_PHYS_NET_NAME" "UPI_CPU0_CPU1_P0P0_DN<13>"
					( Origin gPackager )
				)
				( attribute "PNN" "UPI_CPU0_CPU1_P0P0_DN<13>"
					( Origin gPackager )
				)
				( objectStatus "UPI_CPU0_CPU1_P0P0_DN<13>" )
			)
			( signal "@baseboard_fab2_lib.baseboard_fab2(sch_1):upi_cpu0_cpu1_p0p0_dn(14)"
				( attribute "CDS_PHYS_NET_NAME" "UPI_CPU0_CPU1_P0P0_DN<14>"
					( Origin gPackager )
				)
				( attribute "PNN" "UPI_CPU0_CPU1_P0P0_DN<14>"
					( Origin gPackager )
				)
				( objectStatus "UPI_CPU0_CPU1_P0P0_DN<14>" )
			)
			( signal "@baseboard_fab2_lib.baseboard_fab2(sch_1):upi_cpu0_cpu1_p0p0_dn(15)"
				( attribute "CDS_PHYS_NET_NAME" "UPI_CPU0_CPU1_P0P0_DN<15>"
					( Origin gPackager )
				)
				( attribute "PNN" "UPI_CPU0_CPU1_P0P0_DN<15>"
					( Origin gPackager )
				)
				( objectStatus "UPI_CPU0_CPU1_P0P0_DN<15>" )
			)
			( signal "@baseboard_fab2_lib.baseboard_fab2(sch_1):upi_cpu0_cpu1_p0p0_dn(16)"
				( attribute "CDS_PHYS_NET_NAME" "UPI_CPU0_CPU1_P0P0_DN<16>"
					( Origin gPackager )
				)
				( attribute "PNN" "UPI_CPU0_CPU1_P0P0_DN<16>"
					( Origin gPackager )
				)
				( objectStatus "UPI_CPU0_CPU1_P0P0_DN<16>" )
			)
			( signal "@baseboard_fab2_lib.baseboard_fab2(sch_1):upi_cpu0_cpu1_p0p0_dn(17)"
				( attribute "CDS_PHYS_NET_NAME" "UPI_CPU0_CPU1_P0P0_DN<17>"
					( Origin gPackager )
				)
				( attribute "PNN" "UPI_CPU0_CPU1_P0P0_DN<17>"
					( Origin gPackager )
				)
				( objectStatus "UPI_CPU0_CPU1_P0P0_DN<17>" )
			)
			( signal "@baseboard_fab2_lib.baseboard_fab2(sch_1):upi_cpu0_cpu1_p0p0_dn(18)"
				( attribute "CDS_PHYS_NET_NAME" "UPI_CPU0_CPU1_P0P0_DN<18>"
					( Origin gPackager )
				)
				( attribute "PNN" "UPI_CPU0_CPU1_P0P0_DN<18>"
					( Origin gPackager )
				)
				( objectStatus "UPI_CPU0_CPU1_P0P0_DN<18>" )
			)
			( signal "@baseboard_fab2_lib.baseboard_fab2(sch_1):upi_cpu0_cpu1_p0p0_dn(19)"
				( attribute "CDS_PHYS_NET_NAME" "UPI_CPU0_CPU1_P0P0_DN<19>"
					( Origin gPackager )
				)
				( attribute "PNN" "UPI_CPU0_CPU1_P0P0_DN<19>"
					( Origin gPackager )
				)
				( objectStatus "UPI_CPU0_CPU1_P0P0_DN<19>" )
			)
			( signal "@baseboard_fab2_lib.baseboard_fab2(sch_1):upi_cpu0_cpu1_p0p0_dp(0)"
				( attribute "CDS_PHYS_NET_NAME" "UPI_CPU0_CPU1_P0P0_DP<0>"
					( Origin gPackager )
				)
				( attribute "PNN" "UPI_CPU0_CPU1_P0P0_DP<0>"
					( Origin gPackager )
				)
				( objectStatus "UPI_CPU0_CPU1_P0P0_DP<0>" )
			)
			( signal "@baseboard_fab2_lib.baseboard_fab2(sch_1):upi_cpu0_cpu1_p0p0_dp(1)"
				( attribute "CDS_PHYS_NET_NAME" "UPI_CPU0_CPU1_P0P0_DP<1>"
					( Origin gPackager )
				)
				( attribute "PNN" "UPI_CPU0_CPU1_P0P0_DP<1>"
					( Origin gPackager )
				)
				( objectStatus "UPI_CPU0_CPU1_P0P0_DP<1>" )
			)
			( signal "@baseboard_fab2_lib.baseboard_fab2(sch_1):upi_cpu0_cpu1_p0p0_dp(2)"
				( attribute "CDS_PHYS_NET_NAME" "UPI_CPU0_CPU1_P0P0_DP<2>"
					( Origin gPackager )
				)
				( attribute "PNN" "UPI_CPU0_CPU1_P0P0_DP<2>"
					( Origin gPackager )
				)
				( objectStatus "UPI_CPU0_CPU1_P0P0_DP<2>" )
			)
			( signal "@baseboard_fab2_lib.baseboard_fab2(sch_1):upi_cpu0_cpu1_p0p0_dp(3)"
				( attribute "CDS_PHYS_NET_NAME" "UPI_CPU0_CPU1_P0P0_DP<3>"
					( Origin gPackager )
				)
				( attribute "PNN" "UPI_CPU0_CPU1_P0P0_DP<3>"
					( Origin gPackager )
				)
				( objectStatus "UPI_CPU0_CPU1_P0P0_DP<3>" )
			)
			( signal "@baseboard_fab2_lib.baseboard_fab2(sch_1):upi_cpu0_cpu1_p0p0_dp(4)"
				( attribute "CDS_PHYS_NET_NAME" "UPI_CPU0_CPU1_P0P0_DP<4>"
					( Origin gPackager )
				)
				( attribute "PNN" "UPI_CPU0_CPU1_P0P0_DP<4>"
					( Origin gPackager )
				)
				( objectStatus "UPI_CPU0_CPU1_P0P0_DP<4>" )
			)
			( signal "@baseboard_fab2_lib.baseboard_fab2(sch_1):upi_cpu0_cpu1_p0p0_dp(5)"
				( attribute "CDS_PHYS_NET_NAME" "UPI_CPU0_CPU1_P0P0_DP<5>"
					( Origin gPackager )
				)
				( attribute "PNN" "UPI_CPU0_CPU1_P0P0_DP<5>"
					( Origin gPackager )
				)
				( objectStatus "UPI_CPU0_CPU1_P0P0_DP<5>" )
			)
			( signal "@baseboard_fab2_lib.baseboard_fab2(sch_1):upi_cpu0_cpu1_p0p0_dp(6)"
				( attribute "CDS_PHYS_NET_NAME" "UPI_CPU0_CPU1_P0P0_DP<6>"
					( Origin gPackager )
				)
				( attribute "PNN" "UPI_CPU0_CPU1_P0P0_DP<6>"
					( Origin gPackager )
				)
				( objectStatus "UPI_CPU0_CPU1_P0P0_DP<6>" )
			)
			( signal "@baseboard_fab2_lib.baseboard_fab2(sch_1):upi_cpu0_cpu1_p0p0_dp(7)"
				( attribute "CDS_PHYS_NET_NAME" "UPI_CPU0_CPU1_P0P0_DP<7>"
					( Origin gPackager )
				)
				( attribute "PNN" "UPI_CPU0_CPU1_P0P0_DP<7>"
					( Origin gPackager )
				)
				( objectStatus "UPI_CPU0_CPU1_P0P0_DP<7>" )
			)
			( signal "@baseboard_fab2_lib.baseboard_fab2(sch_1):upi_cpu0_cpu1_p0p0_dp(8)"
				( attribute "CDS_PHYS_NET_NAME" "UPI_CPU0_CPU1_P0P0_DP<8>"
					( Origin gPackager )
				)
				( attribute "PNN" "UPI_CPU0_CPU1_P0P0_DP<8>"
					( Origin gPackager )
				)
				( objectStatus "UPI_CPU0_CPU1_P0P0_DP<8>" )
			)
			( signal "@baseboard_fab2_lib.baseboard_fab2(sch_1):upi_cpu0_cpu1_p0p0_dp(9)"
				( attribute "CDS_PHYS_NET_NAME" "UPI_CPU0_CPU1_P0P0_DP<9>"
					( Origin gPackager )
				)
				( attribute "PNN" "UPI_CPU0_CPU1_P0P0_DP<9>"
					( Origin gPackager )
				)
				( objectStatus "UPI_CPU0_CPU1_P0P0_DP<9>" )
			)
			( signal "@baseboard_fab2_lib.baseboard_fab2(sch_1):upi_cpu0_cpu1_p0p0_dp(10)"
				( attribute "CDS_PHYS_NET_NAME" "UPI_CPU0_CPU1_P0P0_DP<10>"
					( Origin gPackager )
				)
				( attribute "PNN" "UPI_CPU0_CPU1_P0P0_DP<10>"
					( Origin gPackager )
				)
				( objectStatus "UPI_CPU0_CPU1_P0P0_DP<10>" )
			)
			( signal "@baseboard_fab2_lib.baseboard_fab2(sch_1):upi_cpu0_cpu1_p0p0_dp(11)"
				( attribute "CDS_PHYS_NET_NAME" "UPI_CPU0_CPU1_P0P0_DP<11>"
					( Origin gPackager )
				)
				( attribute "PNN" "UPI_CPU0_CPU1_P0P0_DP<11>"
					( Origin gPackager )
				)
				( objectStatus "UPI_CPU0_CPU1_P0P0_DP<11>" )
			)
			( signal "@baseboard_fab2_lib.baseboard_fab2(sch_1):upi_cpu0_cpu1_p0p0_dp(12)"
				( attribute "CDS_PHYS_NET_NAME" "UPI_CPU0_CPU1_P0P0_DP<12>"
					( Origin gPackager )
				)
				( attribute "PNN" "UPI_CPU0_CPU1_P0P0_DP<12>"
					( Origin gPackager )
				)
				( objectStatus "UPI_CPU0_CPU1_P0P0_DP<12>" )
			)
			( signal "@baseboard_fab2_lib.baseboard_fab2(sch_1):upi_cpu0_cpu1_p0p0_dp(13)"
				( attribute "CDS_PHYS_NET_NAME" "UPI_CPU0_CPU1_P0P0_DP<13>"
					( Origin gPackager )
				)
				( attribute "PNN" "UPI_CPU0_CPU1_P0P0_DP<13>"
					( Origin gPackager )
				)
				( objectStatus "UPI_CPU0_CPU1_P0P0_DP<13>" )
			)
			( signal "@baseboard_fab2_lib.baseboard_fab2(sch_1):upi_cpu0_cpu1_p0p0_dp(14)"
				( attribute "CDS_PHYS_NET_NAME" "UPI_CPU0_CPU1_P0P0_DP<14>"
					( Origin gPackager )
				)
				( attribute "PNN" "UPI_CPU0_CPU1_P0P0_DP<14>"
					( Origin gPackager )
				)
				( objectStatus "UPI_CPU0_CPU1_P0P0_DP<14>" )
			)
			( signal "@baseboard_fab2_lib.baseboard_fab2(sch_1):upi_cpu0_cpu1_p0p0_dp(15)"
				( attribute "CDS_PHYS_NET_NAME" "UPI_CPU0_CPU1_P0P0_DP<15>"
					( Origin gPackager )
				)
				( attribute "PNN" "UPI_CPU0_CPU1_P0P0_DP<15>"
					( Origin gPackager )
				)
				( objectStatus "UPI_CPU0_CPU1_P0P0_DP<15>" )
			)
			( signal "@baseboard_fab2_lib.baseboard_fab2(sch_1):upi_cpu0_cpu1_p0p0_dp(16)"
				( attribute "CDS_PHYS_NET_NAME" "UPI_CPU0_CPU1_P0P0_DP<16>"
					( Origin gPackager )
				)
				( attribute "PNN" "UPI_CPU0_CPU1_P0P0_DP<16>"
					( Origin gPackager )
				)
				( objectStatus "UPI_CPU0_CPU1_P0P0_DP<16>" )
			)
			( signal "@baseboard_fab2_lib.baseboard_fab2(sch_1):upi_cpu0_cpu1_p0p0_dp(17)"
				( attribute "CDS_PHYS_NET_NAME" "UPI_CPU0_CPU1_P0P0_DP<17>"
					( Origin gPackager )
				)
				( attribute "PNN" "UPI_CPU0_CPU1_P0P0_DP<17>"
					( Origin gPackager )
				)
				( objectStatus "UPI_CPU0_CPU1_P0P0_DP<17>" )
			)
			( signal "@baseboard_fab2_lib.baseboard_fab2(sch_1):upi_cpu0_cpu1_p0p0_dp(18)"
				( attribute "CDS_PHYS_NET_NAME" "UPI_CPU0_CPU1_P0P0_DP<18>"
					( Origin gPackager )
				)
				( attribute "PNN" "UPI_CPU0_CPU1_P0P0_DP<18>"
					( Origin gPackager )
				)
				( objectStatus "UPI_CPU0_CPU1_P0P0_DP<18>" )
			)
			( signal "@baseboard_fab2_lib.baseboard_fab2(sch_1):upi_cpu0_cpu1_p0p0_dp(19)"
				( attribute "CDS_PHYS_NET_NAME" "UPI_CPU0_CPU1_P0P0_DP<19>"
					( Origin gPackager )
				)
				( attribute "PNN" "UPI_CPU0_CPU1_P0P0_DP<19>"
					( Origin gPackager )
				)
				( objectStatus "UPI_CPU0_CPU1_P0P0_DP<19>" )
			)
			( signal "@baseboard_fab2_lib.baseboard_fab2(sch_1):upi_cpu1_cpu0_p0p0_dn(0)"
				( attribute "CDS_PHYS_NET_NAME" "UPI_CPU1_CPU0_P0P0_DN<0>"
					( Origin gPackager )
				)
				( attribute "PNN" "UPI_CPU1_CPU0_P0P0_DN<0>"
					( Origin gPackager )
				)
				( objectStatus "UPI_CPU1_CPU0_P0P0_DN<0>" )
			)
			( signal "@baseboard_fab2_lib.baseboard_fab2(sch_1):upi_cpu1_cpu0_p0p0_dn(1)"
				( attribute "CDS_PHYS_NET_NAME" "UPI_CPU1_CPU0_P0P0_DN<1>"
					( Origin gPackager )
				)
				( attribute "PNN" "UPI_CPU1_CPU0_P0P0_DN<1>"
					( Origin gPackager )
				)
				( objectStatus "UPI_CPU1_CPU0_P0P0_DN<1>" )
			)
			( signal "@baseboard_fab2_lib.baseboard_fab2(sch_1):upi_cpu1_cpu0_p0p0_dn(2)"
				( attribute "CDS_PHYS_NET_NAME" "UPI_CPU1_CPU0_P0P0_DN<2>"
					( Origin gPackager )
				)
				( attribute "PNN" "UPI_CPU1_CPU0_P0P0_DN<2>"
					( Origin gPackager )
				)
				( objectStatus "UPI_CPU1_CPU0_P0P0_DN<2>" )
			)
			( signal "@baseboard_fab2_lib.baseboard_fab2(sch_1):upi_cpu1_cpu0_p0p0_dn(3)"
				( attribute "CDS_PHYS_NET_NAME" "UPI_CPU1_CPU0_P0P0_DN<3>"
					( Origin gPackager )
				)
				( attribute "PNN" "UPI_CPU1_CPU0_P0P0_DN<3>"
					( Origin gPackager )
				)
				( objectStatus "UPI_CPU1_CPU0_P0P0_DN<3>" )
			)
			( signal "@baseboard_fab2_lib.baseboard_fab2(sch_1):upi_cpu1_cpu0_p0p0_dn(4)"
				( attribute "CDS_PHYS_NET_NAME" "UPI_CPU1_CPU0_P0P0_DN<4>"
					( Origin gPackager )
				)
				( attribute "PNN" "UPI_CPU1_CPU0_P0P0_DN<4>"
					( Origin gPackager )
				)
				( objectStatus "UPI_CPU1_CPU0_P0P0_DN<4>" )
			)
			( signal "@baseboard_fab2_lib.baseboard_fab2(sch_1):upi_cpu1_cpu0_p0p0_dn(5)"
				( attribute "CDS_PHYS_NET_NAME" "UPI_CPU1_CPU0_P0P0_DN<5>"
					( Origin gPackager )
				)
				( attribute "PNN" "UPI_CPU1_CPU0_P0P0_DN<5>"
					( Origin gPackager )
				)
				( objectStatus "UPI_CPU1_CPU0_P0P0_DN<5>" )
			)
			( signal "@baseboard_fab2_lib.baseboard_fab2(sch_1):upi_cpu1_cpu0_p0p0_dn(6)"
				( attribute "CDS_PHYS_NET_NAME" "UPI_CPU1_CPU0_P0P0_DN<6>"
					( Origin gPackager )
				)
				( attribute "PNN" "UPI_CPU1_CPU0_P0P0_DN<6>"
					( Origin gPackager )
				)
				( objectStatus "UPI_CPU1_CPU0_P0P0_DN<6>" )
			)
			( signal "@baseboard_fab2_lib.baseboard_fab2(sch_1):upi_cpu1_cpu0_p0p0_dn(7)"
				( attribute "CDS_PHYS_NET_NAME" "UPI_CPU1_CPU0_P0P0_DN<7>"
					( Origin gPackager )
				)
				( attribute "PNN" "UPI_CPU1_CPU0_P0P0_DN<7>"
					( Origin gPackager )
				)
				( objectStatus "UPI_CPU1_CPU0_P0P0_DN<7>" )
			)
			( signal "@baseboard_fab2_lib.baseboard_fab2(sch_1):upi_cpu1_cpu0_p0p0_dn(8)"
				( attribute "CDS_PHYS_NET_NAME" "UPI_CPU1_CPU0_P0P0_DN<8>"
					( Origin gPackager )
				)
				( attribute "PNN" "UPI_CPU1_CPU0_P0P0_DN<8>"
					( Origin gPackager )
				)
				( objectStatus "UPI_CPU1_CPU0_P0P0_DN<8>" )
			)
			( signal "@baseboard_fab2_lib.baseboard_fab2(sch_1):upi_cpu1_cpu0_p0p0_dn(9)"
				( attribute "CDS_PHYS_NET_NAME" "UPI_CPU1_CPU0_P0P0_DN<9>"
					( Origin gPackager )
				)
				( attribute "PNN" "UPI_CPU1_CPU0_P0P0_DN<9>"
					( Origin gPackager )
				)
				( objectStatus "UPI_CPU1_CPU0_P0P0_DN<9>" )
			)
			( signal "@baseboard_fab2_lib.baseboard_fab2(sch_1):upi_cpu1_cpu0_p0p0_dn(10)"
				( attribute "CDS_PHYS_NET_NAME" "UPI_CPU1_CPU0_P0P0_DN<10>"
					( Origin gPackager )
				)
				( attribute "PNN" "UPI_CPU1_CPU0_P0P0_DN<10>"
					( Origin gPackager )
				)
				( objectStatus "UPI_CPU1_CPU0_P0P0_DN<10>" )
			)
			( signal "@baseboard_fab2_lib.baseboard_fab2(sch_1):upi_cpu1_cpu0_p0p0_dn(11)"
				( attribute "CDS_PHYS_NET_NAME" "UPI_CPU1_CPU0_P0P0_DN<11>"
					( Origin gPackager )
				)
				( attribute "PNN" "UPI_CPU1_CPU0_P0P0_DN<11>"
					( Origin gPackager )
				)
				( objectStatus "UPI_CPU1_CPU0_P0P0_DN<11>" )
			)
			( signal "@baseboard_fab2_lib.baseboard_fab2(sch_1):upi_cpu1_cpu0_p0p0_dn(12)"
				( attribute "CDS_PHYS_NET_NAME" "UPI_CPU1_CPU0_P0P0_DN<12>"
					( Origin gPackager )
				)
				( attribute "PNN" "UPI_CPU1_CPU0_P0P0_DN<12>"
					( Origin gPackager )
				)
				( objectStatus "UPI_CPU1_CPU0_P0P0_DN<12>" )
			)
			( signal "@baseboard_fab2_lib.baseboard_fab2(sch_1):upi_cpu1_cpu0_p0p0_dn(13)"
				( attribute "CDS_PHYS_NET_NAME" "UPI_CPU1_CPU0_P0P0_DN<13>"
					( Origin gPackager )
				)
				( attribute "PNN" "UPI_CPU1_CPU0_P0P0_DN<13>"
					( Origin gPackager )
				)
				( objectStatus "UPI_CPU1_CPU0_P0P0_DN<13>" )
			)
			( signal "@baseboard_fab2_lib.baseboard_fab2(sch_1):upi_cpu1_cpu0_p0p0_dn(14)"
				( attribute "CDS_PHYS_NET_NAME" "UPI_CPU1_CPU0_P0P0_DN<14>"
					( Origin gPackager )
				)
				( attribute "PNN" "UPI_CPU1_CPU0_P0P0_DN<14>"
					( Origin gPackager )
				)
				( objectStatus "UPI_CPU1_CPU0_P0P0_DN<14>" )
			)
			( signal "@baseboard_fab2_lib.baseboard_fab2(sch_1):upi_cpu1_cpu0_p0p0_dn(15)"
				( attribute "CDS_PHYS_NET_NAME" "UPI_CPU1_CPU0_P0P0_DN<15>"
					( Origin gPackager )
				)
				( attribute "PNN" "UPI_CPU1_CPU0_P0P0_DN<15>"
					( Origin gPackager )
				)
				( objectStatus "UPI_CPU1_CPU0_P0P0_DN<15>" )
			)
			( signal "@baseboard_fab2_lib.baseboard_fab2(sch_1):upi_cpu1_cpu0_p0p0_dn(16)"
				( attribute "CDS_PHYS_NET_NAME" "UPI_CPU1_CPU0_P0P0_DN<16>"
					( Origin gPackager )
				)
				( attribute "PNN" "UPI_CPU1_CPU0_P0P0_DN<16>"
					( Origin gPackager )
				)
				( objectStatus "UPI_CPU1_CPU0_P0P0_DN<16>" )
			)
			( signal "@baseboard_fab2_lib.baseboard_fab2(sch_1):upi_cpu1_cpu0_p0p0_dn(17)"
				( attribute "CDS_PHYS_NET_NAME" "UPI_CPU1_CPU0_P0P0_DN<17>"
					( Origin gPackager )
				)
				( attribute "PNN" "UPI_CPU1_CPU0_P0P0_DN<17>"
					( Origin gPackager )
				)
				( objectStatus "UPI_CPU1_CPU0_P0P0_DN<17>" )
			)
			( signal "@baseboard_fab2_lib.baseboard_fab2(sch_1):upi_cpu1_cpu0_p0p0_dn(18)"
				( attribute "CDS_PHYS_NET_NAME" "UPI_CPU1_CPU0_P0P0_DN<18>"
					( Origin gPackager )
				)
				( attribute "PNN" "UPI_CPU1_CPU0_P0P0_DN<18>"
					( Origin gPackager )
				)
				( objectStatus "UPI_CPU1_CPU0_P0P0_DN<18>" )
			)
			( signal "@baseboard_fab2_lib.baseboard_fab2(sch_1):upi_cpu1_cpu0_p0p0_dn(19)"
				( attribute "CDS_PHYS_NET_NAME" "UPI_CPU1_CPU0_P0P0_DN<19>"
					( Origin gPackager )
				)
				( attribute "PNN" "UPI_CPU1_CPU0_P0P0_DN<19>"
					( Origin gPackager )
				)
				( objectStatus "UPI_CPU1_CPU0_P0P0_DN<19>" )
			)
			( signal "@baseboard_fab2_lib.baseboard_fab2(sch_1):upi_cpu1_cpu0_p0p0_dp(0)"
				( attribute "CDS_PHYS_NET_NAME" "UPI_CPU1_CPU0_P0P0_DP<0>"
					( Origin gPackager )
				)
				( attribute "PNN" "UPI_CPU1_CPU0_P0P0_DP<0>"
					( Origin gPackager )
				)
				( objectStatus "UPI_CPU1_CPU0_P0P0_DP<0>" )
			)
			( signal "@baseboard_fab2_lib.baseboard_fab2(sch_1):upi_cpu1_cpu0_p0p0_dp(1)"
				( attribute "CDS_PHYS_NET_NAME" "UPI_CPU1_CPU0_P0P0_DP<1>"
					( Origin gPackager )
				)
				( attribute "PNN" "UPI_CPU1_CPU0_P0P0_DP<1>"
					( Origin gPackager )
				)
				( objectStatus "UPI_CPU1_CPU0_P0P0_DP<1>" )
			)
			( signal "@baseboard_fab2_lib.baseboard_fab2(sch_1):upi_cpu1_cpu0_p0p0_dp(2)"
				( attribute "CDS_PHYS_NET_NAME" "UPI_CPU1_CPU0_P0P0_DP<2>"
					( Origin gPackager )
				)
				( attribute "PNN" "UPI_CPU1_CPU0_P0P0_DP<2>"
					( Origin gPackager )
				)
				( objectStatus "UPI_CPU1_CPU0_P0P0_DP<2>" )
			)
			( signal "@baseboard_fab2_lib.baseboard_fab2(sch_1):upi_cpu1_cpu0_p0p0_dp(3)"
				( attribute "CDS_PHYS_NET_NAME" "UPI_CPU1_CPU0_P0P0_DP<3>"
					( Origin gPackager )
				)
				( attribute "PNN" "UPI_CPU1_CPU0_P0P0_DP<3>"
					( Origin gPackager )
				)
				( objectStatus "UPI_CPU1_CPU0_P0P0_DP<3>" )
			)
			( signal "@baseboard_fab2_lib.baseboard_fab2(sch_1):upi_cpu1_cpu0_p0p0_dp(4)"
				( attribute "CDS_PHYS_NET_NAME" "UPI_CPU1_CPU0_P0P0_DP<4>"
					( Origin gPackager )
				)
				( attribute "PNN" "UPI_CPU1_CPU0_P0P0_DP<4>"
					( Origin gPackager )
				)
				( objectStatus "UPI_CPU1_CPU0_P0P0_DP<4>" )
			)
			( signal "@baseboard_fab2_lib.baseboard_fab2(sch_1):upi_cpu1_cpu0_p0p0_dp(5)"
				( attribute "CDS_PHYS_NET_NAME" "UPI_CPU1_CPU0_P0P0_DP<5>"
					( Origin gPackager )
				)
				( attribute "PNN" "UPI_CPU1_CPU0_P0P0_DP<5>"
					( Origin gPackager )
				)
				( objectStatus "UPI_CPU1_CPU0_P0P0_DP<5>" )
			)
			( signal "@baseboard_fab2_lib.baseboard_fab2(sch_1):upi_cpu1_cpu0_p0p0_dp(6)"
				( attribute "CDS_PHYS_NET_NAME" "UPI_CPU1_CPU0_P0P0_DP<6>"
					( Origin gPackager )
				)
				( attribute "PNN" "UPI_CPU1_CPU0_P0P0_DP<6>"
					( Origin gPackager )
				)
				( objectStatus "UPI_CPU1_CPU0_P0P0_DP<6>" )
			)
			( signal "@baseboard_fab2_lib.baseboard_fab2(sch_1):upi_cpu1_cpu0_p0p0_dp(7)"
				( attribute "CDS_PHYS_NET_NAME" "UPI_CPU1_CPU0_P0P0_DP<7>"
					( Origin gPackager )
				)
				( attribute "PNN" "UPI_CPU1_CPU0_P0P0_DP<7>"
					( Origin gPackager )
				)
				( objectStatus "UPI_CPU1_CPU0_P0P0_DP<7>" )
			)
			( signal "@baseboard_fab2_lib.baseboard_fab2(sch_1):upi_cpu1_cpu0_p0p0_dp(8)"
				( attribute "CDS_PHYS_NET_NAME" "UPI_CPU1_CPU0_P0P0_DP<8>"
					( Origin gPackager )
				)
				( attribute "PNN" "UPI_CPU1_CPU0_P0P0_DP<8>"
					( Origin gPackager )
				)
				( objectStatus "UPI_CPU1_CPU0_P0P0_DP<8>" )
			)
			( signal "@baseboard_fab2_lib.baseboard_fab2(sch_1):upi_cpu1_cpu0_p0p0_dp(9)"
				( attribute "CDS_PHYS_NET_NAME" "UPI_CPU1_CPU0_P0P0_DP<9>"
					( Origin gPackager )
				)
				( attribute "PNN" "UPI_CPU1_CPU0_P0P0_DP<9>"
					( Origin gPackager )
				)
				( objectStatus "UPI_CPU1_CPU0_P0P0_DP<9>" )
			)
			( signal "@baseboard_fab2_lib.baseboard_fab2(sch_1):upi_cpu1_cpu0_p0p0_dp(10)"
				( attribute "CDS_PHYS_NET_NAME" "UPI_CPU1_CPU0_P0P0_DP<10>"
					( Origin gPackager )
				)
				( attribute "PNN" "UPI_CPU1_CPU0_P0P0_DP<10>"
					( Origin gPackager )
				)
				( objectStatus "UPI_CPU1_CPU0_P0P0_DP<10>" )
			)
			( signal "@baseboard_fab2_lib.baseboard_fab2(sch_1):upi_cpu1_cpu0_p0p0_dp(11)"
				( attribute "CDS_PHYS_NET_NAME" "UPI_CPU1_CPU0_P0P0_DP<11>"
					( Origin gPackager )
				)
				( attribute "PNN" "UPI_CPU1_CPU0_P0P0_DP<11>"
					( Origin gPackager )
				)
				( objectStatus "UPI_CPU1_CPU0_P0P0_DP<11>" )
			)
			( signal "@baseboard_fab2_lib.baseboard_fab2(sch_1):upi_cpu1_cpu0_p0p0_dp(12)"
				( attribute "CDS_PHYS_NET_NAME" "UPI_CPU1_CPU0_P0P0_DP<12>"
					( Origin gPackager )
				)
				( attribute "PNN" "UPI_CPU1_CPU0_P0P0_DP<12>"
					( Origin gPackager )
				)
				( objectStatus "UPI_CPU1_CPU0_P0P0_DP<12>" )
			)
			( signal "@baseboard_fab2_lib.baseboard_fab2(sch_1):upi_cpu1_cpu0_p0p0_dp(13)"
				( attribute "CDS_PHYS_NET_NAME" "UPI_CPU1_CPU0_P0P0_DP<13>"
					( Origin gPackager )
				)
				( attribute "PNN" "UPI_CPU1_CPU0_P0P0_DP<13>"
					( Origin gPackager )
				)
				( objectStatus "UPI_CPU1_CPU0_P0P0_DP<13>" )
			)
			( signal "@baseboard_fab2_lib.baseboard_fab2(sch_1):upi_cpu1_cpu0_p0p0_dp(14)"
				( attribute "CDS_PHYS_NET_NAME" "UPI_CPU1_CPU0_P0P0_DP<14>"
					( Origin gPackager )
				)
				( attribute "PNN" "UPI_CPU1_CPU0_P0P0_DP<14>"
					( Origin gPackager )
				)
				( objectStatus "UPI_CPU1_CPU0_P0P0_DP<14>" )
			)
			( signal "@baseboard_fab2_lib.baseboard_fab2(sch_1):upi_cpu1_cpu0_p0p0_dp(15)"
				( attribute "CDS_PHYS_NET_NAME" "UPI_CPU1_CPU0_P0P0_DP<15>"
					( Origin gPackager )
				)
				( attribute "PNN" "UPI_CPU1_CPU0_P0P0_DP<15>"
					( Origin gPackager )
				)
				( objectStatus "UPI_CPU1_CPU0_P0P0_DP<15>" )
			)
			( signal "@baseboard_fab2_lib.baseboard_fab2(sch_1):upi_cpu1_cpu0_p0p0_dp(16)"
				( attribute "CDS_PHYS_NET_NAME" "UPI_CPU1_CPU0_P0P0_DP<16>"
					( Origin gPackager )
				)
				( attribute "PNN" "UPI_CPU1_CPU0_P0P0_DP<16>"
					( Origin gPackager )
				)
				( objectStatus "UPI_CPU1_CPU0_P0P0_DP<16>" )
			)
			( signal "@baseboard_fab2_lib.baseboard_fab2(sch_1):upi_cpu1_cpu0_p0p0_dp(17)"
				( attribute "CDS_PHYS_NET_NAME" "UPI_CPU1_CPU0_P0P0_DP<17>"
					( Origin gPackager )
				)
				( attribute "PNN" "UPI_CPU1_CPU0_P0P0_DP<17>"
					( Origin gPackager )
				)
				( objectStatus "UPI_CPU1_CPU0_P0P0_DP<17>" )
			)
			( signal "@baseboard_fab2_lib.baseboard_fab2(sch_1):upi_cpu1_cpu0_p0p0_dp(18)"
				( attribute "CDS_PHYS_NET_NAME" "UPI_CPU1_CPU0_P0P0_DP<18>"
					( Origin gPackager )
				)
				( attribute "PNN" "UPI_CPU1_CPU0_P0P0_DP<18>"
					( Origin gPackager )
				)
				( objectStatus "UPI_CPU1_CPU0_P0P0_DP<18>" )
			)
			( signal "@baseboard_fab2_lib.baseboard_fab2(sch_1):upi_cpu1_cpu0_p0p0_dp(19)"
				( attribute "CDS_PHYS_NET_NAME" "UPI_CPU1_CPU0_P0P0_DP<19>"
					( Origin gPackager )
				)
				( attribute "PNN" "UPI_CPU1_CPU0_P0P0_DP<19>"
					( Origin gPackager )
				)
				( objectStatus "UPI_CPU1_CPU0_P0P0_DP<19>" )
			)
			( signal "@baseboard_fab2_lib.baseboard_fab2(sch_1):upi_cpu0_cpu1_p1p1_dn(0)"
				( attribute "CDS_PHYS_NET_NAME" "UPI_CPU0_CPU1_P1P1_DN<0>"
					( Origin gPackager )
				)
				( attribute "PNN" "UPI_CPU0_CPU1_P1P1_DN<0>"
					( Origin gPackager )
				)
				( objectStatus "UPI_CPU0_CPU1_P1P1_DN<0>" )
			)
			( signal "@baseboard_fab2_lib.baseboard_fab2(sch_1):upi_cpu0_cpu1_p1p1_dn(1)"
				( attribute "CDS_PHYS_NET_NAME" "UPI_CPU0_CPU1_P1P1_DN<1>"
					( Origin gPackager )
				)
				( attribute "PNN" "UPI_CPU0_CPU1_P1P1_DN<1>"
					( Origin gPackager )
				)
				( objectStatus "UPI_CPU0_CPU1_P1P1_DN<1>" )
			)
			( signal "@baseboard_fab2_lib.baseboard_fab2(sch_1):upi_cpu0_cpu1_p1p1_dn(2)"
				( attribute "CDS_PHYS_NET_NAME" "UPI_CPU0_CPU1_P1P1_DN<2>"
					( Origin gPackager )
				)
				( attribute "PNN" "UPI_CPU0_CPU1_P1P1_DN<2>"
					( Origin gPackager )
				)
				( objectStatus "UPI_CPU0_CPU1_P1P1_DN<2>" )
			)
			( signal "@baseboard_fab2_lib.baseboard_fab2(sch_1):upi_cpu0_cpu1_p1p1_dn(3)"
				( attribute "CDS_PHYS_NET_NAME" "UPI_CPU0_CPU1_P1P1_DN<3>"
					( Origin gPackager )
				)
				( attribute "PNN" "UPI_CPU0_CPU1_P1P1_DN<3>"
					( Origin gPackager )
				)
				( objectStatus "UPI_CPU0_CPU1_P1P1_DN<3>" )
			)
			( signal "@baseboard_fab2_lib.baseboard_fab2(sch_1):upi_cpu0_cpu1_p1p1_dn(4)"
				( attribute "CDS_PHYS_NET_NAME" "UPI_CPU0_CPU1_P1P1_DN<4>"
					( Origin gPackager )
				)
				( attribute "PNN" "UPI_CPU0_CPU1_P1P1_DN<4>"
					( Origin gPackager )
				)
				( objectStatus "UPI_CPU0_CPU1_P1P1_DN<4>" )
			)
			( signal "@baseboard_fab2_lib.baseboard_fab2(sch_1):upi_cpu0_cpu1_p1p1_dn(5)"
				( attribute "CDS_PHYS_NET_NAME" "UPI_CPU0_CPU1_P1P1_DN<5>"
					( Origin gPackager )
				)
				( attribute "PNN" "UPI_CPU0_CPU1_P1P1_DN<5>"
					( Origin gPackager )
				)
				( objectStatus "UPI_CPU0_CPU1_P1P1_DN<5>" )
			)
			( signal "@baseboard_fab2_lib.baseboard_fab2(sch_1):upi_cpu0_cpu1_p1p1_dn(6)"
				( attribute "CDS_PHYS_NET_NAME" "UPI_CPU0_CPU1_P1P1_DN<6>"
					( Origin gPackager )
				)
				( attribute "PNN" "UPI_CPU0_CPU1_P1P1_DN<6>"
					( Origin gPackager )
				)
				( objectStatus "UPI_CPU0_CPU1_P1P1_DN<6>" )
			)
			( signal "@baseboard_fab2_lib.baseboard_fab2(sch_1):upi_cpu0_cpu1_p1p1_dn(7)"
				( attribute "CDS_PHYS_NET_NAME" "UPI_CPU0_CPU1_P1P1_DN<7>"
					( Origin gPackager )
				)
				( attribute "PNN" "UPI_CPU0_CPU1_P1P1_DN<7>"
					( Origin gPackager )
				)
				( objectStatus "UPI_CPU0_CPU1_P1P1_DN<7>" )
			)
			( signal "@baseboard_fab2_lib.baseboard_fab2(sch_1):upi_cpu0_cpu1_p1p1_dn(8)"
				( attribute "CDS_PHYS_NET_NAME" "UPI_CPU0_CPU1_P1P1_DN<8>"
					( Origin gPackager )
				)
				( attribute "PNN" "UPI_CPU0_CPU1_P1P1_DN<8>"
					( Origin gPackager )
				)
				( objectStatus "UPI_CPU0_CPU1_P1P1_DN<8>" )
			)
			( signal "@baseboard_fab2_lib.baseboard_fab2(sch_1):upi_cpu0_cpu1_p1p1_dn(9)"
				( attribute "CDS_PHYS_NET_NAME" "UPI_CPU0_CPU1_P1P1_DN<9>"
					( Origin gPackager )
				)
				( attribute "PNN" "UPI_CPU0_CPU1_P1P1_DN<9>"
					( Origin gPackager )
				)
				( objectStatus "UPI_CPU0_CPU1_P1P1_DN<9>" )
			)
			( signal "@baseboard_fab2_lib.baseboard_fab2(sch_1):upi_cpu0_cpu1_p1p1_dn(10)"
				( attribute "CDS_PHYS_NET_NAME" "UPI_CPU0_CPU1_P1P1_DN<10>"
					( Origin gPackager )
				)
				( attribute "PNN" "UPI_CPU0_CPU1_P1P1_DN<10>"
					( Origin gPackager )
				)
				( objectStatus "UPI_CPU0_CPU1_P1P1_DN<10>" )
			)
			( signal "@baseboard_fab2_lib.baseboard_fab2(sch_1):upi_cpu0_cpu1_p1p1_dn(11)"
				( attribute "CDS_PHYS_NET_NAME" "UPI_CPU0_CPU1_P1P1_DN<11>"
					( Origin gPackager )
				)
				( attribute "PNN" "UPI_CPU0_CPU1_P1P1_DN<11>"
					( Origin gPackager )
				)
				( objectStatus "UPI_CPU0_CPU1_P1P1_DN<11>" )
			)
			( signal "@baseboard_fab2_lib.baseboard_fab2(sch_1):upi_cpu0_cpu1_p1p1_dn(12)"
				( attribute "CDS_PHYS_NET_NAME" "UPI_CPU0_CPU1_P1P1_DN<12>"
					( Origin gPackager )
				)
				( attribute "PNN" "UPI_CPU0_CPU1_P1P1_DN<12>"
					( Origin gPackager )
				)
				( objectStatus "UPI_CPU0_CPU1_P1P1_DN<12>" )
			)
			( signal "@baseboard_fab2_lib.baseboard_fab2(sch_1):upi_cpu0_cpu1_p1p1_dn(13)"
				( attribute "CDS_PHYS_NET_NAME" "UPI_CPU0_CPU1_P1P1_DN<13>"
					( Origin gPackager )
				)
				( attribute "PNN" "UPI_CPU0_CPU1_P1P1_DN<13>"
					( Origin gPackager )
				)
				( objectStatus "UPI_CPU0_CPU1_P1P1_DN<13>" )
			)
			( signal "@baseboard_fab2_lib.baseboard_fab2(sch_1):upi_cpu0_cpu1_p1p1_dn(14)"
				( attribute "CDS_PHYS_NET_NAME" "UPI_CPU0_CPU1_P1P1_DN<14>"
					( Origin gPackager )
				)
				( attribute "PNN" "UPI_CPU0_CPU1_P1P1_DN<14>"
					( Origin gPackager )
				)
				( objectStatus "UPI_CPU0_CPU1_P1P1_DN<14>" )
			)
			( signal "@baseboard_fab2_lib.baseboard_fab2(sch_1):upi_cpu0_cpu1_p1p1_dn(15)"
				( attribute "CDS_PHYS_NET_NAME" "UPI_CPU0_CPU1_P1P1_DN<15>"
					( Origin gPackager )
				)
				( attribute "PNN" "UPI_CPU0_CPU1_P1P1_DN<15>"
					( Origin gPackager )
				)
				( objectStatus "UPI_CPU0_CPU1_P1P1_DN<15>" )
			)
			( signal "@baseboard_fab2_lib.baseboard_fab2(sch_1):upi_cpu0_cpu1_p1p1_dn(16)"
				( attribute "CDS_PHYS_NET_NAME" "UPI_CPU0_CPU1_P1P1_DN<16>"
					( Origin gPackager )
				)
				( attribute "PNN" "UPI_CPU0_CPU1_P1P1_DN<16>"
					( Origin gPackager )
				)
				( objectStatus "UPI_CPU0_CPU1_P1P1_DN<16>" )
			)
			( signal "@baseboard_fab2_lib.baseboard_fab2(sch_1):upi_cpu0_cpu1_p1p1_dn(17)"
				( attribute "CDS_PHYS_NET_NAME" "UPI_CPU0_CPU1_P1P1_DN<17>"
					( Origin gPackager )
				)
				( attribute "PNN" "UPI_CPU0_CPU1_P1P1_DN<17>"
					( Origin gPackager )
				)
				( objectStatus "UPI_CPU0_CPU1_P1P1_DN<17>" )
			)
			( signal "@baseboard_fab2_lib.baseboard_fab2(sch_1):upi_cpu0_cpu1_p1p1_dn(18)"
				( attribute "CDS_PHYS_NET_NAME" "UPI_CPU0_CPU1_P1P1_DN<18>"
					( Origin gPackager )
				)
				( attribute "PNN" "UPI_CPU0_CPU1_P1P1_DN<18>"
					( Origin gPackager )
				)
				( objectStatus "UPI_CPU0_CPU1_P1P1_DN<18>" )
			)
			( signal "@baseboard_fab2_lib.baseboard_fab2(sch_1):upi_cpu0_cpu1_p1p1_dn(19)"
				( attribute "CDS_PHYS_NET_NAME" "UPI_CPU0_CPU1_P1P1_DN<19>"
					( Origin gPackager )
				)
				( attribute "PNN" "UPI_CPU0_CPU1_P1P1_DN<19>"
					( Origin gPackager )
				)
				( objectStatus "UPI_CPU0_CPU1_P1P1_DN<19>" )
			)
			( signal "@baseboard_fab2_lib.baseboard_fab2(sch_1):upi_cpu0_cpu1_p1p1_dp(0)"
				( attribute "CDS_PHYS_NET_NAME" "UPI_CPU0_CPU1_P1P1_DP<0>"
					( Origin gPackager )
				)
				( attribute "PNN" "UPI_CPU0_CPU1_P1P1_DP<0>"
					( Origin gPackager )
				)
				( objectStatus "UPI_CPU0_CPU1_P1P1_DP<0>" )
			)
			( signal "@baseboard_fab2_lib.baseboard_fab2(sch_1):upi_cpu0_cpu1_p1p1_dp(1)"
				( attribute "CDS_PHYS_NET_NAME" "UPI_CPU0_CPU1_P1P1_DP<1>"
					( Origin gPackager )
				)
				( attribute "PNN" "UPI_CPU0_CPU1_P1P1_DP<1>"
					( Origin gPackager )
				)
				( objectStatus "UPI_CPU0_CPU1_P1P1_DP<1>" )
			)
			( signal "@baseboard_fab2_lib.baseboard_fab2(sch_1):upi_cpu0_cpu1_p1p1_dp(2)"
				( attribute "CDS_PHYS_NET_NAME" "UPI_CPU0_CPU1_P1P1_DP<2>"
					( Origin gPackager )
				)
				( attribute "PNN" "UPI_CPU0_CPU1_P1P1_DP<2>"
					( Origin gPackager )
				)
				( objectStatus "UPI_CPU0_CPU1_P1P1_DP<2>" )
			)
			( signal "@baseboard_fab2_lib.baseboard_fab2(sch_1):upi_cpu0_cpu1_p1p1_dp(3)"
				( attribute "CDS_PHYS_NET_NAME" "UPI_CPU0_CPU1_P1P1_DP<3>"
					( Origin gPackager )
				)
				( attribute "PNN" "UPI_CPU0_CPU1_P1P1_DP<3>"
					( Origin gPackager )
				)
				( objectStatus "UPI_CPU0_CPU1_P1P1_DP<3>" )
			)
			( signal "@baseboard_fab2_lib.baseboard_fab2(sch_1):upi_cpu0_cpu1_p1p1_dp(4)"
				( attribute "CDS_PHYS_NET_NAME" "UPI_CPU0_CPU1_P1P1_DP<4>"
					( Origin gPackager )
				)
				( attribute "PNN" "UPI_CPU0_CPU1_P1P1_DP<4>"
					( Origin gPackager )
				)
				( objectStatus "UPI_CPU0_CPU1_P1P1_DP<4>" )
			)
			( signal "@baseboard_fab2_lib.baseboard_fab2(sch_1):upi_cpu0_cpu1_p1p1_dp(5)"
				( attribute "CDS_PHYS_NET_NAME" "UPI_CPU0_CPU1_P1P1_DP<5>"
					( Origin gPackager )
				)
				( attribute "PNN" "UPI_CPU0_CPU1_P1P1_DP<5>"
					( Origin gPackager )
				)
				( objectStatus "UPI_CPU0_CPU1_P1P1_DP<5>" )
			)
			( signal "@baseboard_fab2_lib.baseboard_fab2(sch_1):upi_cpu0_cpu1_p1p1_dp(6)"
				( attribute "CDS_PHYS_NET_NAME" "UPI_CPU0_CPU1_P1P1_DP<6>"
					( Origin gPackager )
				)
				( attribute "PNN" "UPI_CPU0_CPU1_P1P1_DP<6>"
					( Origin gPackager )
				)
				( objectStatus "UPI_CPU0_CPU1_P1P1_DP<6>" )
			)
			( signal "@baseboard_fab2_lib.baseboard_fab2(sch_1):upi_cpu0_cpu1_p1p1_dp(7)"
				( attribute "CDS_PHYS_NET_NAME" "UPI_CPU0_CPU1_P1P1_DP<7>"
					( Origin gPackager )
				)
				( attribute "PNN" "UPI_CPU0_CPU1_P1P1_DP<7>"
					( Origin gPackager )
				)
				( objectStatus "UPI_CPU0_CPU1_P1P1_DP<7>" )
			)
			( signal "@baseboard_fab2_lib.baseboard_fab2(sch_1):upi_cpu0_cpu1_p1p1_dp(8)"
				( attribute "CDS_PHYS_NET_NAME" "UPI_CPU0_CPU1_P1P1_DP<8>"
					( Origin gPackager )
				)
				( attribute "PNN" "UPI_CPU0_CPU1_P1P1_DP<8>"
					( Origin gPackager )
				)
				( objectStatus "UPI_CPU0_CPU1_P1P1_DP<8>" )
			)
			( signal "@baseboard_fab2_lib.baseboard_fab2(sch_1):upi_cpu0_cpu1_p1p1_dp(9)"
				( attribute "CDS_PHYS_NET_NAME" "UPI_CPU0_CPU1_P1P1_DP<9>"
					( Origin gPackager )
				)
				( attribute "PNN" "UPI_CPU0_CPU1_P1P1_DP<9>"
					( Origin gPackager )
				)
				( objectStatus "UPI_CPU0_CPU1_P1P1_DP<9>" )
			)
			( signal "@baseboard_fab2_lib.baseboard_fab2(sch_1):upi_cpu0_cpu1_p1p1_dp(10)"
				( attribute "CDS_PHYS_NET_NAME" "UPI_CPU0_CPU1_P1P1_DP<10>"
					( Origin gPackager )
				)
				( attribute "PNN" "UPI_CPU0_CPU1_P1P1_DP<10>"
					( Origin gPackager )
				)
				( objectStatus "UPI_CPU0_CPU1_P1P1_DP<10>" )
			)
			( signal "@baseboard_fab2_lib.baseboard_fab2(sch_1):upi_cpu0_cpu1_p1p1_dp(11)"
				( attribute "CDS_PHYS_NET_NAME" "UPI_CPU0_CPU1_P1P1_DP<11>"
					( Origin gPackager )
				)
				( attribute "PNN" "UPI_CPU0_CPU1_P1P1_DP<11>"
					( Origin gPackager )
				)
				( objectStatus "UPI_CPU0_CPU1_P1P1_DP<11>" )
			)
			( signal "@baseboard_fab2_lib.baseboard_fab2(sch_1):upi_cpu0_cpu1_p1p1_dp(12)"
				( attribute "CDS_PHYS_NET_NAME" "UPI_CPU0_CPU1_P1P1_DP<12>"
					( Origin gPackager )
				)
				( attribute "PNN" "UPI_CPU0_CPU1_P1P1_DP<12>"
					( Origin gPackager )
				)
				( objectStatus "UPI_CPU0_CPU1_P1P1_DP<12>" )
			)
			( signal "@baseboard_fab2_lib.baseboard_fab2(sch_1):upi_cpu0_cpu1_p1p1_dp(13)"
				( attribute "CDS_PHYS_NET_NAME" "UPI_CPU0_CPU1_P1P1_DP<13>"
					( Origin gPackager )
				)
				( attribute "PNN" "UPI_CPU0_CPU1_P1P1_DP<13>"
					( Origin gPackager )
				)
				( objectStatus "UPI_CPU0_CPU1_P1P1_DP<13>" )
			)
			( signal "@baseboard_fab2_lib.baseboard_fab2(sch_1):upi_cpu0_cpu1_p1p1_dp(14)"
				( attribute "CDS_PHYS_NET_NAME" "UPI_CPU0_CPU1_P1P1_DP<14>"
					( Origin gPackager )
				)
				( attribute "PNN" "UPI_CPU0_CPU1_P1P1_DP<14>"
					( Origin gPackager )
				)
				( objectStatus "UPI_CPU0_CPU1_P1P1_DP<14>" )
			)
			( signal "@baseboard_fab2_lib.baseboard_fab2(sch_1):upi_cpu0_cpu1_p1p1_dp(15)"
				( attribute "CDS_PHYS_NET_NAME" "UPI_CPU0_CPU1_P1P1_DP<15>"
					( Origin gPackager )
				)
				( attribute "PNN" "UPI_CPU0_CPU1_P1P1_DP<15>"
					( Origin gPackager )
				)
				( objectStatus "UPI_CPU0_CPU1_P1P1_DP<15>" )
			)
			( signal "@baseboard_fab2_lib.baseboard_fab2(sch_1):upi_cpu0_cpu1_p1p1_dp(16)"
				( attribute "CDS_PHYS_NET_NAME" "UPI_CPU0_CPU1_P1P1_DP<16>"
					( Origin gPackager )
				)
				( attribute "PNN" "UPI_CPU0_CPU1_P1P1_DP<16>"
					( Origin gPackager )
				)
				( objectStatus "UPI_CPU0_CPU1_P1P1_DP<16>" )
			)
			( signal "@baseboard_fab2_lib.baseboard_fab2(sch_1):upi_cpu0_cpu1_p1p1_dp(17)"
				( attribute "CDS_PHYS_NET_NAME" "UPI_CPU0_CPU1_P1P1_DP<17>"
					( Origin gPackager )
				)
				( attribute "PNN" "UPI_CPU0_CPU1_P1P1_DP<17>"
					( Origin gPackager )
				)
				( objectStatus "UPI_CPU0_CPU1_P1P1_DP<17>" )
			)
			( signal "@baseboard_fab2_lib.baseboard_fab2(sch_1):upi_cpu0_cpu1_p1p1_dp(18)"
				( attribute "CDS_PHYS_NET_NAME" "UPI_CPU0_CPU1_P1P1_DP<18>"
					( Origin gPackager )
				)
				( attribute "PNN" "UPI_CPU0_CPU1_P1P1_DP<18>"
					( Origin gPackager )
				)
				( objectStatus "UPI_CPU0_CPU1_P1P1_DP<18>" )
			)
			( signal "@baseboard_fab2_lib.baseboard_fab2(sch_1):upi_cpu0_cpu1_p1p1_dp(19)"
				( attribute "CDS_PHYS_NET_NAME" "UPI_CPU0_CPU1_P1P1_DP<19>"
					( Origin gPackager )
				)
				( attribute "PNN" "UPI_CPU0_CPU1_P1P1_DP<19>"
					( Origin gPackager )
				)
				( objectStatus "UPI_CPU0_CPU1_P1P1_DP<19>" )
			)
			( signal "@baseboard_fab2_lib.baseboard_fab2(sch_1):upi_cpu1_cpu0_p1p1_dn(0)"
				( attribute "CDS_PHYS_NET_NAME" "UPI_CPU1_CPU0_P1P1_DN<0>"
					( Origin gPackager )
				)
				( attribute "PNN" "UPI_CPU1_CPU0_P1P1_DN<0>"
					( Origin gPackager )
				)
				( objectStatus "UPI_CPU1_CPU0_P1P1_DN<0>" )
			)
			( signal "@baseboard_fab2_lib.baseboard_fab2(sch_1):upi_cpu1_cpu0_p1p1_dn(1)"
				( attribute "CDS_PHYS_NET_NAME" "UPI_CPU1_CPU0_P1P1_DN<1>"
					( Origin gPackager )
				)
				( attribute "PNN" "UPI_CPU1_CPU0_P1P1_DN<1>"
					( Origin gPackager )
				)
				( objectStatus "UPI_CPU1_CPU0_P1P1_DN<1>" )
			)
			( signal "@baseboard_fab2_lib.baseboard_fab2(sch_1):upi_cpu1_cpu0_p1p1_dn(2)"
				( attribute "CDS_PHYS_NET_NAME" "UPI_CPU1_CPU0_P1P1_DN<2>"
					( Origin gPackager )
				)
				( attribute "PNN" "UPI_CPU1_CPU0_P1P1_DN<2>"
					( Origin gPackager )
				)
				( objectStatus "UPI_CPU1_CPU0_P1P1_DN<2>" )
			)
			( signal "@baseboard_fab2_lib.baseboard_fab2(sch_1):upi_cpu1_cpu0_p1p1_dn(3)"
				( attribute "CDS_PHYS_NET_NAME" "UPI_CPU1_CPU0_P1P1_DN<3>"
					( Origin gPackager )
				)
				( attribute "PNN" "UPI_CPU1_CPU0_P1P1_DN<3>"
					( Origin gPackager )
				)
				( objectStatus "UPI_CPU1_CPU0_P1P1_DN<3>" )
			)
			( signal "@baseboard_fab2_lib.baseboard_fab2(sch_1):upi_cpu1_cpu0_p1p1_dn(4)"
				( attribute "CDS_PHYS_NET_NAME" "UPI_CPU1_CPU0_P1P1_DN<4>"
					( Origin gPackager )
				)
				( attribute "PNN" "UPI_CPU1_CPU0_P1P1_DN<4>"
					( Origin gPackager )
				)
				( objectStatus "UPI_CPU1_CPU0_P1P1_DN<4>" )
			)
			( signal "@baseboard_fab2_lib.baseboard_fab2(sch_1):upi_cpu1_cpu0_p1p1_dn(5)"
				( attribute "CDS_PHYS_NET_NAME" "UPI_CPU1_CPU0_P1P1_DN<5>"
					( Origin gPackager )
				)
				( attribute "PNN" "UPI_CPU1_CPU0_P1P1_DN<5>"
					( Origin gPackager )
				)
				( objectStatus "UPI_CPU1_CPU0_P1P1_DN<5>" )
			)
			( signal "@baseboard_fab2_lib.baseboard_fab2(sch_1):upi_cpu1_cpu0_p1p1_dn(6)"
				( attribute "CDS_PHYS_NET_NAME" "UPI_CPU1_CPU0_P1P1_DN<6>"
					( Origin gPackager )
				)
				( attribute "PNN" "UPI_CPU1_CPU0_P1P1_DN<6>"
					( Origin gPackager )
				)
				( objectStatus "UPI_CPU1_CPU0_P1P1_DN<6>" )
			)
			( signal "@baseboard_fab2_lib.baseboard_fab2(sch_1):upi_cpu1_cpu0_p1p1_dn(7)"
				( attribute "CDS_PHYS_NET_NAME" "UPI_CPU1_CPU0_P1P1_DN<7>"
					( Origin gPackager )
				)
				( attribute "PNN" "UPI_CPU1_CPU0_P1P1_DN<7>"
					( Origin gPackager )
				)
				( objectStatus "UPI_CPU1_CPU0_P1P1_DN<7>" )
			)
			( signal "@baseboard_fab2_lib.baseboard_fab2(sch_1):upi_cpu1_cpu0_p1p1_dn(8)"
				( attribute "CDS_PHYS_NET_NAME" "UPI_CPU1_CPU0_P1P1_DN<8>"
					( Origin gPackager )
				)
				( attribute "PNN" "UPI_CPU1_CPU0_P1P1_DN<8>"
					( Origin gPackager )
				)
				( objectStatus "UPI_CPU1_CPU0_P1P1_DN<8>" )
			)
			( signal "@baseboard_fab2_lib.baseboard_fab2(sch_1):upi_cpu1_cpu0_p1p1_dn(9)"
				( attribute "CDS_PHYS_NET_NAME" "UPI_CPU1_CPU0_P1P1_DN<9>"
					( Origin gPackager )
				)
				( attribute "PNN" "UPI_CPU1_CPU0_P1P1_DN<9>"
					( Origin gPackager )
				)
				( objectStatus "UPI_CPU1_CPU0_P1P1_DN<9>" )
			)
			( signal "@baseboard_fab2_lib.baseboard_fab2(sch_1):upi_cpu1_cpu0_p1p1_dn(10)"
				( attribute "CDS_PHYS_NET_NAME" "UPI_CPU1_CPU0_P1P1_DN<10>"
					( Origin gPackager )
				)
				( attribute "PNN" "UPI_CPU1_CPU0_P1P1_DN<10>"
					( Origin gPackager )
				)
				( objectStatus "UPI_CPU1_CPU0_P1P1_DN<10>" )
			)
			( signal "@baseboard_fab2_lib.baseboard_fab2(sch_1):upi_cpu1_cpu0_p1p1_dn(11)"
				( attribute "CDS_PHYS_NET_NAME" "UPI_CPU1_CPU0_P1P1_DN<11>"
					( Origin gPackager )
				)
				( attribute "PNN" "UPI_CPU1_CPU0_P1P1_DN<11>"
					( Origin gPackager )
				)
				( objectStatus "UPI_CPU1_CPU0_P1P1_DN<11>" )
			)
			( signal "@baseboard_fab2_lib.baseboard_fab2(sch_1):upi_cpu1_cpu0_p1p1_dn(12)"
				( attribute "CDS_PHYS_NET_NAME" "UPI_CPU1_CPU0_P1P1_DN<12>"
					( Origin gPackager )
				)
				( attribute "PNN" "UPI_CPU1_CPU0_P1P1_DN<12>"
					( Origin gPackager )
				)
				( objectStatus "UPI_CPU1_CPU0_P1P1_DN<12>" )
			)
			( signal "@baseboard_fab2_lib.baseboard_fab2(sch_1):upi_cpu1_cpu0_p1p1_dn(13)"
				( attribute "CDS_PHYS_NET_NAME" "UPI_CPU1_CPU0_P1P1_DN<13>"
					( Origin gPackager )
				)
				( attribute "PNN" "UPI_CPU1_CPU0_P1P1_DN<13>"
					( Origin gPackager )
				)
				( objectStatus "UPI_CPU1_CPU0_P1P1_DN<13>" )
			)
			( signal "@baseboard_fab2_lib.baseboard_fab2(sch_1):upi_cpu1_cpu0_p1p1_dn(14)"
				( attribute "CDS_PHYS_NET_NAME" "UPI_CPU1_CPU0_P1P1_DN<14>"
					( Origin gPackager )
				)
				( attribute "PNN" "UPI_CPU1_CPU0_P1P1_DN<14>"
					( Origin gPackager )
				)
				( objectStatus "UPI_CPU1_CPU0_P1P1_DN<14>" )
			)
			( signal "@baseboard_fab2_lib.baseboard_fab2(sch_1):upi_cpu1_cpu0_p1p1_dn(15)"
				( attribute "CDS_PHYS_NET_NAME" "UPI_CPU1_CPU0_P1P1_DN<15>"
					( Origin gPackager )
				)
				( attribute "PNN" "UPI_CPU1_CPU0_P1P1_DN<15>"
					( Origin gPackager )
				)
				( objectStatus "UPI_CPU1_CPU0_P1P1_DN<15>" )
			)
			( signal "@baseboard_fab2_lib.baseboard_fab2(sch_1):upi_cpu1_cpu0_p1p1_dn(16)"
				( attribute "CDS_PHYS_NET_NAME" "UPI_CPU1_CPU0_P1P1_DN<16>"
					( Origin gPackager )
				)
				( attribute "PNN" "UPI_CPU1_CPU0_P1P1_DN<16>"
					( Origin gPackager )
				)
				( objectStatus "UPI_CPU1_CPU0_P1P1_DN<16>" )
			)
			( signal "@baseboard_fab2_lib.baseboard_fab2(sch_1):upi_cpu1_cpu0_p1p1_dn(17)"
				( attribute "CDS_PHYS_NET_NAME" "UPI_CPU1_CPU0_P1P1_DN<17>"
					( Origin gPackager )
				)
				( attribute "PNN" "UPI_CPU1_CPU0_P1P1_DN<17>"
					( Origin gPackager )
				)
				( objectStatus "UPI_CPU1_CPU0_P1P1_DN<17>" )
			)
			( signal "@baseboard_fab2_lib.baseboard_fab2(sch_1):upi_cpu1_cpu0_p1p1_dn(18)"
				( attribute "CDS_PHYS_NET_NAME" "UPI_CPU1_CPU0_P1P1_DN<18>"
					( Origin gPackager )
				)
				( attribute "PNN" "UPI_CPU1_CPU0_P1P1_DN<18>"
					( Origin gPackager )
				)
				( objectStatus "UPI_CPU1_CPU0_P1P1_DN<18>" )
			)
			( signal "@baseboard_fab2_lib.baseboard_fab2(sch_1):upi_cpu1_cpu0_p1p1_dn(19)"
				( attribute "CDS_PHYS_NET_NAME" "UPI_CPU1_CPU0_P1P1_DN<19>"
					( Origin gPackager )
				)
				( attribute "PNN" "UPI_CPU1_CPU0_P1P1_DN<19>"
					( Origin gPackager )
				)
				( objectStatus "UPI_CPU1_CPU0_P1P1_DN<19>" )
			)
			( signal "@baseboard_fab2_lib.baseboard_fab2(sch_1):upi_cpu1_cpu0_p1p1_dp(0)"
				( attribute "CDS_PHYS_NET_NAME" "UPI_CPU1_CPU0_P1P1_DP<0>"
					( Origin gPackager )
				)
				( attribute "PNN" "UPI_CPU1_CPU0_P1P1_DP<0>"
					( Origin gPackager )
				)
				( objectStatus "UPI_CPU1_CPU0_P1P1_DP<0>" )
			)
			( signal "@baseboard_fab2_lib.baseboard_fab2(sch_1):upi_cpu1_cpu0_p1p1_dp(1)"
				( attribute "CDS_PHYS_NET_NAME" "UPI_CPU1_CPU0_P1P1_DP<1>"
					( Origin gPackager )
				)
				( attribute "PNN" "UPI_CPU1_CPU0_P1P1_DP<1>"
					( Origin gPackager )
				)
				( objectStatus "UPI_CPU1_CPU0_P1P1_DP<1>" )
			)
			( signal "@baseboard_fab2_lib.baseboard_fab2(sch_1):upi_cpu1_cpu0_p1p1_dp(2)"
				( attribute "CDS_PHYS_NET_NAME" "UPI_CPU1_CPU0_P1P1_DP<2>"
					( Origin gPackager )
				)
				( attribute "PNN" "UPI_CPU1_CPU0_P1P1_DP<2>"
					( Origin gPackager )
				)
				( objectStatus "UPI_CPU1_CPU0_P1P1_DP<2>" )
			)
			( signal "@baseboard_fab2_lib.baseboard_fab2(sch_1):upi_cpu1_cpu0_p1p1_dp(3)"
				( attribute "CDS_PHYS_NET_NAME" "UPI_CPU1_CPU0_P1P1_DP<3>"
					( Origin gPackager )
				)
				( attribute "PNN" "UPI_CPU1_CPU0_P1P1_DP<3>"
					( Origin gPackager )
				)
				( objectStatus "UPI_CPU1_CPU0_P1P1_DP<3>" )
			)
			( signal "@baseboard_fab2_lib.baseboard_fab2(sch_1):upi_cpu1_cpu0_p1p1_dp(4)"
				( attribute "CDS_PHYS_NET_NAME" "UPI_CPU1_CPU0_P1P1_DP<4>"
					( Origin gPackager )
				)
				( attribute "PNN" "UPI_CPU1_CPU0_P1P1_DP<4>"
					( Origin gPackager )
				)
				( objectStatus "UPI_CPU1_CPU0_P1P1_DP<4>" )
			)
			( signal "@baseboard_fab2_lib.baseboard_fab2(sch_1):upi_cpu1_cpu0_p1p1_dp(5)"
				( attribute "CDS_PHYS_NET_NAME" "UPI_CPU1_CPU0_P1P1_DP<5>"
					( Origin gPackager )
				)
				( attribute "PNN" "UPI_CPU1_CPU0_P1P1_DP<5>"
					( Origin gPackager )
				)
				( objectStatus "UPI_CPU1_CPU0_P1P1_DP<5>" )
			)
			( signal "@baseboard_fab2_lib.baseboard_fab2(sch_1):upi_cpu1_cpu0_p1p1_dp(6)"
				( attribute "CDS_PHYS_NET_NAME" "UPI_CPU1_CPU0_P1P1_DP<6>"
					( Origin gPackager )
				)
				( attribute "PNN" "UPI_CPU1_CPU0_P1P1_DP<6>"
					( Origin gPackager )
				)
				( objectStatus "UPI_CPU1_CPU0_P1P1_DP<6>" )
			)
			( signal "@baseboard_fab2_lib.baseboard_fab2(sch_1):upi_cpu1_cpu0_p1p1_dp(7)"
				( attribute "CDS_PHYS_NET_NAME" "UPI_CPU1_CPU0_P1P1_DP<7>"
					( Origin gPackager )
				)
				( attribute "PNN" "UPI_CPU1_CPU0_P1P1_DP<7>"
					( Origin gPackager )
				)
				( objectStatus "UPI_CPU1_CPU0_P1P1_DP<7>" )
			)
			( signal "@baseboard_fab2_lib.baseboard_fab2(sch_1):upi_cpu1_cpu0_p1p1_dp(8)"
				( attribute "CDS_PHYS_NET_NAME" "UPI_CPU1_CPU0_P1P1_DP<8>"
					( Origin gPackager )
				)
				( attribute "PNN" "UPI_CPU1_CPU0_P1P1_DP<8>"
					( Origin gPackager )
				)
				( objectStatus "UPI_CPU1_CPU0_P1P1_DP<8>" )
			)
			( signal "@baseboard_fab2_lib.baseboard_fab2(sch_1):upi_cpu1_cpu0_p1p1_dp(9)"
				( attribute "CDS_PHYS_NET_NAME" "UPI_CPU1_CPU0_P1P1_DP<9>"
					( Origin gPackager )
				)
				( attribute "PNN" "UPI_CPU1_CPU0_P1P1_DP<9>"
					( Origin gPackager )
				)
				( objectStatus "UPI_CPU1_CPU0_P1P1_DP<9>" )
			)
			( signal "@baseboard_fab2_lib.baseboard_fab2(sch_1):upi_cpu1_cpu0_p1p1_dp(10)"
				( attribute "CDS_PHYS_NET_NAME" "UPI_CPU1_CPU0_P1P1_DP<10>"
					( Origin gPackager )
				)
				( attribute "PNN" "UPI_CPU1_CPU0_P1P1_DP<10>"
					( Origin gPackager )
				)
				( objectStatus "UPI_CPU1_CPU0_P1P1_DP<10>" )
			)
			( signal "@baseboard_fab2_lib.baseboard_fab2(sch_1):upi_cpu1_cpu0_p1p1_dp(11)"
				( attribute "CDS_PHYS_NET_NAME" "UPI_CPU1_CPU0_P1P1_DP<11>"
					( Origin gPackager )
				)
				( attribute "PNN" "UPI_CPU1_CPU0_P1P1_DP<11>"
					( Origin gPackager )
				)
				( objectStatus "UPI_CPU1_CPU0_P1P1_DP<11>" )
			)
			( signal "@baseboard_fab2_lib.baseboard_fab2(sch_1):upi_cpu1_cpu0_p1p1_dp(12)"
				( attribute "CDS_PHYS_NET_NAME" "UPI_CPU1_CPU0_P1P1_DP<12>"
					( Origin gPackager )
				)
				( attribute "PNN" "UPI_CPU1_CPU0_P1P1_DP<12>"
					( Origin gPackager )
				)
				( objectStatus "UPI_CPU1_CPU0_P1P1_DP<12>" )
			)
			( signal "@baseboard_fab2_lib.baseboard_fab2(sch_1):upi_cpu1_cpu0_p1p1_dp(13)"
				( attribute "CDS_PHYS_NET_NAME" "UPI_CPU1_CPU0_P1P1_DP<13>"
					( Origin gPackager )
				)
				( attribute "PNN" "UPI_CPU1_CPU0_P1P1_DP<13>"
					( Origin gPackager )
				)
				( objectStatus "UPI_CPU1_CPU0_P1P1_DP<13>" )
			)
			( signal "@baseboard_fab2_lib.baseboard_fab2(sch_1):upi_cpu1_cpu0_p1p1_dp(14)"
				( attribute "CDS_PHYS_NET_NAME" "UPI_CPU1_CPU0_P1P1_DP<14>"
					( Origin gPackager )
				)
				( attribute "PNN" "UPI_CPU1_CPU0_P1P1_DP<14>"
					( Origin gPackager )
				)
				( objectStatus "UPI_CPU1_CPU0_P1P1_DP<14>" )
			)
			( signal "@baseboard_fab2_lib.baseboard_fab2(sch_1):upi_cpu1_cpu0_p1p1_dp(15)"
				( attribute "CDS_PHYS_NET_NAME" "UPI_CPU1_CPU0_P1P1_DP<15>"
					( Origin gPackager )
				)
				( attribute "PNN" "UPI_CPU1_CPU0_P1P1_DP<15>"
					( Origin gPackager )
				)
				( objectStatus "UPI_CPU1_CPU0_P1P1_DP<15>" )
			)
			( signal "@baseboard_fab2_lib.baseboard_fab2(sch_1):upi_cpu1_cpu0_p1p1_dp(16)"
				( attribute "CDS_PHYS_NET_NAME" "UPI_CPU1_CPU0_P1P1_DP<16>"
					( Origin gPackager )
				)
				( attribute "PNN" "UPI_CPU1_CPU0_P1P1_DP<16>"
					( Origin gPackager )
				)
				( objectStatus "UPI_CPU1_CPU0_P1P1_DP<16>" )
			)
			( signal "@baseboard_fab2_lib.baseboard_fab2(sch_1):upi_cpu1_cpu0_p1p1_dp(17)"
				( attribute "CDS_PHYS_NET_NAME" "UPI_CPU1_CPU0_P1P1_DP<17>"
					( Origin gPackager )
				)
				( attribute "PNN" "UPI_CPU1_CPU0_P1P1_DP<17>"
					( Origin gPackager )
				)
				( objectStatus "UPI_CPU1_CPU0_P1P1_DP<17>" )
			)
			( signal "@baseboard_fab2_lib.baseboard_fab2(sch_1):upi_cpu1_cpu0_p1p1_dp(18)"
				( attribute "CDS_PHYS_NET_NAME" "UPI_CPU1_CPU0_P1P1_DP<18>"
					( Origin gPackager )
				)
				( attribute "PNN" "UPI_CPU1_CPU0_P1P1_DP<18>"
					( Origin gPackager )
				)
				( objectStatus "UPI_CPU1_CPU0_P1P1_DP<18>" )
			)
			( signal "@baseboard_fab2_lib.baseboard_fab2(sch_1):upi_cpu1_cpu0_p1p1_dp(19)"
				( attribute "CDS_PHYS_NET_NAME" "UPI_CPU1_CPU0_P1P1_DP<19>"
					( Origin gPackager )
				)
				( attribute "PNN" "UPI_CPU1_CPU0_P1P1_DP<19>"
					( Origin gPackager )
				)
				( objectStatus "UPI_CPU1_CPU0_P1P1_DP<19>" )
			)
			( signal "@baseboard_fab2_lib.baseboard_fab2(sch_1):tp_cpu0_upi2_rsvd_ca12"
				( attribute "CDS_PHYS_NET_NAME" "TP_CPU0_UPI2_RSVD_CA12"
					( Origin gPackager )
				)
				( objectStatus "TP_CPU0_UPI2_RSVD_CA12" )
			)
			( signal "@baseboard_fab2_lib.baseboard_fab2(sch_1):tp_cpu0_upi2_rsvd_cb11"
				( attribute "CDS_PHYS_NET_NAME" "TP_CPU0_UPI2_RSVD_CB11"
					( Origin gPackager )
				)
				( objectStatus "TP_CPU0_UPI2_RSVD_CB11" )
			)
			( signal "@baseboard_fab2_lib.baseboard_fab2(sch_1):tp_cpu0_upi2_rsvd_cc10"
				( attribute "CDS_PHYS_NET_NAME" "TP_CPU0_UPI2_RSVD_CC10"
					( Origin gPackager )
				)
				( objectStatus "TP_CPU0_UPI2_RSVD_CC10" )
			)
			( signal "@baseboard_fab2_lib.baseboard_fab2(sch_1):tp_cpu0_upi2_rsvd_cc12"
				( attribute "CDS_PHYS_NET_NAME" "TP_CPU0_UPI2_RSVD_CC12"
					( Origin gPackager )
				)
				( objectStatus "TP_CPU0_UPI2_RSVD_CC12" )
			)
			( signal "@baseboard_fab2_lib.baseboard_fab2(sch_1):tp_cpu0_upi2_rsvd_cd11"
				( attribute "CDS_PHYS_NET_NAME" "TP_CPU0_UPI2_RSVD_CD11"
					( Origin gPackager )
				)
				( objectStatus "TP_CPU0_UPI2_RSVD_CD11" )
			)
			( signal "@baseboard_fab2_lib.baseboard_fab2(sch_1):tp_cpu0_upi2_rsvd_ce12"
				( attribute "CDS_PHYS_NET_NAME" "TP_CPU0_UPI2_RSVD_CE12"
					( Origin gPackager )
				)
				( objectStatus "TP_CPU0_UPI2_RSVD_CE12" )
			)
			( signal "@baseboard_fab2_lib.baseboard_fab2(sch_1):tp_cpu0_upi2_rsvd_cf11"
				( attribute "CDS_PHYS_NET_NAME" "TP_CPU0_UPI2_RSVD_CF11"
					( Origin gPackager )
				)
				( objectStatus "TP_CPU0_UPI2_RSVD_CF11" )
			)
			( signal "@baseboard_fab2_lib.baseboard_fab2(sch_1):tp_cpu0_upi2_rsvd_cf13"
				( attribute "CDS_PHYS_NET_NAME" "TP_CPU0_UPI2_RSVD_CF13"
					( Origin gPackager )
				)
				( objectStatus "TP_CPU0_UPI2_RSVD_CF13" )
			)
			( signal "@baseboard_fab2_lib.baseboard_fab2(sch_1):tp_cpu0_upi2_rsvd_cg12"
				( attribute "CDS_PHYS_NET_NAME" "TP_CPU0_UPI2_RSVD_CG12"
					( Origin gPackager )
				)
				( objectStatus "TP_CPU0_UPI2_RSVD_CG12" )
			)
			( signal "@baseboard_fab2_lib.baseboard_fab2(sch_1):tp_cpu0_upi2_rsvd_ch11"
				( attribute "CDS_PHYS_NET_NAME" "TP_CPU0_UPI2_RSVD_CH11"
					( Origin gPackager )
				)
				( objectStatus "TP_CPU0_UPI2_RSVD_CH11" )
			)
			( signal "@baseboard_fab2_lib.baseboard_fab2(sch_1):tp_cpu0_upi2_rsvd_ch13"
				( attribute "CDS_PHYS_NET_NAME" "TP_CPU0_UPI2_RSVD_CH13"
					( Origin gPackager )
				)
				( objectStatus "TP_CPU0_UPI2_RSVD_CH13" )
			)
			( signal "@baseboard_fab2_lib.baseboard_fab2(sch_1):tp_cpu0_upi2_rsvd_cj14"
				( attribute "CDS_PHYS_NET_NAME" "TP_CPU0_UPI2_RSVD_CJ14"
					( Origin gPackager )
				)
				( objectStatus "TP_CPU0_UPI2_RSVD_CJ14" )
			)
			( signal "@baseboard_fab2_lib.baseboard_fab2(sch_1):tp_cpu0_upi2_rsvd_ck13"
				( attribute "CDS_PHYS_NET_NAME" "TP_CPU0_UPI2_RSVD_CK13"
					( Origin gPackager )
				)
				( objectStatus "TP_CPU0_UPI2_RSVD_CK13" )
			)
			( signal "@baseboard_fab2_lib.baseboard_fab2(sch_1):tp_cpu0_upi2_rsvd_cm13"
				( attribute "CDS_PHYS_NET_NAME" "TP_CPU0_UPI2_RSVD_CM13"
					( Origin gPackager )
				)
				( objectStatus "TP_CPU0_UPI2_RSVD_CM13" )
			)
			( signal "@baseboard_fab2_lib.baseboard_fab2(sch_1):tp_cpu0_upi2_rsvd_cr14"
				( attribute "CDS_PHYS_NET_NAME" "TP_CPU0_UPI2_RSVD_CR14"
					( Origin gPackager )
				)
				( objectStatus "TP_CPU0_UPI2_RSVD_CR14" )
			)
			( signal "@baseboard_fab2_lib.baseboard_fab2(sch_1):tp_cpu0_upi2_rsvd_cu14"
				( attribute "CDS_PHYS_NET_NAME" "TP_CPU0_UPI2_RSVD_CU14"
					( Origin gPackager )
				)
				( objectStatus "TP_CPU0_UPI2_RSVD_CU14" )
			)
			( signal "@baseboard_fab2_lib.baseboard_fab2(sch_1):tp_cpu0_upi2_rsvd_cv13"
				( attribute "CDS_PHYS_NET_NAME" "TP_CPU0_UPI2_RSVD_CV13"
					( Origin gPackager )
				)
				( objectStatus "TP_CPU0_UPI2_RSVD_CV13" )
			)
			( signal "@baseboard_fab2_lib.baseboard_fab2(sch_1):tp_cpu0_upi2_rsvd_cw14"
				( attribute "CDS_PHYS_NET_NAME" "TP_CPU0_UPI2_RSVD_CW14"
					( Origin gPackager )
				)
				( objectStatus "TP_CPU0_UPI2_RSVD_CW14" )
			)
			( signal "@baseboard_fab2_lib.baseboard_fab2(sch_1):tp_cpu0_upi2_rsvd_cw16"
				( attribute "CDS_PHYS_NET_NAME" "TP_CPU0_UPI2_RSVD_CW16"
					( Origin gPackager )
				)
				( objectStatus "TP_CPU0_UPI2_RSVD_CW16" )
			)
			( signal "@baseboard_fab2_lib.baseboard_fab2(sch_1):tp_cpu0_upi2_rsvd_da16"
				( attribute "CDS_PHYS_NET_NAME" "TP_CPU0_UPI2_RSVD_DA16"
					( Origin gPackager )
				)
				( objectStatus "TP_CPU0_UPI2_RSVD_DA16" )
			)
			( signal "@baseboard_fab2_lib.baseboard_fab2(sch_1):tp_cpu0_upi2_rsvd_db15"
				( attribute "CDS_PHYS_NET_NAME" "TP_CPU0_UPI2_RSVD_DB15"
					( Origin gPackager )
				)
				( objectStatus "TP_CPU0_UPI2_RSVD_DB15" )
			)
			( signal "@baseboard_fab2_lib.baseboard_fab2(sch_1):tp_cpu0_upi2_rsvd_dc16"
				( attribute "CDS_PHYS_NET_NAME" "TP_CPU0_UPI2_RSVD_DC16"
					( Origin gPackager )
				)
				( objectStatus "TP_CPU0_UPI2_RSVD_DC16" )
			)
			( signal "@baseboard_fab2_lib.baseboard_fab2(sch_1):tp_cpu0_upi2_rsvd_dd15"
				( attribute "CDS_PHYS_NET_NAME" "TP_CPU0_UPI2_RSVD_DD15"
					( Origin gPackager )
				)
				( objectStatus "TP_CPU0_UPI2_RSVD_DD15" )
			)
			( signal "@baseboard_fab2_lib.baseboard_fab2(sch_1):tp_cpu0_upi2_rsvd_dd17"
				( attribute "CDS_PHYS_NET_NAME" "TP_CPU0_UPI2_RSVD_DD17"
					( Origin gPackager )
				)
				( objectStatus "TP_CPU0_UPI2_RSVD_DD17" )
			)
			( signal "@baseboard_fab2_lib.baseboard_fab2(sch_1):tp_cpu0_upi2_rsvd_de16"
				( attribute "CDS_PHYS_NET_NAME" "TP_CPU0_UPI2_RSVD_DE16"
					( Origin gPackager )
				)
				( objectStatus "TP_CPU0_UPI2_RSVD_DE16" )
			)
			( signal "@baseboard_fab2_lib.baseboard_fab2(sch_1):tp_cpu0_upi2_rsvd_df15"
				( attribute "CDS_PHYS_NET_NAME" "TP_CPU0_UPI2_RSVD_DF15"
					( Origin gPackager )
				)
				( objectStatus "TP_CPU0_UPI2_RSVD_DF15" )
			)
			( signal "@baseboard_fab2_lib.baseboard_fab2(sch_1):tp_cpu0_upi2_rsvd_df17"
				( attribute "CDS_PHYS_NET_NAME" "TP_CPU0_UPI2_RSVD_DF17"
					( Origin gPackager )
				)
				( objectStatus "TP_CPU0_UPI2_RSVD_DF17" )
			)
			( signal "@baseboard_fab2_lib.baseboard_fab2(sch_1):tp_cpu0_upi2_rsvd_dg18"
				( attribute "CDS_PHYS_NET_NAME" "TP_CPU0_UPI2_RSVD_DG18"
					( Origin gPackager )
				)
				( objectStatus "TP_CPU0_UPI2_RSVD_DG18" )
			)
			( signal "@baseboard_fab2_lib.baseboard_fab2(sch_1):tp_cpu0_upi2_rsvd_dg20"
				( attribute "CDS_PHYS_NET_NAME" "TP_CPU0_UPI2_RSVD_DG20"
					( Origin gPackager )
				)
				( objectStatus "TP_CPU0_UPI2_RSVD_DG20" )
			)
			( signal "@baseboard_fab2_lib.baseboard_fab2(sch_1):tp_cpu0_upi2_rsvd_dh17"
				( attribute "CDS_PHYS_NET_NAME" "TP_CPU0_UPI2_RSVD_DH17"
					( Origin gPackager )
				)
				( objectStatus "TP_CPU0_UPI2_RSVD_DH17" )
			)
			( signal "@baseboard_fab2_lib.baseboard_fab2(sch_1):tp_cpu0_upi2_rsvd_dh19"
				( attribute "CDS_PHYS_NET_NAME" "TP_CPU0_UPI2_RSVD_DH19"
					( Origin gPackager )
				)
				( objectStatus "TP_CPU0_UPI2_RSVD_DH19" )
			)
			( signal "@baseboard_fab2_lib.baseboard_fab2(sch_1):tp_cpu0_upi2_rsvd_dj18"
				( attribute "CDS_PHYS_NET_NAME" "TP_CPU0_UPI2_RSVD_DJ18"
					( Origin gPackager )
				)
				( objectStatus "TP_CPU0_UPI2_RSVD_DJ18" )
			)
			( signal "@baseboard_fab2_lib.baseboard_fab2(sch_1):tp_cpu0_upi2_rsvd_dj20"
				( attribute "CDS_PHYS_NET_NAME" "TP_CPU0_UPI2_RSVD_DJ20"
					( Origin gPackager )
				)
				( objectStatus "TP_CPU0_UPI2_RSVD_DJ20" )
			)
			( signal "@baseboard_fab2_lib.baseboard_fab2(sch_1):tp_cpu0_upi2_rsvd_dk17"
				( attribute "CDS_PHYS_NET_NAME" "TP_CPU0_UPI2_RSVD_DK17"
					( Origin gPackager )
				)
				( objectStatus "TP_CPU0_UPI2_RSVD_DK17" )
			)
			( signal "@baseboard_fab2_lib.baseboard_fab2(sch_1):tp_cpu0_upi2_rsvd_dk19"
				( attribute "CDS_PHYS_NET_NAME" "TP_CPU0_UPI2_RSVD_DK19"
					( Origin gPackager )
				)
				( objectStatus "TP_CPU0_UPI2_RSVD_DK19" )
			)
			( signal "@baseboard_fab2_lib.baseboard_fab2(sch_1):tp_cpu0_upi2_rsvd_dl20"
				( attribute "CDS_PHYS_NET_NAME" "TP_CPU0_UPI2_RSVD_DL20"
					( Origin gPackager )
				)
				( objectStatus "TP_CPU0_UPI2_RSVD_DL20" )
			)
			( signal "@baseboard_fab2_lib.baseboard_fab2(sch_1):tp_cpu0_upi2_rsvd_dm21"
				( attribute "CDS_PHYS_NET_NAME" "TP_CPU0_UPI2_RSVD_DM21"
					( Origin gPackager )
				)
				( objectStatus "TP_CPU0_UPI2_RSVD_DM21" )
			)
			( signal "@baseboard_fab2_lib.baseboard_fab2(sch_1):tp_cpu0_upi2_rsvd_dn20"
				( attribute "CDS_PHYS_NET_NAME" "TP_CPU0_UPI2_RSVD_DN20"
					( Origin gPackager )
				)
				( objectStatus "TP_CPU0_UPI2_RSVD_DN20" )
			)
			( signal "@baseboard_fab2_lib.baseboard_fab2(sch_1):tp_cpu0_upi2_rsvd_dp21"
				( attribute "CDS_PHYS_NET_NAME" "TP_CPU0_UPI2_RSVD_DP21"
					( Origin gPackager )
				)
				( objectStatus "TP_CPU0_UPI2_RSVD_DP21" )
			)
			( signal "@baseboard_fab2_lib.baseboard_fab2(sch_1):tp_cpu0_upi2_rsvd_dt21"
				( attribute "CDS_PHYS_NET_NAME" "TP_CPU0_UPI2_RSVD_DT21"
					( Origin gPackager )
				)
				( objectStatus "TP_CPU0_UPI2_RSVD_DT21" )
			)
			( signal "@baseboard_fab2_lib.baseboard_fab2(sch_1):clk_100m_cpu0_rc_refclk1_dn"
				( attribute "CDS_PHYS_NET_NAME" "CLK_100M_CPU0_RC_REFCLK1_DN"
					( Origin gPackager )
				)
				( objectStatus "CLK_100M_CPU0_RC_REFCLK1_DN" )
			)
			( signal "@baseboard_fab2_lib.baseboard_fab2(sch_1):clk_100m_cpu0_rc_refclk1_dp"
				( attribute "CDS_PHYS_NET_NAME" "CLK_100M_CPU0_RC_REFCLK1_DP"
					( Origin gPackager )
				)
				( objectStatus "CLK_100M_CPU0_RC_REFCLK1_DP" )
			)
			( signal "@baseboard_fab2_lib.baseboard_fab2(sch_1):tp_cpu0_rsvd_100"
				( attribute "CDS_PHYS_NET_NAME" "TP_CPU0_RSVD_100"
					( Origin gPackager )
				)
				( objectStatus "TP_CPU0_RSVD_100" )
			)
			( signal "@baseboard_fab2_lib.baseboard_fab2(sch_1):tp_cpu0_rsvd_101"
				( attribute "CDS_PHYS_NET_NAME" "TP_CPU0_RSVD_101"
					( Origin gPackager )
				)
				( objectStatus "TP_CPU0_RSVD_101" )
			)
			( signal "@baseboard_fab2_lib.baseboard_fab2(sch_1):tp_cpu0_rsvd_105"
				( attribute "CDS_PHYS_NET_NAME" "TP_CPU0_RSVD_105"
					( Origin gPackager )
				)
				( objectStatus "TP_CPU0_RSVD_105" )
			)
			( signal "@baseboard_fab2_lib.baseboard_fab2(sch_1):tp_cpu0_rsvd_106"
				( attribute "CDS_PHYS_NET_NAME" "TP_CPU0_RSVD_106"
					( Origin gPackager )
				)
				( objectStatus "TP_CPU0_RSVD_106" )
			)
			( signal "@baseboard_fab2_lib.baseboard_fab2(sch_1):tp_cpu0_rsvd_108"
				( attribute "CDS_PHYS_NET_NAME" "TP_CPU0_RSVD_108"
					( Origin gPackager )
				)
				( objectStatus "TP_CPU0_RSVD_108" )
			)
			( signal "@baseboard_fab2_lib.baseboard_fab2(sch_1):tp_cpu0_rsvd_111"
				( attribute "CDS_PHYS_NET_NAME" "TP_CPU0_RSVD_111"
					( Origin gPackager )
				)
				( objectStatus "TP_CPU0_RSVD_111" )
			)
			( signal "@baseboard_fab2_lib.baseboard_fab2(sch_1):tp_cpu0_rsvd_113"
				( attribute "CDS_PHYS_NET_NAME" "TP_CPU0_RSVD_113"
					( Origin gPackager )
				)
				( objectStatus "TP_CPU0_RSVD_113" )
			)
			( signal "@baseboard_fab2_lib.baseboard_fab2(sch_1):tp_cpu0_rsvd_114"
				( attribute "CDS_PHYS_NET_NAME" "TP_CPU0_RSVD_114"
					( Origin gPackager )
				)
				( objectStatus "TP_CPU0_RSVD_114" )
			)
			( signal "@baseboard_fab2_lib.baseboard_fab2(sch_1):tp_cpu0_rsvd_117"
				( attribute "CDS_PHYS_NET_NAME" "TP_CPU0_RSVD_117"
					( Origin gPackager )
				)
				( objectStatus "TP_CPU0_RSVD_117" )
			)
			( signal "@baseboard_fab2_lib.baseboard_fab2(sch_1):tp_cpu0_rsvd_119"
				( attribute "CDS_PHYS_NET_NAME" "TP_CPU0_RSVD_119"
					( Origin gPackager )
				)
				( objectStatus "TP_CPU0_RSVD_119" )
			)
			( signal "@baseboard_fab2_lib.baseboard_fab2(sch_1):tp_cpu0_rsvd_121"
				( attribute "CDS_PHYS_NET_NAME" "TP_CPU0_RSVD_121"
					( Origin gPackager )
				)
				( objectStatus "TP_CPU0_RSVD_121" )
			)
			( signal "@baseboard_fab2_lib.baseboard_fab2(sch_1):tp_cpu0_rsvd_123"
				( attribute "CDS_PHYS_NET_NAME" "TP_CPU0_RSVD_123"
					( Origin gPackager )
				)
				( objectStatus "TP_CPU0_RSVD_123" )
			)
			( signal "@baseboard_fab2_lib.baseboard_fab2(sch_1):tp_cpu0_rsvd_124"
				( attribute "CDS_PHYS_NET_NAME" "TP_CPU0_RSVD_124"
					( Origin gPackager )
				)
				( objectStatus "TP_CPU0_RSVD_124" )
			)
			( signal "@baseboard_fab2_lib.baseboard_fab2(sch_1):tp_cpu0_rsvd_144"
				( attribute "CDS_PHYS_NET_NAME" "TP_CPU0_RSVD_144"
					( Origin gPackager )
				)
				( objectStatus "TP_CPU0_RSVD_144" )
			)
			( signal "@baseboard_fab2_lib.baseboard_fab2(sch_1):tp_cpu0_rsvd_145"
				( attribute "CDS_PHYS_NET_NAME" "TP_CPU0_RSVD_145"
					( Origin gPackager )
				)
				( objectStatus "TP_CPU0_RSVD_145" )
			)
			( signal "@baseboard_fab2_lib.baseboard_fab2(sch_1):tp_cpu0_rsvd_146"
				( attribute "CDS_PHYS_NET_NAME" "TP_CPU0_RSVD_146"
					( Origin gPackager )
				)
				( objectStatus "TP_CPU0_RSVD_146" )
			)
			( signal "@baseboard_fab2_lib.baseboard_fab2(sch_1):tp_cpu0_rsvd_147"
				( attribute "CDS_PHYS_NET_NAME" "TP_CPU0_RSVD_147"
					( Origin gPackager )
				)
				( objectStatus "TP_CPU0_RSVD_147" )
			)
			( signal "@baseboard_fab2_lib.baseboard_fab2(sch_1):tp_cpu0_rsvd_148"
				( attribute "CDS_PHYS_NET_NAME" "TP_CPU0_RSVD_148"
					( Origin gPackager )
				)
				( objectStatus "TP_CPU0_RSVD_148" )
			)
			( signal "@baseboard_fab2_lib.baseboard_fab2(sch_1):tp_cpu0_rsvd_149"
				( attribute "CDS_PHYS_NET_NAME" "TP_CPU0_RSVD_149"
					( Origin gPackager )
				)
				( objectStatus "TP_CPU0_RSVD_149" )
			)
			( signal "@baseboard_fab2_lib.baseboard_fab2(sch_1):tp_cpu0_rsvd_150"
				( attribute "CDS_PHYS_NET_NAME" "TP_CPU0_RSVD_150"
					( Origin gPackager )
				)
				( objectStatus "TP_CPU0_RSVD_150" )
			)
			( signal "@baseboard_fab2_lib.baseboard_fab2(sch_1):tp_cpu0_rsvd_151"
				( attribute "CDS_PHYS_NET_NAME" "TP_CPU0_RSVD_151"
					( Origin gPackager )
				)
				( objectStatus "TP_CPU0_RSVD_151" )
			)
			( signal "@baseboard_fab2_lib.baseboard_fab2(sch_1):tp_cpu0_rsvd_152"
				( attribute "CDS_PHYS_NET_NAME" "TP_CPU0_RSVD_152"
					( Origin gPackager )
				)
				( objectStatus "TP_CPU0_RSVD_152" )
			)
			( signal "@baseboard_fab2_lib.baseboard_fab2(sch_1):tp_cpu0_rsvd_154"
				( attribute "CDS_PHYS_NET_NAME" "TP_CPU0_RSVD_154"
					( Origin gPackager )
				)
				( objectStatus "TP_CPU0_RSVD_154" )
			)
			( signal "@baseboard_fab2_lib.baseboard_fab2(sch_1):tp_cpu0_rsvd_155"
				( attribute "CDS_PHYS_NET_NAME" "TP_CPU0_RSVD_155"
					( Origin gPackager )
				)
				( objectStatus "TP_CPU0_RSVD_155" )
			)
			( signal "@baseboard_fab2_lib.baseboard_fab2(sch_1):tp_cpu0_rsvd_156"
				( attribute "CDS_PHYS_NET_NAME" "TP_CPU0_RSVD_156"
					( Origin gPackager )
				)
				( objectStatus "TP_CPU0_RSVD_156" )
			)
			( signal "@baseboard_fab2_lib.baseboard_fab2(sch_1):tp_cpu0_rsvd_157"
				( attribute "CDS_PHYS_NET_NAME" "TP_CPU0_RSVD_157"
					( Origin gPackager )
				)
				( objectStatus "TP_CPU0_RSVD_157" )
			)
			( signal "@baseboard_fab2_lib.baseboard_fab2(sch_1):tp_cpu0_rsvd_158"
				( attribute "CDS_PHYS_NET_NAME" "TP_CPU0_RSVD_158"
					( Origin gPackager )
				)
				( objectStatus "TP_CPU0_RSVD_158" )
			)
			( signal "@baseboard_fab2_lib.baseboard_fab2(sch_1):tp_cpu0_rsvd_159"
				( attribute "CDS_PHYS_NET_NAME" "TP_CPU0_RSVD_159"
					( Origin gPackager )
				)
				( objectStatus "TP_CPU0_RSVD_159" )
			)
			( signal "@baseboard_fab2_lib.baseboard_fab2(sch_1):tp_cpu0_rsvd_160"
				( attribute "CDS_PHYS_NET_NAME" "TP_CPU0_RSVD_160"
					( Origin gPackager )
				)
				( objectStatus "TP_CPU0_RSVD_160" )
			)
			( signal "@baseboard_fab2_lib.baseboard_fab2(sch_1):tp_cpu0_rsvd_161"
				( attribute "CDS_PHYS_NET_NAME" "TP_CPU0_RSVD_161"
					( Origin gPackager )
				)
				( objectStatus "TP_CPU0_RSVD_161" )
			)
			( signal "@baseboard_fab2_lib.baseboard_fab2(sch_1):tp_cpu0_rsvd_162"
				( attribute "CDS_PHYS_NET_NAME" "TP_CPU0_RSVD_162"
					( Origin gPackager )
				)
				( objectStatus "TP_CPU0_RSVD_162" )
			)
			( signal "@baseboard_fab2_lib.baseboard_fab2(sch_1):tp_cpu0_rsvd_163"
				( attribute "CDS_PHYS_NET_NAME" "TP_CPU0_RSVD_163"
					( Origin gPackager )
				)
				( objectStatus "TP_CPU0_RSVD_163" )
			)
			( signal "@baseboard_fab2_lib.baseboard_fab2(sch_1):tp_cpu0_rsvd_164"
				( attribute "CDS_PHYS_NET_NAME" "TP_CPU0_RSVD_164"
					( Origin gPackager )
				)
				( objectStatus "TP_CPU0_RSVD_164" )
			)
			( signal "@baseboard_fab2_lib.baseboard_fab2(sch_1):tp_cpu0_rsvd_166"
				( attribute "CDS_PHYS_NET_NAME" "TP_CPU0_RSVD_166"
					( Origin gPackager )
				)
				( objectStatus "TP_CPU0_RSVD_166" )
			)
			( signal "@baseboard_fab2_lib.baseboard_fab2(sch_1):tp_cpu0_rsvd_167"
				( attribute "CDS_PHYS_NET_NAME" "TP_CPU0_RSVD_167"
					( Origin gPackager )
				)
				( objectStatus "TP_CPU0_RSVD_167" )
			)
			( signal "@baseboard_fab2_lib.baseboard_fab2(sch_1):tp_cpu0_rsvd_168"
				( attribute "CDS_PHYS_NET_NAME" "TP_CPU0_RSVD_168"
					( Origin gPackager )
				)
				( objectStatus "TP_CPU0_RSVD_168" )
			)
			( signal "@baseboard_fab2_lib.baseboard_fab2(sch_1):tp_cpu0_rsvd_169"
				( attribute "CDS_PHYS_NET_NAME" "TP_CPU0_RSVD_169"
					( Origin gPackager )
				)
				( objectStatus "TP_CPU0_RSVD_169" )
			)
			( signal "@baseboard_fab2_lib.baseboard_fab2(sch_1):tp_cpu0_rsvd_170"
				( attribute "CDS_PHYS_NET_NAME" "TP_CPU0_RSVD_170"
					( Origin gPackager )
				)
				( objectStatus "TP_CPU0_RSVD_170" )
			)
			( signal "@baseboard_fab2_lib.baseboard_fab2(sch_1):tp_cpu0_rsvd_171"
				( attribute "CDS_PHYS_NET_NAME" "TP_CPU0_RSVD_171"
					( Origin gPackager )
				)
				( objectStatus "TP_CPU0_RSVD_171" )
			)
			( signal "@baseboard_fab2_lib.baseboard_fab2(sch_1):tp_cpu0_rsvd_255"
				( attribute "CDS_PHYS_NET_NAME" "TP_CPU0_RSVD_255"
					( Origin gPackager )
				)
				( objectStatus "TP_CPU0_RSVD_255" )
			)
			( signal "@baseboard_fab2_lib.baseboard_fab2(sch_1):tp_cpu0_rsvd_82"
				( attribute "CDS_PHYS_NET_NAME" "TP_CPU0_RSVD_82"
					( Origin gPackager )
				)
				( objectStatus "TP_CPU0_RSVD_82" )
			)
			( signal "@baseboard_fab2_lib.baseboard_fab2(sch_1):tp_cpu0_rsvd_85"
				( attribute "CDS_PHYS_NET_NAME" "TP_CPU0_RSVD_85"
					( Origin gPackager )
				)
				( objectStatus "TP_CPU0_RSVD_85" )
			)
			( signal "@baseboard_fab2_lib.baseboard_fab2(sch_1):tp_cpu0_rsvd_90"
				( attribute "CDS_PHYS_NET_NAME" "TP_CPU0_RSVD_90"
					( Origin gPackager )
				)
				( objectStatus "TP_CPU0_RSVD_90" )
			)
			( signal "@baseboard_fab2_lib.baseboard_fab2(sch_1):tp_cpu0_rsvd_91"
				( attribute "CDS_PHYS_NET_NAME" "TP_CPU0_RSVD_91"
					( Origin gPackager )
				)
				( objectStatus "TP_CPU0_RSVD_91" )
			)
			( signal "@baseboard_fab2_lib.baseboard_fab2(sch_1):tp_cpu0_rsvd_94"
				( attribute "CDS_PHYS_NET_NAME" "TP_CPU0_RSVD_94"
					( Origin gPackager )
				)
				( objectStatus "TP_CPU0_RSVD_94" )
			)
			( signal "@baseboard_fab2_lib.baseboard_fab2(sch_1):tp_cpu0_rsvd_95"
				( attribute "CDS_PHYS_NET_NAME" "TP_CPU0_RSVD_95"
					( Origin gPackager )
				)
				( objectStatus "TP_CPU0_RSVD_95" )
			)
			( signal "@baseboard_fab2_lib.baseboard_fab2(sch_1):tp_cpu0_rsvd_97"
				( attribute "CDS_PHYS_NET_NAME" "TP_CPU0_RSVD_97"
					( Origin gPackager )
				)
				( objectStatus "TP_CPU0_RSVD_97" )
			)
			( signal "@baseboard_fab2_lib.baseboard_fab2(sch_1):tp_cpu0_rsvd_99"
				( attribute "CDS_PHYS_NET_NAME" "TP_CPU0_RSVD_99"
					( Origin gPackager )
				)
				( objectStatus "TP_CPU0_RSVD_99" )
			)
			( signal "@baseboard_fab2_lib.baseboard_fab2(sch_1):tp_cpu0_test_10"
				( attribute "CDS_PHYS_NET_NAME" "TP_CPU0_TEST_10"
					( Origin gPackager )
				)
				( objectStatus "TP_CPU0_TEST_10" )
			)
			( signal "@baseboard_fab2_lib.baseboard_fab2(sch_1):tp_cpu0_test_6"
				( attribute "CDS_PHYS_NET_NAME" "TP_CPU0_TEST_6"
					( Origin gPackager )
				)
				( objectStatus "TP_CPU0_TEST_6" )
			)
			( signal "@baseboard_fab2_lib.baseboard_fab2(sch_1):tp_cpu0_test_7"
				( attribute "CDS_PHYS_NET_NAME" "TP_CPU0_TEST_7"
					( Origin gPackager )
				)
				( objectStatus "TP_CPU0_TEST_7" )
			)
			( signal "@baseboard_fab2_lib.baseboard_fab2(sch_1):tp_cpu0_test_8"
				( attribute "CDS_PHYS_NET_NAME" "TP_CPU0_TEST_8"
					( Origin gPackager )
				)
				( objectStatus "TP_CPU0_TEST_8" )
			)
			( signal "@baseboard_fab2_lib.baseboard_fab2(sch_1):tp_cpu0_test_9"
				( attribute "CDS_PHYS_NET_NAME" "TP_CPU0_TEST_9"
					( Origin gPackager )
				)
				( objectStatus "TP_CPU0_TEST_9" )
			)
			( signal "@baseboard_fab2_lib.baseboard_fab2(sch_1):pvccin_cpu0"
				( alias ( signalRef "@baseboard_fab2_lib.baseboard_fab2(sch_1):page37_pvccin_cpu0") )
				( alias ( signalRef "@baseboard_fab2_lib.baseboard_fab2(sch_1):page42_pvccin_cpu0") )
				( alias ( signalRef "@baseboard_fab2_lib.baseboard_fab2(sch_1):page202_pvccin_cpu0") )
				( alias ( signalRef "@baseboard_fab2_lib.baseboard_fab2(sch_1):page203_pvccin_cpu0") )
				( alias ( signalRef "@baseboard_fab2_lib.baseboard_fab2(sch_1):page204_pvccin_cpu0") )
				( attribute "CDS_PHYS_NET_NAME" "PVCCIN_CPU0"
					( Origin gPackager )
				)
				( attribute "PHYS_NET_NAME" "PVCCIN_CPU0"
					( Origin gPackager )
				)
				( attribute "VOLTAGE" "2.0V"
					( Units "uVoltage" "V" 1.000000)
					( Status sAliasFlattened )
					( Origin gFrontEnd )
				)
				( objectStatus "PVCCIN_CPU0" )
			)
			( signal "@baseboard_fab2_lib.baseboard_fab2(sch_1):page37_pvccin_cpu0"
				( attribute "VOLTAGE" "2.0V"
					( Units "uVoltage" "V" 1.000000)
					( Origin gFrontEnd )
				)
				( objectFlag fObjectAlias )
				( objectStatus "page37_pvccin_cpu0" )
			)
			( signal "@baseboard_fab2_lib.baseboard_fab2(sch_1):page42_pvccin_cpu0"
				( attribute "VOLTAGE" "2.0V"
					( Units "uVoltage" "V" 1.000000)
					( Origin gFrontEnd )
				)
				( objectFlag fObjectAlias )
				( objectStatus "page42_pvccin_cpu0" )
			)
			( signal "@baseboard_fab2_lib.baseboard_fab2(sch_1):page202_pvccin_cpu0"
				( attribute "VOLTAGE" "2.0V"
					( Units "uVoltage" "V" 1.000000)
					( Origin gFrontEnd )
				)
				( objectFlag fObjectAlias )
				( objectStatus "page202_pvccin_cpu0" )
			)
			( signal "@baseboard_fab2_lib.baseboard_fab2(sch_1):page203_pvccin_cpu0"
				( attribute "VOLTAGE" "2.0V"
					( Units "uVoltage" "V" 1.000000)
					( Origin gFrontEnd )
				)
				( objectFlag fObjectAlias )
				( objectStatus "page203_pvccin_cpu0" )
			)
			( signal "@baseboard_fab2_lib.baseboard_fab2(sch_1):page204_pvccin_cpu0"
				( attribute "VOLTAGE" "2.0V"
					( Units "uVoltage" "V" 1.000000)
					( Origin gFrontEnd )
				)
				( objectFlag fObjectAlias )
				( objectStatus "page204_pvccin_cpu0" )
			)
			( signal "@baseboard_fab2_lib.baseboard_fab2(sch_1):vsense_pmax_cpu0"
				( attribute "CDS_PHYS_NET_NAME" "VSENSE_PMAX_CPU0"
					( Origin gPackager )
				)
				( objectStatus "VSENSE_PMAX_CPU0" )
			)
			( signal "@baseboard_fab2_lib.baseboard_fab2(sch_1):vsense_pvccin_cpu0_skt_vrtn"
				( attribute "CDS_PHYS_NET_NAME" "VSENSE_PVCCIN_CPU0_SKT_VRTN"
					( Origin gPackager )
				)
				( objectStatus "VSENSE_PVCCIN_CPU0_SKT_VRTN" )
			)
			( signal "@baseboard_fab2_lib.baseboard_fab2(sch_1):vsense_pvccin_cpu0_skt_vsen"
				( attribute "CDS_PHYS_NET_NAME" "VSENSE_PVCCIN_CPU0_SKT_VSEN"
					( Origin gPackager )
				)
				( objectStatus "VSENSE_PVCCIN_CPU0_SKT_VSEN" )
			)
			( signal "@baseboard_fab2_lib.baseboard_fab2(sch_1):vsense_vccinr2pmax_cpu0"
				( attribute "CDS_PHYS_NET_NAME" "VSENSE_VCCINR2PMAX_CPU0"
					( Origin gPackager )
				)
				( objectStatus "VSENSE_VCCINR2PMAX_CPU0" )
			)
			( signal "@baseboard_fab2_lib.baseboard_fab2(sch_1):pvcciomcp_cpu0"
				( alias ( signalRef "@baseboard_fab2_lib.baseboard_fab2(sch_1):page38_pvcciomcp_cpu0") )
				( alias ( signalRef "@baseboard_fab2_lib.baseboard_fab2(sch_1):page194_pvcciomcp_cpu0") )
				( alias ( signalRef "@baseboard_fab2_lib.baseboard_fab2(sch_1):page36_pvcciomcp_cpu0") )
				( attribute "CDS_PHYS_NET_NAME" "PVCCIOMCP_CPU0"
					( Origin gPackager )
				)
				( attribute "VOLTAGE" "+0.95"
					( Units "uVoltage" "V" 1.000000)
					( Status sAliasFlattened )
					( Origin gFrontEnd )
				)
				( objectStatus "PVCCIOMCP_CPU0" )
			)
			( signal "@baseboard_fab2_lib.baseboard_fab2(sch_1):page38_pvcciomcp_cpu0"
				( objectFlag fObjectAlias )
				( objectStatus "page38_pvcciomcp_cpu0" )
			)
			( signal "@baseboard_fab2_lib.baseboard_fab2(sch_1):page194_pvcciomcp_cpu0"
				( attribute "VOLTAGE" "+0.95"
					( Units "uVoltage" "V" 1.000000)
					( Origin gFrontEnd )
				)
				( objectFlag fObjectAlias )
				( objectStatus "page194_pvcciomcp_cpu0" )
			)
			( signal "@baseboard_fab2_lib.baseboard_fab2(sch_1):page36_pvcciomcp_cpu0"
				( objectFlag fObjectAlias )
				( objectStatus "page36_pvcciomcp_cpu0" )
			)
			( signal "@baseboard_fab2_lib.baseboard_fab2(sch_1):pvddq_abc"
				( alias ( signalRef "@baseboard_fab2_lib.baseboard_fab2(sch_1):page38_pvddq_abc") )
				( alias ( signalRef "@baseboard_fab2_lib.baseboard_fab2(sch_1):page43_pvddq_abc") )
				( alias ( signalRef "@baseboard_fab2_lib.baseboard_fab2(sch_1):page44_pvddq_abc") )
				( alias ( signalRef "@baseboard_fab2_lib.baseboard_fab2(sch_1):page45_pvddq_abc") )
				( alias ( signalRef "@baseboard_fab2_lib.baseboard_fab2(sch_1):page46_pvddq_abc") )
				( alias ( signalRef "@baseboard_fab2_lib.baseboard_fab2(sch_1):page47_pvddq_abc") )
				( alias ( signalRef "@baseboard_fab2_lib.baseboard_fab2(sch_1):page48_pvddq_abc") )
				( alias ( signalRef "@baseboard_fab2_lib.baseboard_fab2(sch_1):page96_pvddq_abc") )
				( alias ( signalRef "@baseboard_fab2_lib.baseboard_fab2(sch_1):page98_pvddq_abc") )
				( alias ( signalRef "@baseboard_fab2_lib.baseboard_fab2(sch_1):page216_pvddq_abc") )
				( alias ( signalRef "@baseboard_fab2_lib.baseboard_fab2(sch_1):page217_pvddq_abc") )
				( alias ( signalRef "@baseboard_fab2_lib.baseboard_fab2(sch_1):page221_pvddq_abc") )
				( alias ( signalRef "@baseboard_fab2_lib.baseboard_fab2(sch_1):page242_pvddq_abc") )
				( attribute "CDS_PHYS_NET_NAME" "PVDDQ_ABC"
					( Origin gPackager )
				)
				( attribute "VOLTAGE" "1.2V"
					( Units "uVoltage" "V" 1.000000)
					( Status sAliasFlattened )
					( Origin gFrontEnd )
				)
				( objectStatus "PVDDQ_ABC" )
			)
			( signal "@baseboard_fab2_lib.baseboard_fab2(sch_1):page38_pvddq_abc"
				( attribute "VOLTAGE" "1.2V"
					( Units "uVoltage" "V" 1.000000)
					( Origin gFrontEnd )
				)
				( objectFlag fObjectAlias )
				( objectStatus "page38_pvddq_abc" )
			)
			( signal "@baseboard_fab2_lib.baseboard_fab2(sch_1):page43_pvddq_abc"
				( attribute "VOLTAGE" "1.2V"
					( Units "uVoltage" "V" 1.000000)
					( Origin gFrontEnd )
				)
				( objectFlag fObjectAlias )
				( objectStatus "page43_pvddq_abc" )
			)
			( signal "@baseboard_fab2_lib.baseboard_fab2(sch_1):page44_pvddq_abc"
				( attribute "VOLTAGE" "1.2V"
					( Units "uVoltage" "V" 1.000000)
					( Origin gFrontEnd )
				)
				( objectFlag fObjectAlias )
				( objectStatus "page44_pvddq_abc" )
			)
			( signal "@baseboard_fab2_lib.baseboard_fab2(sch_1):page45_pvddq_abc"
				( attribute "VOLTAGE" "1.2V"
					( Units "uVoltage" "V" 1.000000)
					( Origin gFrontEnd )
				)
				( objectFlag fObjectAlias )
				( objectStatus "page45_pvddq_abc" )
			)
			( signal "@baseboard_fab2_lib.baseboard_fab2(sch_1):page46_pvddq_abc"
				( attribute "VOLTAGE" "1.2V"
					( Units "uVoltage" "V" 1.000000)
					( Origin gFrontEnd )
				)
				( objectFlag fObjectAlias )
				( objectStatus "page46_pvddq_abc" )
			)
			( signal "@baseboard_fab2_lib.baseboard_fab2(sch_1):page47_pvddq_abc"
				( attribute "VOLTAGE" "1.2V"
					( Units "uVoltage" "V" 1.000000)
					( Origin gFrontEnd )
				)
				( objectFlag fObjectAlias )
				( objectStatus "page47_pvddq_abc" )
			)
			( signal "@baseboard_fab2_lib.baseboard_fab2(sch_1):page48_pvddq_abc"
				( attribute "VOLTAGE" "1.2V"
					( Units "uVoltage" "V" 1.000000)
					( Origin gFrontEnd )
				)
				( objectFlag fObjectAlias )
				( objectStatus "page48_pvddq_abc" )
			)
			( signal "@baseboard_fab2_lib.baseboard_fab2(sch_1):page96_pvddq_abc"
				( attribute "VOLTAGE" "1.2V"
					( Units "uVoltage" "V" 1.000000)
					( Origin gFrontEnd )
				)
				( objectFlag fObjectAlias )
				( objectStatus "page96_pvddq_abc" )
			)
			( signal "@baseboard_fab2_lib.baseboard_fab2(sch_1):page98_pvddq_abc"
				( attribute "VOLTAGE" "1.2V"
					( Units "uVoltage" "V" 1.000000)
					( Origin gFrontEnd )
				)
				( objectFlag fObjectAlias )
				( objectStatus "page98_pvddq_abc" )
			)
			( signal "@baseboard_fab2_lib.baseboard_fab2(sch_1):page216_pvddq_abc"
				( attribute "VOLTAGE" "1.2V"
					( Units "uVoltage" "V" 1.000000)
					( Origin gFrontEnd )
				)
				( objectFlag fObjectAlias )
				( objectStatus "page216_pvddq_abc" )
			)
			( signal "@baseboard_fab2_lib.baseboard_fab2(sch_1):page217_pvddq_abc"
				( attribute "VOLTAGE" "1.2V"
					( Units "uVoltage" "V" 1.000000)
					( Origin gFrontEnd )
				)
				( objectFlag fObjectAlias )
				( objectStatus "page217_pvddq_abc" )
			)
			( signal "@baseboard_fab2_lib.baseboard_fab2(sch_1):page221_pvddq_abc"
				( attribute "VOLTAGE" "1.2V"
					( Units "uVoltage" "V" 1.000000)
					( Origin gFrontEnd )
				)
				( objectFlag fObjectAlias )
				( objectStatus "page221_pvddq_abc" )
			)
			( signal "@baseboard_fab2_lib.baseboard_fab2(sch_1):page242_pvddq_abc"
				( attribute "VOLTAGE" "1.2V"
					( Units "uVoltage" "V" 1.000000)
					( Origin gFrontEnd )
				)
				( objectFlag fObjectAlias )
				( objectStatus "page242_pvddq_abc" )
			)
			( signal "@baseboard_fab2_lib.baseboard_fab2(sch_1):pvddq_def"
				( alias ( signalRef "@baseboard_fab2_lib.baseboard_fab2(sch_1):page38_pvddq_def") )
				( alias ( signalRef "@baseboard_fab2_lib.baseboard_fab2(sch_1):page49_pvddq_def") )
				( alias ( signalRef "@baseboard_fab2_lib.baseboard_fab2(sch_1):page50_pvddq_def") )
				( alias ( signalRef "@baseboard_fab2_lib.baseboard_fab2(sch_1):page51_pvddq_def") )
				( alias ( signalRef "@baseboard_fab2_lib.baseboard_fab2(sch_1):page52_pvddq_def") )
				( alias ( signalRef "@baseboard_fab2_lib.baseboard_fab2(sch_1):page53_pvddq_def") )
				( alias ( signalRef "@baseboard_fab2_lib.baseboard_fab2(sch_1):page54_pvddq_def") )
				( alias ( signalRef "@baseboard_fab2_lib.baseboard_fab2(sch_1):page96_pvddq_def") )
				( alias ( signalRef "@baseboard_fab2_lib.baseboard_fab2(sch_1):page98_pvddq_def") )
				( alias ( signalRef "@baseboard_fab2_lib.baseboard_fab2(sch_1):page219_pvddq_def") )
				( alias ( signalRef "@baseboard_fab2_lib.baseboard_fab2(sch_1):page220_pvddq_def") )
				( alias ( signalRef "@baseboard_fab2_lib.baseboard_fab2(sch_1):page222_pvddq_def") )
				( alias ( signalRef "@baseboard_fab2_lib.baseboard_fab2(sch_1):page242_pvddq_def") )
				( attribute "CDS_PHYS_NET_NAME" "PVDDQ_DEF"
					( Origin gPackager )
				)
				( attribute "VOLTAGE" "1.2V"
					( Units "uVoltage" "V" 1.000000)
					( Status sAliasFlattened )
					( Origin gFrontEnd )
				)
				( objectStatus "PVDDQ_DEF" )
			)
			( signal "@baseboard_fab2_lib.baseboard_fab2(sch_1):page38_pvddq_def"
				( attribute "VOLTAGE" "1.2V"
					( Units "uVoltage" "V" 1.000000)
					( Origin gFrontEnd )
				)
				( objectFlag fObjectAlias )
				( objectStatus "page38_pvddq_def" )
			)
			( signal "@baseboard_fab2_lib.baseboard_fab2(sch_1):page49_pvddq_def"
				( attribute "VOLTAGE" "1.2V"
					( Units "uVoltage" "V" 1.000000)
					( Origin gFrontEnd )
				)
				( objectFlag fObjectAlias )
				( objectStatus "page49_pvddq_def" )
			)
			( signal "@baseboard_fab2_lib.baseboard_fab2(sch_1):page50_pvddq_def"
				( attribute "VOLTAGE" "1.2V"
					( Units "uVoltage" "V" 1.000000)
					( Origin gFrontEnd )
				)
				( objectFlag fObjectAlias )
				( objectStatus "page50_pvddq_def" )
			)
			( signal "@baseboard_fab2_lib.baseboard_fab2(sch_1):page51_pvddq_def"
				( attribute "VOLTAGE" "1.2V"
					( Units "uVoltage" "V" 1.000000)
					( Origin gFrontEnd )
				)
				( objectFlag fObjectAlias )
				( objectStatus "page51_pvddq_def" )
			)
			( signal "@baseboard_fab2_lib.baseboard_fab2(sch_1):page52_pvddq_def"
				( attribute "VOLTAGE" "1.2V"
					( Units "uVoltage" "V" 1.000000)
					( Origin gFrontEnd )
				)
				( objectFlag fObjectAlias )
				( objectStatus "page52_pvddq_def" )
			)
			( signal "@baseboard_fab2_lib.baseboard_fab2(sch_1):page53_pvddq_def"
				( attribute "VOLTAGE" "1.2V"
					( Units "uVoltage" "V" 1.000000)
					( Origin gFrontEnd )
				)
				( objectFlag fObjectAlias )
				( objectStatus "page53_pvddq_def" )
			)
			( signal "@baseboard_fab2_lib.baseboard_fab2(sch_1):page54_pvddq_def"
				( attribute "VOLTAGE" "1.2V"
					( Units "uVoltage" "V" 1.000000)
					( Origin gFrontEnd )
				)
				( objectFlag fObjectAlias )
				( objectStatus "page54_pvddq_def" )
			)
			( signal "@baseboard_fab2_lib.baseboard_fab2(sch_1):page96_pvddq_def"
				( attribute "VOLTAGE" "1.2V"
					( Units "uVoltage" "V" 1.000000)
					( Origin gFrontEnd )
				)
				( objectFlag fObjectAlias )
				( objectStatus "page96_pvddq_def" )
			)
			( signal "@baseboard_fab2_lib.baseboard_fab2(sch_1):page98_pvddq_def"
				( attribute "VOLTAGE" "1.2V"
					( Units "uVoltage" "V" 1.000000)
					( Origin gFrontEnd )
				)
				( objectFlag fObjectAlias )
				( objectStatus "page98_pvddq_def" )
			)
			( signal "@baseboard_fab2_lib.baseboard_fab2(sch_1):page219_pvddq_def"
				( attribute "VOLTAGE" "1.2V"
					( Units "uVoltage" "V" 1.000000)
					( Origin gFrontEnd )
				)
				( objectFlag fObjectAlias )
				( objectStatus "page219_pvddq_def" )
			)
			( signal "@baseboard_fab2_lib.baseboard_fab2(sch_1):page220_pvddq_def"
				( attribute "VOLTAGE" "1.2V"
					( Units "uVoltage" "V" 1.000000)
					( Origin gFrontEnd )
				)
				( objectFlag fObjectAlias )
				( objectStatus "page220_pvddq_def" )
			)
			( signal "@baseboard_fab2_lib.baseboard_fab2(sch_1):page222_pvddq_def"
				( attribute "VOLTAGE" "1.2V"
					( Units "uVoltage" "V" 1.000000)
					( Origin gFrontEnd )
				)
				( objectFlag fObjectAlias )
				( objectStatus "page222_pvddq_def" )
			)
			( signal "@baseboard_fab2_lib.baseboard_fab2(sch_1):page242_pvddq_def"
				( attribute "VOLTAGE" "1.2V"
					( Units "uVoltage" "V" 1.000000)
					( Origin gFrontEnd )
				)
				( objectFlag fObjectAlias )
				( objectStatus "page242_pvddq_def" )
			)
			( signal "@baseboard_fab2_lib.baseboard_fab2(sch_1):pvpp_abc"
				( alias ( signalRef "@baseboard_fab2_lib.baseboard_fab2(sch_1):page38_pvpp_abc") )
				( alias ( signalRef "@baseboard_fab2_lib.baseboard_fab2(sch_1):page43_pvpp_abc") )
				( alias ( signalRef "@baseboard_fab2_lib.baseboard_fab2(sch_1):page44_pvpp_abc") )
				( alias ( signalRef "@baseboard_fab2_lib.baseboard_fab2(sch_1):page45_pvpp_abc") )
				( alias ( signalRef "@baseboard_fab2_lib.baseboard_fab2(sch_1):page46_pvpp_abc") )
				( alias ( signalRef "@baseboard_fab2_lib.baseboard_fab2(sch_1):page47_pvpp_abc") )
				( alias ( signalRef "@baseboard_fab2_lib.baseboard_fab2(sch_1):page48_pvpp_abc") )
				( alias ( signalRef "@baseboard_fab2_lib.baseboard_fab2(sch_1):page89_pvpp_abc") )
				( alias ( signalRef "@baseboard_fab2_lib.baseboard_fab2(sch_1):page91_pvpp_abc") )
				( alias ( signalRef "@baseboard_fab2_lib.baseboard_fab2(sch_1):page94_pvpp_abc") )
				( alias ( signalRef "@baseboard_fab2_lib.baseboard_fab2(sch_1):page99_pvpp_abc") )
				( alias ( signalRef "@baseboard_fab2_lib.baseboard_fab2(sch_1):page192_pvpp_abc") )
				( alias ( signalRef "@baseboard_fab2_lib.baseboard_fab2(sch_1):page231_pvpp_abc") )
				( attribute "VOLTAGE" "2.5V"
					( Units "uVoltage" "V" 1.000000)
					( Status sAliasFlattened )
					( Origin gFrontEnd )
				)
				( attribute "CDS_PHYS_NET_NAME" "PVPP_ABC"
					( Origin gPackager )
				)
				( objectStatus "PVPP_ABC" )
			)
			( signal "@baseboard_fab2_lib.baseboard_fab2(sch_1):page38_pvpp_abc"
				( attribute "VOLTAGE" "2.5V"
					( Units "uVoltage" "V" 1.000000)
					( Origin gFrontEnd )
				)
				( objectFlag fObjectAlias )
				( objectStatus "page38_pvpp_abc" )
			)
			( signal "@baseboard_fab2_lib.baseboard_fab2(sch_1):page43_pvpp_abc"
				( attribute "VOLTAGE" "2.5V"
					( Units "uVoltage" "V" 1.000000)
					( Origin gFrontEnd )
				)
				( objectFlag fObjectAlias )
				( objectStatus "page43_pvpp_abc" )
			)
			( signal "@baseboard_fab2_lib.baseboard_fab2(sch_1):page44_pvpp_abc"
				( attribute "VOLTAGE" "2.5V"
					( Units "uVoltage" "V" 1.000000)
					( Origin gFrontEnd )
				)
				( objectFlag fObjectAlias )
				( objectStatus "page44_pvpp_abc" )
			)
			( signal "@baseboard_fab2_lib.baseboard_fab2(sch_1):page45_pvpp_abc"
				( attribute "VOLTAGE" "2.5V"
					( Units "uVoltage" "V" 1.000000)
					( Origin gFrontEnd )
				)
				( objectFlag fObjectAlias )
				( objectStatus "page45_pvpp_abc" )
			)
			( signal "@baseboard_fab2_lib.baseboard_fab2(sch_1):page46_pvpp_abc"
				( attribute "VOLTAGE" "2.5V"
					( Units "uVoltage" "V" 1.000000)
					( Origin gFrontEnd )
				)
				( objectFlag fObjectAlias )
				( objectStatus "page46_pvpp_abc" )
			)
			( signal "@baseboard_fab2_lib.baseboard_fab2(sch_1):page47_pvpp_abc"
				( attribute "VOLTAGE" "2.5V"
					( Units "uVoltage" "V" 1.000000)
					( Origin gFrontEnd )
				)
				( objectFlag fObjectAlias )
				( objectStatus "page47_pvpp_abc" )
			)
			( signal "@baseboard_fab2_lib.baseboard_fab2(sch_1):page48_pvpp_abc"
				( attribute "VOLTAGE" "2.5V"
					( Units "uVoltage" "V" 1.000000)
					( Origin gFrontEnd )
				)
				( objectFlag fObjectAlias )
				( objectStatus "page48_pvpp_abc" )
			)
			( signal "@baseboard_fab2_lib.baseboard_fab2(sch_1):page89_pvpp_abc"
				( attribute "VOLTAGE" "2.5V"
					( Units "uVoltage" "V" 1.000000)
					( Origin gFrontEnd )
				)
				( objectFlag fObjectAlias )
				( objectStatus "page89_pvpp_abc" )
			)
			( signal "@baseboard_fab2_lib.baseboard_fab2(sch_1):page91_pvpp_abc"
				( attribute "VOLTAGE" "2.5V"
					( Units "uVoltage" "V" 1.000000)
					( Origin gFrontEnd )
				)
				( objectFlag fObjectAlias )
				( objectStatus "page91_pvpp_abc" )
			)
			( signal "@baseboard_fab2_lib.baseboard_fab2(sch_1):page94_pvpp_abc"
				( attribute "VOLTAGE" "2.5V"
					( Units "uVoltage" "V" 1.000000)
					( Origin gFrontEnd )
				)
				( objectFlag fObjectAlias )
				( objectStatus "page94_pvpp_abc" )
			)
			( signal "@baseboard_fab2_lib.baseboard_fab2(sch_1):page99_pvpp_abc"
				( attribute "VOLTAGE" "2.5V"
					( Units "uVoltage" "V" 1.000000)
					( Origin gFrontEnd )
				)
				( objectFlag fObjectAlias )
				( objectStatus "page99_pvpp_abc" )
			)
			( signal "@baseboard_fab2_lib.baseboard_fab2(sch_1):page192_pvpp_abc"
				( attribute "VOLTAGE" "2.5V"
					( Units "uVoltage" "V" 1.000000)
					( Origin gFrontEnd )
				)
				( objectFlag fObjectAlias )
				( objectStatus "page192_pvpp_abc" )
			)
			( signal "@baseboard_fab2_lib.baseboard_fab2(sch_1):page231_pvpp_abc"
				( attribute "VOLTAGE" "2.5V"
					( Units "uVoltage" "V" 1.000000)
					( Origin gFrontEnd )
				)
				( objectFlag fObjectAlias )
				( objectStatus "page231_pvpp_abc" )
			)
			( signal "@baseboard_fab2_lib.baseboard_fab2(sch_1):pvsa_cpu0"
				( alias ( signalRef "@baseboard_fab2_lib.baseboard_fab2(sch_1):page38_pvsa_cpu0") )
				( alias ( signalRef "@baseboard_fab2_lib.baseboard_fab2(sch_1):page42_pvsa_cpu0") )
				( alias ( signalRef "@baseboard_fab2_lib.baseboard_fab2(sch_1):page205_pvsa_cpu0") )
				( attribute "VOLTAGE" "1.1V"
					( Units "uVoltage" "V" 1.000000)
					( Status sAliasFlattened )
					( Origin gFrontEnd )
				)
				( attribute "CDS_PHYS_NET_NAME" "PVSA_CPU0"
					( Origin gPackager )
				)
				( objectStatus "PVSA_CPU0" )
			)
			( signal "@baseboard_fab2_lib.baseboard_fab2(sch_1):page38_pvsa_cpu0"
				( attribute "VOLTAGE" "1.1V"
					( Units "uVoltage" "V" 1.000000)
					( Origin gFrontEnd )
				)
				( objectFlag fObjectAlias )
				( objectStatus "page38_pvsa_cpu0" )
			)
			( signal "@baseboard_fab2_lib.baseboard_fab2(sch_1):page42_pvsa_cpu0"
				( attribute "VOLTAGE" "1.1V"
					( Units "uVoltage" "V" 1.000000)
					( Origin gFrontEnd )
				)
				( objectFlag fObjectAlias )
				( objectStatus "page42_pvsa_cpu0" )
			)
			( signal "@baseboard_fab2_lib.baseboard_fab2(sch_1):page205_pvsa_cpu0"
				( attribute "VOLTAGE" "1.1V"
					( Units "uVoltage" "V" 1.000000)
					( Origin gFrontEnd )
				)
				( objectFlag fObjectAlias )
				( objectStatus "page205_pvsa_cpu0" )
			)
			( signal "@baseboard_fab2_lib.baseboard_fab2(sch_1):pd_cpu0_mcp01_dmon"
				( attribute "CDS_PHYS_NET_NAME" "PD_CPU0_MCP01_DMON"
					( Origin gPackager )
				)
				( objectStatus "PD_CPU0_MCP01_DMON" )
			)
			( signal "@baseboard_fab2_lib.baseboard_fab2(sch_1):tp_cpu0_kti2_amonv"
				( attribute "CDS_PHYS_NET_NAME" "TP_CPU0_KTI2_AMONV"
					( Origin gPackager )
				)
				( objectStatus "TP_CPU0_KTI2_AMONV" )
			)
			( signal "@baseboard_fab2_lib.baseboard_fab2(sch_1):tp_cpu0_kti2_dfx_dn"
				( attribute "CDS_PHYS_NET_NAME" "TP_CPU0_KTI2_DFX_DN"
					( Origin gPackager )
				)
				( objectStatus "TP_CPU0_KTI2_DFX_DN" )
			)
			( signal "@baseboard_fab2_lib.baseboard_fab2(sch_1):tp_cpu0_rsvd_0"
				( attribute "CDS_PHYS_NET_NAME" "TP_CPU0_RSVD_0"
					( Origin gPackager )
				)
				( objectStatus "TP_CPU0_RSVD_0" )
			)
			( signal "@baseboard_fab2_lib.baseboard_fab2(sch_1):tp_cpu0_rsvd_1"
				( attribute "CDS_PHYS_NET_NAME" "TP_CPU0_RSVD_1"
					( Origin gPackager )
				)
				( objectStatus "TP_CPU0_RSVD_1" )
			)
			( signal "@baseboard_fab2_lib.baseboard_fab2(sch_1):tp_cpu0_rsvd_10"
				( attribute "CDS_PHYS_NET_NAME" "TP_CPU0_RSVD_10"
					( Origin gPackager )
				)
				( objectStatus "TP_CPU0_RSVD_10" )
			)
			( signal "@baseboard_fab2_lib.baseboard_fab2(sch_1):tp_cpu0_rsvd_11"
				( attribute "CDS_PHYS_NET_NAME" "TP_CPU0_RSVD_11"
					( Origin gPackager )
				)
				( objectStatus "TP_CPU0_RSVD_11" )
			)
			( signal "@baseboard_fab2_lib.baseboard_fab2(sch_1):tp_cpu0_rsvd_12"
				( attribute "CDS_PHYS_NET_NAME" "TP_CPU0_RSVD_12"
					( Origin gPackager )
				)
				( objectStatus "TP_CPU0_RSVD_12" )
			)
			( signal "@baseboard_fab2_lib.baseboard_fab2(sch_1):tp_cpu0_rsvd_13"
				( attribute "CDS_PHYS_NET_NAME" "TP_CPU0_RSVD_13"
					( Origin gPackager )
				)
				( objectStatus "TP_CPU0_RSVD_13" )
			)
			( signal "@baseboard_fab2_lib.baseboard_fab2(sch_1):tp_cpu0_rsvd_14"
				( attribute "CDS_PHYS_NET_NAME" "TP_CPU0_RSVD_14"
					( Origin gPackager )
				)
				( objectStatus "TP_CPU0_RSVD_14" )
			)
			( signal "@baseboard_fab2_lib.baseboard_fab2(sch_1):tp_cpu0_rsvd_15"
				( attribute "CDS_PHYS_NET_NAME" "TP_CPU0_RSVD_15"
					( Origin gPackager )
				)
				( objectStatus "TP_CPU0_RSVD_15" )
			)
			( signal "@baseboard_fab2_lib.baseboard_fab2(sch_1):tp_cpu0_rsvd_16"
				( attribute "CDS_PHYS_NET_NAME" "TP_CPU0_RSVD_16"
					( Origin gPackager )
				)
				( objectStatus "TP_CPU0_RSVD_16" )
			)
			( signal "@baseboard_fab2_lib.baseboard_fab2(sch_1):tp_cpu0_rsvd_17"
				( attribute "CDS_PHYS_NET_NAME" "TP_CPU0_RSVD_17"
					( Origin gPackager )
				)
				( objectStatus "TP_CPU0_RSVD_17" )
			)
			( signal "@baseboard_fab2_lib.baseboard_fab2(sch_1):tp_cpu0_rsvd_18"
				( attribute "CDS_PHYS_NET_NAME" "TP_CPU0_RSVD_18"
					( Origin gPackager )
				)
				( objectStatus "TP_CPU0_RSVD_18" )
			)
			( signal "@baseboard_fab2_lib.baseboard_fab2(sch_1):tp_cpu0_rsvd_19"
				( attribute "CDS_PHYS_NET_NAME" "TP_CPU0_RSVD_19"
					( Origin gPackager )
				)
				( objectStatus "TP_CPU0_RSVD_19" )
			)
			( signal "@baseboard_fab2_lib.baseboard_fab2(sch_1):tp_cpu0_rsvd_2"
				( attribute "CDS_PHYS_NET_NAME" "TP_CPU0_RSVD_2"
					( Origin gPackager )
				)
				( objectStatus "TP_CPU0_RSVD_2" )
			)
			( signal "@baseboard_fab2_lib.baseboard_fab2(sch_1):tp_cpu0_rsvd_20"
				( attribute "CDS_PHYS_NET_NAME" "TP_CPU0_RSVD_20"
					( Origin gPackager )
				)
				( objectStatus "TP_CPU0_RSVD_20" )
			)
			( signal "@baseboard_fab2_lib.baseboard_fab2(sch_1):tp_cpu0_rsvd_21"
				( attribute "CDS_PHYS_NET_NAME" "TP_CPU0_RSVD_21"
					( Origin gPackager )
				)
				( objectStatus "TP_CPU0_RSVD_21" )
			)
			( signal "@baseboard_fab2_lib.baseboard_fab2(sch_1):tp_cpu0_rsvd_22"
				( attribute "CDS_PHYS_NET_NAME" "TP_CPU0_RSVD_22"
					( Origin gPackager )
				)
				( objectStatus "TP_CPU0_RSVD_22" )
			)
			( signal "@baseboard_fab2_lib.baseboard_fab2(sch_1):tp_cpu0_rsvd_23"
				( attribute "CDS_PHYS_NET_NAME" "TP_CPU0_RSVD_23"
					( Origin gPackager )
				)
				( objectStatus "TP_CPU0_RSVD_23" )
			)
			( signal "@baseboard_fab2_lib.baseboard_fab2(sch_1):tp_cpu0_rsvd_24"
				( attribute "CDS_PHYS_NET_NAME" "TP_CPU0_RSVD_24"
					( Origin gPackager )
				)
				( objectStatus "TP_CPU0_RSVD_24" )
			)
			( signal "@baseboard_fab2_lib.baseboard_fab2(sch_1):tp_cpu0_rsvd_25"
				( attribute "CDS_PHYS_NET_NAME" "TP_CPU0_RSVD_25"
					( Origin gPackager )
				)
				( objectStatus "TP_CPU0_RSVD_25" )
			)
			( signal "@baseboard_fab2_lib.baseboard_fab2(sch_1):tp_cpu0_rsvd_26"
				( attribute "CDS_PHYS_NET_NAME" "TP_CPU0_RSVD_26"
					( Origin gPackager )
				)
				( objectStatus "TP_CPU0_RSVD_26" )
			)
			( signal "@baseboard_fab2_lib.baseboard_fab2(sch_1):tp_cpu0_rsvd_27"
				( attribute "CDS_PHYS_NET_NAME" "TP_CPU0_RSVD_27"
					( Origin gPackager )
				)
				( objectStatus "TP_CPU0_RSVD_27" )
			)
			( signal "@baseboard_fab2_lib.baseboard_fab2(sch_1):tp_cpu0_rsvd_28"
				( attribute "CDS_PHYS_NET_NAME" "TP_CPU0_RSVD_28"
					( Origin gPackager )
				)
				( objectStatus "TP_CPU0_RSVD_28" )
			)
			( signal "@baseboard_fab2_lib.baseboard_fab2(sch_1):tp_cpu0_rsvd_29"
				( attribute "CDS_PHYS_NET_NAME" "TP_CPU0_RSVD_29"
					( Origin gPackager )
				)
				( objectStatus "TP_CPU0_RSVD_29" )
			)
			( signal "@baseboard_fab2_lib.baseboard_fab2(sch_1):tp_cpu0_rsvd_3"
				( attribute "CDS_PHYS_NET_NAME" "TP_CPU0_RSVD_3"
					( Origin gPackager )
				)
				( objectStatus "TP_CPU0_RSVD_3" )
			)
			( signal "@baseboard_fab2_lib.baseboard_fab2(sch_1):tp_cpu0_rsvd_30"
				( attribute "CDS_PHYS_NET_NAME" "TP_CPU0_RSVD_30"
					( Origin gPackager )
				)
				( objectStatus "TP_CPU0_RSVD_30" )
			)
			( signal "@baseboard_fab2_lib.baseboard_fab2(sch_1):tp_cpu0_rsvd_31"
				( attribute "CDS_PHYS_NET_NAME" "TP_CPU0_RSVD_31"
					( Origin gPackager )
				)
				( objectStatus "TP_CPU0_RSVD_31" )
			)
			( signal "@baseboard_fab2_lib.baseboard_fab2(sch_1):tp_cpu0_rsvd_32"
				( attribute "CDS_PHYS_NET_NAME" "TP_CPU0_RSVD_32"
					( Origin gPackager )
				)
				( objectStatus "TP_CPU0_RSVD_32" )
			)
			( signal "@baseboard_fab2_lib.baseboard_fab2(sch_1):tp_cpu0_rsvd_33"
				( attribute "CDS_PHYS_NET_NAME" "TP_CPU0_RSVD_33"
					( Origin gPackager )
				)
				( objectStatus "TP_CPU0_RSVD_33" )
			)
			( signal "@baseboard_fab2_lib.baseboard_fab2(sch_1):tp_cpu0_rsvd_34"
				( attribute "CDS_PHYS_NET_NAME" "TP_CPU0_RSVD_34"
					( Origin gPackager )
				)
				( objectStatus "TP_CPU0_RSVD_34" )
			)
			( signal "@baseboard_fab2_lib.baseboard_fab2(sch_1):tp_cpu0_rsvd_35"
				( attribute "CDS_PHYS_NET_NAME" "TP_CPU0_RSVD_35"
					( Origin gPackager )
				)
				( objectStatus "TP_CPU0_RSVD_35" )
			)
			( signal "@baseboard_fab2_lib.baseboard_fab2(sch_1):tp_cpu0_rsvd_36"
				( attribute "CDS_PHYS_NET_NAME" "TP_CPU0_RSVD_36"
					( Origin gPackager )
				)
				( objectStatus "TP_CPU0_RSVD_36" )
			)
			( signal "@baseboard_fab2_lib.baseboard_fab2(sch_1):tp_cpu0_rsvd_37"
				( attribute "CDS_PHYS_NET_NAME" "TP_CPU0_RSVD_37"
					( Origin gPackager )
				)
				( objectStatus "TP_CPU0_RSVD_37" )
			)
			( signal "@baseboard_fab2_lib.baseboard_fab2(sch_1):tp_cpu0_rsvd_38"
				( attribute "CDS_PHYS_NET_NAME" "TP_CPU0_RSVD_38"
					( Origin gPackager )
				)
				( objectStatus "TP_CPU0_RSVD_38" )
			)
			( signal "@baseboard_fab2_lib.baseboard_fab2(sch_1):tp_cpu0_rsvd_39"
				( attribute "CDS_PHYS_NET_NAME" "TP_CPU0_RSVD_39"
					( Origin gPackager )
				)
				( objectStatus "TP_CPU0_RSVD_39" )
			)
			( signal "@baseboard_fab2_lib.baseboard_fab2(sch_1):tp_cpu0_rsvd_4"
				( attribute "CDS_PHYS_NET_NAME" "TP_CPU0_RSVD_4"
					( Origin gPackager )
				)
				( objectStatus "TP_CPU0_RSVD_4" )
			)
			( signal "@baseboard_fab2_lib.baseboard_fab2(sch_1):tp_cpu0_rsvd_40"
				( attribute "CDS_PHYS_NET_NAME" "TP_CPU0_RSVD_40"
					( Origin gPackager )
				)
				( objectStatus "TP_CPU0_RSVD_40" )
			)
			( signal "@baseboard_fab2_lib.baseboard_fab2(sch_1):tp_cpu0_rsvd_41"
				( attribute "CDS_PHYS_NET_NAME" "TP_CPU0_RSVD_41"
					( Origin gPackager )
				)
				( objectStatus "TP_CPU0_RSVD_41" )
			)
			( signal "@baseboard_fab2_lib.baseboard_fab2(sch_1):tp_cpu0_rsvd_42"
				( attribute "CDS_PHYS_NET_NAME" "TP_CPU0_RSVD_42"
					( Origin gPackager )
				)
				( objectStatus "TP_CPU0_RSVD_42" )
			)
			( signal "@baseboard_fab2_lib.baseboard_fab2(sch_1):tp_cpu0_rsvd_43"
				( attribute "CDS_PHYS_NET_NAME" "TP_CPU0_RSVD_43"
					( Origin gPackager )
				)
				( objectStatus "TP_CPU0_RSVD_43" )
			)
			( signal "@baseboard_fab2_lib.baseboard_fab2(sch_1):tp_cpu0_rsvd_44"
				( attribute "CDS_PHYS_NET_NAME" "TP_CPU0_RSVD_44"
					( Origin gPackager )
				)
				( objectStatus "TP_CPU0_RSVD_44" )
			)
			( signal "@baseboard_fab2_lib.baseboard_fab2(sch_1):tp_cpu0_rsvd_45"
				( attribute "CDS_PHYS_NET_NAME" "TP_CPU0_RSVD_45"
					( Origin gPackager )
				)
				( objectStatus "TP_CPU0_RSVD_45" )
			)
			( signal "@baseboard_fab2_lib.baseboard_fab2(sch_1):tp_cpu0_rsvd_46"
				( attribute "CDS_PHYS_NET_NAME" "TP_CPU0_RSVD_46"
					( Origin gPackager )
				)
				( objectStatus "TP_CPU0_RSVD_46" )
			)
			( signal "@baseboard_fab2_lib.baseboard_fab2(sch_1):tp_cpu0_rsvd_47"
				( attribute "CDS_PHYS_NET_NAME" "TP_CPU0_RSVD_47"
					( Origin gPackager )
				)
				( objectStatus "TP_CPU0_RSVD_47" )
			)
			( signal "@baseboard_fab2_lib.baseboard_fab2(sch_1):tp_cpu0_rsvd_48"
				( attribute "CDS_PHYS_NET_NAME" "TP_CPU0_RSVD_48"
					( Origin gPackager )
				)
				( objectStatus "TP_CPU0_RSVD_48" )
			)
			( signal "@baseboard_fab2_lib.baseboard_fab2(sch_1):tp_cpu0_rsvd_49"
				( attribute "CDS_PHYS_NET_NAME" "TP_CPU0_RSVD_49"
					( Origin gPackager )
				)
				( objectStatus "TP_CPU0_RSVD_49" )
			)
			( signal "@baseboard_fab2_lib.baseboard_fab2(sch_1):tp_cpu0_rsvd_5"
				( attribute "CDS_PHYS_NET_NAME" "TP_CPU0_RSVD_5"
					( Origin gPackager )
				)
				( objectStatus "TP_CPU0_RSVD_5" )
			)
			( signal "@baseboard_fab2_lib.baseboard_fab2(sch_1):tp_cpu0_rsvd_50"
				( attribute "CDS_PHYS_NET_NAME" "TP_CPU0_RSVD_50"
					( Origin gPackager )
				)
				( objectStatus "TP_CPU0_RSVD_50" )
			)
			( signal "@baseboard_fab2_lib.baseboard_fab2(sch_1):tp_cpu0_rsvd_51"
				( attribute "CDS_PHYS_NET_NAME" "TP_CPU0_RSVD_51"
					( Origin gPackager )
				)
				( objectStatus "TP_CPU0_RSVD_51" )
			)
			( signal "@baseboard_fab2_lib.baseboard_fab2(sch_1):tp_cpu0_rsvd_53"
				( attribute "CDS_PHYS_NET_NAME" "TP_CPU0_RSVD_53"
					( Origin gPackager )
				)
				( objectStatus "TP_CPU0_RSVD_53" )
			)
			( signal "@baseboard_fab2_lib.baseboard_fab2(sch_1):tp_cpu0_rsvd_54"
				( attribute "CDS_PHYS_NET_NAME" "TP_CPU0_RSVD_54"
					( Origin gPackager )
				)
				( objectStatus "TP_CPU0_RSVD_54" )
			)
			( signal "@baseboard_fab2_lib.baseboard_fab2(sch_1):tp_cpu0_rsvd_55"
				( attribute "CDS_PHYS_NET_NAME" "TP_CPU0_RSVD_55"
					( Origin gPackager )
				)
				( objectStatus "TP_CPU0_RSVD_55" )
			)
			( signal "@baseboard_fab2_lib.baseboard_fab2(sch_1):tp_cpu0_rsvd_56"
				( attribute "CDS_PHYS_NET_NAME" "TP_CPU0_RSVD_56"
					( Origin gPackager )
				)
				( objectStatus "TP_CPU0_RSVD_56" )
			)
			( signal "@baseboard_fab2_lib.baseboard_fab2(sch_1):tp_cpu0_rsvd_57"
				( attribute "CDS_PHYS_NET_NAME" "TP_CPU0_RSVD_57"
					( Origin gPackager )
				)
				( objectStatus "TP_CPU0_RSVD_57" )
			)
			( signal "@baseboard_fab2_lib.baseboard_fab2(sch_1):tp_cpu0_rsvd_59"
				( attribute "CDS_PHYS_NET_NAME" "TP_CPU0_RSVD_59"
					( Origin gPackager )
				)
				( objectStatus "TP_CPU0_RSVD_59" )
			)
			( signal "@baseboard_fab2_lib.baseboard_fab2(sch_1):tp_cpu0_rsvd_6"
				( attribute "CDS_PHYS_NET_NAME" "TP_CPU0_RSVD_6"
					( Origin gPackager )
				)
				( objectStatus "TP_CPU0_RSVD_6" )
			)
			( signal "@baseboard_fab2_lib.baseboard_fab2(sch_1):tp_cpu0_rsvd_60"
				( attribute "CDS_PHYS_NET_NAME" "TP_CPU0_RSVD_60"
					( Origin gPackager )
				)
				( objectStatus "TP_CPU0_RSVD_60" )
			)
			( signal "@baseboard_fab2_lib.baseboard_fab2(sch_1):tp_cpu0_rsvd_61"
				( attribute "CDS_PHYS_NET_NAME" "TP_CPU0_RSVD_61"
					( Origin gPackager )
				)
				( objectStatus "TP_CPU0_RSVD_61" )
			)
			( signal "@baseboard_fab2_lib.baseboard_fab2(sch_1):tp_cpu0_rsvd_64"
				( attribute "CDS_PHYS_NET_NAME" "TP_CPU0_RSVD_64"
					( Origin gPackager )
				)
				( objectStatus "TP_CPU0_RSVD_64" )
			)
			( signal "@baseboard_fab2_lib.baseboard_fab2(sch_1):tp_cpu0_rsvd_66"
				( attribute "CDS_PHYS_NET_NAME" "TP_CPU0_RSVD_66"
					( Origin gPackager )
				)
				( objectStatus "TP_CPU0_RSVD_66" )
			)
			( signal "@baseboard_fab2_lib.baseboard_fab2(sch_1):tp_cpu0_rsvd_67"
				( attribute "CDS_PHYS_NET_NAME" "TP_CPU0_RSVD_67"
					( Origin gPackager )
				)
				( objectStatus "TP_CPU0_RSVD_67" )
			)
			( signal "@baseboard_fab2_lib.baseboard_fab2(sch_1):tp_cpu0_rsvd_69"
				( attribute "CDS_PHYS_NET_NAME" "TP_CPU0_RSVD_69"
					( Origin gPackager )
				)
				( objectStatus "TP_CPU0_RSVD_69" )
			)
			( signal "@baseboard_fab2_lib.baseboard_fab2(sch_1):tp_cpu0_rsvd_7"
				( attribute "CDS_PHYS_NET_NAME" "TP_CPU0_RSVD_7"
					( Origin gPackager )
				)
				( objectStatus "TP_CPU0_RSVD_7" )
			)
			( signal "@baseboard_fab2_lib.baseboard_fab2(sch_1):tp_cpu0_rsvd_70"
				( attribute "CDS_PHYS_NET_NAME" "TP_CPU0_RSVD_70"
					( Origin gPackager )
				)
				( objectStatus "TP_CPU0_RSVD_70" )
			)
			( signal "@baseboard_fab2_lib.baseboard_fab2(sch_1):tp_cpu0_rsvd_72"
				( attribute "CDS_PHYS_NET_NAME" "TP_CPU0_RSVD_72"
					( Origin gPackager )
				)
				( objectStatus "TP_CPU0_RSVD_72" )
			)
			( signal "@baseboard_fab2_lib.baseboard_fab2(sch_1):tp_cpu0_rsvd_73"
				( attribute "CDS_PHYS_NET_NAME" "TP_CPU0_RSVD_73"
					( Origin gPackager )
				)
				( objectStatus "TP_CPU0_RSVD_73" )
			)
			( signal "@baseboard_fab2_lib.baseboard_fab2(sch_1):tp_cpu0_rsvd_8"
				( attribute "CDS_PHYS_NET_NAME" "TP_CPU0_RSVD_8"
					( Origin gPackager )
				)
				( objectStatus "TP_CPU0_RSVD_8" )
			)
			( signal "@baseboard_fab2_lib.baseboard_fab2(sch_1):tp_cpu0_rsvd_9"
				( attribute "CDS_PHYS_NET_NAME" "TP_CPU0_RSVD_9"
					( Origin gPackager )
				)
				( objectStatus "TP_CPU0_RSVD_9" )
			)
			( signal "@baseboard_fab2_lib.baseboard_fab2(sch_1):vsense_pvccio_cpu0_skt_vrtn"
				( attribute "CDS_PHYS_NET_NAME" "VSENSE_PVCCIO_CPU0_SKT_VRTN"
					( Origin gPackager )
				)
				( objectStatus "VSENSE_PVCCIO_CPU0_SKT_VRTN" )
			)
			( signal "@baseboard_fab2_lib.baseboard_fab2(sch_1):vsense_pvccio_cpu0_skt_vsen"
				( attribute "CDS_PHYS_NET_NAME" "VSENSE_PVCCIO_CPU0_SKT_VSEN"
					( Origin gPackager )
				)
				( objectStatus "VSENSE_PVCCIO_CPU0_SKT_VSEN" )
			)
			( signal "@baseboard_fab2_lib.baseboard_fab2(sch_1):vsense_pvcciomcp_cpu0_skt_vrtn"
				( attribute "CDS_PHYS_NET_NAME" "VSENSE_PVCCIOMCP_CPU0_SKT_VRTN"
					( Origin gPackager )
				)
				( objectStatus "VSENSE_PVCCIOMCP_CPU0_SKT_VRTN" )
			)
			( signal "@baseboard_fab2_lib.baseboard_fab2(sch_1):vsense_pvcciomcp_cpu0_skt_vsen"
				( attribute "CDS_PHYS_NET_NAME" "VSENSE_PVCCIOMCP_CPU0_SKT_VSEN"
					( Origin gPackager )
				)
				( objectStatus "VSENSE_PVCCIOMCP_CPU0_SKT_VSEN" )
			)
			( signal "@baseboard_fab2_lib.baseboard_fab2(sch_1):vsense_pvccmcp_cpu0_skt_vrtn"
				( attribute "CDS_PHYS_NET_NAME" "VSENSE_PVCCMCP_CPU0_SKT_VRTN"
					( Origin gPackager )
				)
				( objectStatus "VSENSE_PVCCMCP_CPU0_SKT_VRTN" )
			)
			( signal "@baseboard_fab2_lib.baseboard_fab2(sch_1):vsense_pvccmcp_cpu0_skt_vsen"
				( attribute "CDS_PHYS_NET_NAME" "VSENSE_PVCCMCP_CPU0_SKT_VSEN"
					( Origin gPackager )
				)
				( objectStatus "VSENSE_PVCCMCP_CPU0_SKT_VSEN" )
			)
			( signal "@baseboard_fab2_lib.baseboard_fab2(sch_1):vsense_pvsa_cpu0_skt_vrtn"
				( attribute "CDS_PHYS_NET_NAME" "VSENSE_PVSA_CPU0_SKT_VRTN"
					( Origin gPackager )
				)
				( objectStatus "VSENSE_PVSA_CPU0_SKT_VRTN" )
			)
			( signal "@baseboard_fab2_lib.baseboard_fab2(sch_1):vsense_pvsa_cpu0_skt_vsen"
				( attribute "CDS_PHYS_NET_NAME" "VSENSE_PVSA_CPU0_SKT_VSEN"
					( Origin gPackager )
				)
				( objectStatus "VSENSE_PVSA_CPU0_SKT_VSEN" )
			)
			( signal "@baseboard_fab2_lib.baseboard_fab2(sch_1):fm_adr_complete_abc_n"
				( attribute "CDS_PHYS_NET_NAME" "FM_ADR_COMPLETE_ABC_N"
					( Origin gPackager )
				)
				( objectStatus "FM_ADR_COMPLETE_ABC_N" )
			)
			( signal "@baseboard_fab2_lib.baseboard_fab2(sch_1):fm_dimm_event_cod_n"
				( attribute "CDS_PHYS_NET_NAME" "FM_DIMM_EVENT_COD_N"
					( Origin gPackager )
				)
				( objectStatus "FM_DIMM_EVENT_COD_N" )
			)
			( signal "@baseboard_fab2_lib.baseboard_fab2(sch_1):m_a_vref"
				( attribute "CDS_PHYS_NET_NAME" "M_A_VREF"
					( Origin gPackager )
				)
				( objectStatus "M_A_VREF" )
			)
			( signal "@baseboard_fab2_lib.baseboard_fab2(sch_1):p12v_nvdimm_abc"
				( alias ( signalRef "@baseboard_fab2_lib.baseboard_fab2(sch_1):page43_p12v_nvdimm_abc") )
				( alias ( signalRef "@baseboard_fab2_lib.baseboard_fab2(sch_1):page44_p12v_nvdimm_abc") )
				( alias ( signalRef "@baseboard_fab2_lib.baseboard_fab2(sch_1):page45_p12v_nvdimm_abc") )
				( alias ( signalRef "@baseboard_fab2_lib.baseboard_fab2(sch_1):page46_p12v_nvdimm_abc") )
				( alias ( signalRef "@baseboard_fab2_lib.baseboard_fab2(sch_1):page47_p12v_nvdimm_abc") )
				( alias ( signalRef "@baseboard_fab2_lib.baseboard_fab2(sch_1):page48_p12v_nvdimm_abc") )
				( alias ( signalRef "@baseboard_fab2_lib.baseboard_fab2(sch_1):page197_p12v_nvdimm_abc") )
				( attribute "VOLTAGE" "12.0"
					( Units "uVoltage" "V" 1.000000)
					( Status sAliasFlattened )
					( Origin gFrontEnd )
				)
				( attribute "CDS_PHYS_NET_NAME" "P12V_NVDIMM_ABC"
					( Origin gPackager )
				)
				( objectStatus "P12V_NVDIMM_ABC" )
			)
			( signal "@baseboard_fab2_lib.baseboard_fab2(sch_1):page43_p12v_nvdimm_abc"
				( attribute "VOLTAGE" "12.0"
					( Units "uVoltage" "V" 1.000000)
					( Origin gFrontEnd )
				)
				( objectFlag fObjectAlias )
				( objectStatus "page43_p12v_nvdimm_abc" )
			)
			( signal "@baseboard_fab2_lib.baseboard_fab2(sch_1):page44_p12v_nvdimm_abc"
				( attribute "VOLTAGE" "12.0"
					( Units "uVoltage" "V" 1.000000)
					( Origin gFrontEnd )
				)
				( objectFlag fObjectAlias )
				( objectStatus "page44_p12v_nvdimm_abc" )
			)
			( signal "@baseboard_fab2_lib.baseboard_fab2(sch_1):page45_p12v_nvdimm_abc"
				( attribute "VOLTAGE" "12.0"
					( Units "uVoltage" "V" 1.000000)
					( Origin gFrontEnd )
				)
				( objectFlag fObjectAlias )
				( objectStatus "page45_p12v_nvdimm_abc" )
			)
			( signal "@baseboard_fab2_lib.baseboard_fab2(sch_1):page46_p12v_nvdimm_abc"
				( attribute "VOLTAGE" "12.0"
					( Units "uVoltage" "V" 1.000000)
					( Origin gFrontEnd )
				)
				( objectFlag fObjectAlias )
				( objectStatus "page46_p12v_nvdimm_abc" )
			)
			( signal "@baseboard_fab2_lib.baseboard_fab2(sch_1):page47_p12v_nvdimm_abc"
				( attribute "VOLTAGE" "12.0"
					( Units "uVoltage" "V" 1.000000)
					( Origin gFrontEnd )
				)
				( objectFlag fObjectAlias )
				( objectStatus "page47_p12v_nvdimm_abc" )
			)
			( signal "@baseboard_fab2_lib.baseboard_fab2(sch_1):page48_p12v_nvdimm_abc"
				( attribute "VOLTAGE" "12.0"
					( Units "uVoltage" "V" 1.000000)
					( Origin gFrontEnd )
				)
				( objectFlag fObjectAlias )
				( objectStatus "page48_p12v_nvdimm_abc" )
			)
			( signal "@baseboard_fab2_lib.baseboard_fab2(sch_1):page197_p12v_nvdimm_abc"
				( attribute "VOLTAGE" "12.0"
					( Units "uVoltage" "V" 1.000000)
					( Origin gFrontEnd )
				)
				( objectFlag fObjectAlias )
				( objectStatus "page197_p12v_nvdimm_abc" )
			)
			( signal "@baseboard_fab2_lib.baseboard_fab2(sch_1):pvtt_abc"
				( alias ( signalRef "@baseboard_fab2_lib.baseboard_fab2(sch_1):page43_pvtt_abc") )
				( alias ( signalRef "@baseboard_fab2_lib.baseboard_fab2(sch_1):page44_pvtt_abc") )
				( alias ( signalRef "@baseboard_fab2_lib.baseboard_fab2(sch_1):page45_pvtt_abc") )
				( alias ( signalRef "@baseboard_fab2_lib.baseboard_fab2(sch_1):page46_pvtt_abc") )
				( alias ( signalRef "@baseboard_fab2_lib.baseboard_fab2(sch_1):page47_pvtt_abc") )
				( alias ( signalRef "@baseboard_fab2_lib.baseboard_fab2(sch_1):page48_pvtt_abc") )
				( alias ( signalRef "@baseboard_fab2_lib.baseboard_fab2(sch_1):page221_pvtt_abc") )
				( attribute "VOLTAGE" "0.6V"
					( Units "uVoltage" "V" 1.000000)
					( Status sAliasFlattened )
					( Origin gFrontEnd )
				)
				( attribute "CDS_PHYS_NET_NAME" "PVTT_ABC"
					( Origin gPackager )
				)
				( objectStatus "PVTT_ABC" )
			)
			( signal "@baseboard_fab2_lib.baseboard_fab2(sch_1):page43_pvtt_abc"
				( attribute "VOLTAGE" "0.6V"
					( Units "uVoltage" "V" 1.000000)
					( Origin gFrontEnd )
				)
				( objectFlag fObjectAlias )
				( objectStatus "page43_pvtt_abc" )
			)
			( signal "@baseboard_fab2_lib.baseboard_fab2(sch_1):page44_pvtt_abc"
				( attribute "VOLTAGE" "0.6V"
					( Units "uVoltage" "V" 1.000000)
					( Origin gFrontEnd )
				)
				( objectFlag fObjectAlias )
				( objectStatus "page44_pvtt_abc" )
			)
			( signal "@baseboard_fab2_lib.baseboard_fab2(sch_1):page45_pvtt_abc"
				( attribute "VOLTAGE" "0.6V"
					( Units "uVoltage" "V" 1.000000)
					( Origin gFrontEnd )
				)
				( objectFlag fObjectAlias )
				( objectStatus "page45_pvtt_abc" )
			)
			( signal "@baseboard_fab2_lib.baseboard_fab2(sch_1):page46_pvtt_abc"
				( attribute "VOLTAGE" "0.6V"
					( Units "uVoltage" "V" 1.000000)
					( Origin gFrontEnd )
				)
				( objectFlag fObjectAlias )
				( objectStatus "page46_pvtt_abc" )
			)
			( signal "@baseboard_fab2_lib.baseboard_fab2(sch_1):page47_pvtt_abc"
				( attribute "VOLTAGE" "0.6V"
					( Units "uVoltage" "V" 1.000000)
					( Origin gFrontEnd )
				)
				( objectFlag fObjectAlias )
				( objectStatus "page47_pvtt_abc" )
			)
			( signal "@baseboard_fab2_lib.baseboard_fab2(sch_1):page48_pvtt_abc"
				( attribute "VOLTAGE" "0.6V"
					( Units "uVoltage" "V" 1.000000)
					( Origin gFrontEnd )
				)
				( objectFlag fObjectAlias )
				( objectStatus "page48_pvtt_abc" )
			)
			( signal "@baseboard_fab2_lib.baseboard_fab2(sch_1):page221_pvtt_abc"
				( attribute "VOLTAGE" "0.6V"
					( Units "uVoltage" "V" 1.000000)
					( Origin gFrontEnd )
				)
				( objectFlag fObjectAlias )
				( objectStatus "page221_pvtt_abc" )
			)
			( signal "@baseboard_fab2_lib.baseboard_fab2(sch_1):smb_ddr_abc_vpp_scl"
				( attribute "CDS_PHYS_NET_NAME" "SMB_DDR_ABC_VPP_SCL"
					( Origin gPackager )
				)
				( objectStatus "SMB_DDR_ABC_VPP_SCL" )
			)
			( signal "@baseboard_fab2_lib.baseboard_fab2(sch_1):smb_ddr_abc_vpp_sda"
				( attribute "CDS_PHYS_NET_NAME" "SMB_DDR_ABC_VPP_SDA"
					( Origin gPackager )
				)
				( objectStatus "SMB_DDR_ABC_VPP_SDA" )
			)
			( signal "@baseboard_fab2_lib.baseboard_fab2(sch_1):tp_ch_a_dimm_a0_rfu_0"
				( attribute "CDS_PHYS_NET_NAME" "TP_CH_A_DIMM_A0_RFU_0"
					( Origin gPackager )
				)
				( objectStatus "TP_CH_A_DIMM_A0_RFU_0" )
			)
			( signal "@baseboard_fab2_lib.baseboard_fab2(sch_1):tp_ch_a_dimm_a0_rfu_1"
				( attribute "CDS_PHYS_NET_NAME" "TP_CH_A_DIMM_A0_RFU_1"
					( Origin gPackager )
				)
				( objectStatus "TP_CH_A_DIMM_A0_RFU_1" )
			)
			( signal "@baseboard_fab2_lib.baseboard_fab2(sch_1):tp_ch_a_dimm_a0_rfu_2"
				( attribute "CDS_PHYS_NET_NAME" "TP_CH_A_DIMM_A0_RFU_2"
					( Origin gPackager )
				)
				( objectStatus "TP_CH_A_DIMM_A0_RFU_2" )
			)
			( signal "@baseboard_fab2_lib.baseboard_fab2(sch_1):tp_ch_a_dimm_a1_rfu_0"
				( attribute "CDS_PHYS_NET_NAME" "TP_CH_A_DIMM_A1_RFU_0"
					( Origin gPackager )
				)
				( objectStatus "TP_CH_A_DIMM_A1_RFU_0" )
			)
			( signal "@baseboard_fab2_lib.baseboard_fab2(sch_1):tp_ch_a_dimm_a1_rfu_1"
				( attribute "CDS_PHYS_NET_NAME" "TP_CH_A_DIMM_A1_RFU_1"
					( Origin gPackager )
				)
				( objectStatus "TP_CH_A_DIMM_A1_RFU_1" )
			)
			( signal "@baseboard_fab2_lib.baseboard_fab2(sch_1):tp_ch_a_dimm_a1_rfu_2"
				( attribute "CDS_PHYS_NET_NAME" "TP_CH_A_DIMM_A1_RFU_2"
					( Origin gPackager )
				)
				( objectStatus "TP_CH_A_DIMM_A1_RFU_2" )
			)
			( signal "@baseboard_fab2_lib.baseboard_fab2(sch_1):m_b_vref"
				( attribute "CDS_PHYS_NET_NAME" "M_B_VREF"
					( Origin gPackager )
				)
				( objectStatus "M_B_VREF" )
			)
			( signal "@baseboard_fab2_lib.baseboard_fab2(sch_1):tp_ch_b_dimm_b0_rfu_0"
				( attribute "CDS_PHYS_NET_NAME" "TP_CH_B_DIMM_B0_RFU_0"
					( Origin gPackager )
				)
				( objectStatus "TP_CH_B_DIMM_B0_RFU_0" )
			)
			( signal "@baseboard_fab2_lib.baseboard_fab2(sch_1):tp_ch_b_dimm_b0_rfu_1"
				( attribute "CDS_PHYS_NET_NAME" "TP_CH_B_DIMM_B0_RFU_1"
					( Origin gPackager )
				)
				( objectStatus "TP_CH_B_DIMM_B0_RFU_1" )
			)
			( signal "@baseboard_fab2_lib.baseboard_fab2(sch_1):tp_ch_b_dimm_b0_rfu_2"
				( attribute "CDS_PHYS_NET_NAME" "TP_CH_B_DIMM_B0_RFU_2"
					( Origin gPackager )
				)
				( objectStatus "TP_CH_B_DIMM_B0_RFU_2" )
			)
			( signal "@baseboard_fab2_lib.baseboard_fab2(sch_1):tp_ch_b_dimm_b1_rfu_0"
				( attribute "CDS_PHYS_NET_NAME" "TP_CH_B_DIMM_B1_RFU_0"
					( Origin gPackager )
				)
				( objectStatus "TP_CH_B_DIMM_B1_RFU_0" )
			)
			( signal "@baseboard_fab2_lib.baseboard_fab2(sch_1):tp_ch_b_dimm_b1_rfu_1"
				( attribute "CDS_PHYS_NET_NAME" "TP_CH_B_DIMM_B1_RFU_1"
					( Origin gPackager )
				)
				( objectStatus "TP_CH_B_DIMM_B1_RFU_1" )
			)
			( signal "@baseboard_fab2_lib.baseboard_fab2(sch_1):tp_ch_b_dimm_b1_rfu_2"
				( attribute "CDS_PHYS_NET_NAME" "TP_CH_B_DIMM_B1_RFU_2"
					( Origin gPackager )
				)
				( objectStatus "TP_CH_B_DIMM_B1_RFU_2" )
			)
			( signal "@baseboard_fab2_lib.baseboard_fab2(sch_1):m_c_vref"
				( attribute "CDS_PHYS_NET_NAME" "M_C_VREF"
					( Origin gPackager )
				)
				( objectStatus "M_C_VREF" )
			)
			( signal "@baseboard_fab2_lib.baseboard_fab2(sch_1):tp_ch_c_dimm_c0_rfu_0"
				( attribute "CDS_PHYS_NET_NAME" "TP_CH_C_DIMM_C0_RFU_0"
					( Origin gPackager )
				)
				( objectStatus "TP_CH_C_DIMM_C0_RFU_0" )
			)
			( signal "@baseboard_fab2_lib.baseboard_fab2(sch_1):tp_ch_c_dimm_c0_rfu_1"
				( attribute "CDS_PHYS_NET_NAME" "TP_CH_C_DIMM_C0_RFU_1"
					( Origin gPackager )
				)
				( objectStatus "TP_CH_C_DIMM_C0_RFU_1" )
			)
			( signal "@baseboard_fab2_lib.baseboard_fab2(sch_1):tp_ch_c_dimm_c0_rfu_2"
				( attribute "CDS_PHYS_NET_NAME" "TP_CH_C_DIMM_C0_RFU_2"
					( Origin gPackager )
				)
				( objectStatus "TP_CH_C_DIMM_C0_RFU_2" )
			)
			( signal "@baseboard_fab2_lib.baseboard_fab2(sch_1):tp_ch_c_dimm_c1_rfu_0"
				( attribute "CDS_PHYS_NET_NAME" "TP_CH_C_DIMM_C1_RFU_0"
					( Origin gPackager )
				)
				( objectStatus "TP_CH_C_DIMM_C1_RFU_0" )
			)
			( signal "@baseboard_fab2_lib.baseboard_fab2(sch_1):tp_ch_c_dimm_c1_rfu_1"
				( attribute "CDS_PHYS_NET_NAME" "TP_CH_C_DIMM_C1_RFU_1"
					( Origin gPackager )
				)
				( objectStatus "TP_CH_C_DIMM_C1_RFU_1" )
			)
			( signal "@baseboard_fab2_lib.baseboard_fab2(sch_1):tp_ch_c_dimm_c1_rfu_2"
				( attribute "CDS_PHYS_NET_NAME" "TP_CH_C_DIMM_C1_RFU_2"
					( Origin gPackager )
				)
				( objectStatus "TP_CH_C_DIMM_C1_RFU_2" )
			)
			( signal "@baseboard_fab2_lib.baseboard_fab2(sch_1):fm_adr_complete_def_n"
				( attribute "CDS_PHYS_NET_NAME" "FM_ADR_COMPLETE_DEF_N"
					( Origin gPackager )
				)
				( objectStatus "FM_ADR_COMPLETE_DEF_N" )
			)
			( signal "@baseboard_fab2_lib.baseboard_fab2(sch_1):m_d_vref"
				( attribute "CDS_PHYS_NET_NAME" "M_D_VREF"
					( Origin gPackager )
				)
				( objectStatus "M_D_VREF" )
			)
			( signal "@baseboard_fab2_lib.baseboard_fab2(sch_1):p12v_nvdimm_def"
				( alias ( signalRef "@baseboard_fab2_lib.baseboard_fab2(sch_1):page49_p12v_nvdimm_def") )
				( alias ( signalRef "@baseboard_fab2_lib.baseboard_fab2(sch_1):page50_p12v_nvdimm_def") )
				( alias ( signalRef "@baseboard_fab2_lib.baseboard_fab2(sch_1):page51_p12v_nvdimm_def") )
				( alias ( signalRef "@baseboard_fab2_lib.baseboard_fab2(sch_1):page52_p12v_nvdimm_def") )
				( alias ( signalRef "@baseboard_fab2_lib.baseboard_fab2(sch_1):page53_p12v_nvdimm_def") )
				( alias ( signalRef "@baseboard_fab2_lib.baseboard_fab2(sch_1):page54_p12v_nvdimm_def") )
				( alias ( signalRef "@baseboard_fab2_lib.baseboard_fab2(sch_1):page197_p12v_nvdimm_def") )
				( attribute "VOLTAGE" "12.0"
					( Units "uVoltage" "V" 1.000000)
					( Status sAliasFlattened )
					( Origin gFrontEnd )
				)
				( attribute "CDS_PHYS_NET_NAME" "P12V_NVDIMM_DEF"
					( Origin gPackager )
				)
				( objectStatus "P12V_NVDIMM_DEF" )
			)
			( signal "@baseboard_fab2_lib.baseboard_fab2(sch_1):page49_p12v_nvdimm_def"
				( attribute "VOLTAGE" "12.0"
					( Units "uVoltage" "V" 1.000000)
					( Origin gFrontEnd )
				)
				( objectFlag fObjectAlias )
				( objectStatus "page49_p12v_nvdimm_def" )
			)
			( signal "@baseboard_fab2_lib.baseboard_fab2(sch_1):page50_p12v_nvdimm_def"
				( attribute "VOLTAGE" "12.0"
					( Units "uVoltage" "V" 1.000000)
					( Origin gFrontEnd )
				)
				( objectFlag fObjectAlias )
				( objectStatus "page50_p12v_nvdimm_def" )
			)
			( signal "@baseboard_fab2_lib.baseboard_fab2(sch_1):page51_p12v_nvdimm_def"
				( attribute "VOLTAGE" "12.0"
					( Units "uVoltage" "V" 1.000000)
					( Origin gFrontEnd )
				)
				( objectFlag fObjectAlias )
				( objectStatus "page51_p12v_nvdimm_def" )
			)
			( signal "@baseboard_fab2_lib.baseboard_fab2(sch_1):page52_p12v_nvdimm_def"
				( attribute "VOLTAGE" "12.0"
					( Units "uVoltage" "V" 1.000000)
					( Origin gFrontEnd )
				)
				( objectFlag fObjectAlias )
				( objectStatus "page52_p12v_nvdimm_def" )
			)
			( signal "@baseboard_fab2_lib.baseboard_fab2(sch_1):page53_p12v_nvdimm_def"
				( attribute "VOLTAGE" "12.0"
					( Units "uVoltage" "V" 1.000000)
					( Origin gFrontEnd )
				)
				( objectFlag fObjectAlias )
				( objectStatus "page53_p12v_nvdimm_def" )
			)
			( signal "@baseboard_fab2_lib.baseboard_fab2(sch_1):page54_p12v_nvdimm_def"
				( attribute "VOLTAGE" "12.0"
					( Units "uVoltage" "V" 1.000000)
					( Origin gFrontEnd )
				)
				( objectFlag fObjectAlias )
				( objectStatus "page54_p12v_nvdimm_def" )
			)
			( signal "@baseboard_fab2_lib.baseboard_fab2(sch_1):page197_p12v_nvdimm_def"
				( attribute "VOLTAGE" "12.0"
					( Units "uVoltage" "V" 1.000000)
					( Origin gFrontEnd )
				)
				( objectFlag fObjectAlias )
				( objectStatus "page197_p12v_nvdimm_def" )
			)
			( signal "@baseboard_fab2_lib.baseboard_fab2(sch_1):pvpp_def"
				( alias ( signalRef "@baseboard_fab2_lib.baseboard_fab2(sch_1):page49_pvpp_def") )
				( alias ( signalRef "@baseboard_fab2_lib.baseboard_fab2(sch_1):page50_pvpp_def") )
				( alias ( signalRef "@baseboard_fab2_lib.baseboard_fab2(sch_1):page51_pvpp_def") )
				( alias ( signalRef "@baseboard_fab2_lib.baseboard_fab2(sch_1):page52_pvpp_def") )
				( alias ( signalRef "@baseboard_fab2_lib.baseboard_fab2(sch_1):page53_pvpp_def") )
				( alias ( signalRef "@baseboard_fab2_lib.baseboard_fab2(sch_1):page54_pvpp_def") )
				( alias ( signalRef "@baseboard_fab2_lib.baseboard_fab2(sch_1):page99_pvpp_def") )
				( alias ( signalRef "@baseboard_fab2_lib.baseboard_fab2(sch_1):page232_pvpp_def") )
				( attribute "VOLTAGE" "2.5V"
					( Units "uVoltage" "V" 1.000000)
					( Status sAliasFlattened )
					( Origin gFrontEnd )
				)
				( attribute "CDS_PHYS_NET_NAME" "PVPP_DEF"
					( Origin gPackager )
				)
				( objectStatus "PVPP_DEF" )
			)
			( signal "@baseboard_fab2_lib.baseboard_fab2(sch_1):page49_pvpp_def"
				( attribute "VOLTAGE" "2.5V"
					( Units "uVoltage" "V" 1.000000)
					( Origin gFrontEnd )
				)
				( objectFlag fObjectAlias )
				( objectStatus "page49_pvpp_def" )
			)
			( signal "@baseboard_fab2_lib.baseboard_fab2(sch_1):page50_pvpp_def"
				( attribute "VOLTAGE" "2.5V"
					( Units "uVoltage" "V" 1.000000)
					( Origin gFrontEnd )
				)
				( objectFlag fObjectAlias )
				( objectStatus "page50_pvpp_def" )
			)
			( signal "@baseboard_fab2_lib.baseboard_fab2(sch_1):page51_pvpp_def"
				( attribute "VOLTAGE" "2.5V"
					( Units "uVoltage" "V" 1.000000)
					( Origin gFrontEnd )
				)
				( objectFlag fObjectAlias )
				( objectStatus "page51_pvpp_def" )
			)
			( signal "@baseboard_fab2_lib.baseboard_fab2(sch_1):page52_pvpp_def"
				( attribute "VOLTAGE" "2.5V"
					( Units "uVoltage" "V" 1.000000)
					( Origin gFrontEnd )
				)
				( objectFlag fObjectAlias )
				( objectStatus "page52_pvpp_def" )
			)
			( signal "@baseboard_fab2_lib.baseboard_fab2(sch_1):page53_pvpp_def"
				( attribute "VOLTAGE" "2.5V"
					( Units "uVoltage" "V" 1.000000)
					( Origin gFrontEnd )
				)
				( objectFlag fObjectAlias )
				( objectStatus "page53_pvpp_def" )
			)
			( signal "@baseboard_fab2_lib.baseboard_fab2(sch_1):page54_pvpp_def"
				( attribute "VOLTAGE" "2.5V"
					( Units "uVoltage" "V" 1.000000)
					( Origin gFrontEnd )
				)
				( objectFlag fObjectAlias )
				( objectStatus "page54_pvpp_def" )
			)
			( signal "@baseboard_fab2_lib.baseboard_fab2(sch_1):page99_pvpp_def"
				( attribute "VOLTAGE" "2.5V"
					( Units "uVoltage" "V" 1.000000)
					( Origin gFrontEnd )
				)
				( objectFlag fObjectAlias )
				( objectStatus "page99_pvpp_def" )
			)
			( signal "@baseboard_fab2_lib.baseboard_fab2(sch_1):page232_pvpp_def"
				( attribute "VOLTAGE" "2.5V"
					( Units "uVoltage" "V" 1.000000)
					( Origin gFrontEnd )
				)
				( objectFlag fObjectAlias )
				( objectStatus "page232_pvpp_def" )
			)
			( signal "@baseboard_fab2_lib.baseboard_fab2(sch_1):pvtt_def"
				( alias ( signalRef "@baseboard_fab2_lib.baseboard_fab2(sch_1):page49_pvtt_def") )
				( alias ( signalRef "@baseboard_fab2_lib.baseboard_fab2(sch_1):page50_pvtt_def") )
				( alias ( signalRef "@baseboard_fab2_lib.baseboard_fab2(sch_1):page51_pvtt_def") )
				( alias ( signalRef "@baseboard_fab2_lib.baseboard_fab2(sch_1):page52_pvtt_def") )
				( alias ( signalRef "@baseboard_fab2_lib.baseboard_fab2(sch_1):page53_pvtt_def") )
				( alias ( signalRef "@baseboard_fab2_lib.baseboard_fab2(sch_1):page54_pvtt_def") )
				( alias ( signalRef "@baseboard_fab2_lib.baseboard_fab2(sch_1):page222_pvtt_def") )
				( attribute "VOLTAGE" "0.6V"
					( Units "uVoltage" "V" 1.000000)
					( Status sAliasFlattened )
					( Origin gFrontEnd )
				)
				( attribute "CDS_PHYS_NET_NAME" "PVTT_DEF"
					( Origin gPackager )
				)
				( objectStatus "PVTT_DEF" )
			)
			( signal "@baseboard_fab2_lib.baseboard_fab2(sch_1):page49_pvtt_def"
				( attribute "VOLTAGE" "0.6V"
					( Units "uVoltage" "V" 1.000000)
					( Origin gFrontEnd )
				)
				( objectFlag fObjectAlias )
				( objectStatus "page49_pvtt_def" )
			)
			( signal "@baseboard_fab2_lib.baseboard_fab2(sch_1):page50_pvtt_def"
				( attribute "VOLTAGE" "0.6V"
					( Units "uVoltage" "V" 1.000000)
					( Origin gFrontEnd )
				)
				( objectFlag fObjectAlias )
				( objectStatus "page50_pvtt_def" )
			)
			( signal "@baseboard_fab2_lib.baseboard_fab2(sch_1):page51_pvtt_def"
				( attribute "VOLTAGE" "0.6V"
					( Units "uVoltage" "V" 1.000000)
					( Origin gFrontEnd )
				)
				( objectFlag fObjectAlias )
				( objectStatus "page51_pvtt_def" )
			)
			( signal "@baseboard_fab2_lib.baseboard_fab2(sch_1):page52_pvtt_def"
				( attribute "VOLTAGE" "0.6V"
					( Units "uVoltage" "V" 1.000000)
					( Origin gFrontEnd )
				)
				( objectFlag fObjectAlias )
				( objectStatus "page52_pvtt_def" )
			)
			( signal "@baseboard_fab2_lib.baseboard_fab2(sch_1):page53_pvtt_def"
				( attribute "VOLTAGE" "0.6V"
					( Units "uVoltage" "V" 1.000000)
					( Origin gFrontEnd )
				)
				( objectFlag fObjectAlias )
				( objectStatus "page53_pvtt_def" )
			)
			( signal "@baseboard_fab2_lib.baseboard_fab2(sch_1):page54_pvtt_def"
				( attribute "VOLTAGE" "0.6V"
					( Units "uVoltage" "V" 1.000000)
					( Origin gFrontEnd )
				)
				( objectFlag fObjectAlias )
				( objectStatus "page54_pvtt_def" )
			)
			( signal "@baseboard_fab2_lib.baseboard_fab2(sch_1):page222_pvtt_def"
				( attribute "VOLTAGE" "0.6V"
					( Units "uVoltage" "V" 1.000000)
					( Origin gFrontEnd )
				)
				( objectFlag fObjectAlias )
				( objectStatus "page222_pvtt_def" )
			)
			( signal "@baseboard_fab2_lib.baseboard_fab2(sch_1):smb_ddr_def_vpp_scl"
				( attribute "CDS_PHYS_NET_NAME" "SMB_DDR_DEF_VPP_SCL"
					( Origin gPackager )
				)
				( objectStatus "SMB_DDR_DEF_VPP_SCL" )
			)
			( signal "@baseboard_fab2_lib.baseboard_fab2(sch_1):smb_ddr_def_vpp_sda"
				( attribute "CDS_PHYS_NET_NAME" "SMB_DDR_DEF_VPP_SDA"
					( Origin gPackager )
				)
				( objectStatus "SMB_DDR_DEF_VPP_SDA" )
			)
			( signal "@baseboard_fab2_lib.baseboard_fab2(sch_1):tp_ch_d_dimm_d0_rfu_0"
				( attribute "CDS_PHYS_NET_NAME" "TP_CH_D_DIMM_D0_RFU_0"
					( Origin gPackager )
				)
				( objectStatus "TP_CH_D_DIMM_D0_RFU_0" )
			)
			( signal "@baseboard_fab2_lib.baseboard_fab2(sch_1):tp_ch_d_dimm_d0_rfu_1"
				( attribute "CDS_PHYS_NET_NAME" "TP_CH_D_DIMM_D0_RFU_1"
					( Origin gPackager )
				)
				( objectStatus "TP_CH_D_DIMM_D0_RFU_1" )
			)
			( signal "@baseboard_fab2_lib.baseboard_fab2(sch_1):tp_ch_d_dimm_d0_rfu_2"
				( attribute "CDS_PHYS_NET_NAME" "TP_CH_D_DIMM_D0_RFU_2"
					( Origin gPackager )
				)
				( objectStatus "TP_CH_D_DIMM_D0_RFU_2" )
			)
			( signal "@baseboard_fab2_lib.baseboard_fab2(sch_1):tp_ch_d_dimm_d1_rfu_0"
				( attribute "CDS_PHYS_NET_NAME" "TP_CH_D_DIMM_D1_RFU_0"
					( Origin gPackager )
				)
				( objectStatus "TP_CH_D_DIMM_D1_RFU_0" )
			)
			( signal "@baseboard_fab2_lib.baseboard_fab2(sch_1):tp_ch_d_dimm_d1_rfu_1"
				( attribute "CDS_PHYS_NET_NAME" "TP_CH_D_DIMM_D1_RFU_1"
					( Origin gPackager )
				)
				( objectStatus "TP_CH_D_DIMM_D1_RFU_1" )
			)
			( signal "@baseboard_fab2_lib.baseboard_fab2(sch_1):tp_ch_d_dimm_d1_rfu_2"
				( attribute "CDS_PHYS_NET_NAME" "TP_CH_D_DIMM_D1_RFU_2"
					( Origin gPackager )
				)
				( objectStatus "TP_CH_D_DIMM_D1_RFU_2" )
			)
			( signal "@baseboard_fab2_lib.baseboard_fab2(sch_1):m_e_vref"
				( attribute "CDS_PHYS_NET_NAME" "M_E_VREF"
					( Origin gPackager )
				)
				( objectStatus "M_E_VREF" )
			)
			( signal "@baseboard_fab2_lib.baseboard_fab2(sch_1):tp_ch_e_dimm_e0_rfu_0"
				( attribute "CDS_PHYS_NET_NAME" "TP_CH_E_DIMM_E0_RFU_0"
					( Origin gPackager )
				)
				( objectStatus "TP_CH_E_DIMM_E0_RFU_0" )
			)
			( signal "@baseboard_fab2_lib.baseboard_fab2(sch_1):tp_ch_e_dimm_e0_rfu_1"
				( attribute "CDS_PHYS_NET_NAME" "TP_CH_E_DIMM_E0_RFU_1"
					( Origin gPackager )
				)
				( objectStatus "TP_CH_E_DIMM_E0_RFU_1" )
			)
			( signal "@baseboard_fab2_lib.baseboard_fab2(sch_1):tp_ch_e_dimm_e0_rfu_2"
				( attribute "CDS_PHYS_NET_NAME" "TP_CH_E_DIMM_E0_RFU_2"
					( Origin gPackager )
				)
				( objectStatus "TP_CH_E_DIMM_E0_RFU_2" )
			)
			( signal "@baseboard_fab2_lib.baseboard_fab2(sch_1):tp_ch_e_dimm_e1_rfu_0"
				( attribute "CDS_PHYS_NET_NAME" "TP_CH_E_DIMM_E1_RFU_0"
					( Origin gPackager )
				)
				( objectStatus "TP_CH_E_DIMM_E1_RFU_0" )
			)
			( signal "@baseboard_fab2_lib.baseboard_fab2(sch_1):tp_ch_e_dimm_e1_rfu_1"
				( attribute "CDS_PHYS_NET_NAME" "TP_CH_E_DIMM_E1_RFU_1"
					( Origin gPackager )
				)
				( objectStatus "TP_CH_E_DIMM_E1_RFU_1" )
			)
			( signal "@baseboard_fab2_lib.baseboard_fab2(sch_1):tp_ch_e_dimm_e1_rfu_2"
				( attribute "CDS_PHYS_NET_NAME" "TP_CH_E_DIMM_E1_RFU_2"
					( Origin gPackager )
				)
				( objectStatus "TP_CH_E_DIMM_E1_RFU_2" )
			)
			( signal "@baseboard_fab2_lib.baseboard_fab2(sch_1):m_f_vref"
				( attribute "CDS_PHYS_NET_NAME" "M_F_VREF"
					( Origin gPackager )
				)
				( objectStatus "M_F_VREF" )
			)
			( signal "@baseboard_fab2_lib.baseboard_fab2(sch_1):tp_ch_f_dimm_f0_rfu_0"
				( attribute "CDS_PHYS_NET_NAME" "TP_CH_F_DIMM_F0_RFU_0"
					( Origin gPackager )
				)
				( objectStatus "TP_CH_F_DIMM_F0_RFU_0" )
			)
			( signal "@baseboard_fab2_lib.baseboard_fab2(sch_1):tp_ch_f_dimm_f0_rfu_1"
				( attribute "CDS_PHYS_NET_NAME" "TP_CH_F_DIMM_F0_RFU_1"
					( Origin gPackager )
				)
				( objectStatus "TP_CH_F_DIMM_F0_RFU_1" )
			)
			( signal "@baseboard_fab2_lib.baseboard_fab2(sch_1):tp_ch_f_dimm_f0_rfu_2"
				( attribute "CDS_PHYS_NET_NAME" "TP_CH_F_DIMM_F0_RFU_2"
					( Origin gPackager )
				)
				( objectStatus "TP_CH_F_DIMM_F0_RFU_2" )
			)
			( signal "@baseboard_fab2_lib.baseboard_fab2(sch_1):tp_ch_f_dimm_f1_rfu_0"
				( attribute "CDS_PHYS_NET_NAME" "TP_CH_F_DIMM_F1_RFU_0"
					( Origin gPackager )
				)
				( objectStatus "TP_CH_F_DIMM_F1_RFU_0" )
			)
			( signal "@baseboard_fab2_lib.baseboard_fab2(sch_1):tp_ch_f_dimm_f1_rfu_1"
				( attribute "CDS_PHYS_NET_NAME" "TP_CH_F_DIMM_F1_RFU_1"
					( Origin gPackager )
				)
				( objectStatus "TP_CH_F_DIMM_F1_RFU_1" )
			)
			( signal "@baseboard_fab2_lib.baseboard_fab2(sch_1):tp_ch_f_dimm_f1_rfu_2"
				( attribute "CDS_PHYS_NET_NAME" "TP_CH_F_DIMM_F1_RFU_2"
					( Origin gPackager )
				)
				( objectStatus "TP_CH_F_DIMM_F1_RFU_2" )
			)
			( signal "@baseboard_fab2_lib.baseboard_fab2(sch_1):a_cpu1_ghj_rcomp0"
				( attribute "CDS_PHYS_NET_NAME" "A_CPU1_GHJ_RCOMP0"
					( Origin gPackager )
				)
				( objectStatus "A_CPU1_GHJ_RCOMP0" )
			)
			( signal "@baseboard_fab2_lib.baseboard_fab2(sch_1):a_cpu1_ghj_rcomp1"
				( attribute "CDS_PHYS_NET_NAME" "A_CPU1_GHJ_RCOMP1"
					( Origin gPackager )
				)
				( objectStatus "A_CPU1_GHJ_RCOMP1" )
			)
			( signal "@baseboard_fab2_lib.baseboard_fab2(sch_1):a_cpu1_ghj_rcomp2"
				( attribute "CDS_PHYS_NET_NAME" "A_CPU1_GHJ_RCOMP2"
					( Origin gPackager )
				)
				( objectStatus "A_CPU1_GHJ_RCOMP2" )
			)
			( signal "@baseboard_fab2_lib.baseboard_fab2(sch_1):a_cpu1_klm_rcomp0"
				( attribute "CDS_PHYS_NET_NAME" "A_CPU1_KLM_RCOMP0"
					( Origin gPackager )
				)
				( objectStatus "A_CPU1_KLM_RCOMP0" )
			)
			( signal "@baseboard_fab2_lib.baseboard_fab2(sch_1):a_cpu1_klm_rcomp1"
				( attribute "CDS_PHYS_NET_NAME" "A_CPU1_KLM_RCOMP1"
					( Origin gPackager )
				)
				( objectStatus "A_CPU1_KLM_RCOMP1" )
			)
			( signal "@baseboard_fab2_lib.baseboard_fab2(sch_1):a_cpu1_klm_rcomp2"
				( attribute "CDS_PHYS_NET_NAME" "A_CPU1_KLM_RCOMP2"
					( Origin gPackager )
				)
				( objectStatus "A_CPU1_KLM_RCOMP2" )
			)
			( signal "@baseboard_fab2_lib.baseboard_fab2(sch_1):a_cpu1_mcp01_rbias"
				( attribute "CDS_PHYS_NET_NAME" "A_CPU1_MCP01_RBIAS"
					( Origin gPackager )
				)
				( objectStatus "A_CPU1_MCP01_RBIAS" )
			)
			( signal "@baseboard_fab2_lib.baseboard_fab2(sch_1):a_cpu1_pe012_rbias"
				( attribute "CDS_PHYS_NET_NAME" "A_CPU1_PE012_RBIAS"
					( Origin gPackager )
				)
				( objectStatus "A_CPU1_PE012_RBIAS" )
			)
			( signal "@baseboard_fab2_lib.baseboard_fab2(sch_1):a_cpu1_pe3_rbias"
				( attribute "CDS_PHYS_NET_NAME" "A_CPU1_PE3_RBIAS"
					( Origin gPackager )
				)
				( objectStatus "A_CPU1_PE3_RBIAS" )
			)
			( signal "@baseboard_fab2_lib.baseboard_fab2(sch_1):a_cpu1_upi01_rbias"
				( attribute "CDS_PHYS_NET_NAME" "A_CPU1_UPI01_RBIAS"
					( Origin gPackager )
				)
				( objectStatus "A_CPU1_UPI01_RBIAS" )
			)
			( signal "@baseboard_fab2_lib.baseboard_fab2(sch_1):a_cpu1_upi2_rbias"
				( attribute "CDS_PHYS_NET_NAME" "A_CPU1_UPI2_RBIAS"
					( Origin gPackager )
				)
				( objectStatus "A_CPU1_UPI2_RBIAS" )
			)
			( signal "@baseboard_fab2_lib.baseboard_fab2(sch_1):clk_100m_cpu1_bclk0_dn"
				( attribute "CDS_PHYS_NET_NAME" "CLK_100M_CPU1_BCLK0_DN"
					( Origin gPackager )
				)
				( objectStatus "CLK_100M_CPU1_BCLK0_DN" )
			)
			( signal "@baseboard_fab2_lib.baseboard_fab2(sch_1):clk_100m_cpu1_bclk0_dp"
				( attribute "CDS_PHYS_NET_NAME" "CLK_100M_CPU1_BCLK0_DP"
					( Origin gPackager )
				)
				( objectStatus "CLK_100M_CPU1_BCLK0_DP" )
			)
			( signal "@baseboard_fab2_lib.baseboard_fab2(sch_1):clk_100m_cpu1_bclk1_dn"
				( attribute "CDS_PHYS_NET_NAME" "CLK_100M_CPU1_BCLK1_DN"
					( Origin gPackager )
				)
				( objectStatus "CLK_100M_CPU1_BCLK1_DN" )
			)
			( signal "@baseboard_fab2_lib.baseboard_fab2(sch_1):clk_100m_cpu1_bclk1_dp"
				( attribute "CDS_PHYS_NET_NAME" "CLK_100M_CPU1_BCLK1_DP"
					( Origin gPackager )
				)
				( objectStatus "CLK_100M_CPU1_BCLK1_DP" )
			)
			( signal "@baseboard_fab2_lib.baseboard_fab2(sch_1):clk_100m_cpu1_bclk2_dn"
				( attribute "CDS_PHYS_NET_NAME" "CLK_100M_CPU1_BCLK2_DN"
					( Origin gPackager )
				)
				( objectStatus "CLK_100M_CPU1_BCLK2_DN" )
			)
			( signal "@baseboard_fab2_lib.baseboard_fab2(sch_1):clk_100m_cpu1_bclk2_dp"
				( attribute "CDS_PHYS_NET_NAME" "CLK_100M_CPU1_BCLK2_DP"
					( Origin gPackager )
				)
				( objectStatus "CLK_100M_CPU1_BCLK2_DP" )
			)
			( signal "@baseboard_fab2_lib.baseboard_fab2(sch_1):fm_cpu1_pkgid0"
				( attribute "CDS_PHYS_NET_NAME" "FM_CPU1_PKGID0"
					( Origin gPackager )
				)
				( objectStatus "FM_CPU1_PKGID0" )
			)
			( signal "@baseboard_fab2_lib.baseboard_fab2(sch_1):fm_cpu1_pkgid1"
				( attribute "CDS_PHYS_NET_NAME" "FM_CPU1_PKGID1"
					( Origin gPackager )
				)
				( objectStatus "FM_CPU1_PKGID1" )
			)
			( signal "@baseboard_fab2_lib.baseboard_fab2(sch_1):fm_cpu1_pkgid2"
				( attribute "CDS_PHYS_NET_NAME" "FM_CPU1_PKGID2"
					( Origin gPackager )
				)
				( objectStatus "FM_CPU1_PKGID2" )
			)
			( signal "@baseboard_fab2_lib.baseboard_fab2(sch_1):fm_cpu1_proc_id0"
				( attribute "CDS_PHYS_NET_NAME" "FM_CPU1_PROC_ID0"
					( Origin gPackager )
				)
				( objectStatus "FM_CPU1_PROC_ID0" )
			)
			( signal "@baseboard_fab2_lib.baseboard_fab2(sch_1):fm_cpu1_proc_id1"
				( attribute "CDS_PHYS_NET_NAME" "FM_CPU1_PROC_ID1"
					( Origin gPackager )
				)
				( objectStatus "FM_CPU1_PROC_ID1" )
			)
			( signal "@baseboard_fab2_lib.baseboard_fab2(sch_1):fm_cpu1_sktocc_lvt3_n"
				( attribute "CDS_PHYS_NET_NAME" "FM_CPU1_SKTOCC_LVT3_N"
					( Origin gPackager )
				)
				( attribute "PHYS_NET_NAME" "FM_CPU1_SKTOCC_LVT3_N"
					( Origin gPackager )
				)
				( objectStatus "FM_CPU1_SKTOCC_LVT3_N" )
			)
			( signal "@baseboard_fab2_lib.baseboard_fab2(sch_1):fm_cpu1_sm_wp"
				( attribute "CDS_PHYS_NET_NAME" "FM_CPU1_SM_WP"
					( Origin gPackager )
				)
				( objectStatus "FM_CPU1_SM_WP" )
			)
			( signal "@baseboard_fab2_lib.baseboard_fab2(sch_1):h_cpu1_bmcinit"
				( attribute "CDS_PHYS_NET_NAME" "H_CPU1_BMCINIT"
					( Origin gPackager )
				)
				( objectStatus "H_CPU1_BMCINIT" )
			)
			( signal "@baseboard_fab2_lib.baseboard_fab2(sch_1):h_cpu1_caterr_g_n"
				( attribute "CDS_PHYS_NET_NAME" "H_CPU1_CATERR_G_N"
					( Origin gPackager )
				)
				( objectStatus "H_CPU1_CATERR_G_N" )
			)
			( signal "@baseboard_fab2_lib.baseboard_fab2(sch_1):h_cpu1_err0_g_n"
				( attribute "CDS_PHYS_NET_NAME" "H_CPU1_ERR0_G_N"
					( Origin gPackager )
				)
				( objectStatus "H_CPU1_ERR0_G_N" )
			)
			( signal "@baseboard_fab2_lib.baseboard_fab2(sch_1):h_cpu1_err1_g_n"
				( attribute "CDS_PHYS_NET_NAME" "H_CPU1_ERR1_G_N"
					( Origin gPackager )
				)
				( objectStatus "H_CPU1_ERR1_G_N" )
			)
			( signal "@baseboard_fab2_lib.baseboard_fab2(sch_1):h_cpu1_err2_g_n"
				( attribute "CDS_PHYS_NET_NAME" "H_CPU1_ERR2_G_N"
					( Origin gPackager )
				)
				( objectStatus "H_CPU1_ERR2_G_N" )
			)
			( signal "@baseboard_fab2_lib.baseboard_fab2(sch_1):h_cpu1_fast_wake_n"
				( attribute "CDS_PHYS_NET_NAME" "H_CPU1_FAST_WAKE_N"
					( Origin gPackager )
				)
				( objectStatus "H_CPU1_FAST_WAKE_N" )
			)
			( signal "@baseboard_fab2_lib.baseboard_fab2(sch_1):h_cpu1_memghj_memhot_g_n"
				( attribute "CDS_PHYS_NET_NAME" "H_CPU1_MEMGHJ_MEMHOT_G_N"
					( Origin gPackager )
				)
				( objectStatus "H_CPU1_MEMGHJ_MEMHOT_G_N" )
			)
			( signal "@baseboard_fab2_lib.baseboard_fab2(sch_1):h_cpu1_memklm_memhot_g_n"
				( attribute "CDS_PHYS_NET_NAME" "H_CPU1_MEMKLM_MEMHOT_G_N"
					( Origin gPackager )
				)
				( objectStatus "H_CPU1_MEMKLM_MEMHOT_G_N" )
			)
			( signal "@baseboard_fab2_lib.baseboard_fab2(sch_1):h_cpu1_msmi_g_n"
				( attribute "CDS_PHYS_NET_NAME" "H_CPU1_MSMI_G_N"
					( Origin gPackager )
				)
				( objectStatus "H_CPU1_MSMI_G_N" )
			)
			( signal "@baseboard_fab2_lib.baseboard_fab2(sch_1):h_cpu1_prochot_g_n"
				( attribute "CDS_PHYS_NET_NAME" "H_CPU1_PROCHOT_G_N"
					( Origin gPackager )
				)
				( objectStatus "H_CPU1_PROCHOT_G_N" )
			)
			( signal "@baseboard_fab2_lib.baseboard_fab2(sch_1):h_cpu1_thermtrip_g_n"
				( attribute "CDS_PHYS_NET_NAME" "H_CPU1_THERMTRIP_G_N"
					( Origin gPackager )
				)
				( objectStatus "H_CPU1_THERMTRIP_G_N" )
			)
			( signal "@baseboard_fab2_lib.baseboard_fab2(sch_1):h_pm_sync_gtl_r2"
				( attribute "CDS_PHYS_NET_NAME" "H_PM_SYNC_GTL_R2"
					( Origin gPackager )
				)
				( objectStatus "H_PM_SYNC_GTL_R2" )
			)
			( signal "@baseboard_fab2_lib.baseboard_fab2(sch_1):h_pmsync_clk_24m_cpu1"
				( attribute "CDS_PHYS_NET_NAME" "H_PMSYNC_CLK_24M_CPU1"
					( Origin gPackager )
				)
				( objectStatus "H_PMSYNC_CLK_24M_CPU1" )
			)
			( signal "@baseboard_fab2_lib.baseboard_fab2(sch_1):m_g_cpu_vref"
				( attribute "CDS_PHYS_NET_NAME" "M_G_CPU_VREF"
					( Origin gPackager )
				)
				( objectStatus "M_G_CPU_VREF" )
			)
			( signal "@baseboard_fab2_lib.baseboard_fab2(sch_1):m_ghj_rst_n"
				( attribute "CDS_PHYS_NET_NAME" "M_GHJ_RST_N"
					( Origin gPackager )
				)
				( objectStatus "M_GHJ_RST_N" )
			)
			( signal "@baseboard_fab2_lib.baseboard_fab2(sch_1):m_h_cpu_vref"
				( attribute "CDS_PHYS_NET_NAME" "M_H_CPU_VREF"
					( Origin gPackager )
				)
				( objectStatus "M_H_CPU_VREF" )
			)
			( signal "@baseboard_fab2_lib.baseboard_fab2(sch_1):m_j_cpu_vref"
				( attribute "CDS_PHYS_NET_NAME" "M_J_CPU_VREF"
					( Origin gPackager )
				)
				( objectStatus "M_J_CPU_VREF" )
			)
			( signal "@baseboard_fab2_lib.baseboard_fab2(sch_1):m_k_cpu_vref"
				( attribute "CDS_PHYS_NET_NAME" "M_K_CPU_VREF"
					( Origin gPackager )
				)
				( objectStatus "M_K_CPU_VREF" )
			)
			( signal "@baseboard_fab2_lib.baseboard_fab2(sch_1):m_klm_rst_n"
				( attribute "CDS_PHYS_NET_NAME" "M_KLM_RST_N"
					( Origin gPackager )
				)
				( objectStatus "M_KLM_RST_N" )
			)
			( signal "@baseboard_fab2_lib.baseboard_fab2(sch_1):m_l_cpu_vref"
				( attribute "CDS_PHYS_NET_NAME" "M_L_CPU_VREF"
					( Origin gPackager )
				)
				( objectStatus "M_L_CPU_VREF" )
			)
			( signal "@baseboard_fab2_lib.baseboard_fab2(sch_1):m_m_cpu_vref"
				( attribute "CDS_PHYS_NET_NAME" "M_M_CPU_VREF"
					( Origin gPackager )
				)
				( objectStatus "M_M_CPU_VREF" )
			)
			( signal "@baseboard_fab2_lib.baseboard_fab2(sch_1):pd_cpu1_bist_enable"
				( attribute "CDS_PHYS_NET_NAME" "PD_CPU1_BIST_ENABLE"
					( Origin gPackager )
				)
				( objectStatus "PD_CPU1_BIST_ENABLE" )
			)
			( signal "@baseboard_fab2_lib.baseboard_fab2(sch_1):pd_cpu1_ksfc_dis"
				( attribute "CDS_PHYS_NET_NAME" "PD_CPU1_KSFC_DIS"
					( Origin gPackager )
				)
				( objectStatus "PD_CPU1_KSFC_DIS" )
			)
			( signal "@baseboard_fab2_lib.baseboard_fab2(sch_1):pd_cpu1_test12"
				( attribute "CDS_PHYS_NET_NAME" "PD_CPU1_TEST12"
					( Origin gPackager )
				)
				( objectStatus "PD_CPU1_TEST12" )
			)
			( signal "@baseboard_fab2_lib.baseboard_fab2(sch_1):pd_cpu1_test13"
				( attribute "CDS_PHYS_NET_NAME" "PD_CPU1_TEST13"
					( Origin gPackager )
				)
				( objectStatus "PD_CPU1_TEST13" )
			)
			( signal "@baseboard_fab2_lib.baseboard_fab2(sch_1):pd_cpu1_test14"
				( attribute "CDS_PHYS_NET_NAME" "PD_CPU1_TEST14"
					( Origin gPackager )
				)
				( objectStatus "PD_CPU1_TEST14" )
			)
			( signal "@baseboard_fab2_lib.baseboard_fab2(sch_1):pd_cpu1_txt_plten"
				( attribute "CDS_PHYS_NET_NAME" "PD_CPU1_TXT_PLTEN"
					( Origin gPackager )
				)
				( objectStatus "PD_CPU1_TXT_PLTEN" )
			)
			( signal "@baseboard_fab2_lib.baseboard_fab2(sch_1):pd_pirom_cpu1_addr1"
				( attribute "CDS_PHYS_NET_NAME" "PD_PIROM_CPU1_ADDR1"
					( Origin gPackager )
				)
				( objectStatus "PD_PIROM_CPU1_ADDR1" )
			)
			( signal "@baseboard_fab2_lib.baseboard_fab2(sch_1):pd_pirom_cpu1_addr2"
				( attribute "CDS_PHYS_NET_NAME" "PD_PIROM_CPU1_ADDR2"
					( Origin gPackager )
				)
				( objectStatus "PD_PIROM_CPU1_ADDR2" )
			)
			( signal "@baseboard_fab2_lib.baseboard_fab2(sch_1):pu_cpu1_frmagent"
				( attribute "CDS_PHYS_NET_NAME" "PU_CPU1_FRMAGENT"
					( Origin gPackager )
				)
				( objectStatus "PU_CPU1_FRMAGENT" )
			)
			( signal "@baseboard_fab2_lib.baseboard_fab2(sch_1):pu_cpu1_legacy_skt"
				( attribute "CDS_PHYS_NET_NAME" "PU_CPU1_LEGACY_SKT"
					( Origin gPackager )
				)
				( objectStatus "PU_CPU1_LEGACY_SKT" )
			)
			( signal "@baseboard_fab2_lib.baseboard_fab2(sch_1):pu_cpu1_safe_mode_boot"
				( attribute "CDS_PHYS_NET_NAME" "PU_CPU1_SAFE_MODE_BOOT"
					( Origin gPackager )
				)
				( objectStatus "PU_CPU1_SAFE_MODE_BOOT" )
			)
			( signal "@baseboard_fab2_lib.baseboard_fab2(sch_1):pu_cpu1_socket_id_0"
				( attribute "CDS_PHYS_NET_NAME" "PU_CPU1_SOCKET_ID_0"
					( Origin gPackager )
				)
				( objectStatus "PU_CPU1_SOCKET_ID_0" )
			)
			( signal "@baseboard_fab2_lib.baseboard_fab2(sch_1):pu_cpu1_socket_id_1"
				( attribute "CDS_PHYS_NET_NAME" "PU_CPU1_SOCKET_ID_1"
					( Origin gPackager )
				)
				( objectStatus "PU_CPU1_SOCKET_ID_1" )
			)
			( signal "@baseboard_fab2_lib.baseboard_fab2(sch_1):pu_cpu1_tsc_sync"
				( attribute "CDS_PHYS_NET_NAME" "PU_CPU1_TSC_SYNC"
					( Origin gPackager )
				)
				( objectStatus "PU_CPU1_TSC_SYNC" )
			)
			( signal "@baseboard_fab2_lib.baseboard_fab2(sch_1):pu_cpu1_txt_agent"
				( attribute "CDS_PHYS_NET_NAME" "PU_CPU1_TXT_AGENT"
					( Origin gPackager )
				)
				( objectStatus "PU_CPU1_TXT_AGENT" )
			)
			( signal "@baseboard_fab2_lib.baseboard_fab2(sch_1):pu_pirom_cpu1_addr0"
				( attribute "CDS_PHYS_NET_NAME" "PU_PIROM_CPU1_ADDR0"
					( Origin gPackager )
				)
				( objectStatus "PU_PIROM_CPU1_ADDR0" )
			)
			( signal "@baseboard_fab2_lib.baseboard_fab2(sch_1):pvccio_cpu1"
				( alias ( signalRef "@baseboard_fab2_lib.baseboard_fab2(sch_1):page55_pvccio_cpu1") )
				( alias ( signalRef "@baseboard_fab2_lib.baseboard_fab2(sch_1):page71_pvccio_cpu1") )
				( alias ( signalRef "@baseboard_fab2_lib.baseboard_fab2(sch_1):page72_pvccio_cpu1") )
				( alias ( signalRef "@baseboard_fab2_lib.baseboard_fab2(sch_1):page73_pvccio_cpu1") )
				( alias ( signalRef "@baseboard_fab2_lib.baseboard_fab2(sch_1):page76_pvccio_cpu1") )
				( alias ( signalRef "@baseboard_fab2_lib.baseboard_fab2(sch_1):page90_pvccio_cpu1") )
				( alias ( signalRef "@baseboard_fab2_lib.baseboard_fab2(sch_1):page92_pvccio_cpu1") )
				( alias ( signalRef "@baseboard_fab2_lib.baseboard_fab2(sch_1):page93_pvccio_cpu1") )
				( alias ( signalRef "@baseboard_fab2_lib.baseboard_fab2(sch_1):page96_pvccio_cpu1") )
				( alias ( signalRef "@baseboard_fab2_lib.baseboard_fab2(sch_1):page97_pvccio_cpu1") )
				( alias ( signalRef "@baseboard_fab2_lib.baseboard_fab2(sch_1):page99_pvccio_cpu1") )
				( alias ( signalRef "@baseboard_fab2_lib.baseboard_fab2(sch_1):page112_pvccio_cpu1") )
				( alias ( signalRef "@baseboard_fab2_lib.baseboard_fab2(sch_1):page152_pvccio_cpu1") )
				( alias ( signalRef "@baseboard_fab2_lib.baseboard_fab2(sch_1):page163_pvccio_cpu1") )
				( alias ( signalRef "@baseboard_fab2_lib.baseboard_fab2(sch_1):page193_pvccio_cpu1") )
				( alias ( signalRef "@baseboard_fab2_lib.baseboard_fab2(sch_1):page206_pvccio_cpu1") )
				( alias ( signalRef "@baseboard_fab2_lib.baseboard_fab2(sch_1):page213_pvccio_cpu1") )
				( alias ( signalRef "@baseboard_fab2_lib.baseboard_fab2(sch_1):page214_pvccio_cpu1") )
				( alias ( signalRef "@baseboard_fab2_lib.baseboard_fab2(sch_1):page223_pvccio_cpu1") )
				( alias ( signalRef "@baseboard_fab2_lib.baseboard_fab2(sch_1):page226_pvccio_cpu1") )
				( attribute "CDS_PHYS_NET_NAME" "PVCCIO_CPU1"
					( Origin gPackager )
				)
				( attribute "VOLTAGE" "1.1V"
					( Units "uVoltage" "V" 1.000000)
					( Status sAliasFlattened )
					( Origin gFrontEnd )
				)
				( objectStatus "PVCCIO_CPU1" )
			)
			( signal "@baseboard_fab2_lib.baseboard_fab2(sch_1):page55_pvccio_cpu1"
				( attribute "VOLTAGE" "1.1V"
					( Units "uVoltage" "V" 1.000000)
					( Origin gFrontEnd )
				)
				( objectFlag fObjectAlias )
				( objectStatus "page55_pvccio_cpu1" )
			)
			( signal "@baseboard_fab2_lib.baseboard_fab2(sch_1):page71_pvccio_cpu1"
				( attribute "VOLTAGE" "1.1V"
					( Units "uVoltage" "V" 1.000000)
					( Origin gFrontEnd )
				)
				( objectFlag fObjectAlias )
				( objectStatus "page71_pvccio_cpu1" )
			)
			( signal "@baseboard_fab2_lib.baseboard_fab2(sch_1):page72_pvccio_cpu1"
				( attribute "VOLTAGE" "1.1V"
					( Units "uVoltage" "V" 1.000000)
					( Origin gFrontEnd )
				)
				( objectFlag fObjectAlias )
				( objectStatus "page72_pvccio_cpu1" )
			)
			( signal "@baseboard_fab2_lib.baseboard_fab2(sch_1):page73_pvccio_cpu1"
				( attribute "VOLTAGE" "1.1V"
					( Units "uVoltage" "V" 1.000000)
					( Origin gFrontEnd )
				)
				( objectFlag fObjectAlias )
				( objectStatus "page73_pvccio_cpu1" )
			)
			( signal "@baseboard_fab2_lib.baseboard_fab2(sch_1):page76_pvccio_cpu1"
				( attribute "VOLTAGE" "1.1V"
					( Units "uVoltage" "V" 1.000000)
					( Origin gFrontEnd )
				)
				( objectFlag fObjectAlias )
				( objectStatus "page76_pvccio_cpu1" )
			)
			( signal "@baseboard_fab2_lib.baseboard_fab2(sch_1):page90_pvccio_cpu1"
				( attribute "VOLTAGE" "1.1V"
					( Units "uVoltage" "V" 1.000000)
					( Origin gFrontEnd )
				)
				( objectFlag fObjectAlias )
				( objectStatus "page90_pvccio_cpu1" )
			)
			( signal "@baseboard_fab2_lib.baseboard_fab2(sch_1):page92_pvccio_cpu1"
				( attribute "VOLTAGE" "1.1V"
					( Units "uVoltage" "V" 1.000000)
					( Origin gFrontEnd )
				)
				( objectFlag fObjectAlias )
				( objectStatus "page92_pvccio_cpu1" )
			)
			( signal "@baseboard_fab2_lib.baseboard_fab2(sch_1):page93_pvccio_cpu1"
				( attribute "VOLTAGE" "1.1V"
					( Units "uVoltage" "V" 1.000000)
					( Origin gFrontEnd )
				)
				( objectFlag fObjectAlias )
				( objectStatus "page93_pvccio_cpu1" )
			)
			( signal "@baseboard_fab2_lib.baseboard_fab2(sch_1):page96_pvccio_cpu1"
				( attribute "VOLTAGE" "1.1V"
					( Units "uVoltage" "V" 1.000000)
					( Origin gFrontEnd )
				)
				( objectFlag fObjectAlias )
				( objectStatus "page96_pvccio_cpu1" )
			)
			( signal "@baseboard_fab2_lib.baseboard_fab2(sch_1):page97_pvccio_cpu1"
				( attribute "VOLTAGE" "1.1V"
					( Units "uVoltage" "V" 1.000000)
					( Origin gFrontEnd )
				)
				( objectFlag fObjectAlias )
				( objectStatus "page97_pvccio_cpu1" )
			)
			( signal "@baseboard_fab2_lib.baseboard_fab2(sch_1):page99_pvccio_cpu1"
				( attribute "VOLTAGE" "1.1V"
					( Units "uVoltage" "V" 1.000000)
					( Origin gFrontEnd )
				)
				( objectFlag fObjectAlias )
				( objectStatus "page99_pvccio_cpu1" )
			)
			( signal "@baseboard_fab2_lib.baseboard_fab2(sch_1):page112_pvccio_cpu1"
				( attribute "VOLTAGE" "1.1V"
					( Units "uVoltage" "V" 1.000000)
					( Origin gFrontEnd )
				)
				( objectFlag fObjectAlias )
				( objectStatus "page112_pvccio_cpu1" )
			)
			( signal "@baseboard_fab2_lib.baseboard_fab2(sch_1):page152_pvccio_cpu1"
				( attribute "VOLTAGE" "1.1V"
					( Units "uVoltage" "V" 1.000000)
					( Origin gFrontEnd )
				)
				( objectFlag fObjectAlias )
				( objectStatus "page152_pvccio_cpu1" )
			)
			( signal "@baseboard_fab2_lib.baseboard_fab2(sch_1):page163_pvccio_cpu1"
				( attribute "VOLTAGE" "1.1V"
					( Units "uVoltage" "V" 1.000000)
					( Origin gFrontEnd )
				)
				( objectFlag fObjectAlias )
				( objectStatus "page163_pvccio_cpu1" )
			)
			( signal "@baseboard_fab2_lib.baseboard_fab2(sch_1):page193_pvccio_cpu1"
				( attribute "VOLTAGE" "1.1V"
					( Units "uVoltage" "V" 1.000000)
					( Origin gFrontEnd )
				)
				( objectFlag fObjectAlias )
				( objectStatus "page193_pvccio_cpu1" )
			)
			( signal "@baseboard_fab2_lib.baseboard_fab2(sch_1):page206_pvccio_cpu1"
				( attribute "VOLTAGE" "1.1V"
					( Units "uVoltage" "V" 1.000000)
					( Origin gFrontEnd )
				)
				( objectFlag fObjectAlias )
				( objectStatus "page206_pvccio_cpu1" )
			)
			( signal "@baseboard_fab2_lib.baseboard_fab2(sch_1):page213_pvccio_cpu1"
				( attribute "VOLTAGE" "1.1V"
					( Units "uVoltage" "V" 1.000000)
					( Origin gFrontEnd )
				)
				( objectFlag fObjectAlias )
				( objectStatus "page213_pvccio_cpu1" )
			)
			( signal "@baseboard_fab2_lib.baseboard_fab2(sch_1):page214_pvccio_cpu1"
				( attribute "VOLTAGE" "1.1V"
					( Units "uVoltage" "V" 1.000000)
					( Origin gFrontEnd )
				)
				( objectFlag fObjectAlias )
				( objectStatus "page214_pvccio_cpu1" )
			)
			( signal "@baseboard_fab2_lib.baseboard_fab2(sch_1):page223_pvccio_cpu1"
				( attribute "VOLTAGE" "1.1V"
					( Units "uVoltage" "V" 1.000000)
					( Origin gFrontEnd )
				)
				( objectFlag fObjectAlias )
				( objectStatus "page223_pvccio_cpu1" )
			)
			( signal "@baseboard_fab2_lib.baseboard_fab2(sch_1):page226_pvccio_cpu1"
				( attribute "VOLTAGE" "1.1V"
					( Units "uVoltage" "V" 1.000000)
					( Origin gFrontEnd )
				)
				( objectFlag fObjectAlias )
				( objectStatus "page226_pvccio_cpu1" )
			)
			( signal "@baseboard_fab2_lib.baseboard_fab2(sch_1):pwrgd_cpu1_drampwrok_ghj_g"
				( attribute "CDS_PHYS_NET_NAME" "PWRGD_CPU1_DRAMPWROK_GHJ_G"
					( Origin gPackager )
				)
				( objectStatus "PWRGD_CPU1_DRAMPWROK_GHJ_G" )
			)
			( signal "@baseboard_fab2_lib.baseboard_fab2(sch_1):pwrgd_cpu1_drampwrok_klm_g"
				( attribute "CDS_PHYS_NET_NAME" "PWRGD_CPU1_DRAMPWROK_KLM_G"
					( Origin gPackager )
				)
				( objectStatus "PWRGD_CPU1_DRAMPWROK_KLM_G" )
			)
			( signal "@baseboard_fab2_lib.baseboard_fab2(sch_1):pwrgd_cpu1_g"
				( attribute "CDS_PHYS_NET_NAME" "PWRGD_CPU1_G"
					( Origin gPackager )
				)
				( objectStatus "PWRGD_CPU1_G" )
			)
			( signal "@baseboard_fab2_lib.baseboard_fab2(sch_1):rst_cpu1_g_n"
				( attribute "CDS_PHYS_NET_NAME" "RST_CPU1_G_N"
					( Origin gPackager )
				)
				( objectStatus "RST_CPU1_G_N" )
			)
			( signal "@baseboard_fab2_lib.baseboard_fab2(sch_1):smb_cpu1_pe_hp_gtl_scl"
				( attribute "CDS_PHYS_NET_NAME" "SMB_CPU1_PE_HP_GTL_SCL"
					( Origin gPackager )
				)
				( objectStatus "SMB_CPU1_PE_HP_GTL_SCL" )
			)
			( signal "@baseboard_fab2_lib.baseboard_fab2(sch_1):smb_cpu1_pe_hp_gtl_sda"
				( attribute "CDS_PHYS_NET_NAME" "SMB_CPU1_PE_HP_GTL_SDA"
					( Origin gPackager )
				)
				( objectStatus "SMB_CPU1_PE_HP_GTL_SDA" )
			)
			( signal "@baseboard_fab2_lib.baseboard_fab2(sch_1):smb_ddr_ghj_scl_g_r"
				( attribute "CDS_PHYS_NET_NAME" "SMB_DDR_GHJ_SCL_G_R"
					( Origin gPackager )
				)
				( objectStatus "SMB_DDR_GHJ_SCL_G_R" )
			)
			( signal "@baseboard_fab2_lib.baseboard_fab2(sch_1):smb_ddr_ghj_sda_g_r"
				( attribute "CDS_PHYS_NET_NAME" "SMB_DDR_GHJ_SDA_G_R"
					( Origin gPackager )
				)
				( objectStatus "SMB_DDR_GHJ_SDA_G_R" )
			)
			( signal "@baseboard_fab2_lib.baseboard_fab2(sch_1):smb_ddr_klm_scl_g_r"
				( attribute "CDS_PHYS_NET_NAME" "SMB_DDR_KLM_SCL_G_R"
					( Origin gPackager )
				)
				( objectStatus "SMB_DDR_KLM_SCL_G_R" )
			)
			( signal "@baseboard_fab2_lib.baseboard_fab2(sch_1):smb_ddr_klm_sda_g_r"
				( attribute "CDS_PHYS_NET_NAME" "SMB_DDR_KLM_SDA_G_R"
					( Origin gPackager )
				)
				( objectStatus "SMB_DDR_KLM_SDA_G_R" )
			)
			( signal "@baseboard_fab2_lib.baseboard_fab2(sch_1):smb_pirom_cpu1_scl"
				( attribute "CDS_PHYS_NET_NAME" "SMB_PIROM_CPU1_SCL"
					( Origin gPackager )
				)
				( objectStatus "SMB_PIROM_CPU1_SCL" )
			)
			( signal "@baseboard_fab2_lib.baseboard_fab2(sch_1):smb_pirom_cpu1_sda"
				( attribute "CDS_PHYS_NET_NAME" "SMB_PIROM_CPU1_SDA"
					( Origin gPackager )
				)
				( objectStatus "SMB_PIROM_CPU1_SDA" )
			)
			( signal "@baseboard_fab2_lib.baseboard_fab2(sch_1):svid_alert0_cpu1_n"
				( attribute "CDS_PHYS_NET_NAME" "SVID_ALERT0_CPU1_N"
					( Origin gPackager )
				)
				( objectStatus "SVID_ALERT0_CPU1_N" )
			)
			( signal "@baseboard_fab2_lib.baseboard_fab2(sch_1):svid_alert0_cpu1_r_n"
				( attribute "CDS_PHYS_NET_NAME" "SVID_ALERT0_CPU1_R_N"
					( Origin gPackager )
				)
				( objectStatus "SVID_ALERT0_CPU1_R_N" )
			)
			( signal "@baseboard_fab2_lib.baseboard_fab2(sch_1):svid_alert1_cpu1_n"
				( attribute "CDS_PHYS_NET_NAME" "SVID_ALERT1_CPU1_N"
					( Origin gPackager )
				)
				( objectStatus "SVID_ALERT1_CPU1_N" )
			)
			( signal "@baseboard_fab2_lib.baseboard_fab2(sch_1):svid_alert1_cpu1_r_n"
				( attribute "CDS_PHYS_NET_NAME" "SVID_ALERT1_CPU1_R_N"
					( Origin gPackager )
				)
				( objectStatus "SVID_ALERT1_CPU1_R_N" )
			)
			( signal "@baseboard_fab2_lib.baseboard_fab2(sch_1):svid_clk0_cpu1"
				( attribute "CDS_PHYS_NET_NAME" "SVID_CLK0_CPU1"
					( Origin gPackager )
				)
				( objectStatus "SVID_CLK0_CPU1" )
			)
			( signal "@baseboard_fab2_lib.baseboard_fab2(sch_1):svid_clk0_cpu1_r"
				( attribute "CDS_PHYS_NET_NAME" "SVID_CLK0_CPU1_R"
					( Origin gPackager )
				)
				( objectStatus "SVID_CLK0_CPU1_R" )
			)
			( signal "@baseboard_fab2_lib.baseboard_fab2(sch_1):svid_clk1_cpu1"
				( attribute "CDS_PHYS_NET_NAME" "SVID_CLK1_CPU1"
					( Origin gPackager )
				)
				( objectStatus "SVID_CLK1_CPU1" )
			)
			( signal "@baseboard_fab2_lib.baseboard_fab2(sch_1):svid_clk1_cpu1_r"
				( attribute "CDS_PHYS_NET_NAME" "SVID_CLK1_CPU1_R"
					( Origin gPackager )
				)
				( objectStatus "SVID_CLK1_CPU1_R" )
			)
			( signal "@baseboard_fab2_lib.baseboard_fab2(sch_1):svid_dio0_cpu1"
				( attribute "CDS_PHYS_NET_NAME" "SVID_DIO0_CPU1"
					( Origin gPackager )
				)
				( objectStatus "SVID_DIO0_CPU1" )
			)
			( signal "@baseboard_fab2_lib.baseboard_fab2(sch_1):svid_dio0_cpu1_r"
				( attribute "CDS_PHYS_NET_NAME" "SVID_DIO0_CPU1_R"
					( Origin gPackager )
				)
				( objectStatus "SVID_DIO0_CPU1_R" )
			)
			( signal "@baseboard_fab2_lib.baseboard_fab2(sch_1):svid_dio1_cpu1"
				( attribute "CDS_PHYS_NET_NAME" "SVID_DIO1_CPU1"
					( Origin gPackager )
				)
				( objectStatus "SVID_DIO1_CPU1" )
			)
			( signal "@baseboard_fab2_lib.baseboard_fab2(sch_1):svid_dio1_cpu1_r"
				( attribute "CDS_PHYS_NET_NAME" "SVID_DIO1_CPU1_R"
					( Origin gPackager )
				)
				( objectStatus "SVID_DIO1_CPU1_R" )
			)
			( signal "@baseboard_fab2_lib.baseboard_fab2(sch_1):tp_cpu1_nmi"
				( attribute "CDS_PHYS_NET_NAME" "TP_CPU1_NMI"
					( Origin gPackager )
				)
				( objectStatus "TP_CPU1_NMI" )
			)
			( signal "@baseboard_fab2_lib.baseboard_fab2(sch_1):tp_cpu1_proc_dis_g_n"
				( attribute "CDS_PHYS_NET_NAME" "TP_CPU1_PROC_DIS_G_N"
					( Origin gPackager )
				)
				( objectStatus "TP_CPU1_PROC_DIS_G_N" )
			)
			( signal "@baseboard_fab2_lib.baseboard_fab2(sch_1):tp_cpu1_socket_id_2"
				( attribute "CDS_PHYS_NET_NAME" "TP_CPU1_SOCKET_ID_2"
					( Origin gPackager )
				)
				( objectStatus "TP_CPU1_SOCKET_ID_2" )
			)
			( signal "@baseboard_fab2_lib.baseboard_fab2(sch_1):tp_xdp_cpu1_obsdata_b0_mbp2_n"
				( attribute "CDS_PHYS_NET_NAME" "TP_XDP_CPU1_OBSDATA_B0_MBP2_N"
					( Origin gPackager )
				)
				( objectStatus "TP_XDP_CPU1_OBSDATA_B0_MBP2_N" )
			)
			( signal "@baseboard_fab2_lib.baseboard_fab2(sch_1):tp_xdp_cpu1_obsdata_b1_mbp3_n"
				( attribute "CDS_PHYS_NET_NAME" "TP_XDP_CPU1_OBSDATA_B1_MBP3_N"
					( Origin gPackager )
				)
				( objectStatus "TP_XDP_CPU1_OBSDATA_B1_MBP3_N" )
			)
			( signal "@baseboard_fab2_lib.baseboard_fab2(sch_1):tp_xdp_cpu1_obsdata_b2_mbp4_n"
				( attribute "CDS_PHYS_NET_NAME" "TP_XDP_CPU1_OBSDATA_B2_MBP4_N"
					( Origin gPackager )
				)
				( objectStatus "TP_XDP_CPU1_OBSDATA_B2_MBP4_N" )
			)
			( signal "@baseboard_fab2_lib.baseboard_fab2(sch_1):tp_xdp_cpu1_obsdata_b3_mbp5_n"
				( attribute "CDS_PHYS_NET_NAME" "TP_XDP_CPU1_OBSDATA_B3_MBP5_N"
					( Origin gPackager )
				)
				( objectStatus "TP_XDP_CPU1_OBSDATA_B3_MBP5_N" )
			)
			( signal "@baseboard_fab2_lib.baseboard_fab2(sch_1):xdp_cpu1_tdi"
				( attribute "CDS_PHYS_NET_NAME" "XDP_CPU1_TDI"
					( Origin gPackager )
				)
				( objectStatus "XDP_CPU1_TDI" )
			)
			( signal "@baseboard_fab2_lib.baseboard_fab2(sch_1):xdp_cpu1_tdo"
				( attribute "CDS_PHYS_NET_NAME" "XDP_CPU1_TDO"
					( Origin gPackager )
				)
				( objectStatus "XDP_CPU1_TDO" )
			)
			( signal "@baseboard_fab2_lib.baseboard_fab2(sch_1):clk_100m_cpu1_rc_refclk0_dn"
				( attribute "CDS_PHYS_NET_NAME" "CLK_100M_CPU1_RC_REFCLK0_DN"
					( Origin gPackager )
				)
				( objectStatus "CLK_100M_CPU1_RC_REFCLK0_DN" )
			)
			( signal "@baseboard_fab2_lib.baseboard_fab2(sch_1):clk_100m_cpu1_rc_refclk0_dp"
				( attribute "CDS_PHYS_NET_NAME" "CLK_100M_CPU1_RC_REFCLK0_DP"
					( Origin gPackager )
				)
				( objectStatus "CLK_100M_CPU1_RC_REFCLK0_DP" )
			)
			( signal "@baseboard_fab2_lib.baseboard_fab2(sch_1):clk_322m_osc_cpu1_rc_dn"
				( attribute "CDS_PHYS_NET_NAME" "CLK_322M_OSC_CPU1_RC_DN"
					( Origin gPackager )
				)
				( objectStatus "CLK_322M_OSC_CPU1_RC_DN" )
			)
			( signal "@baseboard_fab2_lib.baseboard_fab2(sch_1):clk_322m_osc_cpu1_rc_dp"
				( attribute "CDS_PHYS_NET_NAME" "CLK_322M_OSC_CPU1_RC_DP"
					( Origin gPackager )
				)
				( objectStatus "CLK_322M_OSC_CPU1_RC_DP" )
			)
			( signal "@baseboard_fab2_lib.baseboard_fab2(sch_1):fm_cpu1_rc_error_n"
				( alias ( signalRef "@baseboard_fab2_lib.baseboard_fab2(sch_1):page145_fm_cpu1_rc_error_n") )
				( attribute "CDS_PHYS_NET_NAME" "FM_CPU1_RC_ERROR_N"
					( Origin gPackager )
				)
				( attribute "PHYS_NET_NAME" "FM_CPU1_RC_ERROR_N"
					( Origin gPackager )
				)
				( objectStatus "FM_CPU1_RC_ERROR_N" )
			)
			( signal "@baseboard_fab2_lib.baseboard_fab2(sch_1):page145_fm_cpu1_rc_error_n"
				( attribute "CDS_PHYS_NET_NAME" "FM_CPU1_RC_ERROR_N"
					( Origin gPackager )
				)
				( attribute "PHYS_NET_NAME" "FM_CPU1_RC_ERROR_N"
					( Origin gFrontEnd )
				)
				( objectFlag fObjectAlias )
				( objectStatus "page145_fm_cpu1_rc_error_n" )
			)
			( signal "@baseboard_fab2_lib.baseboard_fab2(sch_1):h_cpu1_fivr_fault_g"
				( attribute "CDS_PHYS_NET_NAME" "H_CPU1_FIVR_FAULT_G"
					( Origin gPackager )
				)
				( objectStatus "H_CPU1_FIVR_FAULT_G" )
			)
			( signal "@baseboard_fab2_lib.baseboard_fab2(sch_1):p1v8_mcp_cpu1"
				( alias ( signalRef "@baseboard_fab2_lib.baseboard_fab2(sch_1):page56_p1v8_mcp_cpu1") )
				( alias ( signalRef "@baseboard_fab2_lib.baseboard_fab2(sch_1):page72_p1v8_mcp_cpu1") )
				( alias ( signalRef "@baseboard_fab2_lib.baseboard_fab2(sch_1):page113_p1v8_mcp_cpu1") )
				( alias ( signalRef "@baseboard_fab2_lib.baseboard_fab2(sch_1):page193_p1v8_mcp_cpu1") )
				( attribute "VOLTAGE" "1.8"
					( Units "uVoltage" "V" 1.000000)
					( Status sAliasFlattened )
					( Origin gFrontEnd )
				)
				( attribute "CDS_PHYS_NET_NAME" "P1V8_MCP_CPU1"
					( Origin gPackager )
				)
				( objectStatus "P1V8_MCP_CPU1" )
			)
			( signal "@baseboard_fab2_lib.baseboard_fab2(sch_1):page56_p1v8_mcp_cpu1"
				( attribute "VOLTAGE" "1.8"
					( Units "uVoltage" "V" 1.000000)
					( Origin gFrontEnd )
				)
				( objectFlag fObjectAlias )
				( objectStatus "page56_p1v8_mcp_cpu1" )
			)
			( signal "@baseboard_fab2_lib.baseboard_fab2(sch_1):page72_p1v8_mcp_cpu1"
				( attribute "VOLTAGE" "1.8"
					( Units "uVoltage" "V" 1.000000)
					( Origin gFrontEnd )
				)
				( objectFlag fObjectAlias )
				( objectStatus "page72_p1v8_mcp_cpu1" )
			)
			( signal "@baseboard_fab2_lib.baseboard_fab2(sch_1):page113_p1v8_mcp_cpu1"
				( attribute "VOLTAGE" "1.8"
					( Units "uVoltage" "V" 1.000000)
					( Origin gFrontEnd )
				)
				( objectFlag fObjectAlias )
				( objectStatus "page113_p1v8_mcp_cpu1" )
			)
			( signal "@baseboard_fab2_lib.baseboard_fab2(sch_1):page193_p1v8_mcp_cpu1"
				( attribute "VOLTAGE" "1.8"
					( Units "uVoltage" "V" 1.000000)
					( Origin gFrontEnd )
				)
				( objectFlag fObjectAlias )
				( objectStatus "page193_p1v8_mcp_cpu1" )
			)
			( signal "@baseboard_fab2_lib.baseboard_fab2(sch_1):pd_cpu1_dmimode_override"
				( attribute "CDS_PHYS_NET_NAME" "PD_CPU1_DMIMODE_OVERRIDE"
					( Origin gPackager )
				)
				( objectStatus "PD_CPU1_DMIMODE_OVERRIDE" )
			)
			( signal "@baseboard_fab2_lib.baseboard_fab2(sch_1):pd_cpu1_rsvd_test_1"
				( attribute "CDS_PHYS_NET_NAME" "PD_CPU1_RSVD_TEST_1"
					( Origin gPackager )
				)
				( objectStatus "PD_CPU1_RSVD_TEST_1" )
			)
			( signal "@baseboard_fab2_lib.baseboard_fab2(sch_1):pd_cpu1_rsvd_test_2"
				( attribute "CDS_PHYS_NET_NAME" "PD_CPU1_RSVD_TEST_2"
					( Origin gPackager )
				)
				( objectStatus "PD_CPU1_RSVD_TEST_2" )
			)
			( signal "@baseboard_fab2_lib.baseboard_fab2(sch_1):pvccmcp_cpu1"
				( alias ( signalRef "@baseboard_fab2_lib.baseboard_fab2(sch_1):page56_pvccmcp_cpu1") )
				( alias ( signalRef "@baseboard_fab2_lib.baseboard_fab2(sch_1):page63_pvccmcp_cpu1") )
				( alias ( signalRef "@baseboard_fab2_lib.baseboard_fab2(sch_1):page70_pvccmcp_cpu1") )
				( alias ( signalRef "@baseboard_fab2_lib.baseboard_fab2(sch_1):page72_pvccmcp_cpu1") )
				( alias ( signalRef "@baseboard_fab2_lib.baseboard_fab2(sch_1):page73_pvccmcp_cpu1") )
				( alias ( signalRef "@baseboard_fab2_lib.baseboard_fab2(sch_1):page76_pvccmcp_cpu1") )
				( alias ( signalRef "@baseboard_fab2_lib.baseboard_fab2(sch_1):page193_pvccmcp_cpu1") )
				( attribute "VOLTAGE" "+0.95"
					( Units "uVoltage" "V" 1.000000)
					( Status sAliasFlattened )
					( Origin gFrontEnd )
				)
				( attribute "CDS_PHYS_NET_NAME" "PVCCMCP_CPU1"
					( Origin gPackager )
				)
				( objectStatus "PVCCMCP_CPU1" )
			)
			( signal "@baseboard_fab2_lib.baseboard_fab2(sch_1):page56_pvccmcp_cpu1"
				( objectFlag fObjectAlias )
				( objectStatus "page56_pvccmcp_cpu1" )
			)
			( signal "@baseboard_fab2_lib.baseboard_fab2(sch_1):page63_pvccmcp_cpu1"
				( objectFlag fObjectAlias )
				( objectStatus "page63_pvccmcp_cpu1" )
			)
			( signal "@baseboard_fab2_lib.baseboard_fab2(sch_1):page70_pvccmcp_cpu1"
				( objectFlag fObjectAlias )
				( objectStatus "page70_pvccmcp_cpu1" )
			)
			( signal "@baseboard_fab2_lib.baseboard_fab2(sch_1):page72_pvccmcp_cpu1"
				( objectFlag fObjectAlias )
				( objectStatus "page72_pvccmcp_cpu1" )
			)
			( signal "@baseboard_fab2_lib.baseboard_fab2(sch_1):page73_pvccmcp_cpu1"
				( objectFlag fObjectAlias )
				( objectStatus "page73_pvccmcp_cpu1" )
			)
			( signal "@baseboard_fab2_lib.baseboard_fab2(sch_1):page76_pvccmcp_cpu1"
				( objectFlag fObjectAlias )
				( objectStatus "page76_pvccmcp_cpu1" )
			)
			( signal "@baseboard_fab2_lib.baseboard_fab2(sch_1):page193_pvccmcp_cpu1"
				( attribute "VOLTAGE" "+0.95"
					( Units "uVoltage" "V" 1.000000)
					( Origin gFrontEnd )
				)
				( objectFlag fObjectAlias )
				( objectStatus "page193_pvccmcp_cpu1" )
			)
			( signal "@baseboard_fab2_lib.baseboard_fab2(sch_1):tp_cpu1_rsvd_194"
				( attribute "CDS_PHYS_NET_NAME" "TP_CPU1_RSVD_194"
					( Origin gPackager )
				)
				( objectStatus "TP_CPU1_RSVD_194" )
			)
			( signal "@baseboard_fab2_lib.baseboard_fab2(sch_1):tp_cpu1_rsvd_198"
				( attribute "CDS_PHYS_NET_NAME" "TP_CPU1_RSVD_198"
					( Origin gPackager )
				)
				( objectStatus "TP_CPU1_RSVD_198" )
			)
			( signal "@baseboard_fab2_lib.baseboard_fab2(sch_1):tp_cpu1_rsvd_199"
				( attribute "CDS_PHYS_NET_NAME" "TP_CPU1_RSVD_199"
					( Origin gPackager )
				)
				( objectStatus "TP_CPU1_RSVD_199" )
			)
			( signal "@baseboard_fab2_lib.baseboard_fab2(sch_1):tp_cpu1_rsvd_204"
				( attribute "CDS_PHYS_NET_NAME" "TP_CPU1_RSVD_204"
					( Origin gPackager )
				)
				( objectStatus "TP_CPU1_RSVD_204" )
			)
			( signal "@baseboard_fab2_lib.baseboard_fab2(sch_1):tp_cpu1_rsvd_205"
				( attribute "CDS_PHYS_NET_NAME" "TP_CPU1_RSVD_205"
					( Origin gPackager )
				)
				( objectStatus "TP_CPU1_RSVD_205" )
			)
			( signal "@baseboard_fab2_lib.baseboard_fab2(sch_1):tp_cpu1_rsvd_208"
				( attribute "CDS_PHYS_NET_NAME" "TP_CPU1_RSVD_208"
					( Origin gPackager )
				)
				( objectStatus "TP_CPU1_RSVD_208" )
			)
			( signal "@baseboard_fab2_lib.baseboard_fab2(sch_1):tp_cpu1_rsvd_210"
				( attribute "CDS_PHYS_NET_NAME" "TP_CPU1_RSVD_210"
					( Origin gPackager )
				)
				( objectStatus "TP_CPU1_RSVD_210" )
			)
			( signal "@baseboard_fab2_lib.baseboard_fab2(sch_1):tp_cpu1_rsvd_211"
				( attribute "CDS_PHYS_NET_NAME" "TP_CPU1_RSVD_211"
					( Origin gPackager )
				)
				( objectStatus "TP_CPU1_RSVD_211" )
			)
			( signal "@baseboard_fab2_lib.baseboard_fab2(sch_1):tp_cpu1_rsvd_212"
				( attribute "CDS_PHYS_NET_NAME" "TP_CPU1_RSVD_212"
					( Origin gPackager )
				)
				( objectStatus "TP_CPU1_RSVD_212" )
			)
			( signal "@baseboard_fab2_lib.baseboard_fab2(sch_1):tp_cpu1_rsvd_214"
				( attribute "CDS_PHYS_NET_NAME" "TP_CPU1_RSVD_214"
					( Origin gPackager )
				)
				( objectStatus "TP_CPU1_RSVD_214" )
			)
			( signal "@baseboard_fab2_lib.baseboard_fab2(sch_1):tp_cpu1_rsvd_216"
				( attribute "CDS_PHYS_NET_NAME" "TP_CPU1_RSVD_216"
					( Origin gPackager )
				)
				( objectStatus "TP_CPU1_RSVD_216" )
			)
			( signal "@baseboard_fab2_lib.baseboard_fab2(sch_1):tp_cpu1_rsvd_217"
				( attribute "CDS_PHYS_NET_NAME" "TP_CPU1_RSVD_217"
					( Origin gPackager )
				)
				( objectStatus "TP_CPU1_RSVD_217" )
			)
			( signal "@baseboard_fab2_lib.baseboard_fab2(sch_1):tp_cpu1_rsvd_218"
				( attribute "CDS_PHYS_NET_NAME" "TP_CPU1_RSVD_218"
					( Origin gPackager )
				)
				( objectStatus "TP_CPU1_RSVD_218" )
			)
			( signal "@baseboard_fab2_lib.baseboard_fab2(sch_1):tp_cpu1_rsvd_219"
				( attribute "CDS_PHYS_NET_NAME" "TP_CPU1_RSVD_219"
					( Origin gPackager )
				)
				( objectStatus "TP_CPU1_RSVD_219" )
			)
			( signal "@baseboard_fab2_lib.baseboard_fab2(sch_1):tp_cpu1_rsvd_222"
				( attribute "CDS_PHYS_NET_NAME" "TP_CPU1_RSVD_222"
					( Origin gPackager )
				)
				( objectStatus "TP_CPU1_RSVD_222" )
			)
			( signal "@baseboard_fab2_lib.baseboard_fab2(sch_1):tp_cpu1_rsvd_223"
				( attribute "CDS_PHYS_NET_NAME" "TP_CPU1_RSVD_223"
					( Origin gPackager )
				)
				( objectStatus "TP_CPU1_RSVD_223" )
			)
			( signal "@baseboard_fab2_lib.baseboard_fab2(sch_1):tp_cpu1_rsvd_224"
				( attribute "CDS_PHYS_NET_NAME" "TP_CPU1_RSVD_224"
					( Origin gPackager )
				)
				( objectStatus "TP_CPU1_RSVD_224" )
			)
			( signal "@baseboard_fab2_lib.baseboard_fab2(sch_1):tp_cpu1_rsvd_225"
				( attribute "CDS_PHYS_NET_NAME" "TP_CPU1_RSVD_225"
					( Origin gPackager )
				)
				( objectStatus "TP_CPU1_RSVD_225" )
			)
			( signal "@baseboard_fab2_lib.baseboard_fab2(sch_1):tp_cpu1_rsvd_226"
				( attribute "CDS_PHYS_NET_NAME" "TP_CPU1_RSVD_226"
					( Origin gPackager )
				)
				( objectStatus "TP_CPU1_RSVD_226" )
			)
			( signal "@baseboard_fab2_lib.baseboard_fab2(sch_1):tp_cpu1_rsvd_227"
				( attribute "CDS_PHYS_NET_NAME" "TP_CPU1_RSVD_227"
					( Origin gPackager )
				)
				( objectStatus "TP_CPU1_RSVD_227" )
			)
			( signal "@baseboard_fab2_lib.baseboard_fab2(sch_1):tp_cpu1_rsvd_228"
				( attribute "CDS_PHYS_NET_NAME" "TP_CPU1_RSVD_228"
					( Origin gPackager )
				)
				( objectStatus "TP_CPU1_RSVD_228" )
			)
			( signal "@baseboard_fab2_lib.baseboard_fab2(sch_1):tp_cpu1_rsvd_229"
				( attribute "CDS_PHYS_NET_NAME" "TP_CPU1_RSVD_229"
					( Origin gPackager )
				)
				( objectStatus "TP_CPU1_RSVD_229" )
			)
			( signal "@baseboard_fab2_lib.baseboard_fab2(sch_1):tp_cpu1_rsvd_230"
				( attribute "CDS_PHYS_NET_NAME" "TP_CPU1_RSVD_230"
					( Origin gPackager )
				)
				( objectStatus "TP_CPU1_RSVD_230" )
			)
			( signal "@baseboard_fab2_lib.baseboard_fab2(sch_1):tp_cpu1_rsvd_231"
				( attribute "CDS_PHYS_NET_NAME" "TP_CPU1_RSVD_231"
					( Origin gPackager )
				)
				( objectStatus "TP_CPU1_RSVD_231" )
			)
			( signal "@baseboard_fab2_lib.baseboard_fab2(sch_1):tp_cpu1_rsvd_232"
				( attribute "CDS_PHYS_NET_NAME" "TP_CPU1_RSVD_232"
					( Origin gPackager )
				)
				( objectStatus "TP_CPU1_RSVD_232" )
			)
			( signal "@baseboard_fab2_lib.baseboard_fab2(sch_1):tp_cpu1_rsvd_233"
				( attribute "CDS_PHYS_NET_NAME" "TP_CPU1_RSVD_233"
					( Origin gPackager )
				)
				( objectStatus "TP_CPU1_RSVD_233" )
			)
			( signal "@baseboard_fab2_lib.baseboard_fab2(sch_1):tp_cpu1_rsvd_234"
				( attribute "CDS_PHYS_NET_NAME" "TP_CPU1_RSVD_234"
					( Origin gPackager )
				)
				( objectStatus "TP_CPU1_RSVD_234" )
			)
			( signal "@baseboard_fab2_lib.baseboard_fab2(sch_1):tp_cpu1_rsvd_235"
				( attribute "CDS_PHYS_NET_NAME" "TP_CPU1_RSVD_235"
					( Origin gPackager )
				)
				( objectStatus "TP_CPU1_RSVD_235" )
			)
			( signal "@baseboard_fab2_lib.baseboard_fab2(sch_1):tp_cpu1_rsvd_236"
				( attribute "CDS_PHYS_NET_NAME" "TP_CPU1_RSVD_236"
					( Origin gPackager )
				)
				( objectStatus "TP_CPU1_RSVD_236" )
			)
			( signal "@baseboard_fab2_lib.baseboard_fab2(sch_1):tp_cpu1_rsvd_237"
				( attribute "CDS_PHYS_NET_NAME" "TP_CPU1_RSVD_237"
					( Origin gPackager )
				)
				( objectStatus "TP_CPU1_RSVD_237" )
			)
			( signal "@baseboard_fab2_lib.baseboard_fab2(sch_1):tp_cpu1_rsvd_238"
				( attribute "CDS_PHYS_NET_NAME" "TP_CPU1_RSVD_238"
					( Origin gPackager )
				)
				( objectStatus "TP_CPU1_RSVD_238" )
			)
			( signal "@baseboard_fab2_lib.baseboard_fab2(sch_1):tp_cpu1_rsvd_239"
				( attribute "CDS_PHYS_NET_NAME" "TP_CPU1_RSVD_239"
					( Origin gPackager )
				)
				( objectStatus "TP_CPU1_RSVD_239" )
			)
			( signal "@baseboard_fab2_lib.baseboard_fab2(sch_1):tp_cpu1_rsvd_240"
				( attribute "CDS_PHYS_NET_NAME" "TP_CPU1_RSVD_240"
					( Origin gPackager )
				)
				( objectStatus "TP_CPU1_RSVD_240" )
			)
			( signal "@baseboard_fab2_lib.baseboard_fab2(sch_1):tp_cpu1_rsvd_241"
				( attribute "CDS_PHYS_NET_NAME" "TP_CPU1_RSVD_241"
					( Origin gPackager )
				)
				( objectStatus "TP_CPU1_RSVD_241" )
			)
			( signal "@baseboard_fab2_lib.baseboard_fab2(sch_1):tp_cpu1_rsvd_242"
				( attribute "CDS_PHYS_NET_NAME" "TP_CPU1_RSVD_242"
					( Origin gPackager )
				)
				( objectStatus "TP_CPU1_RSVD_242" )
			)
			( signal "@baseboard_fab2_lib.baseboard_fab2(sch_1):tp_cpu1_rsvd_243"
				( attribute "CDS_PHYS_NET_NAME" "TP_CPU1_RSVD_243"
					( Origin gPackager )
				)
				( objectStatus "TP_CPU1_RSVD_243" )
			)
			( signal "@baseboard_fab2_lib.baseboard_fab2(sch_1):tp_cpu1_rsvd_244"
				( attribute "CDS_PHYS_NET_NAME" "TP_CPU1_RSVD_244"
					( Origin gPackager )
				)
				( objectStatus "TP_CPU1_RSVD_244" )
			)
			( signal "@baseboard_fab2_lib.baseboard_fab2(sch_1):tp_cpu1_rsvd_245"
				( attribute "CDS_PHYS_NET_NAME" "TP_CPU1_RSVD_245"
					( Origin gPackager )
				)
				( objectStatus "TP_CPU1_RSVD_245" )
			)
			( signal "@baseboard_fab2_lib.baseboard_fab2(sch_1):tp_cpu1_rsvd_246"
				( attribute "CDS_PHYS_NET_NAME" "TP_CPU1_RSVD_246"
					( Origin gPackager )
				)
				( objectStatus "TP_CPU1_RSVD_246" )
			)
			( signal "@baseboard_fab2_lib.baseboard_fab2(sch_1):tp_cpu1_rsvd_247"
				( attribute "CDS_PHYS_NET_NAME" "TP_CPU1_RSVD_247"
					( Origin gPackager )
				)
				( objectStatus "TP_CPU1_RSVD_247" )
			)
			( signal "@baseboard_fab2_lib.baseboard_fab2(sch_1):tp_cpu1_rsvd_248"
				( attribute "CDS_PHYS_NET_NAME" "TP_CPU1_RSVD_248"
					( Origin gPackager )
				)
				( objectStatus "TP_CPU1_RSVD_248" )
			)
			( signal "@baseboard_fab2_lib.baseboard_fab2(sch_1):tp_cpu1_rsvd_249"
				( attribute "CDS_PHYS_NET_NAME" "TP_CPU1_RSVD_249"
					( Origin gPackager )
				)
				( objectStatus "TP_CPU1_RSVD_249" )
			)
			( signal "@baseboard_fab2_lib.baseboard_fab2(sch_1):tp_cpu1_rsvd_250"
				( attribute "CDS_PHYS_NET_NAME" "TP_CPU1_RSVD_250"
					( Origin gPackager )
				)
				( objectStatus "TP_CPU1_RSVD_250" )
			)
			( signal "@baseboard_fab2_lib.baseboard_fab2(sch_1):tp_cpu1_rsvd_251"
				( attribute "CDS_PHYS_NET_NAME" "TP_CPU1_RSVD_251"
					( Origin gPackager )
				)
				( objectStatus "TP_CPU1_RSVD_251" )
			)
			( signal "@baseboard_fab2_lib.baseboard_fab2(sch_1):tp_cpu1_rsvd_252"
				( attribute "CDS_PHYS_NET_NAME" "TP_CPU1_RSVD_252"
					( Origin gPackager )
				)
				( objectStatus "TP_CPU1_RSVD_252" )
			)
			( signal "@baseboard_fab2_lib.baseboard_fab2(sch_1):tp_cpu1_rsvd_253"
				( attribute "CDS_PHYS_NET_NAME" "TP_CPU1_RSVD_253"
					( Origin gPackager )
				)
				( objectStatus "TP_CPU1_RSVD_253" )
			)
			( signal "@baseboard_fab2_lib.baseboard_fab2(sch_1):tp_cpu1_rsvd_254"
				( attribute "CDS_PHYS_NET_NAME" "TP_CPU1_RSVD_254"
					( Origin gPackager )
				)
				( objectStatus "TP_CPU1_RSVD_254" )
			)
			( signal "@baseboard_fab2_lib.baseboard_fab2(sch_1):tp_cpu1_rsvd_256"
				( attribute "CDS_PHYS_NET_NAME" "TP_CPU1_RSVD_256"
					( Origin gPackager )
				)
				( objectStatus "TP_CPU1_RSVD_256" )
			)
			( signal "@baseboard_fab2_lib.baseboard_fab2(sch_1):tp_cpu1_rsvd_258"
				( attribute "CDS_PHYS_NET_NAME" "TP_CPU1_RSVD_258"
					( Origin gPackager )
				)
				( objectStatus "TP_CPU1_RSVD_258" )
			)
			( signal "@baseboard_fab2_lib.baseboard_fab2(sch_1):tp_cpu1_rsvd_259"
				( attribute "CDS_PHYS_NET_NAME" "TP_CPU1_RSVD_259"
					( Origin gPackager )
				)
				( objectStatus "TP_CPU1_RSVD_259" )
			)
			( signal "@baseboard_fab2_lib.baseboard_fab2(sch_1):tp_cpu1_rsvd_260"
				( attribute "CDS_PHYS_NET_NAME" "TP_CPU1_RSVD_260"
					( Origin gPackager )
				)
				( objectStatus "TP_CPU1_RSVD_260" )
			)
			( signal "@baseboard_fab2_lib.baseboard_fab2(sch_1):tp_cpu1_rsvd_261"
				( attribute "CDS_PHYS_NET_NAME" "TP_CPU1_RSVD_261"
					( Origin gPackager )
				)
				( objectStatus "TP_CPU1_RSVD_261" )
			)
			( signal "@baseboard_fab2_lib.baseboard_fab2(sch_1):tp_cpu1_rsvd_262"
				( attribute "CDS_PHYS_NET_NAME" "TP_CPU1_RSVD_262"
					( Origin gPackager )
				)
				( objectStatus "TP_CPU1_RSVD_262" )
			)
			( signal "@baseboard_fab2_lib.baseboard_fab2(sch_1):tp_cpu1_rsvd_263"
				( attribute "CDS_PHYS_NET_NAME" "TP_CPU1_RSVD_263"
					( Origin gPackager )
				)
				( objectStatus "TP_CPU1_RSVD_263" )
			)
			( signal "@baseboard_fab2_lib.baseboard_fab2(sch_1):tp_cpu1_rsvd_264"
				( attribute "CDS_PHYS_NET_NAME" "TP_CPU1_RSVD_264"
					( Origin gPackager )
				)
				( objectStatus "TP_CPU1_RSVD_264" )
			)
			( signal "@baseboard_fab2_lib.baseboard_fab2(sch_1):tp_cpu1_rsvd_265"
				( attribute "CDS_PHYS_NET_NAME" "TP_CPU1_RSVD_265"
					( Origin gPackager )
				)
				( objectStatus "TP_CPU1_RSVD_265" )
			)
			( signal "@baseboard_fab2_lib.baseboard_fab2(sch_1):tp_cpu1_rsvd_266"
				( attribute "CDS_PHYS_NET_NAME" "TP_CPU1_RSVD_266"
					( Origin gPackager )
				)
				( objectStatus "TP_CPU1_RSVD_266" )
			)
			( signal "@baseboard_fab2_lib.baseboard_fab2(sch_1):tp_cpu1_rsvd_267"
				( attribute "CDS_PHYS_NET_NAME" "TP_CPU1_RSVD_267"
					( Origin gPackager )
				)
				( objectStatus "TP_CPU1_RSVD_267" )
			)
			( signal "@baseboard_fab2_lib.baseboard_fab2(sch_1):tp_cpu1_rsvd_268"
				( attribute "CDS_PHYS_NET_NAME" "TP_CPU1_RSVD_268"
					( Origin gPackager )
				)
				( objectStatus "TP_CPU1_RSVD_268" )
			)
			( signal "@baseboard_fab2_lib.baseboard_fab2(sch_1):tp_cpu1_rsvd_269"
				( attribute "CDS_PHYS_NET_NAME" "TP_CPU1_RSVD_269"
					( Origin gPackager )
				)
				( objectStatus "TP_CPU1_RSVD_269" )
			)
			( signal "@baseboard_fab2_lib.baseboard_fab2(sch_1):tp_cpu1_rsvd_270"
				( attribute "CDS_PHYS_NET_NAME" "TP_CPU1_RSVD_270"
					( Origin gPackager )
				)
				( objectStatus "TP_CPU1_RSVD_270" )
			)
			( signal "@baseboard_fab2_lib.baseboard_fab2(sch_1):tp_cpu1_rsvd_271"
				( attribute "CDS_PHYS_NET_NAME" "TP_CPU1_RSVD_271"
					( Origin gPackager )
				)
				( objectStatus "TP_CPU1_RSVD_271" )
			)
			( signal "@baseboard_fab2_lib.baseboard_fab2(sch_1):tp_cpu1_rsvd_272"
				( attribute "CDS_PHYS_NET_NAME" "TP_CPU1_RSVD_272"
					( Origin gPackager )
				)
				( objectStatus "TP_CPU1_RSVD_272" )
			)
			( signal "@baseboard_fab2_lib.baseboard_fab2(sch_1):tp_cpu1_rsvd_273"
				( attribute "CDS_PHYS_NET_NAME" "TP_CPU1_RSVD_273"
					( Origin gPackager )
				)
				( objectStatus "TP_CPU1_RSVD_273" )
			)
			( signal "@baseboard_fab2_lib.baseboard_fab2(sch_1):tp_cpu1_rsvd_274"
				( attribute "CDS_PHYS_NET_NAME" "TP_CPU1_RSVD_274"
					( Origin gPackager )
				)
				( objectStatus "TP_CPU1_RSVD_274" )
			)
			( signal "@baseboard_fab2_lib.baseboard_fab2(sch_1):tp_cpu1_rsvd_275"
				( attribute "CDS_PHYS_NET_NAME" "TP_CPU1_RSVD_275"
					( Origin gPackager )
				)
				( objectStatus "TP_CPU1_RSVD_275" )
			)
			( signal "@baseboard_fab2_lib.baseboard_fab2(sch_1):tp_cpu1_rsvd_276"
				( attribute "CDS_PHYS_NET_NAME" "TP_CPU1_RSVD_276"
					( Origin gPackager )
				)
				( objectStatus "TP_CPU1_RSVD_276" )
			)
			( signal "@baseboard_fab2_lib.baseboard_fab2(sch_1):tp_cpu1_rsvd_277"
				( attribute "CDS_PHYS_NET_NAME" "TP_CPU1_RSVD_277"
					( Origin gPackager )
				)
				( objectStatus "TP_CPU1_RSVD_277" )
			)
			( signal "@baseboard_fab2_lib.baseboard_fab2(sch_1):tp_cpu1_rsvd_278"
				( attribute "CDS_PHYS_NET_NAME" "TP_CPU1_RSVD_278"
					( Origin gPackager )
				)
				( objectStatus "TP_CPU1_RSVD_278" )
			)
			( signal "@baseboard_fab2_lib.baseboard_fab2(sch_1):tp_cpu1_rsvd_279"
				( attribute "CDS_PHYS_NET_NAME" "TP_CPU1_RSVD_279"
					( Origin gPackager )
				)
				( objectStatus "TP_CPU1_RSVD_279" )
			)
			( signal "@baseboard_fab2_lib.baseboard_fab2(sch_1):tp_cpu1_rsvd_280"
				( attribute "CDS_PHYS_NET_NAME" "TP_CPU1_RSVD_280"
					( Origin gPackager )
				)
				( objectStatus "TP_CPU1_RSVD_280" )
			)
			( signal "@baseboard_fab2_lib.baseboard_fab2(sch_1):tp_cpu1_rsvd_281"
				( attribute "CDS_PHYS_NET_NAME" "TP_CPU1_RSVD_281"
					( Origin gPackager )
				)
				( objectStatus "TP_CPU1_RSVD_281" )
			)
			( signal "@baseboard_fab2_lib.baseboard_fab2(sch_1):tp_cpu1_rsvd_282"
				( attribute "CDS_PHYS_NET_NAME" "TP_CPU1_RSVD_282"
					( Origin gPackager )
				)
				( objectStatus "TP_CPU1_RSVD_282" )
			)
			( signal "@baseboard_fab2_lib.baseboard_fab2(sch_1):tp_cpu1_rsvd_283"
				( attribute "CDS_PHYS_NET_NAME" "TP_CPU1_RSVD_283"
					( Origin gPackager )
				)
				( objectStatus "TP_CPU1_RSVD_283" )
			)
			( signal "@baseboard_fab2_lib.baseboard_fab2(sch_1):tp_cpu1_rsvd_284"
				( attribute "CDS_PHYS_NET_NAME" "TP_CPU1_RSVD_284"
					( Origin gPackager )
				)
				( objectStatus "TP_CPU1_RSVD_284" )
			)
			( signal "@baseboard_fab2_lib.baseboard_fab2(sch_1):tp_cpu1_rsvd_285"
				( attribute "CDS_PHYS_NET_NAME" "TP_CPU1_RSVD_285"
					( Origin gPackager )
				)
				( objectStatus "TP_CPU1_RSVD_285" )
			)
			( signal "@baseboard_fab2_lib.baseboard_fab2(sch_1):tp_cpu1_rsvd_286"
				( attribute "CDS_PHYS_NET_NAME" "TP_CPU1_RSVD_286"
					( Origin gPackager )
				)
				( objectStatus "TP_CPU1_RSVD_286" )
			)
			( signal "@baseboard_fab2_lib.baseboard_fab2(sch_1):tp_cpu1_rsvd_287"
				( attribute "CDS_PHYS_NET_NAME" "TP_CPU1_RSVD_287"
					( Origin gPackager )
				)
				( objectStatus "TP_CPU1_RSVD_287" )
			)
			( signal "@baseboard_fab2_lib.baseboard_fab2(sch_1):tp_cpu1_rsvd_288"
				( attribute "CDS_PHYS_NET_NAME" "TP_CPU1_RSVD_288"
					( Origin gPackager )
				)
				( objectStatus "TP_CPU1_RSVD_288" )
			)
			( signal "@baseboard_fab2_lib.baseboard_fab2(sch_1):tp_cpu1_rsvd_289"
				( attribute "CDS_PHYS_NET_NAME" "TP_CPU1_RSVD_289"
					( Origin gPackager )
				)
				( objectStatus "TP_CPU1_RSVD_289" )
			)
			( signal "@baseboard_fab2_lib.baseboard_fab2(sch_1):tp_cpu1_rsvd_290"
				( attribute "CDS_PHYS_NET_NAME" "TP_CPU1_RSVD_290"
					( Origin gPackager )
				)
				( objectStatus "TP_CPU1_RSVD_290" )
			)
			( signal "@baseboard_fab2_lib.baseboard_fab2(sch_1):tp_cpu1_rsvd_291"
				( attribute "CDS_PHYS_NET_NAME" "TP_CPU1_RSVD_291"
					( Origin gPackager )
				)
				( objectStatus "TP_CPU1_RSVD_291" )
			)
			( signal "@baseboard_fab2_lib.baseboard_fab2(sch_1):tp_cpu1_rsvd_292"
				( attribute "CDS_PHYS_NET_NAME" "TP_CPU1_RSVD_292"
					( Origin gPackager )
				)
				( objectStatus "TP_CPU1_RSVD_292" )
			)
			( signal "@baseboard_fab2_lib.baseboard_fab2(sch_1):tp_cpu1_rsvd_293"
				( attribute "CDS_PHYS_NET_NAME" "TP_CPU1_RSVD_293"
					( Origin gPackager )
				)
				( objectStatus "TP_CPU1_RSVD_293" )
			)
			( signal "@baseboard_fab2_lib.baseboard_fab2(sch_1):tp_cpu1_rsvd_298"
				( attribute "CDS_PHYS_NET_NAME" "TP_CPU1_RSVD_298"
					( Origin gPackager )
				)
				( objectStatus "TP_CPU1_RSVD_298" )
			)
			( signal "@baseboard_fab2_lib.baseboard_fab2(sch_1):tp_cpu1_rsvd_299"
				( attribute "CDS_PHYS_NET_NAME" "TP_CPU1_RSVD_299"
					( Origin gPackager )
				)
				( objectStatus "TP_CPU1_RSVD_299" )
			)
			( signal "@baseboard_fab2_lib.baseboard_fab2(sch_1):tp_cpu1_rsvd_300"
				( attribute "CDS_PHYS_NET_NAME" "TP_CPU1_RSVD_300"
					( Origin gPackager )
				)
				( objectStatus "TP_CPU1_RSVD_300" )
			)
			( signal "@baseboard_fab2_lib.baseboard_fab2(sch_1):tp_cpu1_rsvd_303"
				( attribute "CDS_PHYS_NET_NAME" "TP_CPU1_RSVD_303"
					( Origin gPackager )
				)
				( objectStatus "TP_CPU1_RSVD_303" )
			)
			( signal "@baseboard_fab2_lib.baseboard_fab2(sch_1):tp_cpu1_rsvd_304"
				( attribute "CDS_PHYS_NET_NAME" "TP_CPU1_RSVD_304"
					( Origin gPackager )
				)
				( objectStatus "TP_CPU1_RSVD_304" )
			)
			( signal "@baseboard_fab2_lib.baseboard_fab2(sch_1):tp_cpu1_rsvd_test_11"
				( attribute "CDS_PHYS_NET_NAME" "TP_CPU1_RSVD_TEST_11"
					( Origin gPackager )
				)
				( objectStatus "TP_CPU1_RSVD_TEST_11" )
			)
			( signal "@baseboard_fab2_lib.baseboard_fab2(sch_1):tp_cpu1_rsvd_test_3"
				( attribute "CDS_PHYS_NET_NAME" "TP_CPU1_RSVD_TEST_3"
					( Origin gPackager )
				)
				( objectStatus "TP_CPU1_RSVD_TEST_3" )
			)
			( signal "@baseboard_fab2_lib.baseboard_fab2(sch_1):tp_cpu1_rsvd_test_4"
				( attribute "CDS_PHYS_NET_NAME" "TP_CPU1_RSVD_TEST_4"
					( Origin gPackager )
				)
				( objectStatus "TP_CPU1_RSVD_TEST_4" )
			)
			( signal "@baseboard_fab2_lib.baseboard_fab2(sch_1):tp_cpu1_rsvd_test_5"
				( attribute "CDS_PHYS_NET_NAME" "TP_CPU1_RSVD_TEST_5"
					( Origin gPackager )
				)
				( objectStatus "TP_CPU1_RSVD_TEST_5" )
			)
			( signal "@baseboard_fab2_lib.baseboard_fab2(sch_1):vsense_p1v8mcp_cpu1_skt_vrtn"
				( attribute "CDS_PHYS_NET_NAME" "VSENSE_P1V8MCP_CPU1_SKT_VRTN"
					( Origin gPackager )
				)
				( objectStatus "VSENSE_P1V8MCP_CPU1_SKT_VRTN" )
			)
			( signal "@baseboard_fab2_lib.baseboard_fab2(sch_1):vsense_p1v8mcp_cpu1_skt_vsen"
				( attribute "CDS_PHYS_NET_NAME" "VSENSE_P1V8MCP_CPU1_SKT_VSEN"
					( Origin gPackager )
				)
				( objectStatus "VSENSE_P1V8MCP_CPU1_SKT_VSEN" )
			)
			( signal "@baseboard_fab2_lib.baseboard_fab2(sch_1):m_g_act_n"
				( attribute "CDS_PHYS_NET_NAME" "M_G_ACT_N"
					( Origin gPackager )
				)
				( objectStatus "M_G_ACT_N" )
			)
			( signal "@baseboard_fab2_lib.baseboard_fab2(sch_1):m_g_alert_n"
				( attribute "CDS_PHYS_NET_NAME" "M_G_ALERT_N"
					( Origin gPackager )
				)
				( objectStatus "M_G_ALERT_N" )
			)
			( signal "@baseboard_fab2_lib.baseboard_fab2(sch_1):m_g_ba(0)"
				( attribute "CDS_PHYS_NET_NAME" "M_G_BA<0>"
					( Origin gPackager )
				)
				( attribute "PNN" "M_G_BA<0>"
					( Origin gPackager )
				)
				( objectStatus "M_G_BA<0>" )
			)
			( signal "@baseboard_fab2_lib.baseboard_fab2(sch_1):m_g_ba(1)"
				( attribute "CDS_PHYS_NET_NAME" "M_G_BA<1>"
					( Origin gPackager )
				)
				( attribute "PNN" "M_G_BA<1>"
					( Origin gPackager )
				)
				( objectStatus "M_G_BA<1>" )
			)
			( signal "@baseboard_fab2_lib.baseboard_fab2(sch_1):m_g_bg(0)"
				( attribute "CDS_PHYS_NET_NAME" "M_G_BG<0>"
					( Origin gPackager )
				)
				( attribute "PNN" "M_G_BG<0>"
					( Origin gPackager )
				)
				( objectStatus "M_G_BG<0>" )
			)
			( signal "@baseboard_fab2_lib.baseboard_fab2(sch_1):m_g_bg(1)"
				( attribute "CDS_PHYS_NET_NAME" "M_G_BG<1>"
					( Origin gPackager )
				)
				( attribute "PNN" "M_G_BG<1>"
					( Origin gPackager )
				)
				( objectStatus "M_G_BG<1>" )
			)
			( signal "@baseboard_fab2_lib.baseboard_fab2(sch_1):m_g_c(2)"
				( attribute "CDS_PHYS_NET_NAME" "M_G_C<2>"
					( Origin gPackager )
				)
				( attribute "PNN" "M_G_C<2>"
					( Origin gPackager )
				)
				( objectStatus "M_G_C<2>" )
			)
			( signal "@baseboard_fab2_lib.baseboard_fab2(sch_1):m_g_cke(0)"
				( attribute "CDS_PHYS_NET_NAME" "M_G_CKE<0>"
					( Origin gPackager )
				)
				( attribute "PNN" "M_G_CKE<0>"
					( Origin gPackager )
				)
				( objectStatus "M_G_CKE<0>" )
			)
			( signal "@baseboard_fab2_lib.baseboard_fab2(sch_1):m_g_cke(1)"
				( attribute "CDS_PHYS_NET_NAME" "M_G_CKE<1>"
					( Origin gPackager )
				)
				( attribute "PNN" "M_G_CKE<1>"
					( Origin gPackager )
				)
				( objectStatus "M_G_CKE<1>" )
			)
			( signal "@baseboard_fab2_lib.baseboard_fab2(sch_1):m_g_cke(2)"
				( attribute "CDS_PHYS_NET_NAME" "M_G_CKE<2>"
					( Origin gPackager )
				)
				( attribute "PNN" "M_G_CKE<2>"
					( Origin gPackager )
				)
				( objectStatus "M_G_CKE<2>" )
			)
			( signal "@baseboard_fab2_lib.baseboard_fab2(sch_1):m_g_cke(3)"
				( attribute "CDS_PHYS_NET_NAME" "M_G_CKE<3>"
					( Origin gPackager )
				)
				( attribute "PNN" "M_G_CKE<3>"
					( Origin gPackager )
				)
				( objectStatus "M_G_CKE<3>" )
			)
			( signal "@baseboard_fab2_lib.baseboard_fab2(sch_1):m_g_clk_dn(0)"
				( attribute "CDS_PHYS_NET_NAME" "M_G_CLK_DN<0>"
					( Origin gPackager )
				)
				( attribute "PNN" "M_G_CLK_DN<0>"
					( Origin gPackager )
				)
				( objectStatus "M_G_CLK_DN<0>" )
			)
			( signal "@baseboard_fab2_lib.baseboard_fab2(sch_1):m_g_clk_dn(1)"
				( attribute "CDS_PHYS_NET_NAME" "M_G_CLK_DN<1>"
					( Origin gPackager )
				)
				( attribute "PNN" "M_G_CLK_DN<1>"
					( Origin gPackager )
				)
				( objectStatus "M_G_CLK_DN<1>" )
			)
			( signal "@baseboard_fab2_lib.baseboard_fab2(sch_1):m_g_clk_dn(2)"
				( attribute "CDS_PHYS_NET_NAME" "M_G_CLK_DN<2>"
					( Origin gPackager )
				)
				( attribute "PNN" "M_G_CLK_DN<2>"
					( Origin gPackager )
				)
				( objectStatus "M_G_CLK_DN<2>" )
			)
			( signal "@baseboard_fab2_lib.baseboard_fab2(sch_1):m_g_clk_dn(3)"
				( attribute "CDS_PHYS_NET_NAME" "M_G_CLK_DN<3>"
					( Origin gPackager )
				)
				( attribute "PNN" "M_G_CLK_DN<3>"
					( Origin gPackager )
				)
				( objectStatus "M_G_CLK_DN<3>" )
			)
			( signal "@baseboard_fab2_lib.baseboard_fab2(sch_1):m_g_clk_dp(0)"
				( attribute "CDS_PHYS_NET_NAME" "M_G_CLK_DP<0>"
					( Origin gPackager )
				)
				( attribute "PNN" "M_G_CLK_DP<0>"
					( Origin gPackager )
				)
				( objectStatus "M_G_CLK_DP<0>" )
			)
			( signal "@baseboard_fab2_lib.baseboard_fab2(sch_1):m_g_clk_dp(1)"
				( attribute "CDS_PHYS_NET_NAME" "M_G_CLK_DP<1>"
					( Origin gPackager )
				)
				( attribute "PNN" "M_G_CLK_DP<1>"
					( Origin gPackager )
				)
				( objectStatus "M_G_CLK_DP<1>" )
			)
			( signal "@baseboard_fab2_lib.baseboard_fab2(sch_1):m_g_clk_dp(2)"
				( attribute "CDS_PHYS_NET_NAME" "M_G_CLK_DP<2>"
					( Origin gPackager )
				)
				( attribute "PNN" "M_G_CLK_DP<2>"
					( Origin gPackager )
				)
				( objectStatus "M_G_CLK_DP<2>" )
			)
			( signal "@baseboard_fab2_lib.baseboard_fab2(sch_1):m_g_clk_dp(3)"
				( attribute "CDS_PHYS_NET_NAME" "M_G_CLK_DP<3>"
					( Origin gPackager )
				)
				( attribute "PNN" "M_G_CLK_DP<3>"
					( Origin gPackager )
				)
				( objectStatus "M_G_CLK_DP<3>" )
			)
			( signal "@baseboard_fab2_lib.baseboard_fab2(sch_1):m_g_cs_n(0)"
				( attribute "CDS_PHYS_NET_NAME" "M_G_CS_N<0>"
					( Origin gPackager )
				)
				( attribute "PNN" "M_G_CS_N<0>"
					( Origin gPackager )
				)
				( objectStatus "M_G_CS_N<0>" )
			)
			( signal "@baseboard_fab2_lib.baseboard_fab2(sch_1):m_g_cs_n(1)"
				( attribute "CDS_PHYS_NET_NAME" "M_G_CS_N<1>"
					( Origin gPackager )
				)
				( attribute "PNN" "M_G_CS_N<1>"
					( Origin gPackager )
				)
				( objectStatus "M_G_CS_N<1>" )
			)
			( signal "@baseboard_fab2_lib.baseboard_fab2(sch_1):m_g_cs_n(2)"
				( attribute "CDS_PHYS_NET_NAME" "M_G_CS_N<2>"
					( Origin gPackager )
				)
				( attribute "PNN" "M_G_CS_N<2>"
					( Origin gPackager )
				)
				( objectStatus "M_G_CS_N<2>" )
			)
			( signal "@baseboard_fab2_lib.baseboard_fab2(sch_1):m_g_cs_n(3)"
				( attribute "CDS_PHYS_NET_NAME" "M_G_CS_N<3>"
					( Origin gPackager )
				)
				( attribute "PNN" "M_G_CS_N<3>"
					( Origin gPackager )
				)
				( objectStatus "M_G_CS_N<3>" )
			)
			( signal "@baseboard_fab2_lib.baseboard_fab2(sch_1):m_g_cs_n(4)"
				( attribute "CDS_PHYS_NET_NAME" "M_G_CS_N<4>"
					( Origin gPackager )
				)
				( attribute "PNN" "M_G_CS_N<4>"
					( Origin gPackager )
				)
				( objectStatus "M_G_CS_N<4>" )
			)
			( signal "@baseboard_fab2_lib.baseboard_fab2(sch_1):m_g_cs_n(5)"
				( attribute "CDS_PHYS_NET_NAME" "M_G_CS_N<5>"
					( Origin gPackager )
				)
				( attribute "PNN" "M_G_CS_N<5>"
					( Origin gPackager )
				)
				( objectStatus "M_G_CS_N<5>" )
			)
			( signal "@baseboard_fab2_lib.baseboard_fab2(sch_1):m_g_cs_n(6)"
				( attribute "CDS_PHYS_NET_NAME" "M_G_CS_N<6>"
					( Origin gPackager )
				)
				( attribute "PNN" "M_G_CS_N<6>"
					( Origin gPackager )
				)
				( objectStatus "M_G_CS_N<6>" )
			)
			( signal "@baseboard_fab2_lib.baseboard_fab2(sch_1):m_g_cs_n(7)"
				( attribute "CDS_PHYS_NET_NAME" "M_G_CS_N<7>"
					( Origin gPackager )
				)
				( attribute "PNN" "M_G_CS_N<7>"
					( Origin gPackager )
				)
				( objectStatus "M_G_CS_N<7>" )
			)
			( signal "@baseboard_fab2_lib.baseboard_fab2(sch_1):m_g_dq(0)"
				( attribute "CDS_PHYS_NET_NAME" "M_G_DQ<0>"
					( Origin gPackager )
				)
				( attribute "PNN" "M_G_DQ<0>"
					( Origin gPackager )
				)
				( objectStatus "M_G_DQ<0>" )
			)
			( signal "@baseboard_fab2_lib.baseboard_fab2(sch_1):m_g_dq(1)"
				( attribute "CDS_PHYS_NET_NAME" "M_G_DQ<1>"
					( Origin gPackager )
				)
				( attribute "PNN" "M_G_DQ<1>"
					( Origin gPackager )
				)
				( objectStatus "M_G_DQ<1>" )
			)
			( signal "@baseboard_fab2_lib.baseboard_fab2(sch_1):m_g_dq(2)"
				( attribute "CDS_PHYS_NET_NAME" "M_G_DQ<2>"
					( Origin gPackager )
				)
				( attribute "PNN" "M_G_DQ<2>"
					( Origin gPackager )
				)
				( objectStatus "M_G_DQ<2>" )
			)
			( signal "@baseboard_fab2_lib.baseboard_fab2(sch_1):m_g_dq(3)"
				( attribute "CDS_PHYS_NET_NAME" "M_G_DQ<3>"
					( Origin gPackager )
				)
				( attribute "PNN" "M_G_DQ<3>"
					( Origin gPackager )
				)
				( objectStatus "M_G_DQ<3>" )
			)
			( signal "@baseboard_fab2_lib.baseboard_fab2(sch_1):m_g_dq(4)"
				( attribute "CDS_PHYS_NET_NAME" "M_G_DQ<4>"
					( Origin gPackager )
				)
				( attribute "PNN" "M_G_DQ<4>"
					( Origin gPackager )
				)
				( objectStatus "M_G_DQ<4>" )
			)
			( signal "@baseboard_fab2_lib.baseboard_fab2(sch_1):m_g_dq(5)"
				( attribute "CDS_PHYS_NET_NAME" "M_G_DQ<5>"
					( Origin gPackager )
				)
				( attribute "PNN" "M_G_DQ<5>"
					( Origin gPackager )
				)
				( objectStatus "M_G_DQ<5>" )
			)
			( signal "@baseboard_fab2_lib.baseboard_fab2(sch_1):m_g_dq(6)"
				( attribute "CDS_PHYS_NET_NAME" "M_G_DQ<6>"
					( Origin gPackager )
				)
				( attribute "PNN" "M_G_DQ<6>"
					( Origin gPackager )
				)
				( objectStatus "M_G_DQ<6>" )
			)
			( signal "@baseboard_fab2_lib.baseboard_fab2(sch_1):m_g_dq(7)"
				( attribute "CDS_PHYS_NET_NAME" "M_G_DQ<7>"
					( Origin gPackager )
				)
				( attribute "PNN" "M_G_DQ<7>"
					( Origin gPackager )
				)
				( objectStatus "M_G_DQ<7>" )
			)
			( signal "@baseboard_fab2_lib.baseboard_fab2(sch_1):m_g_dq(8)"
				( attribute "CDS_PHYS_NET_NAME" "M_G_DQ<8>"
					( Origin gPackager )
				)
				( attribute "PNN" "M_G_DQ<8>"
					( Origin gPackager )
				)
				( objectStatus "M_G_DQ<8>" )
			)
			( signal "@baseboard_fab2_lib.baseboard_fab2(sch_1):m_g_dq(9)"
				( attribute "CDS_PHYS_NET_NAME" "M_G_DQ<9>"
					( Origin gPackager )
				)
				( attribute "PNN" "M_G_DQ<9>"
					( Origin gPackager )
				)
				( objectStatus "M_G_DQ<9>" )
			)
			( signal "@baseboard_fab2_lib.baseboard_fab2(sch_1):m_g_dq(10)"
				( attribute "CDS_PHYS_NET_NAME" "M_G_DQ<10>"
					( Origin gPackager )
				)
				( attribute "PNN" "M_G_DQ<10>"
					( Origin gPackager )
				)
				( objectStatus "M_G_DQ<10>" )
			)
			( signal "@baseboard_fab2_lib.baseboard_fab2(sch_1):m_g_dq(11)"
				( attribute "CDS_PHYS_NET_NAME" "M_G_DQ<11>"
					( Origin gPackager )
				)
				( attribute "PNN" "M_G_DQ<11>"
					( Origin gPackager )
				)
				( objectStatus "M_G_DQ<11>" )
			)
			( signal "@baseboard_fab2_lib.baseboard_fab2(sch_1):m_g_dq(12)"
				( attribute "CDS_PHYS_NET_NAME" "M_G_DQ<12>"
					( Origin gPackager )
				)
				( attribute "PNN" "M_G_DQ<12>"
					( Origin gPackager )
				)
				( objectStatus "M_G_DQ<12>" )
			)
			( signal "@baseboard_fab2_lib.baseboard_fab2(sch_1):m_g_dq(13)"
				( attribute "CDS_PHYS_NET_NAME" "M_G_DQ<13>"
					( Origin gPackager )
				)
				( attribute "PNN" "M_G_DQ<13>"
					( Origin gPackager )
				)
				( objectStatus "M_G_DQ<13>" )
			)
			( signal "@baseboard_fab2_lib.baseboard_fab2(sch_1):m_g_dq(14)"
				( attribute "CDS_PHYS_NET_NAME" "M_G_DQ<14>"
					( Origin gPackager )
				)
				( attribute "PNN" "M_G_DQ<14>"
					( Origin gPackager )
				)
				( objectStatus "M_G_DQ<14>" )
			)
			( signal "@baseboard_fab2_lib.baseboard_fab2(sch_1):m_g_dq(15)"
				( attribute "CDS_PHYS_NET_NAME" "M_G_DQ<15>"
					( Origin gPackager )
				)
				( attribute "PNN" "M_G_DQ<15>"
					( Origin gPackager )
				)
				( objectStatus "M_G_DQ<15>" )
			)
			( signal "@baseboard_fab2_lib.baseboard_fab2(sch_1):m_g_dq(16)"
				( attribute "CDS_PHYS_NET_NAME" "M_G_DQ<16>"
					( Origin gPackager )
				)
				( attribute "PNN" "M_G_DQ<16>"
					( Origin gPackager )
				)
				( objectStatus "M_G_DQ<16>" )
			)
			( signal "@baseboard_fab2_lib.baseboard_fab2(sch_1):m_g_dq(17)"
				( attribute "CDS_PHYS_NET_NAME" "M_G_DQ<17>"
					( Origin gPackager )
				)
				( attribute "PNN" "M_G_DQ<17>"
					( Origin gPackager )
				)
				( objectStatus "M_G_DQ<17>" )
			)
			( signal "@baseboard_fab2_lib.baseboard_fab2(sch_1):m_g_dq(18)"
				( attribute "CDS_PHYS_NET_NAME" "M_G_DQ<18>"
					( Origin gPackager )
				)
				( attribute "PNN" "M_G_DQ<18>"
					( Origin gPackager )
				)
				( objectStatus "M_G_DQ<18>" )
			)
			( signal "@baseboard_fab2_lib.baseboard_fab2(sch_1):m_g_dq(19)"
				( attribute "CDS_PHYS_NET_NAME" "M_G_DQ<19>"
					( Origin gPackager )
				)
				( attribute "PNN" "M_G_DQ<19>"
					( Origin gPackager )
				)
				( objectStatus "M_G_DQ<19>" )
			)
			( signal "@baseboard_fab2_lib.baseboard_fab2(sch_1):m_g_dq(20)"
				( attribute "CDS_PHYS_NET_NAME" "M_G_DQ<20>"
					( Origin gPackager )
				)
				( attribute "PNN" "M_G_DQ<20>"
					( Origin gPackager )
				)
				( objectStatus "M_G_DQ<20>" )
			)
			( signal "@baseboard_fab2_lib.baseboard_fab2(sch_1):m_g_dq(21)"
				( attribute "CDS_PHYS_NET_NAME" "M_G_DQ<21>"
					( Origin gPackager )
				)
				( attribute "PNN" "M_G_DQ<21>"
					( Origin gPackager )
				)
				( objectStatus "M_G_DQ<21>" )
			)
			( signal "@baseboard_fab2_lib.baseboard_fab2(sch_1):m_g_dq(22)"
				( attribute "CDS_PHYS_NET_NAME" "M_G_DQ<22>"
					( Origin gPackager )
				)
				( attribute "PNN" "M_G_DQ<22>"
					( Origin gPackager )
				)
				( objectStatus "M_G_DQ<22>" )
			)
			( signal "@baseboard_fab2_lib.baseboard_fab2(sch_1):m_g_dq(23)"
				( attribute "CDS_PHYS_NET_NAME" "M_G_DQ<23>"
					( Origin gPackager )
				)
				( attribute "PNN" "M_G_DQ<23>"
					( Origin gPackager )
				)
				( objectStatus "M_G_DQ<23>" )
			)
			( signal "@baseboard_fab2_lib.baseboard_fab2(sch_1):m_g_dq(24)"
				( attribute "CDS_PHYS_NET_NAME" "M_G_DQ<24>"
					( Origin gPackager )
				)
				( attribute "PNN" "M_G_DQ<24>"
					( Origin gPackager )
				)
				( objectStatus "M_G_DQ<24>" )
			)
			( signal "@baseboard_fab2_lib.baseboard_fab2(sch_1):m_g_dq(25)"
				( attribute "CDS_PHYS_NET_NAME" "M_G_DQ<25>"
					( Origin gPackager )
				)
				( attribute "PNN" "M_G_DQ<25>"
					( Origin gPackager )
				)
				( objectStatus "M_G_DQ<25>" )
			)
			( signal "@baseboard_fab2_lib.baseboard_fab2(sch_1):m_g_dq(26)"
				( attribute "CDS_PHYS_NET_NAME" "M_G_DQ<26>"
					( Origin gPackager )
				)
				( attribute "PNN" "M_G_DQ<26>"
					( Origin gPackager )
				)
				( objectStatus "M_G_DQ<26>" )
			)
			( signal "@baseboard_fab2_lib.baseboard_fab2(sch_1):m_g_dq(27)"
				( attribute "CDS_PHYS_NET_NAME" "M_G_DQ<27>"
					( Origin gPackager )
				)
				( attribute "PNN" "M_G_DQ<27>"
					( Origin gPackager )
				)
				( objectStatus "M_G_DQ<27>" )
			)
			( signal "@baseboard_fab2_lib.baseboard_fab2(sch_1):m_g_dq(28)"
				( attribute "CDS_PHYS_NET_NAME" "M_G_DQ<28>"
					( Origin gPackager )
				)
				( attribute "PNN" "M_G_DQ<28>"
					( Origin gPackager )
				)
				( objectStatus "M_G_DQ<28>" )
			)
			( signal "@baseboard_fab2_lib.baseboard_fab2(sch_1):m_g_dq(29)"
				( attribute "CDS_PHYS_NET_NAME" "M_G_DQ<29>"
					( Origin gPackager )
				)
				( attribute "PNN" "M_G_DQ<29>"
					( Origin gPackager )
				)
				( objectStatus "M_G_DQ<29>" )
			)
			( signal "@baseboard_fab2_lib.baseboard_fab2(sch_1):m_g_dq(30)"
				( attribute "CDS_PHYS_NET_NAME" "M_G_DQ<30>"
					( Origin gPackager )
				)
				( attribute "PNN" "M_G_DQ<30>"
					( Origin gPackager )
				)
				( objectStatus "M_G_DQ<30>" )
			)
			( signal "@baseboard_fab2_lib.baseboard_fab2(sch_1):m_g_dq(31)"
				( attribute "CDS_PHYS_NET_NAME" "M_G_DQ<31>"
					( Origin gPackager )
				)
				( attribute "PNN" "M_G_DQ<31>"
					( Origin gPackager )
				)
				( objectStatus "M_G_DQ<31>" )
			)
			( signal "@baseboard_fab2_lib.baseboard_fab2(sch_1):m_g_dq(32)"
				( attribute "CDS_PHYS_NET_NAME" "M_G_DQ<32>"
					( Origin gPackager )
				)
				( attribute "PNN" "M_G_DQ<32>"
					( Origin gPackager )
				)
				( objectStatus "M_G_DQ<32>" )
			)
			( signal "@baseboard_fab2_lib.baseboard_fab2(sch_1):m_g_dq(33)"
				( attribute "CDS_PHYS_NET_NAME" "M_G_DQ<33>"
					( Origin gPackager )
				)
				( attribute "PNN" "M_G_DQ<33>"
					( Origin gPackager )
				)
				( objectStatus "M_G_DQ<33>" )
			)
			( signal "@baseboard_fab2_lib.baseboard_fab2(sch_1):m_g_dq(34)"
				( attribute "CDS_PHYS_NET_NAME" "M_G_DQ<34>"
					( Origin gPackager )
				)
				( attribute "PNN" "M_G_DQ<34>"
					( Origin gPackager )
				)
				( objectStatus "M_G_DQ<34>" )
			)
			( signal "@baseboard_fab2_lib.baseboard_fab2(sch_1):m_g_dq(35)"
				( attribute "CDS_PHYS_NET_NAME" "M_G_DQ<35>"
					( Origin gPackager )
				)
				( attribute "PNN" "M_G_DQ<35>"
					( Origin gPackager )
				)
				( objectStatus "M_G_DQ<35>" )
			)
			( signal "@baseboard_fab2_lib.baseboard_fab2(sch_1):m_g_dq(36)"
				( attribute "CDS_PHYS_NET_NAME" "M_G_DQ<36>"
					( Origin gPackager )
				)
				( attribute "PNN" "M_G_DQ<36>"
					( Origin gPackager )
				)
				( objectStatus "M_G_DQ<36>" )
			)
			( signal "@baseboard_fab2_lib.baseboard_fab2(sch_1):m_g_dq(37)"
				( attribute "CDS_PHYS_NET_NAME" "M_G_DQ<37>"
					( Origin gPackager )
				)
				( attribute "PNN" "M_G_DQ<37>"
					( Origin gPackager )
				)
				( objectStatus "M_G_DQ<37>" )
			)
			( signal "@baseboard_fab2_lib.baseboard_fab2(sch_1):m_g_dq(38)"
				( attribute "CDS_PHYS_NET_NAME" "M_G_DQ<38>"
					( Origin gPackager )
				)
				( attribute "PNN" "M_G_DQ<38>"
					( Origin gPackager )
				)
				( objectStatus "M_G_DQ<38>" )
			)
			( signal "@baseboard_fab2_lib.baseboard_fab2(sch_1):m_g_dq(39)"
				( attribute "CDS_PHYS_NET_NAME" "M_G_DQ<39>"
					( Origin gPackager )
				)
				( attribute "PNN" "M_G_DQ<39>"
					( Origin gPackager )
				)
				( objectStatus "M_G_DQ<39>" )
			)
			( signal "@baseboard_fab2_lib.baseboard_fab2(sch_1):m_g_dq(40)"
				( attribute "CDS_PHYS_NET_NAME" "M_G_DQ<40>"
					( Origin gPackager )
				)
				( attribute "PNN" "M_G_DQ<40>"
					( Origin gPackager )
				)
				( objectStatus "M_G_DQ<40>" )
			)
			( signal "@baseboard_fab2_lib.baseboard_fab2(sch_1):m_g_dq(41)"
				( attribute "CDS_PHYS_NET_NAME" "M_G_DQ<41>"
					( Origin gPackager )
				)
				( attribute "PNN" "M_G_DQ<41>"
					( Origin gPackager )
				)
				( objectStatus "M_G_DQ<41>" )
			)
			( signal "@baseboard_fab2_lib.baseboard_fab2(sch_1):m_g_dq(42)"
				( attribute "CDS_PHYS_NET_NAME" "M_G_DQ<42>"
					( Origin gPackager )
				)
				( attribute "PNN" "M_G_DQ<42>"
					( Origin gPackager )
				)
				( objectStatus "M_G_DQ<42>" )
			)
			( signal "@baseboard_fab2_lib.baseboard_fab2(sch_1):m_g_dq(43)"
				( attribute "CDS_PHYS_NET_NAME" "M_G_DQ<43>"
					( Origin gPackager )
				)
				( attribute "PNN" "M_G_DQ<43>"
					( Origin gPackager )
				)
				( objectStatus "M_G_DQ<43>" )
			)
			( signal "@baseboard_fab2_lib.baseboard_fab2(sch_1):m_g_dq(44)"
				( attribute "CDS_PHYS_NET_NAME" "M_G_DQ<44>"
					( Origin gPackager )
				)
				( attribute "PNN" "M_G_DQ<44>"
					( Origin gPackager )
				)
				( objectStatus "M_G_DQ<44>" )
			)
			( signal "@baseboard_fab2_lib.baseboard_fab2(sch_1):m_g_dq(45)"
				( attribute "CDS_PHYS_NET_NAME" "M_G_DQ<45>"
					( Origin gPackager )
				)
				( attribute "PNN" "M_G_DQ<45>"
					( Origin gPackager )
				)
				( objectStatus "M_G_DQ<45>" )
			)
			( signal "@baseboard_fab2_lib.baseboard_fab2(sch_1):m_g_dq(46)"
				( attribute "CDS_PHYS_NET_NAME" "M_G_DQ<46>"
					( Origin gPackager )
				)
				( attribute "PNN" "M_G_DQ<46>"
					( Origin gPackager )
				)
				( objectStatus "M_G_DQ<46>" )
			)
			( signal "@baseboard_fab2_lib.baseboard_fab2(sch_1):m_g_dq(47)"
				( attribute "CDS_PHYS_NET_NAME" "M_G_DQ<47>"
					( Origin gPackager )
				)
				( attribute "PNN" "M_G_DQ<47>"
					( Origin gPackager )
				)
				( objectStatus "M_G_DQ<47>" )
			)
			( signal "@baseboard_fab2_lib.baseboard_fab2(sch_1):m_g_dq(48)"
				( attribute "CDS_PHYS_NET_NAME" "M_G_DQ<48>"
					( Origin gPackager )
				)
				( attribute "PNN" "M_G_DQ<48>"
					( Origin gPackager )
				)
				( objectStatus "M_G_DQ<48>" )
			)
			( signal "@baseboard_fab2_lib.baseboard_fab2(sch_1):m_g_dq(49)"
				( attribute "CDS_PHYS_NET_NAME" "M_G_DQ<49>"
					( Origin gPackager )
				)
				( attribute "PNN" "M_G_DQ<49>"
					( Origin gPackager )
				)
				( objectStatus "M_G_DQ<49>" )
			)
			( signal "@baseboard_fab2_lib.baseboard_fab2(sch_1):m_g_dq(50)"
				( attribute "CDS_PHYS_NET_NAME" "M_G_DQ<50>"
					( Origin gPackager )
				)
				( attribute "PNN" "M_G_DQ<50>"
					( Origin gPackager )
				)
				( objectStatus "M_G_DQ<50>" )
			)
			( signal "@baseboard_fab2_lib.baseboard_fab2(sch_1):m_g_dq(51)"
				( attribute "CDS_PHYS_NET_NAME" "M_G_DQ<51>"
					( Origin gPackager )
				)
				( attribute "PNN" "M_G_DQ<51>"
					( Origin gPackager )
				)
				( objectStatus "M_G_DQ<51>" )
			)
			( signal "@baseboard_fab2_lib.baseboard_fab2(sch_1):m_g_dq(52)"
				( attribute "CDS_PHYS_NET_NAME" "M_G_DQ<52>"
					( Origin gPackager )
				)
				( attribute "PNN" "M_G_DQ<52>"
					( Origin gPackager )
				)
				( objectStatus "M_G_DQ<52>" )
			)
			( signal "@baseboard_fab2_lib.baseboard_fab2(sch_1):m_g_dq(53)"
				( attribute "CDS_PHYS_NET_NAME" "M_G_DQ<53>"
					( Origin gPackager )
				)
				( attribute "PNN" "M_G_DQ<53>"
					( Origin gPackager )
				)
				( objectStatus "M_G_DQ<53>" )
			)
			( signal "@baseboard_fab2_lib.baseboard_fab2(sch_1):m_g_dq(54)"
				( attribute "CDS_PHYS_NET_NAME" "M_G_DQ<54>"
					( Origin gPackager )
				)
				( attribute "PNN" "M_G_DQ<54>"
					( Origin gPackager )
				)
				( objectStatus "M_G_DQ<54>" )
			)
			( signal "@baseboard_fab2_lib.baseboard_fab2(sch_1):m_g_dq(55)"
				( attribute "CDS_PHYS_NET_NAME" "M_G_DQ<55>"
					( Origin gPackager )
				)
				( attribute "PNN" "M_G_DQ<55>"
					( Origin gPackager )
				)
				( objectStatus "M_G_DQ<55>" )
			)
			( signal "@baseboard_fab2_lib.baseboard_fab2(sch_1):m_g_dq(56)"
				( attribute "CDS_PHYS_NET_NAME" "M_G_DQ<56>"
					( Origin gPackager )
				)
				( attribute "PNN" "M_G_DQ<56>"
					( Origin gPackager )
				)
				( objectStatus "M_G_DQ<56>" )
			)
			( signal "@baseboard_fab2_lib.baseboard_fab2(sch_1):m_g_dq(57)"
				( attribute "CDS_PHYS_NET_NAME" "M_G_DQ<57>"
					( Origin gPackager )
				)
				( attribute "PNN" "M_G_DQ<57>"
					( Origin gPackager )
				)
				( objectStatus "M_G_DQ<57>" )
			)
			( signal "@baseboard_fab2_lib.baseboard_fab2(sch_1):m_g_dq(58)"
				( attribute "CDS_PHYS_NET_NAME" "M_G_DQ<58>"
					( Origin gPackager )
				)
				( attribute "PNN" "M_G_DQ<58>"
					( Origin gPackager )
				)
				( objectStatus "M_G_DQ<58>" )
			)
			( signal "@baseboard_fab2_lib.baseboard_fab2(sch_1):m_g_dq(59)"
				( attribute "CDS_PHYS_NET_NAME" "M_G_DQ<59>"
					( Origin gPackager )
				)
				( attribute "PNN" "M_G_DQ<59>"
					( Origin gPackager )
				)
				( objectStatus "M_G_DQ<59>" )
			)
			( signal "@baseboard_fab2_lib.baseboard_fab2(sch_1):m_g_dq(60)"
				( attribute "CDS_PHYS_NET_NAME" "M_G_DQ<60>"
					( Origin gPackager )
				)
				( attribute "PNN" "M_G_DQ<60>"
					( Origin gPackager )
				)
				( objectStatus "M_G_DQ<60>" )
			)
			( signal "@baseboard_fab2_lib.baseboard_fab2(sch_1):m_g_dq(61)"
				( attribute "CDS_PHYS_NET_NAME" "M_G_DQ<61>"
					( Origin gPackager )
				)
				( attribute "PNN" "M_G_DQ<61>"
					( Origin gPackager )
				)
				( objectStatus "M_G_DQ<61>" )
			)
			( signal "@baseboard_fab2_lib.baseboard_fab2(sch_1):m_g_dq(62)"
				( attribute "CDS_PHYS_NET_NAME" "M_G_DQ<62>"
					( Origin gPackager )
				)
				( attribute "PNN" "M_G_DQ<62>"
					( Origin gPackager )
				)
				( objectStatus "M_G_DQ<62>" )
			)
			( signal "@baseboard_fab2_lib.baseboard_fab2(sch_1):m_g_dq(63)"
				( attribute "CDS_PHYS_NET_NAME" "M_G_DQ<63>"
					( Origin gPackager )
				)
				( attribute "PNN" "M_G_DQ<63>"
					( Origin gPackager )
				)
				( objectStatus "M_G_DQ<63>" )
			)
			( signal "@baseboard_fab2_lib.baseboard_fab2(sch_1):m_g_dqs_dn(0)"
				( attribute "CDS_PHYS_NET_NAME" "M_G_DQS_DN<0>"
					( Origin gPackager )
				)
				( attribute "PNN" "M_G_DQS_DN<0>"
					( Origin gPackager )
				)
				( objectStatus "M_G_DQS_DN<0>" )
			)
			( signal "@baseboard_fab2_lib.baseboard_fab2(sch_1):m_g_dqs_dn(1)"
				( attribute "CDS_PHYS_NET_NAME" "M_G_DQS_DN<1>"
					( Origin gPackager )
				)
				( attribute "PNN" "M_G_DQS_DN<1>"
					( Origin gPackager )
				)
				( objectStatus "M_G_DQS_DN<1>" )
			)
			( signal "@baseboard_fab2_lib.baseboard_fab2(sch_1):m_g_dqs_dn(2)"
				( attribute "CDS_PHYS_NET_NAME" "M_G_DQS_DN<2>"
					( Origin gPackager )
				)
				( attribute "PNN" "M_G_DQS_DN<2>"
					( Origin gPackager )
				)
				( objectStatus "M_G_DQS_DN<2>" )
			)
			( signal "@baseboard_fab2_lib.baseboard_fab2(sch_1):m_g_dqs_dn(3)"
				( attribute "CDS_PHYS_NET_NAME" "M_G_DQS_DN<3>"
					( Origin gPackager )
				)
				( attribute "PNN" "M_G_DQS_DN<3>"
					( Origin gPackager )
				)
				( objectStatus "M_G_DQS_DN<3>" )
			)
			( signal "@baseboard_fab2_lib.baseboard_fab2(sch_1):m_g_dqs_dn(4)"
				( attribute "CDS_PHYS_NET_NAME" "M_G_DQS_DN<4>"
					( Origin gPackager )
				)
				( attribute "PNN" "M_G_DQS_DN<4>"
					( Origin gPackager )
				)
				( objectStatus "M_G_DQS_DN<4>" )
			)
			( signal "@baseboard_fab2_lib.baseboard_fab2(sch_1):m_g_dqs_dn(5)"
				( attribute "CDS_PHYS_NET_NAME" "M_G_DQS_DN<5>"
					( Origin gPackager )
				)
				( attribute "PNN" "M_G_DQS_DN<5>"
					( Origin gPackager )
				)
				( objectStatus "M_G_DQS_DN<5>" )
			)
			( signal "@baseboard_fab2_lib.baseboard_fab2(sch_1):m_g_dqs_dn(6)"
				( attribute "CDS_PHYS_NET_NAME" "M_G_DQS_DN<6>"
					( Origin gPackager )
				)
				( attribute "PNN" "M_G_DQS_DN<6>"
					( Origin gPackager )
				)
				( objectStatus "M_G_DQS_DN<6>" )
			)
			( signal "@baseboard_fab2_lib.baseboard_fab2(sch_1):m_g_dqs_dn(7)"
				( attribute "CDS_PHYS_NET_NAME" "M_G_DQS_DN<7>"
					( Origin gPackager )
				)
				( attribute "PNN" "M_G_DQS_DN<7>"
					( Origin gPackager )
				)
				( objectStatus "M_G_DQS_DN<7>" )
			)
			( signal "@baseboard_fab2_lib.baseboard_fab2(sch_1):m_g_dqs_dn(8)"
				( attribute "CDS_PHYS_NET_NAME" "M_G_DQS_DN<8>"
					( Origin gPackager )
				)
				( attribute "PNN" "M_G_DQS_DN<8>"
					( Origin gPackager )
				)
				( objectStatus "M_G_DQS_DN<8>" )
			)
			( signal "@baseboard_fab2_lib.baseboard_fab2(sch_1):m_g_dqs_dn(9)"
				( attribute "CDS_PHYS_NET_NAME" "M_G_DQS_DN<9>"
					( Origin gPackager )
				)
				( attribute "PNN" "M_G_DQS_DN<9>"
					( Origin gPackager )
				)
				( objectStatus "M_G_DQS_DN<9>" )
			)
			( signal "@baseboard_fab2_lib.baseboard_fab2(sch_1):m_g_dqs_dn(10)"
				( attribute "CDS_PHYS_NET_NAME" "M_G_DQS_DN<10>"
					( Origin gPackager )
				)
				( attribute "PNN" "M_G_DQS_DN<10>"
					( Origin gPackager )
				)
				( objectStatus "M_G_DQS_DN<10>" )
			)
			( signal "@baseboard_fab2_lib.baseboard_fab2(sch_1):m_g_dqs_dn(11)"
				( attribute "CDS_PHYS_NET_NAME" "M_G_DQS_DN<11>"
					( Origin gPackager )
				)
				( attribute "PNN" "M_G_DQS_DN<11>"
					( Origin gPackager )
				)
				( objectStatus "M_G_DQS_DN<11>" )
			)
			( signal "@baseboard_fab2_lib.baseboard_fab2(sch_1):m_g_dqs_dn(12)"
				( attribute "CDS_PHYS_NET_NAME" "M_G_DQS_DN<12>"
					( Origin gPackager )
				)
				( attribute "PNN" "M_G_DQS_DN<12>"
					( Origin gPackager )
				)
				( objectStatus "M_G_DQS_DN<12>" )
			)
			( signal "@baseboard_fab2_lib.baseboard_fab2(sch_1):m_g_dqs_dn(13)"
				( attribute "CDS_PHYS_NET_NAME" "M_G_DQS_DN<13>"
					( Origin gPackager )
				)
				( attribute "PNN" "M_G_DQS_DN<13>"
					( Origin gPackager )
				)
				( objectStatus "M_G_DQS_DN<13>" )
			)
			( signal "@baseboard_fab2_lib.baseboard_fab2(sch_1):m_g_dqs_dn(14)"
				( attribute "CDS_PHYS_NET_NAME" "M_G_DQS_DN<14>"
					( Origin gPackager )
				)
				( attribute "PNN" "M_G_DQS_DN<14>"
					( Origin gPackager )
				)
				( objectStatus "M_G_DQS_DN<14>" )
			)
			( signal "@baseboard_fab2_lib.baseboard_fab2(sch_1):m_g_dqs_dn(15)"
				( attribute "CDS_PHYS_NET_NAME" "M_G_DQS_DN<15>"
					( Origin gPackager )
				)
				( attribute "PNN" "M_G_DQS_DN<15>"
					( Origin gPackager )
				)
				( objectStatus "M_G_DQS_DN<15>" )
			)
			( signal "@baseboard_fab2_lib.baseboard_fab2(sch_1):m_g_dqs_dn(16)"
				( attribute "CDS_PHYS_NET_NAME" "M_G_DQS_DN<16>"
					( Origin gPackager )
				)
				( attribute "PNN" "M_G_DQS_DN<16>"
					( Origin gPackager )
				)
				( objectStatus "M_G_DQS_DN<16>" )
			)
			( signal "@baseboard_fab2_lib.baseboard_fab2(sch_1):m_g_dqs_dn(17)"
				( attribute "CDS_PHYS_NET_NAME" "M_G_DQS_DN<17>"
					( Origin gPackager )
				)
				( attribute "PNN" "M_G_DQS_DN<17>"
					( Origin gPackager )
				)
				( objectStatus "M_G_DQS_DN<17>" )
			)
			( signal "@baseboard_fab2_lib.baseboard_fab2(sch_1):m_g_dqs_dp(0)"
				( attribute "CDS_PHYS_NET_NAME" "M_G_DQS_DP<0>"
					( Origin gPackager )
				)
				( attribute "PNN" "M_G_DQS_DP<0>"
					( Origin gPackager )
				)
				( objectStatus "M_G_DQS_DP<0>" )
			)
			( signal "@baseboard_fab2_lib.baseboard_fab2(sch_1):m_g_dqs_dp(1)"
				( attribute "CDS_PHYS_NET_NAME" "M_G_DQS_DP<1>"
					( Origin gPackager )
				)
				( attribute "PNN" "M_G_DQS_DP<1>"
					( Origin gPackager )
				)
				( objectStatus "M_G_DQS_DP<1>" )
			)
			( signal "@baseboard_fab2_lib.baseboard_fab2(sch_1):m_g_dqs_dp(2)"
				( attribute "CDS_PHYS_NET_NAME" "M_G_DQS_DP<2>"
					( Origin gPackager )
				)
				( attribute "PNN" "M_G_DQS_DP<2>"
					( Origin gPackager )
				)
				( objectStatus "M_G_DQS_DP<2>" )
			)
			( signal "@baseboard_fab2_lib.baseboard_fab2(sch_1):m_g_dqs_dp(3)"
				( attribute "CDS_PHYS_NET_NAME" "M_G_DQS_DP<3>"
					( Origin gPackager )
				)
				( attribute "PNN" "M_G_DQS_DP<3>"
					( Origin gPackager )
				)
				( objectStatus "M_G_DQS_DP<3>" )
			)
			( signal "@baseboard_fab2_lib.baseboard_fab2(sch_1):m_g_dqs_dp(4)"
				( attribute "CDS_PHYS_NET_NAME" "M_G_DQS_DP<4>"
					( Origin gPackager )
				)
				( attribute "PNN" "M_G_DQS_DP<4>"
					( Origin gPackager )
				)
				( objectStatus "M_G_DQS_DP<4>" )
			)
			( signal "@baseboard_fab2_lib.baseboard_fab2(sch_1):m_g_dqs_dp(5)"
				( attribute "CDS_PHYS_NET_NAME" "M_G_DQS_DP<5>"
					( Origin gPackager )
				)
				( attribute "PNN" "M_G_DQS_DP<5>"
					( Origin gPackager )
				)
				( objectStatus "M_G_DQS_DP<5>" )
			)
			( signal "@baseboard_fab2_lib.baseboard_fab2(sch_1):m_g_dqs_dp(6)"
				( attribute "CDS_PHYS_NET_NAME" "M_G_DQS_DP<6>"
					( Origin gPackager )
				)
				( attribute "PNN" "M_G_DQS_DP<6>"
					( Origin gPackager )
				)
				( objectStatus "M_G_DQS_DP<6>" )
			)
			( signal "@baseboard_fab2_lib.baseboard_fab2(sch_1):m_g_dqs_dp(7)"
				( attribute "CDS_PHYS_NET_NAME" "M_G_DQS_DP<7>"
					( Origin gPackager )
				)
				( attribute "PNN" "M_G_DQS_DP<7>"
					( Origin gPackager )
				)
				( objectStatus "M_G_DQS_DP<7>" )
			)
			( signal "@baseboard_fab2_lib.baseboard_fab2(sch_1):m_g_dqs_dp(8)"
				( attribute "CDS_PHYS_NET_NAME" "M_G_DQS_DP<8>"
					( Origin gPackager )
				)
				( attribute "PNN" "M_G_DQS_DP<8>"
					( Origin gPackager )
				)
				( objectStatus "M_G_DQS_DP<8>" )
			)
			( signal "@baseboard_fab2_lib.baseboard_fab2(sch_1):m_g_dqs_dp(9)"
				( attribute "CDS_PHYS_NET_NAME" "M_G_DQS_DP<9>"
					( Origin gPackager )
				)
				( attribute "PNN" "M_G_DQS_DP<9>"
					( Origin gPackager )
				)
				( objectStatus "M_G_DQS_DP<9>" )
			)
			( signal "@baseboard_fab2_lib.baseboard_fab2(sch_1):m_g_dqs_dp(10)"
				( attribute "CDS_PHYS_NET_NAME" "M_G_DQS_DP<10>"
					( Origin gPackager )
				)
				( attribute "PNN" "M_G_DQS_DP<10>"
					( Origin gPackager )
				)
				( objectStatus "M_G_DQS_DP<10>" )
			)
			( signal "@baseboard_fab2_lib.baseboard_fab2(sch_1):m_g_dqs_dp(11)"
				( attribute "CDS_PHYS_NET_NAME" "M_G_DQS_DP<11>"
					( Origin gPackager )
				)
				( attribute "PNN" "M_G_DQS_DP<11>"
					( Origin gPackager )
				)
				( objectStatus "M_G_DQS_DP<11>" )
			)
			( signal "@baseboard_fab2_lib.baseboard_fab2(sch_1):m_g_dqs_dp(12)"
				( attribute "CDS_PHYS_NET_NAME" "M_G_DQS_DP<12>"
					( Origin gPackager )
				)
				( attribute "PNN" "M_G_DQS_DP<12>"
					( Origin gPackager )
				)
				( objectStatus "M_G_DQS_DP<12>" )
			)
			( signal "@baseboard_fab2_lib.baseboard_fab2(sch_1):m_g_dqs_dp(13)"
				( attribute "CDS_PHYS_NET_NAME" "M_G_DQS_DP<13>"
					( Origin gPackager )
				)
				( attribute "PNN" "M_G_DQS_DP<13>"
					( Origin gPackager )
				)
				( objectStatus "M_G_DQS_DP<13>" )
			)
			( signal "@baseboard_fab2_lib.baseboard_fab2(sch_1):m_g_dqs_dp(14)"
				( attribute "CDS_PHYS_NET_NAME" "M_G_DQS_DP<14>"
					( Origin gPackager )
				)
				( attribute "PNN" "M_G_DQS_DP<14>"
					( Origin gPackager )
				)
				( objectStatus "M_G_DQS_DP<14>" )
			)
			( signal "@baseboard_fab2_lib.baseboard_fab2(sch_1):m_g_dqs_dp(15)"
				( attribute "CDS_PHYS_NET_NAME" "M_G_DQS_DP<15>"
					( Origin gPackager )
				)
				( attribute "PNN" "M_G_DQS_DP<15>"
					( Origin gPackager )
				)
				( objectStatus "M_G_DQS_DP<15>" )
			)
			( signal "@baseboard_fab2_lib.baseboard_fab2(sch_1):m_g_dqs_dp(16)"
				( attribute "CDS_PHYS_NET_NAME" "M_G_DQS_DP<16>"
					( Origin gPackager )
				)
				( attribute "PNN" "M_G_DQS_DP<16>"
					( Origin gPackager )
				)
				( objectStatus "M_G_DQS_DP<16>" )
			)
			( signal "@baseboard_fab2_lib.baseboard_fab2(sch_1):m_g_dqs_dp(17)"
				( attribute "CDS_PHYS_NET_NAME" "M_G_DQS_DP<17>"
					( Origin gPackager )
				)
				( attribute "PNN" "M_G_DQS_DP<17>"
					( Origin gPackager )
				)
				( objectStatus "M_G_DQS_DP<17>" )
			)
			( signal "@baseboard_fab2_lib.baseboard_fab2(sch_1):m_g_ecc(0)"
				( attribute "CDS_PHYS_NET_NAME" "M_G_ECC<0>"
					( Origin gPackager )
				)
				( attribute "PNN" "M_G_ECC<0>"
					( Origin gPackager )
				)
				( objectStatus "M_G_ECC<0>" )
			)
			( signal "@baseboard_fab2_lib.baseboard_fab2(sch_1):m_g_ecc(1)"
				( attribute "CDS_PHYS_NET_NAME" "M_G_ECC<1>"
					( Origin gPackager )
				)
				( attribute "PNN" "M_G_ECC<1>"
					( Origin gPackager )
				)
				( objectStatus "M_G_ECC<1>" )
			)
			( signal "@baseboard_fab2_lib.baseboard_fab2(sch_1):m_g_ecc(2)"
				( attribute "CDS_PHYS_NET_NAME" "M_G_ECC<2>"
					( Origin gPackager )
				)
				( attribute "PNN" "M_G_ECC<2>"
					( Origin gPackager )
				)
				( objectStatus "M_G_ECC<2>" )
			)
			( signal "@baseboard_fab2_lib.baseboard_fab2(sch_1):m_g_ecc(3)"
				( attribute "CDS_PHYS_NET_NAME" "M_G_ECC<3>"
					( Origin gPackager )
				)
				( attribute "PNN" "M_G_ECC<3>"
					( Origin gPackager )
				)
				( objectStatus "M_G_ECC<3>" )
			)
			( signal "@baseboard_fab2_lib.baseboard_fab2(sch_1):m_g_ecc(4)"
				( attribute "CDS_PHYS_NET_NAME" "M_G_ECC<4>"
					( Origin gPackager )
				)
				( attribute "PNN" "M_G_ECC<4>"
					( Origin gPackager )
				)
				( objectStatus "M_G_ECC<4>" )
			)
			( signal "@baseboard_fab2_lib.baseboard_fab2(sch_1):m_g_ecc(5)"
				( attribute "CDS_PHYS_NET_NAME" "M_G_ECC<5>"
					( Origin gPackager )
				)
				( attribute "PNN" "M_G_ECC<5>"
					( Origin gPackager )
				)
				( objectStatus "M_G_ECC<5>" )
			)
			( signal "@baseboard_fab2_lib.baseboard_fab2(sch_1):m_g_ecc(6)"
				( attribute "CDS_PHYS_NET_NAME" "M_G_ECC<6>"
					( Origin gPackager )
				)
				( attribute "PNN" "M_G_ECC<6>"
					( Origin gPackager )
				)
				( objectStatus "M_G_ECC<6>" )
			)
			( signal "@baseboard_fab2_lib.baseboard_fab2(sch_1):m_g_ecc(7)"
				( attribute "CDS_PHYS_NET_NAME" "M_G_ECC<7>"
					( Origin gPackager )
				)
				( attribute "PNN" "M_G_ECC<7>"
					( Origin gPackager )
				)
				( objectStatus "M_G_ECC<7>" )
			)
			( signal "@baseboard_fab2_lib.baseboard_fab2(sch_1):m_g_ma(0)"
				( attribute "CDS_PHYS_NET_NAME" "M_G_MA<0>"
					( Origin gPackager )
				)
				( attribute "PNN" "M_G_MA<0>"
					( Origin gPackager )
				)
				( objectStatus "M_G_MA<0>" )
			)
			( signal "@baseboard_fab2_lib.baseboard_fab2(sch_1):m_g_ma(1)"
				( attribute "CDS_PHYS_NET_NAME" "M_G_MA<1>"
					( Origin gPackager )
				)
				( attribute "PNN" "M_G_MA<1>"
					( Origin gPackager )
				)
				( objectStatus "M_G_MA<1>" )
			)
			( signal "@baseboard_fab2_lib.baseboard_fab2(sch_1):m_g_ma(2)"
				( attribute "CDS_PHYS_NET_NAME" "M_G_MA<2>"
					( Origin gPackager )
				)
				( attribute "PNN" "M_G_MA<2>"
					( Origin gPackager )
				)
				( objectStatus "M_G_MA<2>" )
			)
			( signal "@baseboard_fab2_lib.baseboard_fab2(sch_1):m_g_ma(3)"
				( attribute "CDS_PHYS_NET_NAME" "M_G_MA<3>"
					( Origin gPackager )
				)
				( attribute "PNN" "M_G_MA<3>"
					( Origin gPackager )
				)
				( objectStatus "M_G_MA<3>" )
			)
			( signal "@baseboard_fab2_lib.baseboard_fab2(sch_1):m_g_ma(4)"
				( attribute "CDS_PHYS_NET_NAME" "M_G_MA<4>"
					( Origin gPackager )
				)
				( attribute "PNN" "M_G_MA<4>"
					( Origin gPackager )
				)
				( objectStatus "M_G_MA<4>" )
			)
			( signal "@baseboard_fab2_lib.baseboard_fab2(sch_1):m_g_ma(5)"
				( attribute "CDS_PHYS_NET_NAME" "M_G_MA<5>"
					( Origin gPackager )
				)
				( attribute "PNN" "M_G_MA<5>"
					( Origin gPackager )
				)
				( objectStatus "M_G_MA<5>" )
			)
			( signal "@baseboard_fab2_lib.baseboard_fab2(sch_1):m_g_ma(6)"
				( attribute "CDS_PHYS_NET_NAME" "M_G_MA<6>"
					( Origin gPackager )
				)
				( attribute "PNN" "M_G_MA<6>"
					( Origin gPackager )
				)
				( objectStatus "M_G_MA<6>" )
			)
			( signal "@baseboard_fab2_lib.baseboard_fab2(sch_1):m_g_ma(7)"
				( attribute "CDS_PHYS_NET_NAME" "M_G_MA<7>"
					( Origin gPackager )
				)
				( attribute "PNN" "M_G_MA<7>"
					( Origin gPackager )
				)
				( objectStatus "M_G_MA<7>" )
			)
			( signal "@baseboard_fab2_lib.baseboard_fab2(sch_1):m_g_ma(8)"
				( attribute "CDS_PHYS_NET_NAME" "M_G_MA<8>"
					( Origin gPackager )
				)
				( attribute "PNN" "M_G_MA<8>"
					( Origin gPackager )
				)
				( objectStatus "M_G_MA<8>" )
			)
			( signal "@baseboard_fab2_lib.baseboard_fab2(sch_1):m_g_ma(9)"
				( attribute "CDS_PHYS_NET_NAME" "M_G_MA<9>"
					( Origin gPackager )
				)
				( attribute "PNN" "M_G_MA<9>"
					( Origin gPackager )
				)
				( objectStatus "M_G_MA<9>" )
			)
			( signal "@baseboard_fab2_lib.baseboard_fab2(sch_1):m_g_ma(10)"
				( attribute "CDS_PHYS_NET_NAME" "M_G_MA<10>"
					( Origin gPackager )
				)
				( attribute "PNN" "M_G_MA<10>"
					( Origin gPackager )
				)
				( objectStatus "M_G_MA<10>" )
			)
			( signal "@baseboard_fab2_lib.baseboard_fab2(sch_1):m_g_ma(11)"
				( attribute "CDS_PHYS_NET_NAME" "M_G_MA<11>"
					( Origin gPackager )
				)
				( attribute "PNN" "M_G_MA<11>"
					( Origin gPackager )
				)
				( objectStatus "M_G_MA<11>" )
			)
			( signal "@baseboard_fab2_lib.baseboard_fab2(sch_1):m_g_ma(12)"
				( attribute "CDS_PHYS_NET_NAME" "M_G_MA<12>"
					( Origin gPackager )
				)
				( attribute "PNN" "M_G_MA<12>"
					( Origin gPackager )
				)
				( objectStatus "M_G_MA<12>" )
			)
			( signal "@baseboard_fab2_lib.baseboard_fab2(sch_1):m_g_ma(13)"
				( attribute "CDS_PHYS_NET_NAME" "M_G_MA<13>"
					( Origin gPackager )
				)
				( attribute "PNN" "M_G_MA<13>"
					( Origin gPackager )
				)
				( objectStatus "M_G_MA<13>" )
			)
			( signal "@baseboard_fab2_lib.baseboard_fab2(sch_1):m_g_ma(14)"
				( attribute "CDS_PHYS_NET_NAME" "M_G_MA<14>"
					( Origin gPackager )
				)
				( attribute "PNN" "M_G_MA<14>"
					( Origin gPackager )
				)
				( objectStatus "M_G_MA<14>" )
			)
			( signal "@baseboard_fab2_lib.baseboard_fab2(sch_1):m_g_ma(15)"
				( attribute "CDS_PHYS_NET_NAME" "M_G_MA<15>"
					( Origin gPackager )
				)
				( attribute "PNN" "M_G_MA<15>"
					( Origin gPackager )
				)
				( objectStatus "M_G_MA<15>" )
			)
			( signal "@baseboard_fab2_lib.baseboard_fab2(sch_1):m_g_ma(16)"
				( attribute "CDS_PHYS_NET_NAME" "M_G_MA<16>"
					( Origin gPackager )
				)
				( attribute "PNN" "M_G_MA<16>"
					( Origin gPackager )
				)
				( objectStatus "M_G_MA<16>" )
			)
			( signal "@baseboard_fab2_lib.baseboard_fab2(sch_1):m_g_ma(17)"
				( attribute "CDS_PHYS_NET_NAME" "M_G_MA<17>"
					( Origin gPackager )
				)
				( attribute "PNN" "M_G_MA<17>"
					( Origin gPackager )
				)
				( objectStatus "M_G_MA<17>" )
			)
			( signal "@baseboard_fab2_lib.baseboard_fab2(sch_1):m_g_odt(0)"
				( attribute "CDS_PHYS_NET_NAME" "M_G_ODT<0>"
					( Origin gPackager )
				)
				( attribute "PNN" "M_G_ODT<0>"
					( Origin gPackager )
				)
				( objectStatus "M_G_ODT<0>" )
			)
			( signal "@baseboard_fab2_lib.baseboard_fab2(sch_1):m_g_odt(1)"
				( attribute "CDS_PHYS_NET_NAME" "M_G_ODT<1>"
					( Origin gPackager )
				)
				( attribute "PNN" "M_G_ODT<1>"
					( Origin gPackager )
				)
				( objectStatus "M_G_ODT<1>" )
			)
			( signal "@baseboard_fab2_lib.baseboard_fab2(sch_1):m_g_odt(2)"
				( attribute "CDS_PHYS_NET_NAME" "M_G_ODT<2>"
					( Origin gPackager )
				)
				( attribute "PNN" "M_G_ODT<2>"
					( Origin gPackager )
				)
				( objectStatus "M_G_ODT<2>" )
			)
			( signal "@baseboard_fab2_lib.baseboard_fab2(sch_1):m_g_odt(3)"
				( attribute "CDS_PHYS_NET_NAME" "M_G_ODT<3>"
					( Origin gPackager )
				)
				( attribute "PNN" "M_G_ODT<3>"
					( Origin gPackager )
				)
				( objectStatus "M_G_ODT<3>" )
			)
			( signal "@baseboard_fab2_lib.baseboard_fab2(sch_1):m_g_par"
				( attribute "CDS_PHYS_NET_NAME" "M_G_PAR"
					( Origin gPackager )
				)
				( objectStatus "M_G_PAR" )
			)
			( signal "@baseboard_fab2_lib.baseboard_fab2(sch_1):m_h_act_n"
				( attribute "CDS_PHYS_NET_NAME" "M_H_ACT_N"
					( Origin gPackager )
				)
				( objectStatus "M_H_ACT_N" )
			)
			( signal "@baseboard_fab2_lib.baseboard_fab2(sch_1):m_h_alert_n"
				( attribute "CDS_PHYS_NET_NAME" "M_H_ALERT_N"
					( Origin gPackager )
				)
				( objectStatus "M_H_ALERT_N" )
			)
			( signal "@baseboard_fab2_lib.baseboard_fab2(sch_1):m_h_ba(0)"
				( attribute "CDS_PHYS_NET_NAME" "M_H_BA<0>"
					( Origin gPackager )
				)
				( attribute "PNN" "M_H_BA<0>"
					( Origin gPackager )
				)
				( objectStatus "M_H_BA<0>" )
			)
			( signal "@baseboard_fab2_lib.baseboard_fab2(sch_1):m_h_ba(1)"
				( attribute "CDS_PHYS_NET_NAME" "M_H_BA<1>"
					( Origin gPackager )
				)
				( attribute "PNN" "M_H_BA<1>"
					( Origin gPackager )
				)
				( objectStatus "M_H_BA<1>" )
			)
			( signal "@baseboard_fab2_lib.baseboard_fab2(sch_1):m_h_bg(0)"
				( attribute "CDS_PHYS_NET_NAME" "M_H_BG<0>"
					( Origin gPackager )
				)
				( attribute "PNN" "M_H_BG<0>"
					( Origin gPackager )
				)
				( objectStatus "M_H_BG<0>" )
			)
			( signal "@baseboard_fab2_lib.baseboard_fab2(sch_1):m_h_bg(1)"
				( attribute "CDS_PHYS_NET_NAME" "M_H_BG<1>"
					( Origin gPackager )
				)
				( attribute "PNN" "M_H_BG<1>"
					( Origin gPackager )
				)
				( objectStatus "M_H_BG<1>" )
			)
			( signal "@baseboard_fab2_lib.baseboard_fab2(sch_1):m_h_c(2)"
				( attribute "CDS_PHYS_NET_NAME" "M_H_C<2>"
					( Origin gPackager )
				)
				( attribute "PNN" "M_H_C<2>"
					( Origin gPackager )
				)
				( objectStatus "M_H_C<2>" )
			)
			( signal "@baseboard_fab2_lib.baseboard_fab2(sch_1):m_h_cke(0)"
				( attribute "CDS_PHYS_NET_NAME" "M_H_CKE<0>"
					( Origin gPackager )
				)
				( attribute "PNN" "M_H_CKE<0>"
					( Origin gPackager )
				)
				( objectStatus "M_H_CKE<0>" )
			)
			( signal "@baseboard_fab2_lib.baseboard_fab2(sch_1):m_h_cke(1)"
				( attribute "CDS_PHYS_NET_NAME" "M_H_CKE<1>"
					( Origin gPackager )
				)
				( attribute "PNN" "M_H_CKE<1>"
					( Origin gPackager )
				)
				( objectStatus "M_H_CKE<1>" )
			)
			( signal "@baseboard_fab2_lib.baseboard_fab2(sch_1):m_h_cke(2)"
				( attribute "CDS_PHYS_NET_NAME" "M_H_CKE<2>"
					( Origin gPackager )
				)
				( attribute "PNN" "M_H_CKE<2>"
					( Origin gPackager )
				)
				( objectStatus "M_H_CKE<2>" )
			)
			( signal "@baseboard_fab2_lib.baseboard_fab2(sch_1):m_h_cke(3)"
				( attribute "CDS_PHYS_NET_NAME" "M_H_CKE<3>"
					( Origin gPackager )
				)
				( attribute "PNN" "M_H_CKE<3>"
					( Origin gPackager )
				)
				( objectStatus "M_H_CKE<3>" )
			)
			( signal "@baseboard_fab2_lib.baseboard_fab2(sch_1):m_h_clk_dn(0)"
				( attribute "CDS_PHYS_NET_NAME" "M_H_CLK_DN<0>"
					( Origin gPackager )
				)
				( attribute "PNN" "M_H_CLK_DN<0>"
					( Origin gPackager )
				)
				( objectStatus "M_H_CLK_DN<0>" )
			)
			( signal "@baseboard_fab2_lib.baseboard_fab2(sch_1):m_h_clk_dn(1)"
				( attribute "CDS_PHYS_NET_NAME" "M_H_CLK_DN<1>"
					( Origin gPackager )
				)
				( attribute "PNN" "M_H_CLK_DN<1>"
					( Origin gPackager )
				)
				( objectStatus "M_H_CLK_DN<1>" )
			)
			( signal "@baseboard_fab2_lib.baseboard_fab2(sch_1):m_h_clk_dn(2)"
				( attribute "CDS_PHYS_NET_NAME" "M_H_CLK_DN<2>"
					( Origin gPackager )
				)
				( attribute "PNN" "M_H_CLK_DN<2>"
					( Origin gPackager )
				)
				( objectStatus "M_H_CLK_DN<2>" )
			)
			( signal "@baseboard_fab2_lib.baseboard_fab2(sch_1):m_h_clk_dn(3)"
				( attribute "CDS_PHYS_NET_NAME" "M_H_CLK_DN<3>"
					( Origin gPackager )
				)
				( attribute "PNN" "M_H_CLK_DN<3>"
					( Origin gPackager )
				)
				( objectStatus "M_H_CLK_DN<3>" )
			)
			( signal "@baseboard_fab2_lib.baseboard_fab2(sch_1):m_h_clk_dp(0)"
				( attribute "CDS_PHYS_NET_NAME" "M_H_CLK_DP<0>"
					( Origin gPackager )
				)
				( attribute "PNN" "M_H_CLK_DP<0>"
					( Origin gPackager )
				)
				( objectStatus "M_H_CLK_DP<0>" )
			)
			( signal "@baseboard_fab2_lib.baseboard_fab2(sch_1):m_h_clk_dp(1)"
				( attribute "CDS_PHYS_NET_NAME" "M_H_CLK_DP<1>"
					( Origin gPackager )
				)
				( attribute "PNN" "M_H_CLK_DP<1>"
					( Origin gPackager )
				)
				( objectStatus "M_H_CLK_DP<1>" )
			)
			( signal "@baseboard_fab2_lib.baseboard_fab2(sch_1):m_h_clk_dp(2)"
				( attribute "CDS_PHYS_NET_NAME" "M_H_CLK_DP<2>"
					( Origin gPackager )
				)
				( attribute "PNN" "M_H_CLK_DP<2>"
					( Origin gPackager )
				)
				( objectStatus "M_H_CLK_DP<2>" )
			)
			( signal "@baseboard_fab2_lib.baseboard_fab2(sch_1):m_h_clk_dp(3)"
				( attribute "CDS_PHYS_NET_NAME" "M_H_CLK_DP<3>"
					( Origin gPackager )
				)
				( attribute "PNN" "M_H_CLK_DP<3>"
					( Origin gPackager )
				)
				( objectStatus "M_H_CLK_DP<3>" )
			)
			( signal "@baseboard_fab2_lib.baseboard_fab2(sch_1):m_h_cs_n(0)"
				( attribute "CDS_PHYS_NET_NAME" "M_H_CS_N<0>"
					( Origin gPackager )
				)
				( attribute "PNN" "M_H_CS_N<0>"
					( Origin gPackager )
				)
				( objectStatus "M_H_CS_N<0>" )
			)
			( signal "@baseboard_fab2_lib.baseboard_fab2(sch_1):m_h_cs_n(1)"
				( attribute "CDS_PHYS_NET_NAME" "M_H_CS_N<1>"
					( Origin gPackager )
				)
				( attribute "PNN" "M_H_CS_N<1>"
					( Origin gPackager )
				)
				( objectStatus "M_H_CS_N<1>" )
			)
			( signal "@baseboard_fab2_lib.baseboard_fab2(sch_1):m_h_cs_n(2)"
				( attribute "CDS_PHYS_NET_NAME" "M_H_CS_N<2>"
					( Origin gPackager )
				)
				( attribute "PNN" "M_H_CS_N<2>"
					( Origin gPackager )
				)
				( objectStatus "M_H_CS_N<2>" )
			)
			( signal "@baseboard_fab2_lib.baseboard_fab2(sch_1):m_h_cs_n(3)"
				( attribute "CDS_PHYS_NET_NAME" "M_H_CS_N<3>"
					( Origin gPackager )
				)
				( attribute "PNN" "M_H_CS_N<3>"
					( Origin gPackager )
				)
				( objectStatus "M_H_CS_N<3>" )
			)
			( signal "@baseboard_fab2_lib.baseboard_fab2(sch_1):m_h_cs_n(4)"
				( attribute "CDS_PHYS_NET_NAME" "M_H_CS_N<4>"
					( Origin gPackager )
				)
				( attribute "PNN" "M_H_CS_N<4>"
					( Origin gPackager )
				)
				( objectStatus "M_H_CS_N<4>" )
			)
			( signal "@baseboard_fab2_lib.baseboard_fab2(sch_1):m_h_cs_n(5)"
				( attribute "CDS_PHYS_NET_NAME" "M_H_CS_N<5>"
					( Origin gPackager )
				)
				( attribute "PNN" "M_H_CS_N<5>"
					( Origin gPackager )
				)
				( objectStatus "M_H_CS_N<5>" )
			)
			( signal "@baseboard_fab2_lib.baseboard_fab2(sch_1):m_h_cs_n(6)"
				( attribute "CDS_PHYS_NET_NAME" "M_H_CS_N<6>"
					( Origin gPackager )
				)
				( attribute "PNN" "M_H_CS_N<6>"
					( Origin gPackager )
				)
				( objectStatus "M_H_CS_N<6>" )
			)
			( signal "@baseboard_fab2_lib.baseboard_fab2(sch_1):m_h_cs_n(7)"
				( attribute "CDS_PHYS_NET_NAME" "M_H_CS_N<7>"
					( Origin gPackager )
				)
				( attribute "PNN" "M_H_CS_N<7>"
					( Origin gPackager )
				)
				( objectStatus "M_H_CS_N<7>" )
			)
			( signal "@baseboard_fab2_lib.baseboard_fab2(sch_1):m_h_dq(0)"
				( attribute "CDS_PHYS_NET_NAME" "M_H_DQ<0>"
					( Origin gPackager )
				)
				( attribute "PNN" "M_H_DQ<0>"
					( Origin gPackager )
				)
				( objectStatus "M_H_DQ<0>" )
			)
			( signal "@baseboard_fab2_lib.baseboard_fab2(sch_1):m_h_dq(1)"
				( attribute "CDS_PHYS_NET_NAME" "M_H_DQ<1>"
					( Origin gPackager )
				)
				( attribute "PNN" "M_H_DQ<1>"
					( Origin gPackager )
				)
				( objectStatus "M_H_DQ<1>" )
			)
			( signal "@baseboard_fab2_lib.baseboard_fab2(sch_1):m_h_dq(2)"
				( attribute "CDS_PHYS_NET_NAME" "M_H_DQ<2>"
					( Origin gPackager )
				)
				( attribute "PNN" "M_H_DQ<2>"
					( Origin gPackager )
				)
				( objectStatus "M_H_DQ<2>" )
			)
			( signal "@baseboard_fab2_lib.baseboard_fab2(sch_1):m_h_dq(3)"
				( attribute "CDS_PHYS_NET_NAME" "M_H_DQ<3>"
					( Origin gPackager )
				)
				( attribute "PNN" "M_H_DQ<3>"
					( Origin gPackager )
				)
				( objectStatus "M_H_DQ<3>" )
			)
			( signal "@baseboard_fab2_lib.baseboard_fab2(sch_1):m_h_dq(4)"
				( attribute "CDS_PHYS_NET_NAME" "M_H_DQ<4>"
					( Origin gPackager )
				)
				( attribute "PNN" "M_H_DQ<4>"
					( Origin gPackager )
				)
				( objectStatus "M_H_DQ<4>" )
			)
			( signal "@baseboard_fab2_lib.baseboard_fab2(sch_1):m_h_dq(5)"
				( attribute "CDS_PHYS_NET_NAME" "M_H_DQ<5>"
					( Origin gPackager )
				)
				( attribute "PNN" "M_H_DQ<5>"
					( Origin gPackager )
				)
				( objectStatus "M_H_DQ<5>" )
			)
			( signal "@baseboard_fab2_lib.baseboard_fab2(sch_1):m_h_dq(6)"
				( attribute "CDS_PHYS_NET_NAME" "M_H_DQ<6>"
					( Origin gPackager )
				)
				( attribute "PNN" "M_H_DQ<6>"
					( Origin gPackager )
				)
				( objectStatus "M_H_DQ<6>" )
			)
			( signal "@baseboard_fab2_lib.baseboard_fab2(sch_1):m_h_dq(7)"
				( attribute "CDS_PHYS_NET_NAME" "M_H_DQ<7>"
					( Origin gPackager )
				)
				( attribute "PNN" "M_H_DQ<7>"
					( Origin gPackager )
				)
				( objectStatus "M_H_DQ<7>" )
			)
			( signal "@baseboard_fab2_lib.baseboard_fab2(sch_1):m_h_dq(8)"
				( attribute "CDS_PHYS_NET_NAME" "M_H_DQ<8>"
					( Origin gPackager )
				)
				( attribute "PNN" "M_H_DQ<8>"
					( Origin gPackager )
				)
				( objectStatus "M_H_DQ<8>" )
			)
			( signal "@baseboard_fab2_lib.baseboard_fab2(sch_1):m_h_dq(9)"
				( attribute "CDS_PHYS_NET_NAME" "M_H_DQ<9>"
					( Origin gPackager )
				)
				( attribute "PNN" "M_H_DQ<9>"
					( Origin gPackager )
				)
				( objectStatus "M_H_DQ<9>" )
			)
			( signal "@baseboard_fab2_lib.baseboard_fab2(sch_1):m_h_dq(10)"
				( attribute "CDS_PHYS_NET_NAME" "M_H_DQ<10>"
					( Origin gPackager )
				)
				( attribute "PNN" "M_H_DQ<10>"
					( Origin gPackager )
				)
				( objectStatus "M_H_DQ<10>" )
			)
			( signal "@baseboard_fab2_lib.baseboard_fab2(sch_1):m_h_dq(11)"
				( attribute "CDS_PHYS_NET_NAME" "M_H_DQ<11>"
					( Origin gPackager )
				)
				( attribute "PNN" "M_H_DQ<11>"
					( Origin gPackager )
				)
				( objectStatus "M_H_DQ<11>" )
			)
			( signal "@baseboard_fab2_lib.baseboard_fab2(sch_1):m_h_dq(12)"
				( attribute "CDS_PHYS_NET_NAME" "M_H_DQ<12>"
					( Origin gPackager )
				)
				( attribute "PNN" "M_H_DQ<12>"
					( Origin gPackager )
				)
				( objectStatus "M_H_DQ<12>" )
			)
			( signal "@baseboard_fab2_lib.baseboard_fab2(sch_1):m_h_dq(13)"
				( attribute "CDS_PHYS_NET_NAME" "M_H_DQ<13>"
					( Origin gPackager )
				)
				( attribute "PNN" "M_H_DQ<13>"
					( Origin gPackager )
				)
				( objectStatus "M_H_DQ<13>" )
			)
			( signal "@baseboard_fab2_lib.baseboard_fab2(sch_1):m_h_dq(14)"
				( attribute "CDS_PHYS_NET_NAME" "M_H_DQ<14>"
					( Origin gPackager )
				)
				( attribute "PNN" "M_H_DQ<14>"
					( Origin gPackager )
				)
				( objectStatus "M_H_DQ<14>" )
			)
			( signal "@baseboard_fab2_lib.baseboard_fab2(sch_1):m_h_dq(15)"
				( attribute "CDS_PHYS_NET_NAME" "M_H_DQ<15>"
					( Origin gPackager )
				)
				( attribute "PNN" "M_H_DQ<15>"
					( Origin gPackager )
				)
				( objectStatus "M_H_DQ<15>" )
			)
			( signal "@baseboard_fab2_lib.baseboard_fab2(sch_1):m_h_dq(16)"
				( attribute "CDS_PHYS_NET_NAME" "M_H_DQ<16>"
					( Origin gPackager )
				)
				( attribute "PNN" "M_H_DQ<16>"
					( Origin gPackager )
				)
				( objectStatus "M_H_DQ<16>" )
			)
			( signal "@baseboard_fab2_lib.baseboard_fab2(sch_1):m_h_dq(17)"
				( attribute "CDS_PHYS_NET_NAME" "M_H_DQ<17>"
					( Origin gPackager )
				)
				( attribute "PNN" "M_H_DQ<17>"
					( Origin gPackager )
				)
				( objectStatus "M_H_DQ<17>" )
			)
			( signal "@baseboard_fab2_lib.baseboard_fab2(sch_1):m_h_dq(18)"
				( attribute "CDS_PHYS_NET_NAME" "M_H_DQ<18>"
					( Origin gPackager )
				)
				( attribute "PNN" "M_H_DQ<18>"
					( Origin gPackager )
				)
				( objectStatus "M_H_DQ<18>" )
			)
			( signal "@baseboard_fab2_lib.baseboard_fab2(sch_1):m_h_dq(19)"
				( attribute "CDS_PHYS_NET_NAME" "M_H_DQ<19>"
					( Origin gPackager )
				)
				( attribute "PNN" "M_H_DQ<19>"
					( Origin gPackager )
				)
				( objectStatus "M_H_DQ<19>" )
			)
			( signal "@baseboard_fab2_lib.baseboard_fab2(sch_1):m_h_dq(20)"
				( attribute "CDS_PHYS_NET_NAME" "M_H_DQ<20>"
					( Origin gPackager )
				)
				( attribute "PNN" "M_H_DQ<20>"
					( Origin gPackager )
				)
				( objectStatus "M_H_DQ<20>" )
			)
			( signal "@baseboard_fab2_lib.baseboard_fab2(sch_1):m_h_dq(21)"
				( attribute "CDS_PHYS_NET_NAME" "M_H_DQ<21>"
					( Origin gPackager )
				)
				( attribute "PNN" "M_H_DQ<21>"
					( Origin gPackager )
				)
				( objectStatus "M_H_DQ<21>" )
			)
			( signal "@baseboard_fab2_lib.baseboard_fab2(sch_1):m_h_dq(22)"
				( attribute "CDS_PHYS_NET_NAME" "M_H_DQ<22>"
					( Origin gPackager )
				)
				( attribute "PNN" "M_H_DQ<22>"
					( Origin gPackager )
				)
				( objectStatus "M_H_DQ<22>" )
			)
			( signal "@baseboard_fab2_lib.baseboard_fab2(sch_1):m_h_dq(23)"
				( attribute "CDS_PHYS_NET_NAME" "M_H_DQ<23>"
					( Origin gPackager )
				)
				( attribute "PNN" "M_H_DQ<23>"
					( Origin gPackager )
				)
				( objectStatus "M_H_DQ<23>" )
			)
			( signal "@baseboard_fab2_lib.baseboard_fab2(sch_1):m_h_dq(24)"
				( attribute "CDS_PHYS_NET_NAME" "M_H_DQ<24>"
					( Origin gPackager )
				)
				( attribute "PNN" "M_H_DQ<24>"
					( Origin gPackager )
				)
				( objectStatus "M_H_DQ<24>" )
			)
			( signal "@baseboard_fab2_lib.baseboard_fab2(sch_1):m_h_dq(25)"
				( attribute "CDS_PHYS_NET_NAME" "M_H_DQ<25>"
					( Origin gPackager )
				)
				( attribute "PNN" "M_H_DQ<25>"
					( Origin gPackager )
				)
				( objectStatus "M_H_DQ<25>" )
			)
			( signal "@baseboard_fab2_lib.baseboard_fab2(sch_1):m_h_dq(26)"
				( attribute "CDS_PHYS_NET_NAME" "M_H_DQ<26>"
					( Origin gPackager )
				)
				( attribute "PNN" "M_H_DQ<26>"
					( Origin gPackager )
				)
				( objectStatus "M_H_DQ<26>" )
			)
			( signal "@baseboard_fab2_lib.baseboard_fab2(sch_1):m_h_dq(27)"
				( attribute "CDS_PHYS_NET_NAME" "M_H_DQ<27>"
					( Origin gPackager )
				)
				( attribute "PNN" "M_H_DQ<27>"
					( Origin gPackager )
				)
				( objectStatus "M_H_DQ<27>" )
			)
			( signal "@baseboard_fab2_lib.baseboard_fab2(sch_1):m_h_dq(28)"
				( attribute "CDS_PHYS_NET_NAME" "M_H_DQ<28>"
					( Origin gPackager )
				)
				( attribute "PNN" "M_H_DQ<28>"
					( Origin gPackager )
				)
				( objectStatus "M_H_DQ<28>" )
			)
			( signal "@baseboard_fab2_lib.baseboard_fab2(sch_1):m_h_dq(29)"
				( attribute "CDS_PHYS_NET_NAME" "M_H_DQ<29>"
					( Origin gPackager )
				)
				( attribute "PNN" "M_H_DQ<29>"
					( Origin gPackager )
				)
				( objectStatus "M_H_DQ<29>" )
			)
			( signal "@baseboard_fab2_lib.baseboard_fab2(sch_1):m_h_dq(30)"
				( attribute "CDS_PHYS_NET_NAME" "M_H_DQ<30>"
					( Origin gPackager )
				)
				( attribute "PNN" "M_H_DQ<30>"
					( Origin gPackager )
				)
				( objectStatus "M_H_DQ<30>" )
			)
			( signal "@baseboard_fab2_lib.baseboard_fab2(sch_1):m_h_dq(31)"
				( attribute "CDS_PHYS_NET_NAME" "M_H_DQ<31>"
					( Origin gPackager )
				)
				( attribute "PNN" "M_H_DQ<31>"
					( Origin gPackager )
				)
				( objectStatus "M_H_DQ<31>" )
			)
			( signal "@baseboard_fab2_lib.baseboard_fab2(sch_1):m_h_dq(32)"
				( attribute "CDS_PHYS_NET_NAME" "M_H_DQ<32>"
					( Origin gPackager )
				)
				( attribute "PNN" "M_H_DQ<32>"
					( Origin gPackager )
				)
				( objectStatus "M_H_DQ<32>" )
			)
			( signal "@baseboard_fab2_lib.baseboard_fab2(sch_1):m_h_dq(33)"
				( attribute "CDS_PHYS_NET_NAME" "M_H_DQ<33>"
					( Origin gPackager )
				)
				( attribute "PNN" "M_H_DQ<33>"
					( Origin gPackager )
				)
				( objectStatus "M_H_DQ<33>" )
			)
			( signal "@baseboard_fab2_lib.baseboard_fab2(sch_1):m_h_dq(34)"
				( attribute "CDS_PHYS_NET_NAME" "M_H_DQ<34>"
					( Origin gPackager )
				)
				( attribute "PNN" "M_H_DQ<34>"
					( Origin gPackager )
				)
				( objectStatus "M_H_DQ<34>" )
			)
			( signal "@baseboard_fab2_lib.baseboard_fab2(sch_1):m_h_dq(35)"
				( attribute "CDS_PHYS_NET_NAME" "M_H_DQ<35>"
					( Origin gPackager )
				)
				( attribute "PNN" "M_H_DQ<35>"
					( Origin gPackager )
				)
				( objectStatus "M_H_DQ<35>" )
			)
			( signal "@baseboard_fab2_lib.baseboard_fab2(sch_1):m_h_dq(36)"
				( attribute "CDS_PHYS_NET_NAME" "M_H_DQ<36>"
					( Origin gPackager )
				)
				( attribute "PNN" "M_H_DQ<36>"
					( Origin gPackager )
				)
				( objectStatus "M_H_DQ<36>" )
			)
			( signal "@baseboard_fab2_lib.baseboard_fab2(sch_1):m_h_dq(37)"
				( attribute "CDS_PHYS_NET_NAME" "M_H_DQ<37>"
					( Origin gPackager )
				)
				( attribute "PNN" "M_H_DQ<37>"
					( Origin gPackager )
				)
				( objectStatus "M_H_DQ<37>" )
			)
			( signal "@baseboard_fab2_lib.baseboard_fab2(sch_1):m_h_dq(38)"
				( attribute "CDS_PHYS_NET_NAME" "M_H_DQ<38>"
					( Origin gPackager )
				)
				( attribute "PNN" "M_H_DQ<38>"
					( Origin gPackager )
				)
				( objectStatus "M_H_DQ<38>" )
			)
			( signal "@baseboard_fab2_lib.baseboard_fab2(sch_1):m_h_dq(39)"
				( attribute "CDS_PHYS_NET_NAME" "M_H_DQ<39>"
					( Origin gPackager )
				)
				( attribute "PNN" "M_H_DQ<39>"
					( Origin gPackager )
				)
				( objectStatus "M_H_DQ<39>" )
			)
			( signal "@baseboard_fab2_lib.baseboard_fab2(sch_1):m_h_dq(40)"
				( attribute "CDS_PHYS_NET_NAME" "M_H_DQ<40>"
					( Origin gPackager )
				)
				( attribute "PNN" "M_H_DQ<40>"
					( Origin gPackager )
				)
				( objectStatus "M_H_DQ<40>" )
			)
			( signal "@baseboard_fab2_lib.baseboard_fab2(sch_1):m_h_dq(41)"
				( attribute "CDS_PHYS_NET_NAME" "M_H_DQ<41>"
					( Origin gPackager )
				)
				( attribute "PNN" "M_H_DQ<41>"
					( Origin gPackager )
				)
				( objectStatus "M_H_DQ<41>" )
			)
			( signal "@baseboard_fab2_lib.baseboard_fab2(sch_1):m_h_dq(42)"
				( attribute "CDS_PHYS_NET_NAME" "M_H_DQ<42>"
					( Origin gPackager )
				)
				( attribute "PNN" "M_H_DQ<42>"
					( Origin gPackager )
				)
				( objectStatus "M_H_DQ<42>" )
			)
			( signal "@baseboard_fab2_lib.baseboard_fab2(sch_1):m_h_dq(43)"
				( attribute "CDS_PHYS_NET_NAME" "M_H_DQ<43>"
					( Origin gPackager )
				)
				( attribute "PNN" "M_H_DQ<43>"
					( Origin gPackager )
				)
				( objectStatus "M_H_DQ<43>" )
			)
			( signal "@baseboard_fab2_lib.baseboard_fab2(sch_1):m_h_dq(44)"
				( attribute "CDS_PHYS_NET_NAME" "M_H_DQ<44>"
					( Origin gPackager )
				)
				( attribute "PNN" "M_H_DQ<44>"
					( Origin gPackager )
				)
				( objectStatus "M_H_DQ<44>" )
			)
			( signal "@baseboard_fab2_lib.baseboard_fab2(sch_1):m_h_dq(45)"
				( attribute "CDS_PHYS_NET_NAME" "M_H_DQ<45>"
					( Origin gPackager )
				)
				( attribute "PNN" "M_H_DQ<45>"
					( Origin gPackager )
				)
				( objectStatus "M_H_DQ<45>" )
			)
			( signal "@baseboard_fab2_lib.baseboard_fab2(sch_1):m_h_dq(46)"
				( attribute "CDS_PHYS_NET_NAME" "M_H_DQ<46>"
					( Origin gPackager )
				)
				( attribute "PNN" "M_H_DQ<46>"
					( Origin gPackager )
				)
				( objectStatus "M_H_DQ<46>" )
			)
			( signal "@baseboard_fab2_lib.baseboard_fab2(sch_1):m_h_dq(47)"
				( attribute "CDS_PHYS_NET_NAME" "M_H_DQ<47>"
					( Origin gPackager )
				)
				( attribute "PNN" "M_H_DQ<47>"
					( Origin gPackager )
				)
				( objectStatus "M_H_DQ<47>" )
			)
			( signal "@baseboard_fab2_lib.baseboard_fab2(sch_1):m_h_dq(48)"
				( attribute "CDS_PHYS_NET_NAME" "M_H_DQ<48>"
					( Origin gPackager )
				)
				( attribute "PNN" "M_H_DQ<48>"
					( Origin gPackager )
				)
				( objectStatus "M_H_DQ<48>" )
			)
			( signal "@baseboard_fab2_lib.baseboard_fab2(sch_1):m_h_dq(49)"
				( attribute "CDS_PHYS_NET_NAME" "M_H_DQ<49>"
					( Origin gPackager )
				)
				( attribute "PNN" "M_H_DQ<49>"
					( Origin gPackager )
				)
				( objectStatus "M_H_DQ<49>" )
			)
			( signal "@baseboard_fab2_lib.baseboard_fab2(sch_1):m_h_dq(50)"
				( attribute "CDS_PHYS_NET_NAME" "M_H_DQ<50>"
					( Origin gPackager )
				)
				( attribute "PNN" "M_H_DQ<50>"
					( Origin gPackager )
				)
				( objectStatus "M_H_DQ<50>" )
			)
			( signal "@baseboard_fab2_lib.baseboard_fab2(sch_1):m_h_dq(51)"
				( attribute "CDS_PHYS_NET_NAME" "M_H_DQ<51>"
					( Origin gPackager )
				)
				( attribute "PNN" "M_H_DQ<51>"
					( Origin gPackager )
				)
				( objectStatus "M_H_DQ<51>" )
			)
			( signal "@baseboard_fab2_lib.baseboard_fab2(sch_1):m_h_dq(52)"
				( attribute "CDS_PHYS_NET_NAME" "M_H_DQ<52>"
					( Origin gPackager )
				)
				( attribute "PNN" "M_H_DQ<52>"
					( Origin gPackager )
				)
				( objectStatus "M_H_DQ<52>" )
			)
			( signal "@baseboard_fab2_lib.baseboard_fab2(sch_1):m_h_dq(53)"
				( attribute "CDS_PHYS_NET_NAME" "M_H_DQ<53>"
					( Origin gPackager )
				)
				( attribute "PNN" "M_H_DQ<53>"
					( Origin gPackager )
				)
				( objectStatus "M_H_DQ<53>" )
			)
			( signal "@baseboard_fab2_lib.baseboard_fab2(sch_1):m_h_dq(54)"
				( attribute "CDS_PHYS_NET_NAME" "M_H_DQ<54>"
					( Origin gPackager )
				)
				( attribute "PNN" "M_H_DQ<54>"
					( Origin gPackager )
				)
				( objectStatus "M_H_DQ<54>" )
			)
			( signal "@baseboard_fab2_lib.baseboard_fab2(sch_1):m_h_dq(55)"
				( attribute "CDS_PHYS_NET_NAME" "M_H_DQ<55>"
					( Origin gPackager )
				)
				( attribute "PNN" "M_H_DQ<55>"
					( Origin gPackager )
				)
				( objectStatus "M_H_DQ<55>" )
			)
			( signal "@baseboard_fab2_lib.baseboard_fab2(sch_1):m_h_dq(56)"
				( attribute "CDS_PHYS_NET_NAME" "M_H_DQ<56>"
					( Origin gPackager )
				)
				( attribute "PNN" "M_H_DQ<56>"
					( Origin gPackager )
				)
				( objectStatus "M_H_DQ<56>" )
			)
			( signal "@baseboard_fab2_lib.baseboard_fab2(sch_1):m_h_dq(57)"
				( attribute "CDS_PHYS_NET_NAME" "M_H_DQ<57>"
					( Origin gPackager )
				)
				( attribute "PNN" "M_H_DQ<57>"
					( Origin gPackager )
				)
				( objectStatus "M_H_DQ<57>" )
			)
			( signal "@baseboard_fab2_lib.baseboard_fab2(sch_1):m_h_dq(58)"
				( attribute "CDS_PHYS_NET_NAME" "M_H_DQ<58>"
					( Origin gPackager )
				)
				( attribute "PNN" "M_H_DQ<58>"
					( Origin gPackager )
				)
				( objectStatus "M_H_DQ<58>" )
			)
			( signal "@baseboard_fab2_lib.baseboard_fab2(sch_1):m_h_dq(59)"
				( attribute "CDS_PHYS_NET_NAME" "M_H_DQ<59>"
					( Origin gPackager )
				)
				( attribute "PNN" "M_H_DQ<59>"
					( Origin gPackager )
				)
				( objectStatus "M_H_DQ<59>" )
			)
			( signal "@baseboard_fab2_lib.baseboard_fab2(sch_1):m_h_dq(60)"
				( attribute "CDS_PHYS_NET_NAME" "M_H_DQ<60>"
					( Origin gPackager )
				)
				( attribute "PNN" "M_H_DQ<60>"
					( Origin gPackager )
				)
				( objectStatus "M_H_DQ<60>" )
			)
			( signal "@baseboard_fab2_lib.baseboard_fab2(sch_1):m_h_dq(61)"
				( attribute "CDS_PHYS_NET_NAME" "M_H_DQ<61>"
					( Origin gPackager )
				)
				( attribute "PNN" "M_H_DQ<61>"
					( Origin gPackager )
				)
				( objectStatus "M_H_DQ<61>" )
			)
			( signal "@baseboard_fab2_lib.baseboard_fab2(sch_1):m_h_dq(62)"
				( attribute "CDS_PHYS_NET_NAME" "M_H_DQ<62>"
					( Origin gPackager )
				)
				( attribute "PNN" "M_H_DQ<62>"
					( Origin gPackager )
				)
				( objectStatus "M_H_DQ<62>" )
			)
			( signal "@baseboard_fab2_lib.baseboard_fab2(sch_1):m_h_dq(63)"
				( attribute "CDS_PHYS_NET_NAME" "M_H_DQ<63>"
					( Origin gPackager )
				)
				( attribute "PNN" "M_H_DQ<63>"
					( Origin gPackager )
				)
				( objectStatus "M_H_DQ<63>" )
			)
			( signal "@baseboard_fab2_lib.baseboard_fab2(sch_1):m_h_dqs_dn(0)"
				( attribute "CDS_PHYS_NET_NAME" "M_H_DQS_DN<0>"
					( Origin gPackager )
				)
				( attribute "PNN" "M_H_DQS_DN<0>"
					( Origin gPackager )
				)
				( objectStatus "M_H_DQS_DN<0>" )
			)
			( signal "@baseboard_fab2_lib.baseboard_fab2(sch_1):m_h_dqs_dn(1)"
				( attribute "CDS_PHYS_NET_NAME" "M_H_DQS_DN<1>"
					( Origin gPackager )
				)
				( attribute "PNN" "M_H_DQS_DN<1>"
					( Origin gPackager )
				)
				( objectStatus "M_H_DQS_DN<1>" )
			)
			( signal "@baseboard_fab2_lib.baseboard_fab2(sch_1):m_h_dqs_dn(2)"
				( attribute "CDS_PHYS_NET_NAME" "M_H_DQS_DN<2>"
					( Origin gPackager )
				)
				( attribute "PNN" "M_H_DQS_DN<2>"
					( Origin gPackager )
				)
				( objectStatus "M_H_DQS_DN<2>" )
			)
			( signal "@baseboard_fab2_lib.baseboard_fab2(sch_1):m_h_dqs_dn(3)"
				( attribute "CDS_PHYS_NET_NAME" "M_H_DQS_DN<3>"
					( Origin gPackager )
				)
				( attribute "PNN" "M_H_DQS_DN<3>"
					( Origin gPackager )
				)
				( objectStatus "M_H_DQS_DN<3>" )
			)
			( signal "@baseboard_fab2_lib.baseboard_fab2(sch_1):m_h_dqs_dn(4)"
				( attribute "CDS_PHYS_NET_NAME" "M_H_DQS_DN<4>"
					( Origin gPackager )
				)
				( attribute "PNN" "M_H_DQS_DN<4>"
					( Origin gPackager )
				)
				( objectStatus "M_H_DQS_DN<4>" )
			)
			( signal "@baseboard_fab2_lib.baseboard_fab2(sch_1):m_h_dqs_dn(5)"
				( attribute "CDS_PHYS_NET_NAME" "M_H_DQS_DN<5>"
					( Origin gPackager )
				)
				( attribute "PNN" "M_H_DQS_DN<5>"
					( Origin gPackager )
				)
				( objectStatus "M_H_DQS_DN<5>" )
			)
			( signal "@baseboard_fab2_lib.baseboard_fab2(sch_1):m_h_dqs_dn(6)"
				( attribute "CDS_PHYS_NET_NAME" "M_H_DQS_DN<6>"
					( Origin gPackager )
				)
				( attribute "PNN" "M_H_DQS_DN<6>"
					( Origin gPackager )
				)
				( objectStatus "M_H_DQS_DN<6>" )
			)
			( signal "@baseboard_fab2_lib.baseboard_fab2(sch_1):m_h_dqs_dn(7)"
				( attribute "CDS_PHYS_NET_NAME" "M_H_DQS_DN<7>"
					( Origin gPackager )
				)
				( attribute "PNN" "M_H_DQS_DN<7>"
					( Origin gPackager )
				)
				( objectStatus "M_H_DQS_DN<7>" )
			)
			( signal "@baseboard_fab2_lib.baseboard_fab2(sch_1):m_h_dqs_dn(8)"
				( attribute "CDS_PHYS_NET_NAME" "M_H_DQS_DN<8>"
					( Origin gPackager )
				)
				( attribute "PNN" "M_H_DQS_DN<8>"
					( Origin gPackager )
				)
				( objectStatus "M_H_DQS_DN<8>" )
			)
			( signal "@baseboard_fab2_lib.baseboard_fab2(sch_1):m_h_dqs_dn(9)"
				( attribute "CDS_PHYS_NET_NAME" "M_H_DQS_DN<9>"
					( Origin gPackager )
				)
				( attribute "PNN" "M_H_DQS_DN<9>"
					( Origin gPackager )
				)
				( objectStatus "M_H_DQS_DN<9>" )
			)
			( signal "@baseboard_fab2_lib.baseboard_fab2(sch_1):m_h_dqs_dn(10)"
				( attribute "CDS_PHYS_NET_NAME" "M_H_DQS_DN<10>"
					( Origin gPackager )
				)
				( attribute "PNN" "M_H_DQS_DN<10>"
					( Origin gPackager )
				)
				( objectStatus "M_H_DQS_DN<10>" )
			)
			( signal "@baseboard_fab2_lib.baseboard_fab2(sch_1):m_h_dqs_dn(11)"
				( attribute "CDS_PHYS_NET_NAME" "M_H_DQS_DN<11>"
					( Origin gPackager )
				)
				( attribute "PNN" "M_H_DQS_DN<11>"
					( Origin gPackager )
				)
				( objectStatus "M_H_DQS_DN<11>" )
			)
			( signal "@baseboard_fab2_lib.baseboard_fab2(sch_1):m_h_dqs_dn(12)"
				( attribute "CDS_PHYS_NET_NAME" "M_H_DQS_DN<12>"
					( Origin gPackager )
				)
				( attribute "PNN" "M_H_DQS_DN<12>"
					( Origin gPackager )
				)
				( objectStatus "M_H_DQS_DN<12>" )
			)
			( signal "@baseboard_fab2_lib.baseboard_fab2(sch_1):m_h_dqs_dn(13)"
				( attribute "CDS_PHYS_NET_NAME" "M_H_DQS_DN<13>"
					( Origin gPackager )
				)
				( attribute "PNN" "M_H_DQS_DN<13>"
					( Origin gPackager )
				)
				( objectStatus "M_H_DQS_DN<13>" )
			)
			( signal "@baseboard_fab2_lib.baseboard_fab2(sch_1):m_h_dqs_dn(14)"
				( attribute "CDS_PHYS_NET_NAME" "M_H_DQS_DN<14>"
					( Origin gPackager )
				)
				( attribute "PNN" "M_H_DQS_DN<14>"
					( Origin gPackager )
				)
				( objectStatus "M_H_DQS_DN<14>" )
			)
			( signal "@baseboard_fab2_lib.baseboard_fab2(sch_1):m_h_dqs_dn(15)"
				( attribute "CDS_PHYS_NET_NAME" "M_H_DQS_DN<15>"
					( Origin gPackager )
				)
				( attribute "PNN" "M_H_DQS_DN<15>"
					( Origin gPackager )
				)
				( objectStatus "M_H_DQS_DN<15>" )
			)
			( signal "@baseboard_fab2_lib.baseboard_fab2(sch_1):m_h_dqs_dn(16)"
				( attribute "CDS_PHYS_NET_NAME" "M_H_DQS_DN<16>"
					( Origin gPackager )
				)
				( attribute "PNN" "M_H_DQS_DN<16>"
					( Origin gPackager )
				)
				( objectStatus "M_H_DQS_DN<16>" )
			)
			( signal "@baseboard_fab2_lib.baseboard_fab2(sch_1):m_h_dqs_dn(17)"
				( attribute "CDS_PHYS_NET_NAME" "M_H_DQS_DN<17>"
					( Origin gPackager )
				)
				( attribute "PNN" "M_H_DQS_DN<17>"
					( Origin gPackager )
				)
				( objectStatus "M_H_DQS_DN<17>" )
			)
			( signal "@baseboard_fab2_lib.baseboard_fab2(sch_1):m_h_dqs_dp(0)"
				( attribute "CDS_PHYS_NET_NAME" "M_H_DQS_DP<0>"
					( Origin gPackager )
				)
				( attribute "PNN" "M_H_DQS_DP<0>"
					( Origin gPackager )
				)
				( objectStatus "M_H_DQS_DP<0>" )
			)
			( signal "@baseboard_fab2_lib.baseboard_fab2(sch_1):m_h_dqs_dp(1)"
				( attribute "CDS_PHYS_NET_NAME" "M_H_DQS_DP<1>"
					( Origin gPackager )
				)
				( attribute "PNN" "M_H_DQS_DP<1>"
					( Origin gPackager )
				)
				( objectStatus "M_H_DQS_DP<1>" )
			)
			( signal "@baseboard_fab2_lib.baseboard_fab2(sch_1):m_h_dqs_dp(2)"
				( attribute "CDS_PHYS_NET_NAME" "M_H_DQS_DP<2>"
					( Origin gPackager )
				)
				( attribute "PNN" "M_H_DQS_DP<2>"
					( Origin gPackager )
				)
				( objectStatus "M_H_DQS_DP<2>" )
			)
			( signal "@baseboard_fab2_lib.baseboard_fab2(sch_1):m_h_dqs_dp(3)"
				( attribute "CDS_PHYS_NET_NAME" "M_H_DQS_DP<3>"
					( Origin gPackager )
				)
				( attribute "PNN" "M_H_DQS_DP<3>"
					( Origin gPackager )
				)
				( objectStatus "M_H_DQS_DP<3>" )
			)
			( signal "@baseboard_fab2_lib.baseboard_fab2(sch_1):m_h_dqs_dp(4)"
				( attribute "CDS_PHYS_NET_NAME" "M_H_DQS_DP<4>"
					( Origin gPackager )
				)
				( attribute "PNN" "M_H_DQS_DP<4>"
					( Origin gPackager )
				)
				( objectStatus "M_H_DQS_DP<4>" )
			)
			( signal "@baseboard_fab2_lib.baseboard_fab2(sch_1):m_h_dqs_dp(5)"
				( attribute "CDS_PHYS_NET_NAME" "M_H_DQS_DP<5>"
					( Origin gPackager )
				)
				( attribute "PNN" "M_H_DQS_DP<5>"
					( Origin gPackager )
				)
				( objectStatus "M_H_DQS_DP<5>" )
			)
			( signal "@baseboard_fab2_lib.baseboard_fab2(sch_1):m_h_dqs_dp(6)"
				( attribute "CDS_PHYS_NET_NAME" "M_H_DQS_DP<6>"
					( Origin gPackager )
				)
				( attribute "PNN" "M_H_DQS_DP<6>"
					( Origin gPackager )
				)
				( objectStatus "M_H_DQS_DP<6>" )
			)
			( signal "@baseboard_fab2_lib.baseboard_fab2(sch_1):m_h_dqs_dp(7)"
				( attribute "CDS_PHYS_NET_NAME" "M_H_DQS_DP<7>"
					( Origin gPackager )
				)
				( attribute "PNN" "M_H_DQS_DP<7>"
					( Origin gPackager )
				)
				( objectStatus "M_H_DQS_DP<7>" )
			)
			( signal "@baseboard_fab2_lib.baseboard_fab2(sch_1):m_h_dqs_dp(8)"
				( attribute "CDS_PHYS_NET_NAME" "M_H_DQS_DP<8>"
					( Origin gPackager )
				)
				( attribute "PNN" "M_H_DQS_DP<8>"
					( Origin gPackager )
				)
				( objectStatus "M_H_DQS_DP<8>" )
			)
			( signal "@baseboard_fab2_lib.baseboard_fab2(sch_1):m_h_dqs_dp(9)"
				( attribute "CDS_PHYS_NET_NAME" "M_H_DQS_DP<9>"
					( Origin gPackager )
				)
				( attribute "PNN" "M_H_DQS_DP<9>"
					( Origin gPackager )
				)
				( objectStatus "M_H_DQS_DP<9>" )
			)
			( signal "@baseboard_fab2_lib.baseboard_fab2(sch_1):m_h_dqs_dp(10)"
				( attribute "CDS_PHYS_NET_NAME" "M_H_DQS_DP<10>"
					( Origin gPackager )
				)
				( attribute "PNN" "M_H_DQS_DP<10>"
					( Origin gPackager )
				)
				( objectStatus "M_H_DQS_DP<10>" )
			)
			( signal "@baseboard_fab2_lib.baseboard_fab2(sch_1):m_h_dqs_dp(11)"
				( attribute "CDS_PHYS_NET_NAME" "M_H_DQS_DP<11>"
					( Origin gPackager )
				)
				( attribute "PNN" "M_H_DQS_DP<11>"
					( Origin gPackager )
				)
				( objectStatus "M_H_DQS_DP<11>" )
			)
			( signal "@baseboard_fab2_lib.baseboard_fab2(sch_1):m_h_dqs_dp(12)"
				( attribute "CDS_PHYS_NET_NAME" "M_H_DQS_DP<12>"
					( Origin gPackager )
				)
				( attribute "PNN" "M_H_DQS_DP<12>"
					( Origin gPackager )
				)
				( objectStatus "M_H_DQS_DP<12>" )
			)
			( signal "@baseboard_fab2_lib.baseboard_fab2(sch_1):m_h_dqs_dp(13)"
				( attribute "CDS_PHYS_NET_NAME" "M_H_DQS_DP<13>"
					( Origin gPackager )
				)
				( attribute "PNN" "M_H_DQS_DP<13>"
					( Origin gPackager )
				)
				( objectStatus "M_H_DQS_DP<13>" )
			)
			( signal "@baseboard_fab2_lib.baseboard_fab2(sch_1):m_h_dqs_dp(14)"
				( attribute "CDS_PHYS_NET_NAME" "M_H_DQS_DP<14>"
					( Origin gPackager )
				)
				( attribute "PNN" "M_H_DQS_DP<14>"
					( Origin gPackager )
				)
				( objectStatus "M_H_DQS_DP<14>" )
			)
			( signal "@baseboard_fab2_lib.baseboard_fab2(sch_1):m_h_dqs_dp(15)"
				( attribute "CDS_PHYS_NET_NAME" "M_H_DQS_DP<15>"
					( Origin gPackager )
				)
				( attribute "PNN" "M_H_DQS_DP<15>"
					( Origin gPackager )
				)
				( objectStatus "M_H_DQS_DP<15>" )
			)
			( signal "@baseboard_fab2_lib.baseboard_fab2(sch_1):m_h_dqs_dp(16)"
				( attribute "CDS_PHYS_NET_NAME" "M_H_DQS_DP<16>"
					( Origin gPackager )
				)
				( attribute "PNN" "M_H_DQS_DP<16>"
					( Origin gPackager )
				)
				( objectStatus "M_H_DQS_DP<16>" )
			)
			( signal "@baseboard_fab2_lib.baseboard_fab2(sch_1):m_h_dqs_dp(17)"
				( attribute "CDS_PHYS_NET_NAME" "M_H_DQS_DP<17>"
					( Origin gPackager )
				)
				( attribute "PNN" "M_H_DQS_DP<17>"
					( Origin gPackager )
				)
				( objectStatus "M_H_DQS_DP<17>" )
			)
			( signal "@baseboard_fab2_lib.baseboard_fab2(sch_1):m_h_ecc(0)"
				( attribute "CDS_PHYS_NET_NAME" "M_H_ECC<0>"
					( Origin gPackager )
				)
				( attribute "PNN" "M_H_ECC<0>"
					( Origin gPackager )
				)
				( objectStatus "M_H_ECC<0>" )
			)
			( signal "@baseboard_fab2_lib.baseboard_fab2(sch_1):m_h_ecc(1)"
				( attribute "CDS_PHYS_NET_NAME" "M_H_ECC<1>"
					( Origin gPackager )
				)
				( attribute "PNN" "M_H_ECC<1>"
					( Origin gPackager )
				)
				( objectStatus "M_H_ECC<1>" )
			)
			( signal "@baseboard_fab2_lib.baseboard_fab2(sch_1):m_h_ecc(2)"
				( attribute "CDS_PHYS_NET_NAME" "M_H_ECC<2>"
					( Origin gPackager )
				)
				( attribute "PNN" "M_H_ECC<2>"
					( Origin gPackager )
				)
				( objectStatus "M_H_ECC<2>" )
			)
			( signal "@baseboard_fab2_lib.baseboard_fab2(sch_1):m_h_ecc(3)"
				( attribute "CDS_PHYS_NET_NAME" "M_H_ECC<3>"
					( Origin gPackager )
				)
				( attribute "PNN" "M_H_ECC<3>"
					( Origin gPackager )
				)
				( objectStatus "M_H_ECC<3>" )
			)
			( signal "@baseboard_fab2_lib.baseboard_fab2(sch_1):m_h_ecc(4)"
				( attribute "CDS_PHYS_NET_NAME" "M_H_ECC<4>"
					( Origin gPackager )
				)
				( attribute "PNN" "M_H_ECC<4>"
					( Origin gPackager )
				)
				( objectStatus "M_H_ECC<4>" )
			)
			( signal "@baseboard_fab2_lib.baseboard_fab2(sch_1):m_h_ecc(5)"
				( attribute "CDS_PHYS_NET_NAME" "M_H_ECC<5>"
					( Origin gPackager )
				)
				( attribute "PNN" "M_H_ECC<5>"
					( Origin gPackager )
				)
				( objectStatus "M_H_ECC<5>" )
			)
			( signal "@baseboard_fab2_lib.baseboard_fab2(sch_1):m_h_ecc(6)"
				( attribute "CDS_PHYS_NET_NAME" "M_H_ECC<6>"
					( Origin gPackager )
				)
				( attribute "PNN" "M_H_ECC<6>"
					( Origin gPackager )
				)
				( objectStatus "M_H_ECC<6>" )
			)
			( signal "@baseboard_fab2_lib.baseboard_fab2(sch_1):m_h_ecc(7)"
				( attribute "CDS_PHYS_NET_NAME" "M_H_ECC<7>"
					( Origin gPackager )
				)
				( attribute "PNN" "M_H_ECC<7>"
					( Origin gPackager )
				)
				( objectStatus "M_H_ECC<7>" )
			)
			( signal "@baseboard_fab2_lib.baseboard_fab2(sch_1):m_h_ma(0)"
				( attribute "CDS_PHYS_NET_NAME" "M_H_MA<0>"
					( Origin gPackager )
				)
				( attribute "PNN" "M_H_MA<0>"
					( Origin gPackager )
				)
				( objectStatus "M_H_MA<0>" )
			)
			( signal "@baseboard_fab2_lib.baseboard_fab2(sch_1):m_h_ma(1)"
				( attribute "CDS_PHYS_NET_NAME" "M_H_MA<1>"
					( Origin gPackager )
				)
				( attribute "PNN" "M_H_MA<1>"
					( Origin gPackager )
				)
				( objectStatus "M_H_MA<1>" )
			)
			( signal "@baseboard_fab2_lib.baseboard_fab2(sch_1):m_h_ma(2)"
				( attribute "CDS_PHYS_NET_NAME" "M_H_MA<2>"
					( Origin gPackager )
				)
				( attribute "PNN" "M_H_MA<2>"
					( Origin gPackager )
				)
				( objectStatus "M_H_MA<2>" )
			)
			( signal "@baseboard_fab2_lib.baseboard_fab2(sch_1):m_h_ma(3)"
				( attribute "CDS_PHYS_NET_NAME" "M_H_MA<3>"
					( Origin gPackager )
				)
				( attribute "PNN" "M_H_MA<3>"
					( Origin gPackager )
				)
				( objectStatus "M_H_MA<3>" )
			)
			( signal "@baseboard_fab2_lib.baseboard_fab2(sch_1):m_h_ma(4)"
				( attribute "CDS_PHYS_NET_NAME" "M_H_MA<4>"
					( Origin gPackager )
				)
				( attribute "PNN" "M_H_MA<4>"
					( Origin gPackager )
				)
				( objectStatus "M_H_MA<4>" )
			)
			( signal "@baseboard_fab2_lib.baseboard_fab2(sch_1):m_h_ma(5)"
				( attribute "CDS_PHYS_NET_NAME" "M_H_MA<5>"
					( Origin gPackager )
				)
				( attribute "PNN" "M_H_MA<5>"
					( Origin gPackager )
				)
				( objectStatus "M_H_MA<5>" )
			)
			( signal "@baseboard_fab2_lib.baseboard_fab2(sch_1):m_h_ma(6)"
				( attribute "CDS_PHYS_NET_NAME" "M_H_MA<6>"
					( Origin gPackager )
				)
				( attribute "PNN" "M_H_MA<6>"
					( Origin gPackager )
				)
				( objectStatus "M_H_MA<6>" )
			)
			( signal "@baseboard_fab2_lib.baseboard_fab2(sch_1):m_h_ma(7)"
				( attribute "CDS_PHYS_NET_NAME" "M_H_MA<7>"
					( Origin gPackager )
				)
				( attribute "PNN" "M_H_MA<7>"
					( Origin gPackager )
				)
				( objectStatus "M_H_MA<7>" )
			)
			( signal "@baseboard_fab2_lib.baseboard_fab2(sch_1):m_h_ma(8)"
				( attribute "CDS_PHYS_NET_NAME" "M_H_MA<8>"
					( Origin gPackager )
				)
				( attribute "PNN" "M_H_MA<8>"
					( Origin gPackager )
				)
				( objectStatus "M_H_MA<8>" )
			)
			( signal "@baseboard_fab2_lib.baseboard_fab2(sch_1):m_h_ma(9)"
				( attribute "CDS_PHYS_NET_NAME" "M_H_MA<9>"
					( Origin gPackager )
				)
				( attribute "PNN" "M_H_MA<9>"
					( Origin gPackager )
				)
				( objectStatus "M_H_MA<9>" )
			)
			( signal "@baseboard_fab2_lib.baseboard_fab2(sch_1):m_h_ma(10)"
				( attribute "CDS_PHYS_NET_NAME" "M_H_MA<10>"
					( Origin gPackager )
				)
				( attribute "PNN" "M_H_MA<10>"
					( Origin gPackager )
				)
				( objectStatus "M_H_MA<10>" )
			)
			( signal "@baseboard_fab2_lib.baseboard_fab2(sch_1):m_h_ma(11)"
				( attribute "CDS_PHYS_NET_NAME" "M_H_MA<11>"
					( Origin gPackager )
				)
				( attribute "PNN" "M_H_MA<11>"
					( Origin gPackager )
				)
				( objectStatus "M_H_MA<11>" )
			)
			( signal "@baseboard_fab2_lib.baseboard_fab2(sch_1):m_h_ma(12)"
				( attribute "CDS_PHYS_NET_NAME" "M_H_MA<12>"
					( Origin gPackager )
				)
				( attribute "PNN" "M_H_MA<12>"
					( Origin gPackager )
				)
				( objectStatus "M_H_MA<12>" )
			)
			( signal "@baseboard_fab2_lib.baseboard_fab2(sch_1):m_h_ma(13)"
				( attribute "CDS_PHYS_NET_NAME" "M_H_MA<13>"
					( Origin gPackager )
				)
				( attribute "PNN" "M_H_MA<13>"
					( Origin gPackager )
				)
				( objectStatus "M_H_MA<13>" )
			)
			( signal "@baseboard_fab2_lib.baseboard_fab2(sch_1):m_h_ma(14)"
				( attribute "CDS_PHYS_NET_NAME" "M_H_MA<14>"
					( Origin gPackager )
				)
				( attribute "PNN" "M_H_MA<14>"
					( Origin gPackager )
				)
				( objectStatus "M_H_MA<14>" )
			)
			( signal "@baseboard_fab2_lib.baseboard_fab2(sch_1):m_h_ma(15)"
				( attribute "CDS_PHYS_NET_NAME" "M_H_MA<15>"
					( Origin gPackager )
				)
				( attribute "PNN" "M_H_MA<15>"
					( Origin gPackager )
				)
				( objectStatus "M_H_MA<15>" )
			)
			( signal "@baseboard_fab2_lib.baseboard_fab2(sch_1):m_h_ma(16)"
				( attribute "CDS_PHYS_NET_NAME" "M_H_MA<16>"
					( Origin gPackager )
				)
				( attribute "PNN" "M_H_MA<16>"
					( Origin gPackager )
				)
				( objectStatus "M_H_MA<16>" )
			)
			( signal "@baseboard_fab2_lib.baseboard_fab2(sch_1):m_h_ma(17)"
				( attribute "CDS_PHYS_NET_NAME" "M_H_MA<17>"
					( Origin gPackager )
				)
				( attribute "PNN" "M_H_MA<17>"
					( Origin gPackager )
				)
				( objectStatus "M_H_MA<17>" )
			)
			( signal "@baseboard_fab2_lib.baseboard_fab2(sch_1):m_h_odt(0)"
				( attribute "CDS_PHYS_NET_NAME" "M_H_ODT<0>"
					( Origin gPackager )
				)
				( attribute "PNN" "M_H_ODT<0>"
					( Origin gPackager )
				)
				( objectStatus "M_H_ODT<0>" )
			)
			( signal "@baseboard_fab2_lib.baseboard_fab2(sch_1):m_h_odt(1)"
				( attribute "CDS_PHYS_NET_NAME" "M_H_ODT<1>"
					( Origin gPackager )
				)
				( attribute "PNN" "M_H_ODT<1>"
					( Origin gPackager )
				)
				( objectStatus "M_H_ODT<1>" )
			)
			( signal "@baseboard_fab2_lib.baseboard_fab2(sch_1):m_h_odt(2)"
				( attribute "CDS_PHYS_NET_NAME" "M_H_ODT<2>"
					( Origin gPackager )
				)
				( attribute "PNN" "M_H_ODT<2>"
					( Origin gPackager )
				)
				( objectStatus "M_H_ODT<2>" )
			)
			( signal "@baseboard_fab2_lib.baseboard_fab2(sch_1):m_h_odt(3)"
				( attribute "CDS_PHYS_NET_NAME" "M_H_ODT<3>"
					( Origin gPackager )
				)
				( attribute "PNN" "M_H_ODT<3>"
					( Origin gPackager )
				)
				( objectStatus "M_H_ODT<3>" )
			)
			( signal "@baseboard_fab2_lib.baseboard_fab2(sch_1):m_h_par"
				( attribute "CDS_PHYS_NET_NAME" "M_H_PAR"
					( Origin gPackager )
				)
				( objectStatus "M_H_PAR" )
			)
			( signal "@baseboard_fab2_lib.baseboard_fab2(sch_1):m_j_act_n"
				( attribute "CDS_PHYS_NET_NAME" "M_J_ACT_N"
					( Origin gPackager )
				)
				( objectStatus "M_J_ACT_N" )
			)
			( signal "@baseboard_fab2_lib.baseboard_fab2(sch_1):m_j_alert_n"
				( attribute "CDS_PHYS_NET_NAME" "M_J_ALERT_N"
					( Origin gPackager )
				)
				( objectStatus "M_J_ALERT_N" )
			)
			( signal "@baseboard_fab2_lib.baseboard_fab2(sch_1):m_j_ba(0)"
				( attribute "CDS_PHYS_NET_NAME" "M_J_BA<0>"
					( Origin gPackager )
				)
				( attribute "PNN" "M_J_BA<0>"
					( Origin gPackager )
				)
				( objectStatus "M_J_BA<0>" )
			)
			( signal "@baseboard_fab2_lib.baseboard_fab2(sch_1):m_j_ba(1)"
				( attribute "CDS_PHYS_NET_NAME" "M_J_BA<1>"
					( Origin gPackager )
				)
				( attribute "PNN" "M_J_BA<1>"
					( Origin gPackager )
				)
				( objectStatus "M_J_BA<1>" )
			)
			( signal "@baseboard_fab2_lib.baseboard_fab2(sch_1):m_j_bg(0)"
				( attribute "CDS_PHYS_NET_NAME" "M_J_BG<0>"
					( Origin gPackager )
				)
				( attribute "PNN" "M_J_BG<0>"
					( Origin gPackager )
				)
				( objectStatus "M_J_BG<0>" )
			)
			( signal "@baseboard_fab2_lib.baseboard_fab2(sch_1):m_j_bg(1)"
				( attribute "CDS_PHYS_NET_NAME" "M_J_BG<1>"
					( Origin gPackager )
				)
				( attribute "PNN" "M_J_BG<1>"
					( Origin gPackager )
				)
				( objectStatus "M_J_BG<1>" )
			)
			( signal "@baseboard_fab2_lib.baseboard_fab2(sch_1):m_j_c(2)"
				( attribute "CDS_PHYS_NET_NAME" "M_J_C<2>"
					( Origin gPackager )
				)
				( attribute "PNN" "M_J_C<2>"
					( Origin gPackager )
				)
				( objectStatus "M_J_C<2>" )
			)
			( signal "@baseboard_fab2_lib.baseboard_fab2(sch_1):m_j_cke(0)"
				( attribute "CDS_PHYS_NET_NAME" "M_J_CKE<0>"
					( Origin gPackager )
				)
				( attribute "PNN" "M_J_CKE<0>"
					( Origin gPackager )
				)
				( objectStatus "M_J_CKE<0>" )
			)
			( signal "@baseboard_fab2_lib.baseboard_fab2(sch_1):m_j_cke(1)"
				( attribute "CDS_PHYS_NET_NAME" "M_J_CKE<1>"
					( Origin gPackager )
				)
				( attribute "PNN" "M_J_CKE<1>"
					( Origin gPackager )
				)
				( objectStatus "M_J_CKE<1>" )
			)
			( signal "@baseboard_fab2_lib.baseboard_fab2(sch_1):m_j_cke(2)"
				( attribute "CDS_PHYS_NET_NAME" "M_J_CKE<2>"
					( Origin gPackager )
				)
				( attribute "PNN" "M_J_CKE<2>"
					( Origin gPackager )
				)
				( objectStatus "M_J_CKE<2>" )
			)
			( signal "@baseboard_fab2_lib.baseboard_fab2(sch_1):m_j_cke(3)"
				( attribute "CDS_PHYS_NET_NAME" "M_J_CKE<3>"
					( Origin gPackager )
				)
				( attribute "PNN" "M_J_CKE<3>"
					( Origin gPackager )
				)
				( objectStatus "M_J_CKE<3>" )
			)
			( signal "@baseboard_fab2_lib.baseboard_fab2(sch_1):m_j_clk_dn(0)"
				( attribute "CDS_PHYS_NET_NAME" "M_J_CLK_DN<0>"
					( Origin gPackager )
				)
				( attribute "PNN" "M_J_CLK_DN<0>"
					( Origin gPackager )
				)
				( objectStatus "M_J_CLK_DN<0>" )
			)
			( signal "@baseboard_fab2_lib.baseboard_fab2(sch_1):m_j_clk_dn(1)"
				( attribute "CDS_PHYS_NET_NAME" "M_J_CLK_DN<1>"
					( Origin gPackager )
				)
				( attribute "PNN" "M_J_CLK_DN<1>"
					( Origin gPackager )
				)
				( objectStatus "M_J_CLK_DN<1>" )
			)
			( signal "@baseboard_fab2_lib.baseboard_fab2(sch_1):m_j_clk_dn(2)"
				( attribute "CDS_PHYS_NET_NAME" "M_J_CLK_DN<2>"
					( Origin gPackager )
				)
				( attribute "PNN" "M_J_CLK_DN<2>"
					( Origin gPackager )
				)
				( objectStatus "M_J_CLK_DN<2>" )
			)
			( signal "@baseboard_fab2_lib.baseboard_fab2(sch_1):m_j_clk_dn(3)"
				( attribute "CDS_PHYS_NET_NAME" "M_J_CLK_DN<3>"
					( Origin gPackager )
				)
				( attribute "PNN" "M_J_CLK_DN<3>"
					( Origin gPackager )
				)
				( objectStatus "M_J_CLK_DN<3>" )
			)
			( signal "@baseboard_fab2_lib.baseboard_fab2(sch_1):m_j_clk_dp(0)"
				( attribute "CDS_PHYS_NET_NAME" "M_J_CLK_DP<0>"
					( Origin gPackager )
				)
				( attribute "PNN" "M_J_CLK_DP<0>"
					( Origin gPackager )
				)
				( objectStatus "M_J_CLK_DP<0>" )
			)
			( signal "@baseboard_fab2_lib.baseboard_fab2(sch_1):m_j_clk_dp(1)"
				( attribute "CDS_PHYS_NET_NAME" "M_J_CLK_DP<1>"
					( Origin gPackager )
				)
				( attribute "PNN" "M_J_CLK_DP<1>"
					( Origin gPackager )
				)
				( objectStatus "M_J_CLK_DP<1>" )
			)
			( signal "@baseboard_fab2_lib.baseboard_fab2(sch_1):m_j_clk_dp(2)"
				( attribute "CDS_PHYS_NET_NAME" "M_J_CLK_DP<2>"
					( Origin gPackager )
				)
				( attribute "PNN" "M_J_CLK_DP<2>"
					( Origin gPackager )
				)
				( objectStatus "M_J_CLK_DP<2>" )
			)
			( signal "@baseboard_fab2_lib.baseboard_fab2(sch_1):m_j_clk_dp(3)"
				( attribute "CDS_PHYS_NET_NAME" "M_J_CLK_DP<3>"
					( Origin gPackager )
				)
				( attribute "PNN" "M_J_CLK_DP<3>"
					( Origin gPackager )
				)
				( objectStatus "M_J_CLK_DP<3>" )
			)
			( signal "@baseboard_fab2_lib.baseboard_fab2(sch_1):m_j_cs_n(0)"
				( attribute "CDS_PHYS_NET_NAME" "M_J_CS_N<0>"
					( Origin gPackager )
				)
				( attribute "PNN" "M_J_CS_N<0>"
					( Origin gPackager )
				)
				( objectStatus "M_J_CS_N<0>" )
			)
			( signal "@baseboard_fab2_lib.baseboard_fab2(sch_1):m_j_cs_n(1)"
				( attribute "CDS_PHYS_NET_NAME" "M_J_CS_N<1>"
					( Origin gPackager )
				)
				( attribute "PNN" "M_J_CS_N<1>"
					( Origin gPackager )
				)
				( objectStatus "M_J_CS_N<1>" )
			)
			( signal "@baseboard_fab2_lib.baseboard_fab2(sch_1):m_j_cs_n(2)"
				( attribute "CDS_PHYS_NET_NAME" "M_J_CS_N<2>"
					( Origin gPackager )
				)
				( attribute "PNN" "M_J_CS_N<2>"
					( Origin gPackager )
				)
				( objectStatus "M_J_CS_N<2>" )
			)
			( signal "@baseboard_fab2_lib.baseboard_fab2(sch_1):m_j_cs_n(3)"
				( attribute "CDS_PHYS_NET_NAME" "M_J_CS_N<3>"
					( Origin gPackager )
				)
				( attribute "PNN" "M_J_CS_N<3>"
					( Origin gPackager )
				)
				( objectStatus "M_J_CS_N<3>" )
			)
			( signal "@baseboard_fab2_lib.baseboard_fab2(sch_1):m_j_cs_n(4)"
				( attribute "CDS_PHYS_NET_NAME" "M_J_CS_N<4>"
					( Origin gPackager )
				)
				( attribute "PNN" "M_J_CS_N<4>"
					( Origin gPackager )
				)
				( objectStatus "M_J_CS_N<4>" )
			)
			( signal "@baseboard_fab2_lib.baseboard_fab2(sch_1):m_j_cs_n(5)"
				( attribute "CDS_PHYS_NET_NAME" "M_J_CS_N<5>"
					( Origin gPackager )
				)
				( attribute "PNN" "M_J_CS_N<5>"
					( Origin gPackager )
				)
				( objectStatus "M_J_CS_N<5>" )
			)
			( signal "@baseboard_fab2_lib.baseboard_fab2(sch_1):m_j_cs_n(6)"
				( attribute "CDS_PHYS_NET_NAME" "M_J_CS_N<6>"
					( Origin gPackager )
				)
				( attribute "PNN" "M_J_CS_N<6>"
					( Origin gPackager )
				)
				( objectStatus "M_J_CS_N<6>" )
			)
			( signal "@baseboard_fab2_lib.baseboard_fab2(sch_1):m_j_cs_n(7)"
				( attribute "CDS_PHYS_NET_NAME" "M_J_CS_N<7>"
					( Origin gPackager )
				)
				( attribute "PNN" "M_J_CS_N<7>"
					( Origin gPackager )
				)
				( objectStatus "M_J_CS_N<7>" )
			)
			( signal "@baseboard_fab2_lib.baseboard_fab2(sch_1):m_j_dq(0)"
				( attribute "CDS_PHYS_NET_NAME" "M_J_DQ<0>"
					( Origin gPackager )
				)
				( attribute "PNN" "M_J_DQ<0>"
					( Origin gPackager )
				)
				( objectStatus "M_J_DQ<0>" )
			)
			( signal "@baseboard_fab2_lib.baseboard_fab2(sch_1):m_j_dq(1)"
				( attribute "CDS_PHYS_NET_NAME" "M_J_DQ<1>"
					( Origin gPackager )
				)
				( attribute "PNN" "M_J_DQ<1>"
					( Origin gPackager )
				)
				( objectStatus "M_J_DQ<1>" )
			)
			( signal "@baseboard_fab2_lib.baseboard_fab2(sch_1):m_j_dq(2)"
				( attribute "CDS_PHYS_NET_NAME" "M_J_DQ<2>"
					( Origin gPackager )
				)
				( attribute "PNN" "M_J_DQ<2>"
					( Origin gPackager )
				)
				( objectStatus "M_J_DQ<2>" )
			)
			( signal "@baseboard_fab2_lib.baseboard_fab2(sch_1):m_j_dq(3)"
				( attribute "CDS_PHYS_NET_NAME" "M_J_DQ<3>"
					( Origin gPackager )
				)
				( attribute "PNN" "M_J_DQ<3>"
					( Origin gPackager )
				)
				( objectStatus "M_J_DQ<3>" )
			)
			( signal "@baseboard_fab2_lib.baseboard_fab2(sch_1):m_j_dq(4)"
				( attribute "CDS_PHYS_NET_NAME" "M_J_DQ<4>"
					( Origin gPackager )
				)
				( attribute "PNN" "M_J_DQ<4>"
					( Origin gPackager )
				)
				( objectStatus "M_J_DQ<4>" )
			)
			( signal "@baseboard_fab2_lib.baseboard_fab2(sch_1):m_j_dq(5)"
				( attribute "CDS_PHYS_NET_NAME" "M_J_DQ<5>"
					( Origin gPackager )
				)
				( attribute "PNN" "M_J_DQ<5>"
					( Origin gPackager )
				)
				( objectStatus "M_J_DQ<5>" )
			)
			( signal "@baseboard_fab2_lib.baseboard_fab2(sch_1):m_j_dq(6)"
				( attribute "CDS_PHYS_NET_NAME" "M_J_DQ<6>"
					( Origin gPackager )
				)
				( attribute "PNN" "M_J_DQ<6>"
					( Origin gPackager )
				)
				( objectStatus "M_J_DQ<6>" )
			)
			( signal "@baseboard_fab2_lib.baseboard_fab2(sch_1):m_j_dq(7)"
				( attribute "CDS_PHYS_NET_NAME" "M_J_DQ<7>"
					( Origin gPackager )
				)
				( attribute "PNN" "M_J_DQ<7>"
					( Origin gPackager )
				)
				( objectStatus "M_J_DQ<7>" )
			)
			( signal "@baseboard_fab2_lib.baseboard_fab2(sch_1):m_j_dq(8)"
				( attribute "CDS_PHYS_NET_NAME" "M_J_DQ<8>"
					( Origin gPackager )
				)
				( attribute "PNN" "M_J_DQ<8>"
					( Origin gPackager )
				)
				( objectStatus "M_J_DQ<8>" )
			)
			( signal "@baseboard_fab2_lib.baseboard_fab2(sch_1):m_j_dq(9)"
				( attribute "CDS_PHYS_NET_NAME" "M_J_DQ<9>"
					( Origin gPackager )
				)
				( attribute "PNN" "M_J_DQ<9>"
					( Origin gPackager )
				)
				( objectStatus "M_J_DQ<9>" )
			)
			( signal "@baseboard_fab2_lib.baseboard_fab2(sch_1):m_j_dq(10)"
				( attribute "CDS_PHYS_NET_NAME" "M_J_DQ<10>"
					( Origin gPackager )
				)
				( attribute "PNN" "M_J_DQ<10>"
					( Origin gPackager )
				)
				( objectStatus "M_J_DQ<10>" )
			)
			( signal "@baseboard_fab2_lib.baseboard_fab2(sch_1):m_j_dq(11)"
				( attribute "CDS_PHYS_NET_NAME" "M_J_DQ<11>"
					( Origin gPackager )
				)
				( attribute "PNN" "M_J_DQ<11>"
					( Origin gPackager )
				)
				( objectStatus "M_J_DQ<11>" )
			)
			( signal "@baseboard_fab2_lib.baseboard_fab2(sch_1):m_j_dq(12)"
				( attribute "CDS_PHYS_NET_NAME" "M_J_DQ<12>"
					( Origin gPackager )
				)
				( attribute "PNN" "M_J_DQ<12>"
					( Origin gPackager )
				)
				( objectStatus "M_J_DQ<12>" )
			)
			( signal "@baseboard_fab2_lib.baseboard_fab2(sch_1):m_j_dq(13)"
				( attribute "CDS_PHYS_NET_NAME" "M_J_DQ<13>"
					( Origin gPackager )
				)
				( attribute "PNN" "M_J_DQ<13>"
					( Origin gPackager )
				)
				( objectStatus "M_J_DQ<13>" )
			)
			( signal "@baseboard_fab2_lib.baseboard_fab2(sch_1):m_j_dq(14)"
				( attribute "CDS_PHYS_NET_NAME" "M_J_DQ<14>"
					( Origin gPackager )
				)
				( attribute "PNN" "M_J_DQ<14>"
					( Origin gPackager )
				)
				( objectStatus "M_J_DQ<14>" )
			)
			( signal "@baseboard_fab2_lib.baseboard_fab2(sch_1):m_j_dq(15)"
				( attribute "CDS_PHYS_NET_NAME" "M_J_DQ<15>"
					( Origin gPackager )
				)
				( attribute "PNN" "M_J_DQ<15>"
					( Origin gPackager )
				)
				( objectStatus "M_J_DQ<15>" )
			)
			( signal "@baseboard_fab2_lib.baseboard_fab2(sch_1):m_j_dq(16)"
				( attribute "CDS_PHYS_NET_NAME" "M_J_DQ<16>"
					( Origin gPackager )
				)
				( attribute "PNN" "M_J_DQ<16>"
					( Origin gPackager )
				)
				( objectStatus "M_J_DQ<16>" )
			)
			( signal "@baseboard_fab2_lib.baseboard_fab2(sch_1):m_j_dq(17)"
				( attribute "CDS_PHYS_NET_NAME" "M_J_DQ<17>"
					( Origin gPackager )
				)
				( attribute "PNN" "M_J_DQ<17>"
					( Origin gPackager )
				)
				( objectStatus "M_J_DQ<17>" )
			)
			( signal "@baseboard_fab2_lib.baseboard_fab2(sch_1):m_j_dq(18)"
				( attribute "CDS_PHYS_NET_NAME" "M_J_DQ<18>"
					( Origin gPackager )
				)
				( attribute "PNN" "M_J_DQ<18>"
					( Origin gPackager )
				)
				( objectStatus "M_J_DQ<18>" )
			)
			( signal "@baseboard_fab2_lib.baseboard_fab2(sch_1):m_j_dq(19)"
				( attribute "CDS_PHYS_NET_NAME" "M_J_DQ<19>"
					( Origin gPackager )
				)
				( attribute "PNN" "M_J_DQ<19>"
					( Origin gPackager )
				)
				( objectStatus "M_J_DQ<19>" )
			)
			( signal "@baseboard_fab2_lib.baseboard_fab2(sch_1):m_j_dq(20)"
				( attribute "CDS_PHYS_NET_NAME" "M_J_DQ<20>"
					( Origin gPackager )
				)
				( attribute "PNN" "M_J_DQ<20>"
					( Origin gPackager )
				)
				( objectStatus "M_J_DQ<20>" )
			)
			( signal "@baseboard_fab2_lib.baseboard_fab2(sch_1):m_j_dq(21)"
				( attribute "CDS_PHYS_NET_NAME" "M_J_DQ<21>"
					( Origin gPackager )
				)
				( attribute "PNN" "M_J_DQ<21>"
					( Origin gPackager )
				)
				( objectStatus "M_J_DQ<21>" )
			)
			( signal "@baseboard_fab2_lib.baseboard_fab2(sch_1):m_j_dq(22)"
				( attribute "CDS_PHYS_NET_NAME" "M_J_DQ<22>"
					( Origin gPackager )
				)
				( attribute "PNN" "M_J_DQ<22>"
					( Origin gPackager )
				)
				( objectStatus "M_J_DQ<22>" )
			)
			( signal "@baseboard_fab2_lib.baseboard_fab2(sch_1):m_j_dq(23)"
				( attribute "CDS_PHYS_NET_NAME" "M_J_DQ<23>"
					( Origin gPackager )
				)
				( attribute "PNN" "M_J_DQ<23>"
					( Origin gPackager )
				)
				( objectStatus "M_J_DQ<23>" )
			)
			( signal "@baseboard_fab2_lib.baseboard_fab2(sch_1):m_j_dq(24)"
				( attribute "CDS_PHYS_NET_NAME" "M_J_DQ<24>"
					( Origin gPackager )
				)
				( attribute "PNN" "M_J_DQ<24>"
					( Origin gPackager )
				)
				( objectStatus "M_J_DQ<24>" )
			)
			( signal "@baseboard_fab2_lib.baseboard_fab2(sch_1):m_j_dq(25)"
				( attribute "CDS_PHYS_NET_NAME" "M_J_DQ<25>"
					( Origin gPackager )
				)
				( attribute "PNN" "M_J_DQ<25>"
					( Origin gPackager )
				)
				( objectStatus "M_J_DQ<25>" )
			)
			( signal "@baseboard_fab2_lib.baseboard_fab2(sch_1):m_j_dq(26)"
				( attribute "CDS_PHYS_NET_NAME" "M_J_DQ<26>"
					( Origin gPackager )
				)
				( attribute "PNN" "M_J_DQ<26>"
					( Origin gPackager )
				)
				( objectStatus "M_J_DQ<26>" )
			)
			( signal "@baseboard_fab2_lib.baseboard_fab2(sch_1):m_j_dq(27)"
				( attribute "CDS_PHYS_NET_NAME" "M_J_DQ<27>"
					( Origin gPackager )
				)
				( attribute "PNN" "M_J_DQ<27>"
					( Origin gPackager )
				)
				( objectStatus "M_J_DQ<27>" )
			)
			( signal "@baseboard_fab2_lib.baseboard_fab2(sch_1):m_j_dq(28)"
				( attribute "CDS_PHYS_NET_NAME" "M_J_DQ<28>"
					( Origin gPackager )
				)
				( attribute "PNN" "M_J_DQ<28>"
					( Origin gPackager )
				)
				( objectStatus "M_J_DQ<28>" )
			)
			( signal "@baseboard_fab2_lib.baseboard_fab2(sch_1):m_j_dq(29)"
				( attribute "CDS_PHYS_NET_NAME" "M_J_DQ<29>"
					( Origin gPackager )
				)
				( attribute "PNN" "M_J_DQ<29>"
					( Origin gPackager )
				)
				( objectStatus "M_J_DQ<29>" )
			)
			( signal "@baseboard_fab2_lib.baseboard_fab2(sch_1):m_j_dq(30)"
				( attribute "CDS_PHYS_NET_NAME" "M_J_DQ<30>"
					( Origin gPackager )
				)
				( attribute "PNN" "M_J_DQ<30>"
					( Origin gPackager )
				)
				( objectStatus "M_J_DQ<30>" )
			)
			( signal "@baseboard_fab2_lib.baseboard_fab2(sch_1):m_j_dq(31)"
				( attribute "CDS_PHYS_NET_NAME" "M_J_DQ<31>"
					( Origin gPackager )
				)
				( attribute "PNN" "M_J_DQ<31>"
					( Origin gPackager )
				)
				( objectStatus "M_J_DQ<31>" )
			)
			( signal "@baseboard_fab2_lib.baseboard_fab2(sch_1):m_j_dq(32)"
				( attribute "CDS_PHYS_NET_NAME" "M_J_DQ<32>"
					( Origin gPackager )
				)
				( attribute "PNN" "M_J_DQ<32>"
					( Origin gPackager )
				)
				( objectStatus "M_J_DQ<32>" )
			)
			( signal "@baseboard_fab2_lib.baseboard_fab2(sch_1):m_j_dq(33)"
				( attribute "CDS_PHYS_NET_NAME" "M_J_DQ<33>"
					( Origin gPackager )
				)
				( attribute "PNN" "M_J_DQ<33>"
					( Origin gPackager )
				)
				( objectStatus "M_J_DQ<33>" )
			)
			( signal "@baseboard_fab2_lib.baseboard_fab2(sch_1):m_j_dq(34)"
				( attribute "CDS_PHYS_NET_NAME" "M_J_DQ<34>"
					( Origin gPackager )
				)
				( attribute "PNN" "M_J_DQ<34>"
					( Origin gPackager )
				)
				( objectStatus "M_J_DQ<34>" )
			)
			( signal "@baseboard_fab2_lib.baseboard_fab2(sch_1):m_j_dq(35)"
				( attribute "CDS_PHYS_NET_NAME" "M_J_DQ<35>"
					( Origin gPackager )
				)
				( attribute "PNN" "M_J_DQ<35>"
					( Origin gPackager )
				)
				( objectStatus "M_J_DQ<35>" )
			)
			( signal "@baseboard_fab2_lib.baseboard_fab2(sch_1):m_j_dq(36)"
				( attribute "CDS_PHYS_NET_NAME" "M_J_DQ<36>"
					( Origin gPackager )
				)
				( attribute "PNN" "M_J_DQ<36>"
					( Origin gPackager )
				)
				( objectStatus "M_J_DQ<36>" )
			)
			( signal "@baseboard_fab2_lib.baseboard_fab2(sch_1):m_j_dq(37)"
				( attribute "CDS_PHYS_NET_NAME" "M_J_DQ<37>"
					( Origin gPackager )
				)
				( attribute "PNN" "M_J_DQ<37>"
					( Origin gPackager )
				)
				( objectStatus "M_J_DQ<37>" )
			)
			( signal "@baseboard_fab2_lib.baseboard_fab2(sch_1):m_j_dq(38)"
				( attribute "CDS_PHYS_NET_NAME" "M_J_DQ<38>"
					( Origin gPackager )
				)
				( attribute "PNN" "M_J_DQ<38>"
					( Origin gPackager )
				)
				( objectStatus "M_J_DQ<38>" )
			)
			( signal "@baseboard_fab2_lib.baseboard_fab2(sch_1):m_j_dq(39)"
				( attribute "CDS_PHYS_NET_NAME" "M_J_DQ<39>"
					( Origin gPackager )
				)
				( attribute "PNN" "M_J_DQ<39>"
					( Origin gPackager )
				)
				( objectStatus "M_J_DQ<39>" )
			)
			( signal "@baseboard_fab2_lib.baseboard_fab2(sch_1):m_j_dq(40)"
				( attribute "CDS_PHYS_NET_NAME" "M_J_DQ<40>"
					( Origin gPackager )
				)
				( attribute "PNN" "M_J_DQ<40>"
					( Origin gPackager )
				)
				( objectStatus "M_J_DQ<40>" )
			)
			( signal "@baseboard_fab2_lib.baseboard_fab2(sch_1):m_j_dq(41)"
				( attribute "CDS_PHYS_NET_NAME" "M_J_DQ<41>"
					( Origin gPackager )
				)
				( attribute "PNN" "M_J_DQ<41>"
					( Origin gPackager )
				)
				( objectStatus "M_J_DQ<41>" )
			)
			( signal "@baseboard_fab2_lib.baseboard_fab2(sch_1):m_j_dq(42)"
				( attribute "CDS_PHYS_NET_NAME" "M_J_DQ<42>"
					( Origin gPackager )
				)
				( attribute "PNN" "M_J_DQ<42>"
					( Origin gPackager )
				)
				( objectStatus "M_J_DQ<42>" )
			)
			( signal "@baseboard_fab2_lib.baseboard_fab2(sch_1):m_j_dq(43)"
				( attribute "CDS_PHYS_NET_NAME" "M_J_DQ<43>"
					( Origin gPackager )
				)
				( attribute "PNN" "M_J_DQ<43>"
					( Origin gPackager )
				)
				( objectStatus "M_J_DQ<43>" )
			)
			( signal "@baseboard_fab2_lib.baseboard_fab2(sch_1):m_j_dq(44)"
				( attribute "CDS_PHYS_NET_NAME" "M_J_DQ<44>"
					( Origin gPackager )
				)
				( attribute "PNN" "M_J_DQ<44>"
					( Origin gPackager )
				)
				( objectStatus "M_J_DQ<44>" )
			)
			( signal "@baseboard_fab2_lib.baseboard_fab2(sch_1):m_j_dq(45)"
				( attribute "CDS_PHYS_NET_NAME" "M_J_DQ<45>"
					( Origin gPackager )
				)
				( attribute "PNN" "M_J_DQ<45>"
					( Origin gPackager )
				)
				( objectStatus "M_J_DQ<45>" )
			)
			( signal "@baseboard_fab2_lib.baseboard_fab2(sch_1):m_j_dq(46)"
				( attribute "CDS_PHYS_NET_NAME" "M_J_DQ<46>"
					( Origin gPackager )
				)
				( attribute "PNN" "M_J_DQ<46>"
					( Origin gPackager )
				)
				( objectStatus "M_J_DQ<46>" )
			)
			( signal "@baseboard_fab2_lib.baseboard_fab2(sch_1):m_j_dq(47)"
				( attribute "CDS_PHYS_NET_NAME" "M_J_DQ<47>"
					( Origin gPackager )
				)
				( attribute "PNN" "M_J_DQ<47>"
					( Origin gPackager )
				)
				( objectStatus "M_J_DQ<47>" )
			)
			( signal "@baseboard_fab2_lib.baseboard_fab2(sch_1):m_j_dq(48)"
				( attribute "CDS_PHYS_NET_NAME" "M_J_DQ<48>"
					( Origin gPackager )
				)
				( attribute "PNN" "M_J_DQ<48>"
					( Origin gPackager )
				)
				( objectStatus "M_J_DQ<48>" )
			)
			( signal "@baseboard_fab2_lib.baseboard_fab2(sch_1):m_j_dq(49)"
				( attribute "CDS_PHYS_NET_NAME" "M_J_DQ<49>"
					( Origin gPackager )
				)
				( attribute "PNN" "M_J_DQ<49>"
					( Origin gPackager )
				)
				( objectStatus "M_J_DQ<49>" )
			)
			( signal "@baseboard_fab2_lib.baseboard_fab2(sch_1):m_j_dq(50)"
				( attribute "CDS_PHYS_NET_NAME" "M_J_DQ<50>"
					( Origin gPackager )
				)
				( attribute "PNN" "M_J_DQ<50>"
					( Origin gPackager )
				)
				( objectStatus "M_J_DQ<50>" )
			)
			( signal "@baseboard_fab2_lib.baseboard_fab2(sch_1):m_j_dq(51)"
				( attribute "CDS_PHYS_NET_NAME" "M_J_DQ<51>"
					( Origin gPackager )
				)
				( attribute "PNN" "M_J_DQ<51>"
					( Origin gPackager )
				)
				( objectStatus "M_J_DQ<51>" )
			)
			( signal "@baseboard_fab2_lib.baseboard_fab2(sch_1):m_j_dq(52)"
				( attribute "CDS_PHYS_NET_NAME" "M_J_DQ<52>"
					( Origin gPackager )
				)
				( attribute "PNN" "M_J_DQ<52>"
					( Origin gPackager )
				)
				( objectStatus "M_J_DQ<52>" )
			)
			( signal "@baseboard_fab2_lib.baseboard_fab2(sch_1):m_j_dq(53)"
				( attribute "CDS_PHYS_NET_NAME" "M_J_DQ<53>"
					( Origin gPackager )
				)
				( attribute "PNN" "M_J_DQ<53>"
					( Origin gPackager )
				)
				( objectStatus "M_J_DQ<53>" )
			)
			( signal "@baseboard_fab2_lib.baseboard_fab2(sch_1):m_j_dq(54)"
				( attribute "CDS_PHYS_NET_NAME" "M_J_DQ<54>"
					( Origin gPackager )
				)
				( attribute "PNN" "M_J_DQ<54>"
					( Origin gPackager )
				)
				( objectStatus "M_J_DQ<54>" )
			)
			( signal "@baseboard_fab2_lib.baseboard_fab2(sch_1):m_j_dq(55)"
				( attribute "CDS_PHYS_NET_NAME" "M_J_DQ<55>"
					( Origin gPackager )
				)
				( attribute "PNN" "M_J_DQ<55>"
					( Origin gPackager )
				)
				( objectStatus "M_J_DQ<55>" )
			)
			( signal "@baseboard_fab2_lib.baseboard_fab2(sch_1):m_j_dq(56)"
				( attribute "CDS_PHYS_NET_NAME" "M_J_DQ<56>"
					( Origin gPackager )
				)
				( attribute "PNN" "M_J_DQ<56>"
					( Origin gPackager )
				)
				( objectStatus "M_J_DQ<56>" )
			)
			( signal "@baseboard_fab2_lib.baseboard_fab2(sch_1):m_j_dq(57)"
				( attribute "CDS_PHYS_NET_NAME" "M_J_DQ<57>"
					( Origin gPackager )
				)
				( attribute "PNN" "M_J_DQ<57>"
					( Origin gPackager )
				)
				( objectStatus "M_J_DQ<57>" )
			)
			( signal "@baseboard_fab2_lib.baseboard_fab2(sch_1):m_j_dq(58)"
				( attribute "CDS_PHYS_NET_NAME" "M_J_DQ<58>"
					( Origin gPackager )
				)
				( attribute "PNN" "M_J_DQ<58>"
					( Origin gPackager )
				)
				( objectStatus "M_J_DQ<58>" )
			)
			( signal "@baseboard_fab2_lib.baseboard_fab2(sch_1):m_j_dq(59)"
				( attribute "CDS_PHYS_NET_NAME" "M_J_DQ<59>"
					( Origin gPackager )
				)
				( attribute "PNN" "M_J_DQ<59>"
					( Origin gPackager )
				)
				( objectStatus "M_J_DQ<59>" )
			)
			( signal "@baseboard_fab2_lib.baseboard_fab2(sch_1):m_j_dq(60)"
				( attribute "CDS_PHYS_NET_NAME" "M_J_DQ<60>"
					( Origin gPackager )
				)
				( attribute "PNN" "M_J_DQ<60>"
					( Origin gPackager )
				)
				( objectStatus "M_J_DQ<60>" )
			)
			( signal "@baseboard_fab2_lib.baseboard_fab2(sch_1):m_j_dq(61)"
				( attribute "CDS_PHYS_NET_NAME" "M_J_DQ<61>"
					( Origin gPackager )
				)
				( attribute "PNN" "M_J_DQ<61>"
					( Origin gPackager )
				)
				( objectStatus "M_J_DQ<61>" )
			)
			( signal "@baseboard_fab2_lib.baseboard_fab2(sch_1):m_j_dq(62)"
				( attribute "CDS_PHYS_NET_NAME" "M_J_DQ<62>"
					( Origin gPackager )
				)
				( attribute "PNN" "M_J_DQ<62>"
					( Origin gPackager )
				)
				( objectStatus "M_J_DQ<62>" )
			)
			( signal "@baseboard_fab2_lib.baseboard_fab2(sch_1):m_j_dq(63)"
				( attribute "CDS_PHYS_NET_NAME" "M_J_DQ<63>"
					( Origin gPackager )
				)
				( attribute "PNN" "M_J_DQ<63>"
					( Origin gPackager )
				)
				( objectStatus "M_J_DQ<63>" )
			)
			( signal "@baseboard_fab2_lib.baseboard_fab2(sch_1):m_j_dqs_dn(0)"
				( attribute "CDS_PHYS_NET_NAME" "M_J_DQS_DN<0>"
					( Origin gPackager )
				)
				( attribute "PNN" "M_J_DQS_DN<0>"
					( Origin gPackager )
				)
				( objectStatus "M_J_DQS_DN<0>" )
			)
			( signal "@baseboard_fab2_lib.baseboard_fab2(sch_1):m_j_dqs_dn(1)"
				( attribute "CDS_PHYS_NET_NAME" "M_J_DQS_DN<1>"
					( Origin gPackager )
				)
				( attribute "PNN" "M_J_DQS_DN<1>"
					( Origin gPackager )
				)
				( objectStatus "M_J_DQS_DN<1>" )
			)
			( signal "@baseboard_fab2_lib.baseboard_fab2(sch_1):m_j_dqs_dn(2)"
				( attribute "CDS_PHYS_NET_NAME" "M_J_DQS_DN<2>"
					( Origin gPackager )
				)
				( attribute "PNN" "M_J_DQS_DN<2>"
					( Origin gPackager )
				)
				( objectStatus "M_J_DQS_DN<2>" )
			)
			( signal "@baseboard_fab2_lib.baseboard_fab2(sch_1):m_j_dqs_dn(3)"
				( attribute "CDS_PHYS_NET_NAME" "M_J_DQS_DN<3>"
					( Origin gPackager )
				)
				( attribute "PNN" "M_J_DQS_DN<3>"
					( Origin gPackager )
				)
				( objectStatus "M_J_DQS_DN<3>" )
			)
			( signal "@baseboard_fab2_lib.baseboard_fab2(sch_1):m_j_dqs_dn(4)"
				( attribute "CDS_PHYS_NET_NAME" "M_J_DQS_DN<4>"
					( Origin gPackager )
				)
				( attribute "PNN" "M_J_DQS_DN<4>"
					( Origin gPackager )
				)
				( objectStatus "M_J_DQS_DN<4>" )
			)
			( signal "@baseboard_fab2_lib.baseboard_fab2(sch_1):m_j_dqs_dn(5)"
				( attribute "CDS_PHYS_NET_NAME" "M_J_DQS_DN<5>"
					( Origin gPackager )
				)
				( attribute "PNN" "M_J_DQS_DN<5>"
					( Origin gPackager )
				)
				( objectStatus "M_J_DQS_DN<5>" )
			)
			( signal "@baseboard_fab2_lib.baseboard_fab2(sch_1):m_j_dqs_dn(6)"
				( attribute "CDS_PHYS_NET_NAME" "M_J_DQS_DN<6>"
					( Origin gPackager )
				)
				( attribute "PNN" "M_J_DQS_DN<6>"
					( Origin gPackager )
				)
				( objectStatus "M_J_DQS_DN<6>" )
			)
			( signal "@baseboard_fab2_lib.baseboard_fab2(sch_1):m_j_dqs_dn(7)"
				( attribute "CDS_PHYS_NET_NAME" "M_J_DQS_DN<7>"
					( Origin gPackager )
				)
				( attribute "PNN" "M_J_DQS_DN<7>"
					( Origin gPackager )
				)
				( objectStatus "M_J_DQS_DN<7>" )
			)
			( signal "@baseboard_fab2_lib.baseboard_fab2(sch_1):m_j_dqs_dn(8)"
				( attribute "CDS_PHYS_NET_NAME" "M_J_DQS_DN<8>"
					( Origin gPackager )
				)
				( attribute "PNN" "M_J_DQS_DN<8>"
					( Origin gPackager )
				)
				( objectStatus "M_J_DQS_DN<8>" )
			)
			( signal "@baseboard_fab2_lib.baseboard_fab2(sch_1):m_j_dqs_dn(9)"
				( attribute "CDS_PHYS_NET_NAME" "M_J_DQS_DN<9>"
					( Origin gPackager )
				)
				( attribute "PNN" "M_J_DQS_DN<9>"
					( Origin gPackager )
				)
				( objectStatus "M_J_DQS_DN<9>" )
			)
			( signal "@baseboard_fab2_lib.baseboard_fab2(sch_1):m_j_dqs_dn(10)"
				( attribute "CDS_PHYS_NET_NAME" "M_J_DQS_DN<10>"
					( Origin gPackager )
				)
				( attribute "PNN" "M_J_DQS_DN<10>"
					( Origin gPackager )
				)
				( objectStatus "M_J_DQS_DN<10>" )
			)
			( signal "@baseboard_fab2_lib.baseboard_fab2(sch_1):m_j_dqs_dn(11)"
				( attribute "CDS_PHYS_NET_NAME" "M_J_DQS_DN<11>"
					( Origin gPackager )
				)
				( attribute "PNN" "M_J_DQS_DN<11>"
					( Origin gPackager )
				)
				( objectStatus "M_J_DQS_DN<11>" )
			)
			( signal "@baseboard_fab2_lib.baseboard_fab2(sch_1):m_j_dqs_dn(12)"
				( attribute "CDS_PHYS_NET_NAME" "M_J_DQS_DN<12>"
					( Origin gPackager )
				)
				( attribute "PNN" "M_J_DQS_DN<12>"
					( Origin gPackager )
				)
				( objectStatus "M_J_DQS_DN<12>" )
			)
			( signal "@baseboard_fab2_lib.baseboard_fab2(sch_1):m_j_dqs_dn(13)"
				( attribute "CDS_PHYS_NET_NAME" "M_J_DQS_DN<13>"
					( Origin gPackager )
				)
				( attribute "PNN" "M_J_DQS_DN<13>"
					( Origin gPackager )
				)
				( objectStatus "M_J_DQS_DN<13>" )
			)
			( signal "@baseboard_fab2_lib.baseboard_fab2(sch_1):m_j_dqs_dn(14)"
				( attribute "CDS_PHYS_NET_NAME" "M_J_DQS_DN<14>"
					( Origin gPackager )
				)
				( attribute "PNN" "M_J_DQS_DN<14>"
					( Origin gPackager )
				)
				( objectStatus "M_J_DQS_DN<14>" )
			)
			( signal "@baseboard_fab2_lib.baseboard_fab2(sch_1):m_j_dqs_dn(15)"
				( attribute "CDS_PHYS_NET_NAME" "M_J_DQS_DN<15>"
					( Origin gPackager )
				)
				( attribute "PNN" "M_J_DQS_DN<15>"
					( Origin gPackager )
				)
				( objectStatus "M_J_DQS_DN<15>" )
			)
			( signal "@baseboard_fab2_lib.baseboard_fab2(sch_1):m_j_dqs_dn(16)"
				( attribute "CDS_PHYS_NET_NAME" "M_J_DQS_DN<16>"
					( Origin gPackager )
				)
				( attribute "PNN" "M_J_DQS_DN<16>"
					( Origin gPackager )
				)
				( objectStatus "M_J_DQS_DN<16>" )
			)
			( signal "@baseboard_fab2_lib.baseboard_fab2(sch_1):m_j_dqs_dn(17)"
				( attribute "CDS_PHYS_NET_NAME" "M_J_DQS_DN<17>"
					( Origin gPackager )
				)
				( attribute "PNN" "M_J_DQS_DN<17>"
					( Origin gPackager )
				)
				( objectStatus "M_J_DQS_DN<17>" )
			)
			( signal "@baseboard_fab2_lib.baseboard_fab2(sch_1):m_j_dqs_dp(0)"
				( attribute "CDS_PHYS_NET_NAME" "M_J_DQS_DP<0>"
					( Origin gPackager )
				)
				( attribute "PNN" "M_J_DQS_DP<0>"
					( Origin gPackager )
				)
				( objectStatus "M_J_DQS_DP<0>" )
			)
			( signal "@baseboard_fab2_lib.baseboard_fab2(sch_1):m_j_dqs_dp(1)"
				( attribute "CDS_PHYS_NET_NAME" "M_J_DQS_DP<1>"
					( Origin gPackager )
				)
				( attribute "PNN" "M_J_DQS_DP<1>"
					( Origin gPackager )
				)
				( objectStatus "M_J_DQS_DP<1>" )
			)
			( signal "@baseboard_fab2_lib.baseboard_fab2(sch_1):m_j_dqs_dp(2)"
				( attribute "CDS_PHYS_NET_NAME" "M_J_DQS_DP<2>"
					( Origin gPackager )
				)
				( attribute "PNN" "M_J_DQS_DP<2>"
					( Origin gPackager )
				)
				( objectStatus "M_J_DQS_DP<2>" )
			)
			( signal "@baseboard_fab2_lib.baseboard_fab2(sch_1):m_j_dqs_dp(3)"
				( attribute "CDS_PHYS_NET_NAME" "M_J_DQS_DP<3>"
					( Origin gPackager )
				)
				( attribute "PNN" "M_J_DQS_DP<3>"
					( Origin gPackager )
				)
				( objectStatus "M_J_DQS_DP<3>" )
			)
			( signal "@baseboard_fab2_lib.baseboard_fab2(sch_1):m_j_dqs_dp(4)"
				( attribute "CDS_PHYS_NET_NAME" "M_J_DQS_DP<4>"
					( Origin gPackager )
				)
				( attribute "PNN" "M_J_DQS_DP<4>"
					( Origin gPackager )
				)
				( objectStatus "M_J_DQS_DP<4>" )
			)
			( signal "@baseboard_fab2_lib.baseboard_fab2(sch_1):m_j_dqs_dp(5)"
				( attribute "CDS_PHYS_NET_NAME" "M_J_DQS_DP<5>"
					( Origin gPackager )
				)
				( attribute "PNN" "M_J_DQS_DP<5>"
					( Origin gPackager )
				)
				( objectStatus "M_J_DQS_DP<5>" )
			)
			( signal "@baseboard_fab2_lib.baseboard_fab2(sch_1):m_j_dqs_dp(6)"
				( attribute "CDS_PHYS_NET_NAME" "M_J_DQS_DP<6>"
					( Origin gPackager )
				)
				( attribute "PNN" "M_J_DQS_DP<6>"
					( Origin gPackager )
				)
				( objectStatus "M_J_DQS_DP<6>" )
			)
			( signal "@baseboard_fab2_lib.baseboard_fab2(sch_1):m_j_dqs_dp(7)"
				( attribute "CDS_PHYS_NET_NAME" "M_J_DQS_DP<7>"
					( Origin gPackager )
				)
				( attribute "PNN" "M_J_DQS_DP<7>"
					( Origin gPackager )
				)
				( objectStatus "M_J_DQS_DP<7>" )
			)
			( signal "@baseboard_fab2_lib.baseboard_fab2(sch_1):m_j_dqs_dp(8)"
				( attribute "CDS_PHYS_NET_NAME" "M_J_DQS_DP<8>"
					( Origin gPackager )
				)
				( attribute "PNN" "M_J_DQS_DP<8>"
					( Origin gPackager )
				)
				( objectStatus "M_J_DQS_DP<8>" )
			)
			( signal "@baseboard_fab2_lib.baseboard_fab2(sch_1):m_j_dqs_dp(9)"
				( attribute "CDS_PHYS_NET_NAME" "M_J_DQS_DP<9>"
					( Origin gPackager )
				)
				( attribute "PNN" "M_J_DQS_DP<9>"
					( Origin gPackager )
				)
				( objectStatus "M_J_DQS_DP<9>" )
			)
			( signal "@baseboard_fab2_lib.baseboard_fab2(sch_1):m_j_dqs_dp(10)"
				( attribute "CDS_PHYS_NET_NAME" "M_J_DQS_DP<10>"
					( Origin gPackager )
				)
				( attribute "PNN" "M_J_DQS_DP<10>"
					( Origin gPackager )
				)
				( objectStatus "M_J_DQS_DP<10>" )
			)
			( signal "@baseboard_fab2_lib.baseboard_fab2(sch_1):m_j_dqs_dp(11)"
				( attribute "CDS_PHYS_NET_NAME" "M_J_DQS_DP<11>"
					( Origin gPackager )
				)
				( attribute "PNN" "M_J_DQS_DP<11>"
					( Origin gPackager )
				)
				( objectStatus "M_J_DQS_DP<11>" )
			)
			( signal "@baseboard_fab2_lib.baseboard_fab2(sch_1):m_j_dqs_dp(12)"
				( attribute "CDS_PHYS_NET_NAME" "M_J_DQS_DP<12>"
					( Origin gPackager )
				)
				( attribute "PNN" "M_J_DQS_DP<12>"
					( Origin gPackager )
				)
				( objectStatus "M_J_DQS_DP<12>" )
			)
			( signal "@baseboard_fab2_lib.baseboard_fab2(sch_1):m_j_dqs_dp(13)"
				( attribute "CDS_PHYS_NET_NAME" "M_J_DQS_DP<13>"
					( Origin gPackager )
				)
				( attribute "PNN" "M_J_DQS_DP<13>"
					( Origin gPackager )
				)
				( objectStatus "M_J_DQS_DP<13>" )
			)
			( signal "@baseboard_fab2_lib.baseboard_fab2(sch_1):m_j_dqs_dp(14)"
				( attribute "CDS_PHYS_NET_NAME" "M_J_DQS_DP<14>"
					( Origin gPackager )
				)
				( attribute "PNN" "M_J_DQS_DP<14>"
					( Origin gPackager )
				)
				( objectStatus "M_J_DQS_DP<14>" )
			)
			( signal "@baseboard_fab2_lib.baseboard_fab2(sch_1):m_j_dqs_dp(15)"
				( attribute "CDS_PHYS_NET_NAME" "M_J_DQS_DP<15>"
					( Origin gPackager )
				)
				( attribute "PNN" "M_J_DQS_DP<15>"
					( Origin gPackager )
				)
				( objectStatus "M_J_DQS_DP<15>" )
			)
			( signal "@baseboard_fab2_lib.baseboard_fab2(sch_1):m_j_dqs_dp(16)"
				( attribute "CDS_PHYS_NET_NAME" "M_J_DQS_DP<16>"
					( Origin gPackager )
				)
				( attribute "PNN" "M_J_DQS_DP<16>"
					( Origin gPackager )
				)
				( objectStatus "M_J_DQS_DP<16>" )
			)
			( signal "@baseboard_fab2_lib.baseboard_fab2(sch_1):m_j_dqs_dp(17)"
				( attribute "CDS_PHYS_NET_NAME" "M_J_DQS_DP<17>"
					( Origin gPackager )
				)
				( attribute "PNN" "M_J_DQS_DP<17>"
					( Origin gPackager )
				)
				( objectStatus "M_J_DQS_DP<17>" )
			)
			( signal "@baseboard_fab2_lib.baseboard_fab2(sch_1):m_j_ecc(0)"
				( attribute "CDS_PHYS_NET_NAME" "M_J_ECC<0>"
					( Origin gPackager )
				)
				( attribute "PNN" "M_J_ECC<0>"
					( Origin gPackager )
				)
				( objectStatus "M_J_ECC<0>" )
			)
			( signal "@baseboard_fab2_lib.baseboard_fab2(sch_1):m_j_ecc(1)"
				( attribute "CDS_PHYS_NET_NAME" "M_J_ECC<1>"
					( Origin gPackager )
				)
				( attribute "PNN" "M_J_ECC<1>"
					( Origin gPackager )
				)
				( objectStatus "M_J_ECC<1>" )
			)
			( signal "@baseboard_fab2_lib.baseboard_fab2(sch_1):m_j_ecc(2)"
				( attribute "CDS_PHYS_NET_NAME" "M_J_ECC<2>"
					( Origin gPackager )
				)
				( attribute "PNN" "M_J_ECC<2>"
					( Origin gPackager )
				)
				( objectStatus "M_J_ECC<2>" )
			)
			( signal "@baseboard_fab2_lib.baseboard_fab2(sch_1):m_j_ecc(3)"
				( attribute "CDS_PHYS_NET_NAME" "M_J_ECC<3>"
					( Origin gPackager )
				)
				( attribute "PNN" "M_J_ECC<3>"
					( Origin gPackager )
				)
				( objectStatus "M_J_ECC<3>" )
			)
			( signal "@baseboard_fab2_lib.baseboard_fab2(sch_1):m_j_ecc(4)"
				( attribute "CDS_PHYS_NET_NAME" "M_J_ECC<4>"
					( Origin gPackager )
				)
				( attribute "PNN" "M_J_ECC<4>"
					( Origin gPackager )
				)
				( objectStatus "M_J_ECC<4>" )
			)
			( signal "@baseboard_fab2_lib.baseboard_fab2(sch_1):m_j_ecc(5)"
				( attribute "CDS_PHYS_NET_NAME" "M_J_ECC<5>"
					( Origin gPackager )
				)
				( attribute "PNN" "M_J_ECC<5>"
					( Origin gPackager )
				)
				( objectStatus "M_J_ECC<5>" )
			)
			( signal "@baseboard_fab2_lib.baseboard_fab2(sch_1):m_j_ecc(6)"
				( attribute "CDS_PHYS_NET_NAME" "M_J_ECC<6>"
					( Origin gPackager )
				)
				( attribute "PNN" "M_J_ECC<6>"
					( Origin gPackager )
				)
				( objectStatus "M_J_ECC<6>" )
			)
			( signal "@baseboard_fab2_lib.baseboard_fab2(sch_1):m_j_ecc(7)"
				( attribute "CDS_PHYS_NET_NAME" "M_J_ECC<7>"
					( Origin gPackager )
				)
				( attribute "PNN" "M_J_ECC<7>"
					( Origin gPackager )
				)
				( objectStatus "M_J_ECC<7>" )
			)
			( signal "@baseboard_fab2_lib.baseboard_fab2(sch_1):m_j_ma(0)"
				( attribute "CDS_PHYS_NET_NAME" "M_J_MA<0>"
					( Origin gPackager )
				)
				( attribute "PNN" "M_J_MA<0>"
					( Origin gPackager )
				)
				( objectStatus "M_J_MA<0>" )
			)
			( signal "@baseboard_fab2_lib.baseboard_fab2(sch_1):m_j_ma(1)"
				( attribute "CDS_PHYS_NET_NAME" "M_J_MA<1>"
					( Origin gPackager )
				)
				( attribute "PNN" "M_J_MA<1>"
					( Origin gPackager )
				)
				( objectStatus "M_J_MA<1>" )
			)
			( signal "@baseboard_fab2_lib.baseboard_fab2(sch_1):m_j_ma(2)"
				( attribute "CDS_PHYS_NET_NAME" "M_J_MA<2>"
					( Origin gPackager )
				)
				( attribute "PNN" "M_J_MA<2>"
					( Origin gPackager )
				)
				( objectStatus "M_J_MA<2>" )
			)
			( signal "@baseboard_fab2_lib.baseboard_fab2(sch_1):m_j_ma(3)"
				( attribute "CDS_PHYS_NET_NAME" "M_J_MA<3>"
					( Origin gPackager )
				)
				( attribute "PNN" "M_J_MA<3>"
					( Origin gPackager )
				)
				( objectStatus "M_J_MA<3>" )
			)
			( signal "@baseboard_fab2_lib.baseboard_fab2(sch_1):m_j_ma(4)"
				( attribute "CDS_PHYS_NET_NAME" "M_J_MA<4>"
					( Origin gPackager )
				)
				( attribute "PNN" "M_J_MA<4>"
					( Origin gPackager )
				)
				( objectStatus "M_J_MA<4>" )
			)
			( signal "@baseboard_fab2_lib.baseboard_fab2(sch_1):m_j_ma(5)"
				( attribute "CDS_PHYS_NET_NAME" "M_J_MA<5>"
					( Origin gPackager )
				)
				( attribute "PNN" "M_J_MA<5>"
					( Origin gPackager )
				)
				( objectStatus "M_J_MA<5>" )
			)
			( signal "@baseboard_fab2_lib.baseboard_fab2(sch_1):m_j_ma(6)"
				( attribute "CDS_PHYS_NET_NAME" "M_J_MA<6>"
					( Origin gPackager )
				)
				( attribute "PNN" "M_J_MA<6>"
					( Origin gPackager )
				)
				( objectStatus "M_J_MA<6>" )
			)
			( signal "@baseboard_fab2_lib.baseboard_fab2(sch_1):m_j_ma(7)"
				( attribute "CDS_PHYS_NET_NAME" "M_J_MA<7>"
					( Origin gPackager )
				)
				( attribute "PNN" "M_J_MA<7>"
					( Origin gPackager )
				)
				( objectStatus "M_J_MA<7>" )
			)
			( signal "@baseboard_fab2_lib.baseboard_fab2(sch_1):m_j_ma(8)"
				( attribute "CDS_PHYS_NET_NAME" "M_J_MA<8>"
					( Origin gPackager )
				)
				( attribute "PNN" "M_J_MA<8>"
					( Origin gPackager )
				)
				( objectStatus "M_J_MA<8>" )
			)
			( signal "@baseboard_fab2_lib.baseboard_fab2(sch_1):m_j_ma(9)"
				( attribute "CDS_PHYS_NET_NAME" "M_J_MA<9>"
					( Origin gPackager )
				)
				( attribute "PNN" "M_J_MA<9>"
					( Origin gPackager )
				)
				( objectStatus "M_J_MA<9>" )
			)
			( signal "@baseboard_fab2_lib.baseboard_fab2(sch_1):m_j_ma(10)"
				( attribute "CDS_PHYS_NET_NAME" "M_J_MA<10>"
					( Origin gPackager )
				)
				( attribute "PNN" "M_J_MA<10>"
					( Origin gPackager )
				)
				( objectStatus "M_J_MA<10>" )
			)
			( signal "@baseboard_fab2_lib.baseboard_fab2(sch_1):m_j_ma(11)"
				( attribute "CDS_PHYS_NET_NAME" "M_J_MA<11>"
					( Origin gPackager )
				)
				( attribute "PNN" "M_J_MA<11>"
					( Origin gPackager )
				)
				( objectStatus "M_J_MA<11>" )
			)
			( signal "@baseboard_fab2_lib.baseboard_fab2(sch_1):m_j_ma(12)"
				( attribute "CDS_PHYS_NET_NAME" "M_J_MA<12>"
					( Origin gPackager )
				)
				( attribute "PNN" "M_J_MA<12>"
					( Origin gPackager )
				)
				( objectStatus "M_J_MA<12>" )
			)
			( signal "@baseboard_fab2_lib.baseboard_fab2(sch_1):m_j_ma(13)"
				( attribute "CDS_PHYS_NET_NAME" "M_J_MA<13>"
					( Origin gPackager )
				)
				( attribute "PNN" "M_J_MA<13>"
					( Origin gPackager )
				)
				( objectStatus "M_J_MA<13>" )
			)
			( signal "@baseboard_fab2_lib.baseboard_fab2(sch_1):m_j_ma(14)"
				( attribute "CDS_PHYS_NET_NAME" "M_J_MA<14>"
					( Origin gPackager )
				)
				( attribute "PNN" "M_J_MA<14>"
					( Origin gPackager )
				)
				( objectStatus "M_J_MA<14>" )
			)
			( signal "@baseboard_fab2_lib.baseboard_fab2(sch_1):m_j_ma(15)"
				( attribute "CDS_PHYS_NET_NAME" "M_J_MA<15>"
					( Origin gPackager )
				)
				( attribute "PNN" "M_J_MA<15>"
					( Origin gPackager )
				)
				( objectStatus "M_J_MA<15>" )
			)
			( signal "@baseboard_fab2_lib.baseboard_fab2(sch_1):m_j_ma(16)"
				( attribute "CDS_PHYS_NET_NAME" "M_J_MA<16>"
					( Origin gPackager )
				)
				( attribute "PNN" "M_J_MA<16>"
					( Origin gPackager )
				)
				( objectStatus "M_J_MA<16>" )
			)
			( signal "@baseboard_fab2_lib.baseboard_fab2(sch_1):m_j_ma(17)"
				( attribute "CDS_PHYS_NET_NAME" "M_J_MA<17>"
					( Origin gPackager )
				)
				( attribute "PNN" "M_J_MA<17>"
					( Origin gPackager )
				)
				( objectStatus "M_J_MA<17>" )
			)
			( signal "@baseboard_fab2_lib.baseboard_fab2(sch_1):m_j_odt(0)"
				( attribute "CDS_PHYS_NET_NAME" "M_J_ODT<0>"
					( Origin gPackager )
				)
				( attribute "PNN" "M_J_ODT<0>"
					( Origin gPackager )
				)
				( objectStatus "M_J_ODT<0>" )
			)
			( signal "@baseboard_fab2_lib.baseboard_fab2(sch_1):m_j_odt(1)"
				( attribute "CDS_PHYS_NET_NAME" "M_J_ODT<1>"
					( Origin gPackager )
				)
				( attribute "PNN" "M_J_ODT<1>"
					( Origin gPackager )
				)
				( objectStatus "M_J_ODT<1>" )
			)
			( signal "@baseboard_fab2_lib.baseboard_fab2(sch_1):m_j_odt(2)"
				( attribute "CDS_PHYS_NET_NAME" "M_J_ODT<2>"
					( Origin gPackager )
				)
				( attribute "PNN" "M_J_ODT<2>"
					( Origin gPackager )
				)
				( objectStatus "M_J_ODT<2>" )
			)
			( signal "@baseboard_fab2_lib.baseboard_fab2(sch_1):m_j_odt(3)"
				( attribute "CDS_PHYS_NET_NAME" "M_J_ODT<3>"
					( Origin gPackager )
				)
				( attribute "PNN" "M_J_ODT<3>"
					( Origin gPackager )
				)
				( objectStatus "M_J_ODT<3>" )
			)
			( signal "@baseboard_fab2_lib.baseboard_fab2(sch_1):m_j_par"
				( attribute "CDS_PHYS_NET_NAME" "M_J_PAR"
					( Origin gPackager )
				)
				( objectStatus "M_J_PAR" )
			)
			( signal "@baseboard_fab2_lib.baseboard_fab2(sch_1):m_k_act_n"
				( attribute "CDS_PHYS_NET_NAME" "M_K_ACT_N"
					( Origin gPackager )
				)
				( objectStatus "M_K_ACT_N" )
			)
			( signal "@baseboard_fab2_lib.baseboard_fab2(sch_1):m_k_alert_n"
				( attribute "CDS_PHYS_NET_NAME" "M_K_ALERT_N"
					( Origin gPackager )
				)
				( objectStatus "M_K_ALERT_N" )
			)
			( signal "@baseboard_fab2_lib.baseboard_fab2(sch_1):m_k_ba(0)"
				( attribute "CDS_PHYS_NET_NAME" "M_K_BA<0>"
					( Origin gPackager )
				)
				( attribute "PNN" "M_K_BA<0>"
					( Origin gPackager )
				)
				( objectStatus "M_K_BA<0>" )
			)
			( signal "@baseboard_fab2_lib.baseboard_fab2(sch_1):m_k_ba(1)"
				( attribute "CDS_PHYS_NET_NAME" "M_K_BA<1>"
					( Origin gPackager )
				)
				( attribute "PNN" "M_K_BA<1>"
					( Origin gPackager )
				)
				( objectStatus "M_K_BA<1>" )
			)
			( signal "@baseboard_fab2_lib.baseboard_fab2(sch_1):m_k_bg(0)"
				( attribute "CDS_PHYS_NET_NAME" "M_K_BG<0>"
					( Origin gPackager )
				)
				( attribute "PNN" "M_K_BG<0>"
					( Origin gPackager )
				)
				( objectStatus "M_K_BG<0>" )
			)
			( signal "@baseboard_fab2_lib.baseboard_fab2(sch_1):m_k_bg(1)"
				( attribute "CDS_PHYS_NET_NAME" "M_K_BG<1>"
					( Origin gPackager )
				)
				( attribute "PNN" "M_K_BG<1>"
					( Origin gPackager )
				)
				( objectStatus "M_K_BG<1>" )
			)
			( signal "@baseboard_fab2_lib.baseboard_fab2(sch_1):m_k_c(2)"
				( attribute "CDS_PHYS_NET_NAME" "M_K_C<2>"
					( Origin gPackager )
				)
				( attribute "PNN" "M_K_C<2>"
					( Origin gPackager )
				)
				( objectStatus "M_K_C<2>" )
			)
			( signal "@baseboard_fab2_lib.baseboard_fab2(sch_1):m_k_cke(0)"
				( attribute "CDS_PHYS_NET_NAME" "M_K_CKE<0>"
					( Origin gPackager )
				)
				( attribute "PNN" "M_K_CKE<0>"
					( Origin gPackager )
				)
				( objectStatus "M_K_CKE<0>" )
			)
			( signal "@baseboard_fab2_lib.baseboard_fab2(sch_1):m_k_cke(1)"
				( attribute "CDS_PHYS_NET_NAME" "M_K_CKE<1>"
					( Origin gPackager )
				)
				( attribute "PNN" "M_K_CKE<1>"
					( Origin gPackager )
				)
				( objectStatus "M_K_CKE<1>" )
			)
			( signal "@baseboard_fab2_lib.baseboard_fab2(sch_1):m_k_cke(2)"
				( attribute "CDS_PHYS_NET_NAME" "M_K_CKE<2>"
					( Origin gPackager )
				)
				( attribute "PNN" "M_K_CKE<2>"
					( Origin gPackager )
				)
				( objectStatus "M_K_CKE<2>" )
			)
			( signal "@baseboard_fab2_lib.baseboard_fab2(sch_1):m_k_cke(3)"
				( attribute "CDS_PHYS_NET_NAME" "M_K_CKE<3>"
					( Origin gPackager )
				)
				( attribute "PNN" "M_K_CKE<3>"
					( Origin gPackager )
				)
				( objectStatus "M_K_CKE<3>" )
			)
			( signal "@baseboard_fab2_lib.baseboard_fab2(sch_1):m_k_clk_dn(0)"
				( attribute "CDS_PHYS_NET_NAME" "M_K_CLK_DN<0>"
					( Origin gPackager )
				)
				( attribute "PNN" "M_K_CLK_DN<0>"
					( Origin gPackager )
				)
				( objectStatus "M_K_CLK_DN<0>" )
			)
			( signal "@baseboard_fab2_lib.baseboard_fab2(sch_1):m_k_clk_dn(1)"
				( attribute "CDS_PHYS_NET_NAME" "M_K_CLK_DN<1>"
					( Origin gPackager )
				)
				( attribute "PNN" "M_K_CLK_DN<1>"
					( Origin gPackager )
				)
				( objectStatus "M_K_CLK_DN<1>" )
			)
			( signal "@baseboard_fab2_lib.baseboard_fab2(sch_1):m_k_clk_dn(2)"
				( attribute "CDS_PHYS_NET_NAME" "M_K_CLK_DN<2>"
					( Origin gPackager )
				)
				( attribute "PNN" "M_K_CLK_DN<2>"
					( Origin gPackager )
				)
				( objectStatus "M_K_CLK_DN<2>" )
			)
			( signal "@baseboard_fab2_lib.baseboard_fab2(sch_1):m_k_clk_dn(3)"
				( attribute "CDS_PHYS_NET_NAME" "M_K_CLK_DN<3>"
					( Origin gPackager )
				)
				( attribute "PNN" "M_K_CLK_DN<3>"
					( Origin gPackager )
				)
				( objectStatus "M_K_CLK_DN<3>" )
			)
			( signal "@baseboard_fab2_lib.baseboard_fab2(sch_1):m_k_clk_dp(0)"
				( attribute "CDS_PHYS_NET_NAME" "M_K_CLK_DP<0>"
					( Origin gPackager )
				)
				( attribute "PNN" "M_K_CLK_DP<0>"
					( Origin gPackager )
				)
				( objectStatus "M_K_CLK_DP<0>" )
			)
			( signal "@baseboard_fab2_lib.baseboard_fab2(sch_1):m_k_clk_dp(1)"
				( attribute "CDS_PHYS_NET_NAME" "M_K_CLK_DP<1>"
					( Origin gPackager )
				)
				( attribute "PNN" "M_K_CLK_DP<1>"
					( Origin gPackager )
				)
				( objectStatus "M_K_CLK_DP<1>" )
			)
			( signal "@baseboard_fab2_lib.baseboard_fab2(sch_1):m_k_clk_dp(2)"
				( attribute "CDS_PHYS_NET_NAME" "M_K_CLK_DP<2>"
					( Origin gPackager )
				)
				( attribute "PNN" "M_K_CLK_DP<2>"
					( Origin gPackager )
				)
				( objectStatus "M_K_CLK_DP<2>" )
			)
			( signal "@baseboard_fab2_lib.baseboard_fab2(sch_1):m_k_clk_dp(3)"
				( attribute "CDS_PHYS_NET_NAME" "M_K_CLK_DP<3>"
					( Origin gPackager )
				)
				( attribute "PNN" "M_K_CLK_DP<3>"
					( Origin gPackager )
				)
				( objectStatus "M_K_CLK_DP<3>" )
			)
			( signal "@baseboard_fab2_lib.baseboard_fab2(sch_1):m_k_cs_n(0)"
				( attribute "CDS_PHYS_NET_NAME" "M_K_CS_N<0>"
					( Origin gPackager )
				)
				( attribute "PNN" "M_K_CS_N<0>"
					( Origin gPackager )
				)
				( objectStatus "M_K_CS_N<0>" )
			)
			( signal "@baseboard_fab2_lib.baseboard_fab2(sch_1):m_k_cs_n(1)"
				( attribute "CDS_PHYS_NET_NAME" "M_K_CS_N<1>"
					( Origin gPackager )
				)
				( attribute "PNN" "M_K_CS_N<1>"
					( Origin gPackager )
				)
				( objectStatus "M_K_CS_N<1>" )
			)
			( signal "@baseboard_fab2_lib.baseboard_fab2(sch_1):m_k_cs_n(2)"
				( attribute "CDS_PHYS_NET_NAME" "M_K_CS_N<2>"
					( Origin gPackager )
				)
				( attribute "PNN" "M_K_CS_N<2>"
					( Origin gPackager )
				)
				( objectStatus "M_K_CS_N<2>" )
			)
			( signal "@baseboard_fab2_lib.baseboard_fab2(sch_1):m_k_cs_n(3)"
				( attribute "CDS_PHYS_NET_NAME" "M_K_CS_N<3>"
					( Origin gPackager )
				)
				( attribute "PNN" "M_K_CS_N<3>"
					( Origin gPackager )
				)
				( objectStatus "M_K_CS_N<3>" )
			)
			( signal "@baseboard_fab2_lib.baseboard_fab2(sch_1):m_k_cs_n(4)"
				( attribute "CDS_PHYS_NET_NAME" "M_K_CS_N<4>"
					( Origin gPackager )
				)
				( attribute "PNN" "M_K_CS_N<4>"
					( Origin gPackager )
				)
				( objectStatus "M_K_CS_N<4>" )
			)
			( signal "@baseboard_fab2_lib.baseboard_fab2(sch_1):m_k_cs_n(5)"
				( attribute "CDS_PHYS_NET_NAME" "M_K_CS_N<5>"
					( Origin gPackager )
				)
				( attribute "PNN" "M_K_CS_N<5>"
					( Origin gPackager )
				)
				( objectStatus "M_K_CS_N<5>" )
			)
			( signal "@baseboard_fab2_lib.baseboard_fab2(sch_1):m_k_cs_n(6)"
				( attribute "CDS_PHYS_NET_NAME" "M_K_CS_N<6>"
					( Origin gPackager )
				)
				( attribute "PNN" "M_K_CS_N<6>"
					( Origin gPackager )
				)
				( objectStatus "M_K_CS_N<6>" )
			)
			( signal "@baseboard_fab2_lib.baseboard_fab2(sch_1):m_k_cs_n(7)"
				( attribute "CDS_PHYS_NET_NAME" "M_K_CS_N<7>"
					( Origin gPackager )
				)
				( attribute "PNN" "M_K_CS_N<7>"
					( Origin gPackager )
				)
				( objectStatus "M_K_CS_N<7>" )
			)
			( signal "@baseboard_fab2_lib.baseboard_fab2(sch_1):m_k_dq(0)"
				( attribute "CDS_PHYS_NET_NAME" "M_K_DQ<0>"
					( Origin gPackager )
				)
				( attribute "PNN" "M_K_DQ<0>"
					( Origin gPackager )
				)
				( objectStatus "M_K_DQ<0>" )
			)
			( signal "@baseboard_fab2_lib.baseboard_fab2(sch_1):m_k_dq(1)"
				( attribute "CDS_PHYS_NET_NAME" "M_K_DQ<1>"
					( Origin gPackager )
				)
				( attribute "PNN" "M_K_DQ<1>"
					( Origin gPackager )
				)
				( objectStatus "M_K_DQ<1>" )
			)
			( signal "@baseboard_fab2_lib.baseboard_fab2(sch_1):m_k_dq(2)"
				( attribute "CDS_PHYS_NET_NAME" "M_K_DQ<2>"
					( Origin gPackager )
				)
				( attribute "PNN" "M_K_DQ<2>"
					( Origin gPackager )
				)
				( objectStatus "M_K_DQ<2>" )
			)
			( signal "@baseboard_fab2_lib.baseboard_fab2(sch_1):m_k_dq(3)"
				( attribute "CDS_PHYS_NET_NAME" "M_K_DQ<3>"
					( Origin gPackager )
				)
				( attribute "PNN" "M_K_DQ<3>"
					( Origin gPackager )
				)
				( objectStatus "M_K_DQ<3>" )
			)
			( signal "@baseboard_fab2_lib.baseboard_fab2(sch_1):m_k_dq(4)"
				( attribute "CDS_PHYS_NET_NAME" "M_K_DQ<4>"
					( Origin gPackager )
				)
				( attribute "PNN" "M_K_DQ<4>"
					( Origin gPackager )
				)
				( objectStatus "M_K_DQ<4>" )
			)
			( signal "@baseboard_fab2_lib.baseboard_fab2(sch_1):m_k_dq(5)"
				( attribute "CDS_PHYS_NET_NAME" "M_K_DQ<5>"
					( Origin gPackager )
				)
				( attribute "PNN" "M_K_DQ<5>"
					( Origin gPackager )
				)
				( objectStatus "M_K_DQ<5>" )
			)
			( signal "@baseboard_fab2_lib.baseboard_fab2(sch_1):m_k_dq(6)"
				( attribute "CDS_PHYS_NET_NAME" "M_K_DQ<6>"
					( Origin gPackager )
				)
				( attribute "PNN" "M_K_DQ<6>"
					( Origin gPackager )
				)
				( objectStatus "M_K_DQ<6>" )
			)
			( signal "@baseboard_fab2_lib.baseboard_fab2(sch_1):m_k_dq(7)"
				( attribute "CDS_PHYS_NET_NAME" "M_K_DQ<7>"
					( Origin gPackager )
				)
				( attribute "PNN" "M_K_DQ<7>"
					( Origin gPackager )
				)
				( objectStatus "M_K_DQ<7>" )
			)
			( signal "@baseboard_fab2_lib.baseboard_fab2(sch_1):m_k_dq(8)"
				( attribute "CDS_PHYS_NET_NAME" "M_K_DQ<8>"
					( Origin gPackager )
				)
				( attribute "PNN" "M_K_DQ<8>"
					( Origin gPackager )
				)
				( objectStatus "M_K_DQ<8>" )
			)
			( signal "@baseboard_fab2_lib.baseboard_fab2(sch_1):m_k_dq(9)"
				( attribute "CDS_PHYS_NET_NAME" "M_K_DQ<9>"
					( Origin gPackager )
				)
				( attribute "PNN" "M_K_DQ<9>"
					( Origin gPackager )
				)
				( objectStatus "M_K_DQ<9>" )
			)
			( signal "@baseboard_fab2_lib.baseboard_fab2(sch_1):m_k_dq(10)"
				( attribute "CDS_PHYS_NET_NAME" "M_K_DQ<10>"
					( Origin gPackager )
				)
				( attribute "PNN" "M_K_DQ<10>"
					( Origin gPackager )
				)
				( objectStatus "M_K_DQ<10>" )
			)
			( signal "@baseboard_fab2_lib.baseboard_fab2(sch_1):m_k_dq(11)"
				( attribute "CDS_PHYS_NET_NAME" "M_K_DQ<11>"
					( Origin gPackager )
				)
				( attribute "PNN" "M_K_DQ<11>"
					( Origin gPackager )
				)
				( objectStatus "M_K_DQ<11>" )
			)
			( signal "@baseboard_fab2_lib.baseboard_fab2(sch_1):m_k_dq(12)"
				( attribute "CDS_PHYS_NET_NAME" "M_K_DQ<12>"
					( Origin gPackager )
				)
				( attribute "PNN" "M_K_DQ<12>"
					( Origin gPackager )
				)
				( objectStatus "M_K_DQ<12>" )
			)
			( signal "@baseboard_fab2_lib.baseboard_fab2(sch_1):m_k_dq(13)"
				( attribute "CDS_PHYS_NET_NAME" "M_K_DQ<13>"
					( Origin gPackager )
				)
				( attribute "PNN" "M_K_DQ<13>"
					( Origin gPackager )
				)
				( objectStatus "M_K_DQ<13>" )
			)
			( signal "@baseboard_fab2_lib.baseboard_fab2(sch_1):m_k_dq(14)"
				( attribute "CDS_PHYS_NET_NAME" "M_K_DQ<14>"
					( Origin gPackager )
				)
				( attribute "PNN" "M_K_DQ<14>"
					( Origin gPackager )
				)
				( objectStatus "M_K_DQ<14>" )
			)
			( signal "@baseboard_fab2_lib.baseboard_fab2(sch_1):m_k_dq(15)"
				( attribute "CDS_PHYS_NET_NAME" "M_K_DQ<15>"
					( Origin gPackager )
				)
				( attribute "PNN" "M_K_DQ<15>"
					( Origin gPackager )
				)
				( objectStatus "M_K_DQ<15>" )
			)
			( signal "@baseboard_fab2_lib.baseboard_fab2(sch_1):m_k_dq(16)"
				( attribute "CDS_PHYS_NET_NAME" "M_K_DQ<16>"
					( Origin gPackager )
				)
				( attribute "PNN" "M_K_DQ<16>"
					( Origin gPackager )
				)
				( objectStatus "M_K_DQ<16>" )
			)
			( signal "@baseboard_fab2_lib.baseboard_fab2(sch_1):m_k_dq(17)"
				( attribute "CDS_PHYS_NET_NAME" "M_K_DQ<17>"
					( Origin gPackager )
				)
				( attribute "PNN" "M_K_DQ<17>"
					( Origin gPackager )
				)
				( objectStatus "M_K_DQ<17>" )
			)
			( signal "@baseboard_fab2_lib.baseboard_fab2(sch_1):m_k_dq(18)"
				( attribute "CDS_PHYS_NET_NAME" "M_K_DQ<18>"
					( Origin gPackager )
				)
				( attribute "PNN" "M_K_DQ<18>"
					( Origin gPackager )
				)
				( objectStatus "M_K_DQ<18>" )
			)
			( signal "@baseboard_fab2_lib.baseboard_fab2(sch_1):m_k_dq(19)"
				( attribute "CDS_PHYS_NET_NAME" "M_K_DQ<19>"
					( Origin gPackager )
				)
				( attribute "PNN" "M_K_DQ<19>"
					( Origin gPackager )
				)
				( objectStatus "M_K_DQ<19>" )
			)
			( signal "@baseboard_fab2_lib.baseboard_fab2(sch_1):m_k_dq(20)"
				( attribute "CDS_PHYS_NET_NAME" "M_K_DQ<20>"
					( Origin gPackager )
				)
				( attribute "PNN" "M_K_DQ<20>"
					( Origin gPackager )
				)
				( objectStatus "M_K_DQ<20>" )
			)
			( signal "@baseboard_fab2_lib.baseboard_fab2(sch_1):m_k_dq(21)"
				( attribute "CDS_PHYS_NET_NAME" "M_K_DQ<21>"
					( Origin gPackager )
				)
				( attribute "PNN" "M_K_DQ<21>"
					( Origin gPackager )
				)
				( objectStatus "M_K_DQ<21>" )
			)
			( signal "@baseboard_fab2_lib.baseboard_fab2(sch_1):m_k_dq(22)"
				( attribute "CDS_PHYS_NET_NAME" "M_K_DQ<22>"
					( Origin gPackager )
				)
				( attribute "PNN" "M_K_DQ<22>"
					( Origin gPackager )
				)
				( objectStatus "M_K_DQ<22>" )
			)
			( signal "@baseboard_fab2_lib.baseboard_fab2(sch_1):m_k_dq(23)"
				( attribute "CDS_PHYS_NET_NAME" "M_K_DQ<23>"
					( Origin gPackager )
				)
				( attribute "PNN" "M_K_DQ<23>"
					( Origin gPackager )
				)
				( objectStatus "M_K_DQ<23>" )
			)
			( signal "@baseboard_fab2_lib.baseboard_fab2(sch_1):m_k_dq(24)"
				( attribute "CDS_PHYS_NET_NAME" "M_K_DQ<24>"
					( Origin gPackager )
				)
				( attribute "PNN" "M_K_DQ<24>"
					( Origin gPackager )
				)
				( objectStatus "M_K_DQ<24>" )
			)
			( signal "@baseboard_fab2_lib.baseboard_fab2(sch_1):m_k_dq(25)"
				( attribute "CDS_PHYS_NET_NAME" "M_K_DQ<25>"
					( Origin gPackager )
				)
				( attribute "PNN" "M_K_DQ<25>"
					( Origin gPackager )
				)
				( objectStatus "M_K_DQ<25>" )
			)
			( signal "@baseboard_fab2_lib.baseboard_fab2(sch_1):m_k_dq(26)"
				( attribute "CDS_PHYS_NET_NAME" "M_K_DQ<26>"
					( Origin gPackager )
				)
				( attribute "PNN" "M_K_DQ<26>"
					( Origin gPackager )
				)
				( objectStatus "M_K_DQ<26>" )
			)
			( signal "@baseboard_fab2_lib.baseboard_fab2(sch_1):m_k_dq(27)"
				( attribute "CDS_PHYS_NET_NAME" "M_K_DQ<27>"
					( Origin gPackager )
				)
				( attribute "PNN" "M_K_DQ<27>"
					( Origin gPackager )
				)
				( objectStatus "M_K_DQ<27>" )
			)
			( signal "@baseboard_fab2_lib.baseboard_fab2(sch_1):m_k_dq(28)"
				( attribute "CDS_PHYS_NET_NAME" "M_K_DQ<28>"
					( Origin gPackager )
				)
				( attribute "PNN" "M_K_DQ<28>"
					( Origin gPackager )
				)
				( objectStatus "M_K_DQ<28>" )
			)
			( signal "@baseboard_fab2_lib.baseboard_fab2(sch_1):m_k_dq(29)"
				( attribute "CDS_PHYS_NET_NAME" "M_K_DQ<29>"
					( Origin gPackager )
				)
				( attribute "PNN" "M_K_DQ<29>"
					( Origin gPackager )
				)
				( objectStatus "M_K_DQ<29>" )
			)
			( signal "@baseboard_fab2_lib.baseboard_fab2(sch_1):m_k_dq(30)"
				( attribute "CDS_PHYS_NET_NAME" "M_K_DQ<30>"
					( Origin gPackager )
				)
				( attribute "PNN" "M_K_DQ<30>"
					( Origin gPackager )
				)
				( objectStatus "M_K_DQ<30>" )
			)
			( signal "@baseboard_fab2_lib.baseboard_fab2(sch_1):m_k_dq(31)"
				( attribute "CDS_PHYS_NET_NAME" "M_K_DQ<31>"
					( Origin gPackager )
				)
				( attribute "PNN" "M_K_DQ<31>"
					( Origin gPackager )
				)
				( objectStatus "M_K_DQ<31>" )
			)
			( signal "@baseboard_fab2_lib.baseboard_fab2(sch_1):m_k_dq(32)"
				( attribute "CDS_PHYS_NET_NAME" "M_K_DQ<32>"
					( Origin gPackager )
				)
				( attribute "PNN" "M_K_DQ<32>"
					( Origin gPackager )
				)
				( objectStatus "M_K_DQ<32>" )
			)
			( signal "@baseboard_fab2_lib.baseboard_fab2(sch_1):m_k_dq(33)"
				( attribute "CDS_PHYS_NET_NAME" "M_K_DQ<33>"
					( Origin gPackager )
				)
				( attribute "PNN" "M_K_DQ<33>"
					( Origin gPackager )
				)
				( objectStatus "M_K_DQ<33>" )
			)
			( signal "@baseboard_fab2_lib.baseboard_fab2(sch_1):m_k_dq(34)"
				( attribute "CDS_PHYS_NET_NAME" "M_K_DQ<34>"
					( Origin gPackager )
				)
				( attribute "PNN" "M_K_DQ<34>"
					( Origin gPackager )
				)
				( objectStatus "M_K_DQ<34>" )
			)
			( signal "@baseboard_fab2_lib.baseboard_fab2(sch_1):m_k_dq(35)"
				( attribute "CDS_PHYS_NET_NAME" "M_K_DQ<35>"
					( Origin gPackager )
				)
				( attribute "PNN" "M_K_DQ<35>"
					( Origin gPackager )
				)
				( objectStatus "M_K_DQ<35>" )
			)
			( signal "@baseboard_fab2_lib.baseboard_fab2(sch_1):m_k_dq(36)"
				( attribute "CDS_PHYS_NET_NAME" "M_K_DQ<36>"
					( Origin gPackager )
				)
				( attribute "PNN" "M_K_DQ<36>"
					( Origin gPackager )
				)
				( objectStatus "M_K_DQ<36>" )
			)
			( signal "@baseboard_fab2_lib.baseboard_fab2(sch_1):m_k_dq(37)"
				( attribute "CDS_PHYS_NET_NAME" "M_K_DQ<37>"
					( Origin gPackager )
				)
				( attribute "PNN" "M_K_DQ<37>"
					( Origin gPackager )
				)
				( objectStatus "M_K_DQ<37>" )
			)
			( signal "@baseboard_fab2_lib.baseboard_fab2(sch_1):m_k_dq(38)"
				( attribute "CDS_PHYS_NET_NAME" "M_K_DQ<38>"
					( Origin gPackager )
				)
				( attribute "PNN" "M_K_DQ<38>"
					( Origin gPackager )
				)
				( objectStatus "M_K_DQ<38>" )
			)
			( signal "@baseboard_fab2_lib.baseboard_fab2(sch_1):m_k_dq(39)"
				( attribute "CDS_PHYS_NET_NAME" "M_K_DQ<39>"
					( Origin gPackager )
				)
				( attribute "PNN" "M_K_DQ<39>"
					( Origin gPackager )
				)
				( objectStatus "M_K_DQ<39>" )
			)
			( signal "@baseboard_fab2_lib.baseboard_fab2(sch_1):m_k_dq(40)"
				( attribute "CDS_PHYS_NET_NAME" "M_K_DQ<40>"
					( Origin gPackager )
				)
				( attribute "PNN" "M_K_DQ<40>"
					( Origin gPackager )
				)
				( objectStatus "M_K_DQ<40>" )
			)
			( signal "@baseboard_fab2_lib.baseboard_fab2(sch_1):m_k_dq(41)"
				( attribute "CDS_PHYS_NET_NAME" "M_K_DQ<41>"
					( Origin gPackager )
				)
				( attribute "PNN" "M_K_DQ<41>"
					( Origin gPackager )
				)
				( objectStatus "M_K_DQ<41>" )
			)
			( signal "@baseboard_fab2_lib.baseboard_fab2(sch_1):m_k_dq(42)"
				( attribute "CDS_PHYS_NET_NAME" "M_K_DQ<42>"
					( Origin gPackager )
				)
				( attribute "PNN" "M_K_DQ<42>"
					( Origin gPackager )
				)
				( objectStatus "M_K_DQ<42>" )
			)
			( signal "@baseboard_fab2_lib.baseboard_fab2(sch_1):m_k_dq(43)"
				( attribute "CDS_PHYS_NET_NAME" "M_K_DQ<43>"
					( Origin gPackager )
				)
				( attribute "PNN" "M_K_DQ<43>"
					( Origin gPackager )
				)
				( objectStatus "M_K_DQ<43>" )
			)
			( signal "@baseboard_fab2_lib.baseboard_fab2(sch_1):m_k_dq(44)"
				( attribute "CDS_PHYS_NET_NAME" "M_K_DQ<44>"
					( Origin gPackager )
				)
				( attribute "PNN" "M_K_DQ<44>"
					( Origin gPackager )
				)
				( objectStatus "M_K_DQ<44>" )
			)
			( signal "@baseboard_fab2_lib.baseboard_fab2(sch_1):m_k_dq(45)"
				( attribute "CDS_PHYS_NET_NAME" "M_K_DQ<45>"
					( Origin gPackager )
				)
				( attribute "PNN" "M_K_DQ<45>"
					( Origin gPackager )
				)
				( objectStatus "M_K_DQ<45>" )
			)
			( signal "@baseboard_fab2_lib.baseboard_fab2(sch_1):m_k_dq(46)"
				( attribute "CDS_PHYS_NET_NAME" "M_K_DQ<46>"
					( Origin gPackager )
				)
				( attribute "PNN" "M_K_DQ<46>"
					( Origin gPackager )
				)
				( objectStatus "M_K_DQ<46>" )
			)
			( signal "@baseboard_fab2_lib.baseboard_fab2(sch_1):m_k_dq(47)"
				( attribute "CDS_PHYS_NET_NAME" "M_K_DQ<47>"
					( Origin gPackager )
				)
				( attribute "PNN" "M_K_DQ<47>"
					( Origin gPackager )
				)
				( objectStatus "M_K_DQ<47>" )
			)
			( signal "@baseboard_fab2_lib.baseboard_fab2(sch_1):m_k_dq(48)"
				( attribute "CDS_PHYS_NET_NAME" "M_K_DQ<48>"
					( Origin gPackager )
				)
				( attribute "PNN" "M_K_DQ<48>"
					( Origin gPackager )
				)
				( objectStatus "M_K_DQ<48>" )
			)
			( signal "@baseboard_fab2_lib.baseboard_fab2(sch_1):m_k_dq(49)"
				( attribute "CDS_PHYS_NET_NAME" "M_K_DQ<49>"
					( Origin gPackager )
				)
				( attribute "PNN" "M_K_DQ<49>"
					( Origin gPackager )
				)
				( objectStatus "M_K_DQ<49>" )
			)
			( signal "@baseboard_fab2_lib.baseboard_fab2(sch_1):m_k_dq(50)"
				( attribute "CDS_PHYS_NET_NAME" "M_K_DQ<50>"
					( Origin gPackager )
				)
				( attribute "PNN" "M_K_DQ<50>"
					( Origin gPackager )
				)
				( objectStatus "M_K_DQ<50>" )
			)
			( signal "@baseboard_fab2_lib.baseboard_fab2(sch_1):m_k_dq(51)"
				( attribute "CDS_PHYS_NET_NAME" "M_K_DQ<51>"
					( Origin gPackager )
				)
				( attribute "PNN" "M_K_DQ<51>"
					( Origin gPackager )
				)
				( objectStatus "M_K_DQ<51>" )
			)
			( signal "@baseboard_fab2_lib.baseboard_fab2(sch_1):m_k_dq(52)"
				( attribute "CDS_PHYS_NET_NAME" "M_K_DQ<52>"
					( Origin gPackager )
				)
				( attribute "PNN" "M_K_DQ<52>"
					( Origin gPackager )
				)
				( objectStatus "M_K_DQ<52>" )
			)
			( signal "@baseboard_fab2_lib.baseboard_fab2(sch_1):m_k_dq(53)"
				( attribute "CDS_PHYS_NET_NAME" "M_K_DQ<53>"
					( Origin gPackager )
				)
				( attribute "PNN" "M_K_DQ<53>"
					( Origin gPackager )
				)
				( objectStatus "M_K_DQ<53>" )
			)
			( signal "@baseboard_fab2_lib.baseboard_fab2(sch_1):m_k_dq(54)"
				( attribute "CDS_PHYS_NET_NAME" "M_K_DQ<54>"
					( Origin gPackager )
				)
				( attribute "PNN" "M_K_DQ<54>"
					( Origin gPackager )
				)
				( objectStatus "M_K_DQ<54>" )
			)
			( signal "@baseboard_fab2_lib.baseboard_fab2(sch_1):m_k_dq(55)"
				( attribute "CDS_PHYS_NET_NAME" "M_K_DQ<55>"
					( Origin gPackager )
				)
				( attribute "PNN" "M_K_DQ<55>"
					( Origin gPackager )
				)
				( objectStatus "M_K_DQ<55>" )
			)
			( signal "@baseboard_fab2_lib.baseboard_fab2(sch_1):m_k_dq(56)"
				( attribute "CDS_PHYS_NET_NAME" "M_K_DQ<56>"
					( Origin gPackager )
				)
				( attribute "PNN" "M_K_DQ<56>"
					( Origin gPackager )
				)
				( objectStatus "M_K_DQ<56>" )
			)
			( signal "@baseboard_fab2_lib.baseboard_fab2(sch_1):m_k_dq(57)"
				( attribute "CDS_PHYS_NET_NAME" "M_K_DQ<57>"
					( Origin gPackager )
				)
				( attribute "PNN" "M_K_DQ<57>"
					( Origin gPackager )
				)
				( objectStatus "M_K_DQ<57>" )
			)
			( signal "@baseboard_fab2_lib.baseboard_fab2(sch_1):m_k_dq(58)"
				( attribute "CDS_PHYS_NET_NAME" "M_K_DQ<58>"
					( Origin gPackager )
				)
				( attribute "PNN" "M_K_DQ<58>"
					( Origin gPackager )
				)
				( objectStatus "M_K_DQ<58>" )
			)
			( signal "@baseboard_fab2_lib.baseboard_fab2(sch_1):m_k_dq(59)"
				( attribute "CDS_PHYS_NET_NAME" "M_K_DQ<59>"
					( Origin gPackager )
				)
				( attribute "PNN" "M_K_DQ<59>"
					( Origin gPackager )
				)
				( objectStatus "M_K_DQ<59>" )
			)
			( signal "@baseboard_fab2_lib.baseboard_fab2(sch_1):m_k_dq(60)"
				( attribute "CDS_PHYS_NET_NAME" "M_K_DQ<60>"
					( Origin gPackager )
				)
				( attribute "PNN" "M_K_DQ<60>"
					( Origin gPackager )
				)
				( objectStatus "M_K_DQ<60>" )
			)
			( signal "@baseboard_fab2_lib.baseboard_fab2(sch_1):m_k_dq(61)"
				( attribute "CDS_PHYS_NET_NAME" "M_K_DQ<61>"
					( Origin gPackager )
				)
				( attribute "PNN" "M_K_DQ<61>"
					( Origin gPackager )
				)
				( objectStatus "M_K_DQ<61>" )
			)
			( signal "@baseboard_fab2_lib.baseboard_fab2(sch_1):m_k_dq(62)"
				( attribute "CDS_PHYS_NET_NAME" "M_K_DQ<62>"
					( Origin gPackager )
				)
				( attribute "PNN" "M_K_DQ<62>"
					( Origin gPackager )
				)
				( objectStatus "M_K_DQ<62>" )
			)
			( signal "@baseboard_fab2_lib.baseboard_fab2(sch_1):m_k_dq(63)"
				( attribute "CDS_PHYS_NET_NAME" "M_K_DQ<63>"
					( Origin gPackager )
				)
				( attribute "PNN" "M_K_DQ<63>"
					( Origin gPackager )
				)
				( objectStatus "M_K_DQ<63>" )
			)
			( signal "@baseboard_fab2_lib.baseboard_fab2(sch_1):m_k_dqs_dn(0)"
				( attribute "CDS_PHYS_NET_NAME" "M_K_DQS_DN<0>"
					( Origin gPackager )
				)
				( attribute "PNN" "M_K_DQS_DN<0>"
					( Origin gPackager )
				)
				( objectStatus "M_K_DQS_DN<0>" )
			)
			( signal "@baseboard_fab2_lib.baseboard_fab2(sch_1):m_k_dqs_dn(1)"
				( attribute "CDS_PHYS_NET_NAME" "M_K_DQS_DN<1>"
					( Origin gPackager )
				)
				( attribute "PNN" "M_K_DQS_DN<1>"
					( Origin gPackager )
				)
				( objectStatus "M_K_DQS_DN<1>" )
			)
			( signal "@baseboard_fab2_lib.baseboard_fab2(sch_1):m_k_dqs_dn(2)"
				( attribute "CDS_PHYS_NET_NAME" "M_K_DQS_DN<2>"
					( Origin gPackager )
				)
				( attribute "PNN" "M_K_DQS_DN<2>"
					( Origin gPackager )
				)
				( objectStatus "M_K_DQS_DN<2>" )
			)
			( signal "@baseboard_fab2_lib.baseboard_fab2(sch_1):m_k_dqs_dn(3)"
				( attribute "CDS_PHYS_NET_NAME" "M_K_DQS_DN<3>"
					( Origin gPackager )
				)
				( attribute "PNN" "M_K_DQS_DN<3>"
					( Origin gPackager )
				)
				( objectStatus "M_K_DQS_DN<3>" )
			)
			( signal "@baseboard_fab2_lib.baseboard_fab2(sch_1):m_k_dqs_dn(4)"
				( attribute "CDS_PHYS_NET_NAME" "M_K_DQS_DN<4>"
					( Origin gPackager )
				)
				( attribute "PNN" "M_K_DQS_DN<4>"
					( Origin gPackager )
				)
				( objectStatus "M_K_DQS_DN<4>" )
			)
			( signal "@baseboard_fab2_lib.baseboard_fab2(sch_1):m_k_dqs_dn(5)"
				( attribute "CDS_PHYS_NET_NAME" "M_K_DQS_DN<5>"
					( Origin gPackager )
				)
				( attribute "PNN" "M_K_DQS_DN<5>"
					( Origin gPackager )
				)
				( objectStatus "M_K_DQS_DN<5>" )
			)
			( signal "@baseboard_fab2_lib.baseboard_fab2(sch_1):m_k_dqs_dn(6)"
				( attribute "CDS_PHYS_NET_NAME" "M_K_DQS_DN<6>"
					( Origin gPackager )
				)
				( attribute "PNN" "M_K_DQS_DN<6>"
					( Origin gPackager )
				)
				( objectStatus "M_K_DQS_DN<6>" )
			)
			( signal "@baseboard_fab2_lib.baseboard_fab2(sch_1):m_k_dqs_dn(7)"
				( attribute "CDS_PHYS_NET_NAME" "M_K_DQS_DN<7>"
					( Origin gPackager )
				)
				( attribute "PNN" "M_K_DQS_DN<7>"
					( Origin gPackager )
				)
				( objectStatus "M_K_DQS_DN<7>" )
			)
			( signal "@baseboard_fab2_lib.baseboard_fab2(sch_1):m_k_dqs_dn(8)"
				( attribute "CDS_PHYS_NET_NAME" "M_K_DQS_DN<8>"
					( Origin gPackager )
				)
				( attribute "PNN" "M_K_DQS_DN<8>"
					( Origin gPackager )
				)
				( objectStatus "M_K_DQS_DN<8>" )
			)
			( signal "@baseboard_fab2_lib.baseboard_fab2(sch_1):m_k_dqs_dn(9)"
				( attribute "CDS_PHYS_NET_NAME" "M_K_DQS_DN<9>"
					( Origin gPackager )
				)
				( attribute "PNN" "M_K_DQS_DN<9>"
					( Origin gPackager )
				)
				( objectStatus "M_K_DQS_DN<9>" )
			)
			( signal "@baseboard_fab2_lib.baseboard_fab2(sch_1):m_k_dqs_dn(10)"
				( attribute "CDS_PHYS_NET_NAME" "M_K_DQS_DN<10>"
					( Origin gPackager )
				)
				( attribute "PNN" "M_K_DQS_DN<10>"
					( Origin gPackager )
				)
				( objectStatus "M_K_DQS_DN<10>" )
			)
			( signal "@baseboard_fab2_lib.baseboard_fab2(sch_1):m_k_dqs_dn(11)"
				( attribute "CDS_PHYS_NET_NAME" "M_K_DQS_DN<11>"
					( Origin gPackager )
				)
				( attribute "PNN" "M_K_DQS_DN<11>"
					( Origin gPackager )
				)
				( objectStatus "M_K_DQS_DN<11>" )
			)
			( signal "@baseboard_fab2_lib.baseboard_fab2(sch_1):m_k_dqs_dn(12)"
				( attribute "CDS_PHYS_NET_NAME" "M_K_DQS_DN<12>"
					( Origin gPackager )
				)
				( attribute "PNN" "M_K_DQS_DN<12>"
					( Origin gPackager )
				)
				( objectStatus "M_K_DQS_DN<12>" )
			)
			( signal "@baseboard_fab2_lib.baseboard_fab2(sch_1):m_k_dqs_dn(13)"
				( attribute "CDS_PHYS_NET_NAME" "M_K_DQS_DN<13>"
					( Origin gPackager )
				)
				( attribute "PNN" "M_K_DQS_DN<13>"
					( Origin gPackager )
				)
				( objectStatus "M_K_DQS_DN<13>" )
			)
			( signal "@baseboard_fab2_lib.baseboard_fab2(sch_1):m_k_dqs_dn(14)"
				( attribute "CDS_PHYS_NET_NAME" "M_K_DQS_DN<14>"
					( Origin gPackager )
				)
				( attribute "PNN" "M_K_DQS_DN<14>"
					( Origin gPackager )
				)
				( objectStatus "M_K_DQS_DN<14>" )
			)
			( signal "@baseboard_fab2_lib.baseboard_fab2(sch_1):m_k_dqs_dn(15)"
				( attribute "CDS_PHYS_NET_NAME" "M_K_DQS_DN<15>"
					( Origin gPackager )
				)
				( attribute "PNN" "M_K_DQS_DN<15>"
					( Origin gPackager )
				)
				( objectStatus "M_K_DQS_DN<15>" )
			)
			( signal "@baseboard_fab2_lib.baseboard_fab2(sch_1):m_k_dqs_dn(16)"
				( attribute "CDS_PHYS_NET_NAME" "M_K_DQS_DN<16>"
					( Origin gPackager )
				)
				( attribute "PNN" "M_K_DQS_DN<16>"
					( Origin gPackager )
				)
				( objectStatus "M_K_DQS_DN<16>" )
			)
			( signal "@baseboard_fab2_lib.baseboard_fab2(sch_1):m_k_dqs_dn(17)"
				( attribute "CDS_PHYS_NET_NAME" "M_K_DQS_DN<17>"
					( Origin gPackager )
				)
				( attribute "PNN" "M_K_DQS_DN<17>"
					( Origin gPackager )
				)
				( objectStatus "M_K_DQS_DN<17>" )
			)
			( signal "@baseboard_fab2_lib.baseboard_fab2(sch_1):m_k_dqs_dp(0)"
				( attribute "CDS_PHYS_NET_NAME" "M_K_DQS_DP<0>"
					( Origin gPackager )
				)
				( attribute "PNN" "M_K_DQS_DP<0>"
					( Origin gPackager )
				)
				( objectStatus "M_K_DQS_DP<0>" )
			)
			( signal "@baseboard_fab2_lib.baseboard_fab2(sch_1):m_k_dqs_dp(1)"
				( attribute "CDS_PHYS_NET_NAME" "M_K_DQS_DP<1>"
					( Origin gPackager )
				)
				( attribute "PNN" "M_K_DQS_DP<1>"
					( Origin gPackager )
				)
				( objectStatus "M_K_DQS_DP<1>" )
			)
			( signal "@baseboard_fab2_lib.baseboard_fab2(sch_1):m_k_dqs_dp(2)"
				( attribute "CDS_PHYS_NET_NAME" "M_K_DQS_DP<2>"
					( Origin gPackager )
				)
				( attribute "PNN" "M_K_DQS_DP<2>"
					( Origin gPackager )
				)
				( objectStatus "M_K_DQS_DP<2>" )
			)
			( signal "@baseboard_fab2_lib.baseboard_fab2(sch_1):m_k_dqs_dp(3)"
				( attribute "CDS_PHYS_NET_NAME" "M_K_DQS_DP<3>"
					( Origin gPackager )
				)
				( attribute "PNN" "M_K_DQS_DP<3>"
					( Origin gPackager )
				)
				( objectStatus "M_K_DQS_DP<3>" )
			)
			( signal "@baseboard_fab2_lib.baseboard_fab2(sch_1):m_k_dqs_dp(4)"
				( attribute "CDS_PHYS_NET_NAME" "M_K_DQS_DP<4>"
					( Origin gPackager )
				)
				( attribute "PNN" "M_K_DQS_DP<4>"
					( Origin gPackager )
				)
				( objectStatus "M_K_DQS_DP<4>" )
			)
			( signal "@baseboard_fab2_lib.baseboard_fab2(sch_1):m_k_dqs_dp(5)"
				( attribute "CDS_PHYS_NET_NAME" "M_K_DQS_DP<5>"
					( Origin gPackager )
				)
				( attribute "PNN" "M_K_DQS_DP<5>"
					( Origin gPackager )
				)
				( objectStatus "M_K_DQS_DP<5>" )
			)
			( signal "@baseboard_fab2_lib.baseboard_fab2(sch_1):m_k_dqs_dp(6)"
				( attribute "CDS_PHYS_NET_NAME" "M_K_DQS_DP<6>"
					( Origin gPackager )
				)
				( attribute "PNN" "M_K_DQS_DP<6>"
					( Origin gPackager )
				)
				( objectStatus "M_K_DQS_DP<6>" )
			)
			( signal "@baseboard_fab2_lib.baseboard_fab2(sch_1):m_k_dqs_dp(7)"
				( attribute "CDS_PHYS_NET_NAME" "M_K_DQS_DP<7>"
					( Origin gPackager )
				)
				( attribute "PNN" "M_K_DQS_DP<7>"
					( Origin gPackager )
				)
				( objectStatus "M_K_DQS_DP<7>" )
			)
			( signal "@baseboard_fab2_lib.baseboard_fab2(sch_1):m_k_dqs_dp(8)"
				( attribute "CDS_PHYS_NET_NAME" "M_K_DQS_DP<8>"
					( Origin gPackager )
				)
				( attribute "PNN" "M_K_DQS_DP<8>"
					( Origin gPackager )
				)
				( objectStatus "M_K_DQS_DP<8>" )
			)
			( signal "@baseboard_fab2_lib.baseboard_fab2(sch_1):m_k_dqs_dp(9)"
				( attribute "CDS_PHYS_NET_NAME" "M_K_DQS_DP<9>"
					( Origin gPackager )
				)
				( attribute "PNN" "M_K_DQS_DP<9>"
					( Origin gPackager )
				)
				( objectStatus "M_K_DQS_DP<9>" )
			)
			( signal "@baseboard_fab2_lib.baseboard_fab2(sch_1):m_k_dqs_dp(10)"
				( attribute "CDS_PHYS_NET_NAME" "M_K_DQS_DP<10>"
					( Origin gPackager )
				)
				( attribute "PNN" "M_K_DQS_DP<10>"
					( Origin gPackager )
				)
				( objectStatus "M_K_DQS_DP<10>" )
			)
			( signal "@baseboard_fab2_lib.baseboard_fab2(sch_1):m_k_dqs_dp(11)"
				( attribute "CDS_PHYS_NET_NAME" "M_K_DQS_DP<11>"
					( Origin gPackager )
				)
				( attribute "PNN" "M_K_DQS_DP<11>"
					( Origin gPackager )
				)
				( objectStatus "M_K_DQS_DP<11>" )
			)
			( signal "@baseboard_fab2_lib.baseboard_fab2(sch_1):m_k_dqs_dp(12)"
				( attribute "CDS_PHYS_NET_NAME" "M_K_DQS_DP<12>"
					( Origin gPackager )
				)
				( attribute "PNN" "M_K_DQS_DP<12>"
					( Origin gPackager )
				)
				( objectStatus "M_K_DQS_DP<12>" )
			)
			( signal "@baseboard_fab2_lib.baseboard_fab2(sch_1):m_k_dqs_dp(13)"
				( attribute "CDS_PHYS_NET_NAME" "M_K_DQS_DP<13>"
					( Origin gPackager )
				)
				( attribute "PNN" "M_K_DQS_DP<13>"
					( Origin gPackager )
				)
				( objectStatus "M_K_DQS_DP<13>" )
			)
			( signal "@baseboard_fab2_lib.baseboard_fab2(sch_1):m_k_dqs_dp(14)"
				( attribute "CDS_PHYS_NET_NAME" "M_K_DQS_DP<14>"
					( Origin gPackager )
				)
				( attribute "PNN" "M_K_DQS_DP<14>"
					( Origin gPackager )
				)
				( objectStatus "M_K_DQS_DP<14>" )
			)
			( signal "@baseboard_fab2_lib.baseboard_fab2(sch_1):m_k_dqs_dp(15)"
				( attribute "CDS_PHYS_NET_NAME" "M_K_DQS_DP<15>"
					( Origin gPackager )
				)
				( attribute "PNN" "M_K_DQS_DP<15>"
					( Origin gPackager )
				)
				( objectStatus "M_K_DQS_DP<15>" )
			)
			( signal "@baseboard_fab2_lib.baseboard_fab2(sch_1):m_k_dqs_dp(16)"
				( attribute "CDS_PHYS_NET_NAME" "M_K_DQS_DP<16>"
					( Origin gPackager )
				)
				( attribute "PNN" "M_K_DQS_DP<16>"
					( Origin gPackager )
				)
				( objectStatus "M_K_DQS_DP<16>" )
			)
			( signal "@baseboard_fab2_lib.baseboard_fab2(sch_1):m_k_dqs_dp(17)"
				( attribute "CDS_PHYS_NET_NAME" "M_K_DQS_DP<17>"
					( Origin gPackager )
				)
				( attribute "PNN" "M_K_DQS_DP<17>"
					( Origin gPackager )
				)
				( objectStatus "M_K_DQS_DP<17>" )
			)
			( signal "@baseboard_fab2_lib.baseboard_fab2(sch_1):m_k_ecc(0)"
				( attribute "CDS_PHYS_NET_NAME" "M_K_ECC<0>"
					( Origin gPackager )
				)
				( attribute "PNN" "M_K_ECC<0>"
					( Origin gPackager )
				)
				( objectStatus "M_K_ECC<0>" )
			)
			( signal "@baseboard_fab2_lib.baseboard_fab2(sch_1):m_k_ecc(1)"
				( attribute "CDS_PHYS_NET_NAME" "M_K_ECC<1>"
					( Origin gPackager )
				)
				( attribute "PNN" "M_K_ECC<1>"
					( Origin gPackager )
				)
				( objectStatus "M_K_ECC<1>" )
			)
			( signal "@baseboard_fab2_lib.baseboard_fab2(sch_1):m_k_ecc(2)"
				( attribute "CDS_PHYS_NET_NAME" "M_K_ECC<2>"
					( Origin gPackager )
				)
				( attribute "PNN" "M_K_ECC<2>"
					( Origin gPackager )
				)
				( objectStatus "M_K_ECC<2>" )
			)
			( signal "@baseboard_fab2_lib.baseboard_fab2(sch_1):m_k_ecc(3)"
				( attribute "CDS_PHYS_NET_NAME" "M_K_ECC<3>"
					( Origin gPackager )
				)
				( attribute "PNN" "M_K_ECC<3>"
					( Origin gPackager )
				)
				( objectStatus "M_K_ECC<3>" )
			)
			( signal "@baseboard_fab2_lib.baseboard_fab2(sch_1):m_k_ecc(4)"
				( attribute "CDS_PHYS_NET_NAME" "M_K_ECC<4>"
					( Origin gPackager )
				)
				( attribute "PNN" "M_K_ECC<4>"
					( Origin gPackager )
				)
				( objectStatus "M_K_ECC<4>" )
			)
			( signal "@baseboard_fab2_lib.baseboard_fab2(sch_1):m_k_ecc(5)"
				( attribute "CDS_PHYS_NET_NAME" "M_K_ECC<5>"
					( Origin gPackager )
				)
				( attribute "PNN" "M_K_ECC<5>"
					( Origin gPackager )
				)
				( objectStatus "M_K_ECC<5>" )
			)
			( signal "@baseboard_fab2_lib.baseboard_fab2(sch_1):m_k_ecc(6)"
				( attribute "CDS_PHYS_NET_NAME" "M_K_ECC<6>"
					( Origin gPackager )
				)
				( attribute "PNN" "M_K_ECC<6>"
					( Origin gPackager )
				)
				( objectStatus "M_K_ECC<6>" )
			)
			( signal "@baseboard_fab2_lib.baseboard_fab2(sch_1):m_k_ecc(7)"
				( attribute "CDS_PHYS_NET_NAME" "M_K_ECC<7>"
					( Origin gPackager )
				)
				( attribute "PNN" "M_K_ECC<7>"
					( Origin gPackager )
				)
				( objectStatus "M_K_ECC<7>" )
			)
			( signal "@baseboard_fab2_lib.baseboard_fab2(sch_1):m_k_ma(0)"
				( attribute "CDS_PHYS_NET_NAME" "M_K_MA<0>"
					( Origin gPackager )
				)
				( attribute "PNN" "M_K_MA<0>"
					( Origin gPackager )
				)
				( objectStatus "M_K_MA<0>" )
			)
			( signal "@baseboard_fab2_lib.baseboard_fab2(sch_1):m_k_ma(1)"
				( attribute "CDS_PHYS_NET_NAME" "M_K_MA<1>"
					( Origin gPackager )
				)
				( attribute "PNN" "M_K_MA<1>"
					( Origin gPackager )
				)
				( objectStatus "M_K_MA<1>" )
			)
			( signal "@baseboard_fab2_lib.baseboard_fab2(sch_1):m_k_ma(2)"
				( attribute "CDS_PHYS_NET_NAME" "M_K_MA<2>"
					( Origin gPackager )
				)
				( attribute "PNN" "M_K_MA<2>"
					( Origin gPackager )
				)
				( objectStatus "M_K_MA<2>" )
			)
			( signal "@baseboard_fab2_lib.baseboard_fab2(sch_1):m_k_ma(3)"
				( attribute "CDS_PHYS_NET_NAME" "M_K_MA<3>"
					( Origin gPackager )
				)
				( attribute "PNN" "M_K_MA<3>"
					( Origin gPackager )
				)
				( objectStatus "M_K_MA<3>" )
			)
			( signal "@baseboard_fab2_lib.baseboard_fab2(sch_1):m_k_ma(4)"
				( attribute "CDS_PHYS_NET_NAME" "M_K_MA<4>"
					( Origin gPackager )
				)
				( attribute "PNN" "M_K_MA<4>"
					( Origin gPackager )
				)
				( objectStatus "M_K_MA<4>" )
			)
			( signal "@baseboard_fab2_lib.baseboard_fab2(sch_1):m_k_ma(5)"
				( attribute "CDS_PHYS_NET_NAME" "M_K_MA<5>"
					( Origin gPackager )
				)
				( attribute "PNN" "M_K_MA<5>"
					( Origin gPackager )
				)
				( objectStatus "M_K_MA<5>" )
			)
			( signal "@baseboard_fab2_lib.baseboard_fab2(sch_1):m_k_ma(6)"
				( attribute "CDS_PHYS_NET_NAME" "M_K_MA<6>"
					( Origin gPackager )
				)
				( attribute "PNN" "M_K_MA<6>"
					( Origin gPackager )
				)
				( objectStatus "M_K_MA<6>" )
			)
			( signal "@baseboard_fab2_lib.baseboard_fab2(sch_1):m_k_ma(7)"
				( attribute "CDS_PHYS_NET_NAME" "M_K_MA<7>"
					( Origin gPackager )
				)
				( attribute "PNN" "M_K_MA<7>"
					( Origin gPackager )
				)
				( objectStatus "M_K_MA<7>" )
			)
			( signal "@baseboard_fab2_lib.baseboard_fab2(sch_1):m_k_ma(8)"
				( attribute "CDS_PHYS_NET_NAME" "M_K_MA<8>"
					( Origin gPackager )
				)
				( attribute "PNN" "M_K_MA<8>"
					( Origin gPackager )
				)
				( objectStatus "M_K_MA<8>" )
			)
			( signal "@baseboard_fab2_lib.baseboard_fab2(sch_1):m_k_ma(9)"
				( attribute "CDS_PHYS_NET_NAME" "M_K_MA<9>"
					( Origin gPackager )
				)
				( attribute "PNN" "M_K_MA<9>"
					( Origin gPackager )
				)
				( objectStatus "M_K_MA<9>" )
			)
			( signal "@baseboard_fab2_lib.baseboard_fab2(sch_1):m_k_ma(10)"
				( attribute "CDS_PHYS_NET_NAME" "M_K_MA<10>"
					( Origin gPackager )
				)
				( attribute "PNN" "M_K_MA<10>"
					( Origin gPackager )
				)
				( objectStatus "M_K_MA<10>" )
			)
			( signal "@baseboard_fab2_lib.baseboard_fab2(sch_1):m_k_ma(11)"
				( attribute "CDS_PHYS_NET_NAME" "M_K_MA<11>"
					( Origin gPackager )
				)
				( attribute "PNN" "M_K_MA<11>"
					( Origin gPackager )
				)
				( objectStatus "M_K_MA<11>" )
			)
			( signal "@baseboard_fab2_lib.baseboard_fab2(sch_1):m_k_ma(12)"
				( attribute "CDS_PHYS_NET_NAME" "M_K_MA<12>"
					( Origin gPackager )
				)
				( attribute "PNN" "M_K_MA<12>"
					( Origin gPackager )
				)
				( objectStatus "M_K_MA<12>" )
			)
			( signal "@baseboard_fab2_lib.baseboard_fab2(sch_1):m_k_ma(13)"
				( attribute "CDS_PHYS_NET_NAME" "M_K_MA<13>"
					( Origin gPackager )
				)
				( attribute "PNN" "M_K_MA<13>"
					( Origin gPackager )
				)
				( objectStatus "M_K_MA<13>" )
			)
			( signal "@baseboard_fab2_lib.baseboard_fab2(sch_1):m_k_ma(14)"
				( attribute "CDS_PHYS_NET_NAME" "M_K_MA<14>"
					( Origin gPackager )
				)
				( attribute "PNN" "M_K_MA<14>"
					( Origin gPackager )
				)
				( objectStatus "M_K_MA<14>" )
			)
			( signal "@baseboard_fab2_lib.baseboard_fab2(sch_1):m_k_ma(15)"
				( attribute "CDS_PHYS_NET_NAME" "M_K_MA<15>"
					( Origin gPackager )
				)
				( attribute "PNN" "M_K_MA<15>"
					( Origin gPackager )
				)
				( objectStatus "M_K_MA<15>" )
			)
			( signal "@baseboard_fab2_lib.baseboard_fab2(sch_1):m_k_ma(16)"
				( attribute "CDS_PHYS_NET_NAME" "M_K_MA<16>"
					( Origin gPackager )
				)
				( attribute "PNN" "M_K_MA<16>"
					( Origin gPackager )
				)
				( objectStatus "M_K_MA<16>" )
			)
			( signal "@baseboard_fab2_lib.baseboard_fab2(sch_1):m_k_ma(17)"
				( attribute "CDS_PHYS_NET_NAME" "M_K_MA<17>"
					( Origin gPackager )
				)
				( attribute "PNN" "M_K_MA<17>"
					( Origin gPackager )
				)
				( objectStatus "M_K_MA<17>" )
			)
			( signal "@baseboard_fab2_lib.baseboard_fab2(sch_1):m_k_odt(0)"
				( attribute "CDS_PHYS_NET_NAME" "M_K_ODT<0>"
					( Origin gPackager )
				)
				( attribute "PNN" "M_K_ODT<0>"
					( Origin gPackager )
				)
				( objectStatus "M_K_ODT<0>" )
			)
			( signal "@baseboard_fab2_lib.baseboard_fab2(sch_1):m_k_odt(1)"
				( attribute "CDS_PHYS_NET_NAME" "M_K_ODT<1>"
					( Origin gPackager )
				)
				( attribute "PNN" "M_K_ODT<1>"
					( Origin gPackager )
				)
				( objectStatus "M_K_ODT<1>" )
			)
			( signal "@baseboard_fab2_lib.baseboard_fab2(sch_1):m_k_odt(2)"
				( attribute "CDS_PHYS_NET_NAME" "M_K_ODT<2>"
					( Origin gPackager )
				)
				( attribute "PNN" "M_K_ODT<2>"
					( Origin gPackager )
				)
				( objectStatus "M_K_ODT<2>" )
			)
			( signal "@baseboard_fab2_lib.baseboard_fab2(sch_1):m_k_odt(3)"
				( attribute "CDS_PHYS_NET_NAME" "M_K_ODT<3>"
					( Origin gPackager )
				)
				( attribute "PNN" "M_K_ODT<3>"
					( Origin gPackager )
				)
				( objectStatus "M_K_ODT<3>" )
			)
			( signal "@baseboard_fab2_lib.baseboard_fab2(sch_1):m_k_par"
				( attribute "CDS_PHYS_NET_NAME" "M_K_PAR"
					( Origin gPackager )
				)
				( objectStatus "M_K_PAR" )
			)
			( signal "@baseboard_fab2_lib.baseboard_fab2(sch_1):m_l_act_n"
				( attribute "CDS_PHYS_NET_NAME" "M_L_ACT_N"
					( Origin gPackager )
				)
				( objectStatus "M_L_ACT_N" )
			)
			( signal "@baseboard_fab2_lib.baseboard_fab2(sch_1):m_l_alert_n"
				( attribute "CDS_PHYS_NET_NAME" "M_L_ALERT_N"
					( Origin gPackager )
				)
				( objectStatus "M_L_ALERT_N" )
			)
			( signal "@baseboard_fab2_lib.baseboard_fab2(sch_1):m_l_ba(0)"
				( attribute "CDS_PHYS_NET_NAME" "M_L_BA<0>"
					( Origin gPackager )
				)
				( attribute "PNN" "M_L_BA<0>"
					( Origin gPackager )
				)
				( objectStatus "M_L_BA<0>" )
			)
			( signal "@baseboard_fab2_lib.baseboard_fab2(sch_1):m_l_ba(1)"
				( attribute "CDS_PHYS_NET_NAME" "M_L_BA<1>"
					( Origin gPackager )
				)
				( attribute "PNN" "M_L_BA<1>"
					( Origin gPackager )
				)
				( objectStatus "M_L_BA<1>" )
			)
			( signal "@baseboard_fab2_lib.baseboard_fab2(sch_1):m_l_bg(0)"
				( attribute "CDS_PHYS_NET_NAME" "M_L_BG<0>"
					( Origin gPackager )
				)
				( attribute "PNN" "M_L_BG<0>"
					( Origin gPackager )
				)
				( objectStatus "M_L_BG<0>" )
			)
			( signal "@baseboard_fab2_lib.baseboard_fab2(sch_1):m_l_bg(1)"
				( attribute "CDS_PHYS_NET_NAME" "M_L_BG<1>"
					( Origin gPackager )
				)
				( attribute "PNN" "M_L_BG<1>"
					( Origin gPackager )
				)
				( objectStatus "M_L_BG<1>" )
			)
			( signal "@baseboard_fab2_lib.baseboard_fab2(sch_1):m_l_c(2)"
				( attribute "CDS_PHYS_NET_NAME" "M_L_C<2>"
					( Origin gPackager )
				)
				( attribute "PNN" "M_L_C<2>"
					( Origin gPackager )
				)
				( objectStatus "M_L_C<2>" )
			)
			( signal "@baseboard_fab2_lib.baseboard_fab2(sch_1):m_l_cke(0)"
				( attribute "CDS_PHYS_NET_NAME" "M_L_CKE<0>"
					( Origin gPackager )
				)
				( attribute "PNN" "M_L_CKE<0>"
					( Origin gPackager )
				)
				( objectStatus "M_L_CKE<0>" )
			)
			( signal "@baseboard_fab2_lib.baseboard_fab2(sch_1):m_l_cke(1)"
				( attribute "CDS_PHYS_NET_NAME" "M_L_CKE<1>"
					( Origin gPackager )
				)
				( attribute "PNN" "M_L_CKE<1>"
					( Origin gPackager )
				)
				( objectStatus "M_L_CKE<1>" )
			)
			( signal "@baseboard_fab2_lib.baseboard_fab2(sch_1):m_l_cke(2)"
				( attribute "CDS_PHYS_NET_NAME" "M_L_CKE<2>"
					( Origin gPackager )
				)
				( attribute "PNN" "M_L_CKE<2>"
					( Origin gPackager )
				)
				( objectStatus "M_L_CKE<2>" )
			)
			( signal "@baseboard_fab2_lib.baseboard_fab2(sch_1):m_l_cke(3)"
				( attribute "CDS_PHYS_NET_NAME" "M_L_CKE<3>"
					( Origin gPackager )
				)
				( attribute "PNN" "M_L_CKE<3>"
					( Origin gPackager )
				)
				( objectStatus "M_L_CKE<3>" )
			)
			( signal "@baseboard_fab2_lib.baseboard_fab2(sch_1):m_l_clk_dn(0)"
				( attribute "CDS_PHYS_NET_NAME" "M_L_CLK_DN<0>"
					( Origin gPackager )
				)
				( attribute "PNN" "M_L_CLK_DN<0>"
					( Origin gPackager )
				)
				( objectStatus "M_L_CLK_DN<0>" )
			)
			( signal "@baseboard_fab2_lib.baseboard_fab2(sch_1):m_l_clk_dn(1)"
				( attribute "CDS_PHYS_NET_NAME" "M_L_CLK_DN<1>"
					( Origin gPackager )
				)
				( attribute "PNN" "M_L_CLK_DN<1>"
					( Origin gPackager )
				)
				( objectStatus "M_L_CLK_DN<1>" )
			)
			( signal "@baseboard_fab2_lib.baseboard_fab2(sch_1):m_l_clk_dn(2)"
				( attribute "CDS_PHYS_NET_NAME" "M_L_CLK_DN<2>"
					( Origin gPackager )
				)
				( attribute "PNN" "M_L_CLK_DN<2>"
					( Origin gPackager )
				)
				( objectStatus "M_L_CLK_DN<2>" )
			)
			( signal "@baseboard_fab2_lib.baseboard_fab2(sch_1):m_l_clk_dn(3)"
				( attribute "CDS_PHYS_NET_NAME" "M_L_CLK_DN<3>"
					( Origin gPackager )
				)
				( attribute "PNN" "M_L_CLK_DN<3>"
					( Origin gPackager )
				)
				( objectStatus "M_L_CLK_DN<3>" )
			)
			( signal "@baseboard_fab2_lib.baseboard_fab2(sch_1):m_l_clk_dp(0)"
				( attribute "CDS_PHYS_NET_NAME" "M_L_CLK_DP<0>"
					( Origin gPackager )
				)
				( attribute "PNN" "M_L_CLK_DP<0>"
					( Origin gPackager )
				)
				( objectStatus "M_L_CLK_DP<0>" )
			)
			( signal "@baseboard_fab2_lib.baseboard_fab2(sch_1):m_l_clk_dp(1)"
				( attribute "CDS_PHYS_NET_NAME" "M_L_CLK_DP<1>"
					( Origin gPackager )
				)
				( attribute "PNN" "M_L_CLK_DP<1>"
					( Origin gPackager )
				)
				( objectStatus "M_L_CLK_DP<1>" )
			)
			( signal "@baseboard_fab2_lib.baseboard_fab2(sch_1):m_l_clk_dp(2)"
				( attribute "CDS_PHYS_NET_NAME" "M_L_CLK_DP<2>"
					( Origin gPackager )
				)
				( attribute "PNN" "M_L_CLK_DP<2>"
					( Origin gPackager )
				)
				( objectStatus "M_L_CLK_DP<2>" )
			)
			( signal "@baseboard_fab2_lib.baseboard_fab2(sch_1):m_l_clk_dp(3)"
				( attribute "CDS_PHYS_NET_NAME" "M_L_CLK_DP<3>"
					( Origin gPackager )
				)
				( attribute "PNN" "M_L_CLK_DP<3>"
					( Origin gPackager )
				)
				( objectStatus "M_L_CLK_DP<3>" )
			)
			( signal "@baseboard_fab2_lib.baseboard_fab2(sch_1):m_l_cs_n(0)"
				( attribute "CDS_PHYS_NET_NAME" "M_L_CS_N<0>"
					( Origin gPackager )
				)
				( attribute "PNN" "M_L_CS_N<0>"
					( Origin gPackager )
				)
				( objectStatus "M_L_CS_N<0>" )
			)
			( signal "@baseboard_fab2_lib.baseboard_fab2(sch_1):m_l_cs_n(1)"
				( attribute "CDS_PHYS_NET_NAME" "M_L_CS_N<1>"
					( Origin gPackager )
				)
				( attribute "PNN" "M_L_CS_N<1>"
					( Origin gPackager )
				)
				( objectStatus "M_L_CS_N<1>" )
			)
			( signal "@baseboard_fab2_lib.baseboard_fab2(sch_1):m_l_cs_n(2)"
				( attribute "CDS_PHYS_NET_NAME" "M_L_CS_N<2>"
					( Origin gPackager )
				)
				( attribute "PNN" "M_L_CS_N<2>"
					( Origin gPackager )
				)
				( objectStatus "M_L_CS_N<2>" )
			)
			( signal "@baseboard_fab2_lib.baseboard_fab2(sch_1):m_l_cs_n(3)"
				( attribute "CDS_PHYS_NET_NAME" "M_L_CS_N<3>"
					( Origin gPackager )
				)
				( attribute "PNN" "M_L_CS_N<3>"
					( Origin gPackager )
				)
				( objectStatus "M_L_CS_N<3>" )
			)
			( signal "@baseboard_fab2_lib.baseboard_fab2(sch_1):m_l_cs_n(4)"
				( attribute "CDS_PHYS_NET_NAME" "M_L_CS_N<4>"
					( Origin gPackager )
				)
				( attribute "PNN" "M_L_CS_N<4>"
					( Origin gPackager )
				)
				( objectStatus "M_L_CS_N<4>" )
			)
			( signal "@baseboard_fab2_lib.baseboard_fab2(sch_1):m_l_cs_n(5)"
				( attribute "CDS_PHYS_NET_NAME" "M_L_CS_N<5>"
					( Origin gPackager )
				)
				( attribute "PNN" "M_L_CS_N<5>"
					( Origin gPackager )
				)
				( objectStatus "M_L_CS_N<5>" )
			)
			( signal "@baseboard_fab2_lib.baseboard_fab2(sch_1):m_l_cs_n(6)"
				( attribute "CDS_PHYS_NET_NAME" "M_L_CS_N<6>"
					( Origin gPackager )
				)
				( attribute "PNN" "M_L_CS_N<6>"
					( Origin gPackager )
				)
				( objectStatus "M_L_CS_N<6>" )
			)
			( signal "@baseboard_fab2_lib.baseboard_fab2(sch_1):m_l_cs_n(7)"
				( attribute "CDS_PHYS_NET_NAME" "M_L_CS_N<7>"
					( Origin gPackager )
				)
				( attribute "PNN" "M_L_CS_N<7>"
					( Origin gPackager )
				)
				( objectStatus "M_L_CS_N<7>" )
			)
			( signal "@baseboard_fab2_lib.baseboard_fab2(sch_1):m_l_dq(0)"
				( attribute "CDS_PHYS_NET_NAME" "M_L_DQ<0>"
					( Origin gPackager )
				)
				( attribute "PNN" "M_L_DQ<0>"
					( Origin gPackager )
				)
				( objectStatus "M_L_DQ<0>" )
			)
			( signal "@baseboard_fab2_lib.baseboard_fab2(sch_1):m_l_dq(1)"
				( attribute "CDS_PHYS_NET_NAME" "M_L_DQ<1>"
					( Origin gPackager )
				)
				( attribute "PNN" "M_L_DQ<1>"
					( Origin gPackager )
				)
				( objectStatus "M_L_DQ<1>" )
			)
			( signal "@baseboard_fab2_lib.baseboard_fab2(sch_1):m_l_dq(2)"
				( attribute "CDS_PHYS_NET_NAME" "M_L_DQ<2>"
					( Origin gPackager )
				)
				( attribute "PNN" "M_L_DQ<2>"
					( Origin gPackager )
				)
				( objectStatus "M_L_DQ<2>" )
			)
			( signal "@baseboard_fab2_lib.baseboard_fab2(sch_1):m_l_dq(3)"
				( attribute "CDS_PHYS_NET_NAME" "M_L_DQ<3>"
					( Origin gPackager )
				)
				( attribute "PNN" "M_L_DQ<3>"
					( Origin gPackager )
				)
				( objectStatus "M_L_DQ<3>" )
			)
			( signal "@baseboard_fab2_lib.baseboard_fab2(sch_1):m_l_dq(4)"
				( attribute "CDS_PHYS_NET_NAME" "M_L_DQ<4>"
					( Origin gPackager )
				)
				( attribute "PNN" "M_L_DQ<4>"
					( Origin gPackager )
				)
				( objectStatus "M_L_DQ<4>" )
			)
			( signal "@baseboard_fab2_lib.baseboard_fab2(sch_1):m_l_dq(5)"
				( attribute "CDS_PHYS_NET_NAME" "M_L_DQ<5>"
					( Origin gPackager )
				)
				( attribute "PNN" "M_L_DQ<5>"
					( Origin gPackager )
				)
				( objectStatus "M_L_DQ<5>" )
			)
			( signal "@baseboard_fab2_lib.baseboard_fab2(sch_1):m_l_dq(6)"
				( attribute "CDS_PHYS_NET_NAME" "M_L_DQ<6>"
					( Origin gPackager )
				)
				( attribute "PNN" "M_L_DQ<6>"
					( Origin gPackager )
				)
				( objectStatus "M_L_DQ<6>" )
			)
			( signal "@baseboard_fab2_lib.baseboard_fab2(sch_1):m_l_dq(7)"
				( attribute "CDS_PHYS_NET_NAME" "M_L_DQ<7>"
					( Origin gPackager )
				)
				( attribute "PNN" "M_L_DQ<7>"
					( Origin gPackager )
				)
				( objectStatus "M_L_DQ<7>" )
			)
			( signal "@baseboard_fab2_lib.baseboard_fab2(sch_1):m_l_dq(8)"
				( attribute "CDS_PHYS_NET_NAME" "M_L_DQ<8>"
					( Origin gPackager )
				)
				( attribute "PNN" "M_L_DQ<8>"
					( Origin gPackager )
				)
				( objectStatus "M_L_DQ<8>" )
			)
			( signal "@baseboard_fab2_lib.baseboard_fab2(sch_1):m_l_dq(9)"
				( attribute "CDS_PHYS_NET_NAME" "M_L_DQ<9>"
					( Origin gPackager )
				)
				( attribute "PNN" "M_L_DQ<9>"
					( Origin gPackager )
				)
				( objectStatus "M_L_DQ<9>" )
			)
			( signal "@baseboard_fab2_lib.baseboard_fab2(sch_1):m_l_dq(10)"
				( attribute "CDS_PHYS_NET_NAME" "M_L_DQ<10>"
					( Origin gPackager )
				)
				( attribute "PNN" "M_L_DQ<10>"
					( Origin gPackager )
				)
				( objectStatus "M_L_DQ<10>" )
			)
			( signal "@baseboard_fab2_lib.baseboard_fab2(sch_1):m_l_dq(11)"
				( attribute "CDS_PHYS_NET_NAME" "M_L_DQ<11>"
					( Origin gPackager )
				)
				( attribute "PNN" "M_L_DQ<11>"
					( Origin gPackager )
				)
				( objectStatus "M_L_DQ<11>" )
			)
			( signal "@baseboard_fab2_lib.baseboard_fab2(sch_1):m_l_dq(12)"
				( attribute "CDS_PHYS_NET_NAME" "M_L_DQ<12>"
					( Origin gPackager )
				)
				( attribute "PNN" "M_L_DQ<12>"
					( Origin gPackager )
				)
				( objectStatus "M_L_DQ<12>" )
			)
			( signal "@baseboard_fab2_lib.baseboard_fab2(sch_1):m_l_dq(13)"
				( attribute "CDS_PHYS_NET_NAME" "M_L_DQ<13>"
					( Origin gPackager )
				)
				( attribute "PNN" "M_L_DQ<13>"
					( Origin gPackager )
				)
				( objectStatus "M_L_DQ<13>" )
			)
			( signal "@baseboard_fab2_lib.baseboard_fab2(sch_1):m_l_dq(14)"
				( attribute "CDS_PHYS_NET_NAME" "M_L_DQ<14>"
					( Origin gPackager )
				)
				( attribute "PNN" "M_L_DQ<14>"
					( Origin gPackager )
				)
				( objectStatus "M_L_DQ<14>" )
			)
			( signal "@baseboard_fab2_lib.baseboard_fab2(sch_1):m_l_dq(15)"
				( attribute "CDS_PHYS_NET_NAME" "M_L_DQ<15>"
					( Origin gPackager )
				)
				( attribute "PNN" "M_L_DQ<15>"
					( Origin gPackager )
				)
				( objectStatus "M_L_DQ<15>" )
			)
			( signal "@baseboard_fab2_lib.baseboard_fab2(sch_1):m_l_dq(16)"
				( attribute "CDS_PHYS_NET_NAME" "M_L_DQ<16>"
					( Origin gPackager )
				)
				( attribute "PNN" "M_L_DQ<16>"
					( Origin gPackager )
				)
				( objectStatus "M_L_DQ<16>" )
			)
			( signal "@baseboard_fab2_lib.baseboard_fab2(sch_1):m_l_dq(17)"
				( attribute "CDS_PHYS_NET_NAME" "M_L_DQ<17>"
					( Origin gPackager )
				)
				( attribute "PNN" "M_L_DQ<17>"
					( Origin gPackager )
				)
				( objectStatus "M_L_DQ<17>" )
			)
			( signal "@baseboard_fab2_lib.baseboard_fab2(sch_1):m_l_dq(18)"
				( attribute "CDS_PHYS_NET_NAME" "M_L_DQ<18>"
					( Origin gPackager )
				)
				( attribute "PNN" "M_L_DQ<18>"
					( Origin gPackager )
				)
				( objectStatus "M_L_DQ<18>" )
			)
			( signal "@baseboard_fab2_lib.baseboard_fab2(sch_1):m_l_dq(19)"
				( attribute "CDS_PHYS_NET_NAME" "M_L_DQ<19>"
					( Origin gPackager )
				)
				( attribute "PNN" "M_L_DQ<19>"
					( Origin gPackager )
				)
				( objectStatus "M_L_DQ<19>" )
			)
			( signal "@baseboard_fab2_lib.baseboard_fab2(sch_1):m_l_dq(20)"
				( attribute "CDS_PHYS_NET_NAME" "M_L_DQ<20>"
					( Origin gPackager )
				)
				( attribute "PNN" "M_L_DQ<20>"
					( Origin gPackager )
				)
				( objectStatus "M_L_DQ<20>" )
			)
			( signal "@baseboard_fab2_lib.baseboard_fab2(sch_1):m_l_dq(21)"
				( attribute "CDS_PHYS_NET_NAME" "M_L_DQ<21>"
					( Origin gPackager )
				)
				( attribute "PNN" "M_L_DQ<21>"
					( Origin gPackager )
				)
				( objectStatus "M_L_DQ<21>" )
			)
			( signal "@baseboard_fab2_lib.baseboard_fab2(sch_1):m_l_dq(22)"
				( attribute "CDS_PHYS_NET_NAME" "M_L_DQ<22>"
					( Origin gPackager )
				)
				( attribute "PNN" "M_L_DQ<22>"
					( Origin gPackager )
				)
				( objectStatus "M_L_DQ<22>" )
			)
			( signal "@baseboard_fab2_lib.baseboard_fab2(sch_1):m_l_dq(23)"
				( attribute "CDS_PHYS_NET_NAME" "M_L_DQ<23>"
					( Origin gPackager )
				)
				( attribute "PNN" "M_L_DQ<23>"
					( Origin gPackager )
				)
				( objectStatus "M_L_DQ<23>" )
			)
			( signal "@baseboard_fab2_lib.baseboard_fab2(sch_1):m_l_dq(24)"
				( attribute "CDS_PHYS_NET_NAME" "M_L_DQ<24>"
					( Origin gPackager )
				)
				( attribute "PNN" "M_L_DQ<24>"
					( Origin gPackager )
				)
				( objectStatus "M_L_DQ<24>" )
			)
			( signal "@baseboard_fab2_lib.baseboard_fab2(sch_1):m_l_dq(25)"
				( attribute "CDS_PHYS_NET_NAME" "M_L_DQ<25>"
					( Origin gPackager )
				)
				( attribute "PNN" "M_L_DQ<25>"
					( Origin gPackager )
				)
				( objectStatus "M_L_DQ<25>" )
			)
			( signal "@baseboard_fab2_lib.baseboard_fab2(sch_1):m_l_dq(26)"
				( attribute "CDS_PHYS_NET_NAME" "M_L_DQ<26>"
					( Origin gPackager )
				)
				( attribute "PNN" "M_L_DQ<26>"
					( Origin gPackager )
				)
				( objectStatus "M_L_DQ<26>" )
			)
			( signal "@baseboard_fab2_lib.baseboard_fab2(sch_1):m_l_dq(27)"
				( attribute "CDS_PHYS_NET_NAME" "M_L_DQ<27>"
					( Origin gPackager )
				)
				( attribute "PNN" "M_L_DQ<27>"
					( Origin gPackager )
				)
				( objectStatus "M_L_DQ<27>" )
			)
			( signal "@baseboard_fab2_lib.baseboard_fab2(sch_1):m_l_dq(28)"
				( attribute "CDS_PHYS_NET_NAME" "M_L_DQ<28>"
					( Origin gPackager )
				)
				( attribute "PNN" "M_L_DQ<28>"
					( Origin gPackager )
				)
				( objectStatus "M_L_DQ<28>" )
			)
			( signal "@baseboard_fab2_lib.baseboard_fab2(sch_1):m_l_dq(29)"
				( attribute "CDS_PHYS_NET_NAME" "M_L_DQ<29>"
					( Origin gPackager )
				)
				( attribute "PNN" "M_L_DQ<29>"
					( Origin gPackager )
				)
				( objectStatus "M_L_DQ<29>" )
			)
			( signal "@baseboard_fab2_lib.baseboard_fab2(sch_1):m_l_dq(30)"
				( attribute "CDS_PHYS_NET_NAME" "M_L_DQ<30>"
					( Origin gPackager )
				)
				( attribute "PNN" "M_L_DQ<30>"
					( Origin gPackager )
				)
				( objectStatus "M_L_DQ<30>" )
			)
			( signal "@baseboard_fab2_lib.baseboard_fab2(sch_1):m_l_dq(31)"
				( attribute "CDS_PHYS_NET_NAME" "M_L_DQ<31>"
					( Origin gPackager )
				)
				( attribute "PNN" "M_L_DQ<31>"
					( Origin gPackager )
				)
				( objectStatus "M_L_DQ<31>" )
			)
			( signal "@baseboard_fab2_lib.baseboard_fab2(sch_1):m_l_dq(32)"
				( attribute "CDS_PHYS_NET_NAME" "M_L_DQ<32>"
					( Origin gPackager )
				)
				( attribute "PNN" "M_L_DQ<32>"
					( Origin gPackager )
				)
				( objectStatus "M_L_DQ<32>" )
			)
			( signal "@baseboard_fab2_lib.baseboard_fab2(sch_1):m_l_dq(33)"
				( attribute "CDS_PHYS_NET_NAME" "M_L_DQ<33>"
					( Origin gPackager )
				)
				( attribute "PNN" "M_L_DQ<33>"
					( Origin gPackager )
				)
				( objectStatus "M_L_DQ<33>" )
			)
			( signal "@baseboard_fab2_lib.baseboard_fab2(sch_1):m_l_dq(34)"
				( attribute "CDS_PHYS_NET_NAME" "M_L_DQ<34>"
					( Origin gPackager )
				)
				( attribute "PNN" "M_L_DQ<34>"
					( Origin gPackager )
				)
				( objectStatus "M_L_DQ<34>" )
			)
			( signal "@baseboard_fab2_lib.baseboard_fab2(sch_1):m_l_dq(35)"
				( attribute "CDS_PHYS_NET_NAME" "M_L_DQ<35>"
					( Origin gPackager )
				)
				( attribute "PNN" "M_L_DQ<35>"
					( Origin gPackager )
				)
				( objectStatus "M_L_DQ<35>" )
			)
			( signal "@baseboard_fab2_lib.baseboard_fab2(sch_1):m_l_dq(36)"
				( attribute "CDS_PHYS_NET_NAME" "M_L_DQ<36>"
					( Origin gPackager )
				)
				( attribute "PNN" "M_L_DQ<36>"
					( Origin gPackager )
				)
				( objectStatus "M_L_DQ<36>" )
			)
			( signal "@baseboard_fab2_lib.baseboard_fab2(sch_1):m_l_dq(37)"
				( attribute "CDS_PHYS_NET_NAME" "M_L_DQ<37>"
					( Origin gPackager )
				)
				( attribute "PNN" "M_L_DQ<37>"
					( Origin gPackager )
				)
				( objectStatus "M_L_DQ<37>" )
			)
			( signal "@baseboard_fab2_lib.baseboard_fab2(sch_1):m_l_dq(38)"
				( attribute "CDS_PHYS_NET_NAME" "M_L_DQ<38>"
					( Origin gPackager )
				)
				( attribute "PNN" "M_L_DQ<38>"
					( Origin gPackager )
				)
				( objectStatus "M_L_DQ<38>" )
			)
			( signal "@baseboard_fab2_lib.baseboard_fab2(sch_1):m_l_dq(39)"
				( attribute "CDS_PHYS_NET_NAME" "M_L_DQ<39>"
					( Origin gPackager )
				)
				( attribute "PNN" "M_L_DQ<39>"
					( Origin gPackager )
				)
				( objectStatus "M_L_DQ<39>" )
			)
			( signal "@baseboard_fab2_lib.baseboard_fab2(sch_1):m_l_dq(40)"
				( attribute "CDS_PHYS_NET_NAME" "M_L_DQ<40>"
					( Origin gPackager )
				)
				( attribute "PNN" "M_L_DQ<40>"
					( Origin gPackager )
				)
				( objectStatus "M_L_DQ<40>" )
			)
			( signal "@baseboard_fab2_lib.baseboard_fab2(sch_1):m_l_dq(41)"
				( attribute "CDS_PHYS_NET_NAME" "M_L_DQ<41>"
					( Origin gPackager )
				)
				( attribute "PNN" "M_L_DQ<41>"
					( Origin gPackager )
				)
				( objectStatus "M_L_DQ<41>" )
			)
			( signal "@baseboard_fab2_lib.baseboard_fab2(sch_1):m_l_dq(42)"
				( attribute "CDS_PHYS_NET_NAME" "M_L_DQ<42>"
					( Origin gPackager )
				)
				( attribute "PNN" "M_L_DQ<42>"
					( Origin gPackager )
				)
				( objectStatus "M_L_DQ<42>" )
			)
			( signal "@baseboard_fab2_lib.baseboard_fab2(sch_1):m_l_dq(43)"
				( attribute "CDS_PHYS_NET_NAME" "M_L_DQ<43>"
					( Origin gPackager )
				)
				( attribute "PNN" "M_L_DQ<43>"
					( Origin gPackager )
				)
				( objectStatus "M_L_DQ<43>" )
			)
			( signal "@baseboard_fab2_lib.baseboard_fab2(sch_1):m_l_dq(44)"
				( attribute "CDS_PHYS_NET_NAME" "M_L_DQ<44>"
					( Origin gPackager )
				)
				( attribute "PNN" "M_L_DQ<44>"
					( Origin gPackager )
				)
				( objectStatus "M_L_DQ<44>" )
			)
			( signal "@baseboard_fab2_lib.baseboard_fab2(sch_1):m_l_dq(45)"
				( attribute "CDS_PHYS_NET_NAME" "M_L_DQ<45>"
					( Origin gPackager )
				)
				( attribute "PNN" "M_L_DQ<45>"
					( Origin gPackager )
				)
				( objectStatus "M_L_DQ<45>" )
			)
			( signal "@baseboard_fab2_lib.baseboard_fab2(sch_1):m_l_dq(46)"
				( attribute "CDS_PHYS_NET_NAME" "M_L_DQ<46>"
					( Origin gPackager )
				)
				( attribute "PNN" "M_L_DQ<46>"
					( Origin gPackager )
				)
				( objectStatus "M_L_DQ<46>" )
			)
			( signal "@baseboard_fab2_lib.baseboard_fab2(sch_1):m_l_dq(47)"
				( attribute "CDS_PHYS_NET_NAME" "M_L_DQ<47>"
					( Origin gPackager )
				)
				( attribute "PNN" "M_L_DQ<47>"
					( Origin gPackager )
				)
				( objectStatus "M_L_DQ<47>" )
			)
			( signal "@baseboard_fab2_lib.baseboard_fab2(sch_1):m_l_dq(48)"
				( attribute "CDS_PHYS_NET_NAME" "M_L_DQ<48>"
					( Origin gPackager )
				)
				( attribute "PNN" "M_L_DQ<48>"
					( Origin gPackager )
				)
				( objectStatus "M_L_DQ<48>" )
			)
			( signal "@baseboard_fab2_lib.baseboard_fab2(sch_1):m_l_dq(49)"
				( attribute "CDS_PHYS_NET_NAME" "M_L_DQ<49>"
					( Origin gPackager )
				)
				( attribute "PNN" "M_L_DQ<49>"
					( Origin gPackager )
				)
				( objectStatus "M_L_DQ<49>" )
			)
			( signal "@baseboard_fab2_lib.baseboard_fab2(sch_1):m_l_dq(50)"
				( attribute "CDS_PHYS_NET_NAME" "M_L_DQ<50>"
					( Origin gPackager )
				)
				( attribute "PNN" "M_L_DQ<50>"
					( Origin gPackager )
				)
				( objectStatus "M_L_DQ<50>" )
			)
			( signal "@baseboard_fab2_lib.baseboard_fab2(sch_1):m_l_dq(51)"
				( attribute "CDS_PHYS_NET_NAME" "M_L_DQ<51>"
					( Origin gPackager )
				)
				( attribute "PNN" "M_L_DQ<51>"
					( Origin gPackager )
				)
				( objectStatus "M_L_DQ<51>" )
			)
			( signal "@baseboard_fab2_lib.baseboard_fab2(sch_1):m_l_dq(52)"
				( attribute "CDS_PHYS_NET_NAME" "M_L_DQ<52>"
					( Origin gPackager )
				)
				( attribute "PNN" "M_L_DQ<52>"
					( Origin gPackager )
				)
				( objectStatus "M_L_DQ<52>" )
			)
			( signal "@baseboard_fab2_lib.baseboard_fab2(sch_1):m_l_dq(53)"
				( attribute "CDS_PHYS_NET_NAME" "M_L_DQ<53>"
					( Origin gPackager )
				)
				( attribute "PNN" "M_L_DQ<53>"
					( Origin gPackager )
				)
				( objectStatus "M_L_DQ<53>" )
			)
			( signal "@baseboard_fab2_lib.baseboard_fab2(sch_1):m_l_dq(54)"
				( attribute "CDS_PHYS_NET_NAME" "M_L_DQ<54>"
					( Origin gPackager )
				)
				( attribute "PNN" "M_L_DQ<54>"
					( Origin gPackager )
				)
				( objectStatus "M_L_DQ<54>" )
			)
			( signal "@baseboard_fab2_lib.baseboard_fab2(sch_1):m_l_dq(55)"
				( attribute "CDS_PHYS_NET_NAME" "M_L_DQ<55>"
					( Origin gPackager )
				)
				( attribute "PNN" "M_L_DQ<55>"
					( Origin gPackager )
				)
				( objectStatus "M_L_DQ<55>" )
			)
			( signal "@baseboard_fab2_lib.baseboard_fab2(sch_1):m_l_dq(56)"
				( attribute "CDS_PHYS_NET_NAME" "M_L_DQ<56>"
					( Origin gPackager )
				)
				( attribute "PNN" "M_L_DQ<56>"
					( Origin gPackager )
				)
				( objectStatus "M_L_DQ<56>" )
			)
			( signal "@baseboard_fab2_lib.baseboard_fab2(sch_1):m_l_dq(57)"
				( attribute "CDS_PHYS_NET_NAME" "M_L_DQ<57>"
					( Origin gPackager )
				)
				( attribute "PNN" "M_L_DQ<57>"
					( Origin gPackager )
				)
				( objectStatus "M_L_DQ<57>" )
			)
			( signal "@baseboard_fab2_lib.baseboard_fab2(sch_1):m_l_dq(58)"
				( attribute "CDS_PHYS_NET_NAME" "M_L_DQ<58>"
					( Origin gPackager )
				)
				( attribute "PNN" "M_L_DQ<58>"
					( Origin gPackager )
				)
				( objectStatus "M_L_DQ<58>" )
			)
			( signal "@baseboard_fab2_lib.baseboard_fab2(sch_1):m_l_dq(59)"
				( attribute "CDS_PHYS_NET_NAME" "M_L_DQ<59>"
					( Origin gPackager )
				)
				( attribute "PNN" "M_L_DQ<59>"
					( Origin gPackager )
				)
				( objectStatus "M_L_DQ<59>" )
			)
			( signal "@baseboard_fab2_lib.baseboard_fab2(sch_1):m_l_dq(60)"
				( attribute "CDS_PHYS_NET_NAME" "M_L_DQ<60>"
					( Origin gPackager )
				)
				( attribute "PNN" "M_L_DQ<60>"
					( Origin gPackager )
				)
				( objectStatus "M_L_DQ<60>" )
			)
			( signal "@baseboard_fab2_lib.baseboard_fab2(sch_1):m_l_dq(61)"
				( attribute "CDS_PHYS_NET_NAME" "M_L_DQ<61>"
					( Origin gPackager )
				)
				( attribute "PNN" "M_L_DQ<61>"
					( Origin gPackager )
				)
				( objectStatus "M_L_DQ<61>" )
			)
			( signal "@baseboard_fab2_lib.baseboard_fab2(sch_1):m_l_dq(62)"
				( attribute "CDS_PHYS_NET_NAME" "M_L_DQ<62>"
					( Origin gPackager )
				)
				( attribute "PNN" "M_L_DQ<62>"
					( Origin gPackager )
				)
				( objectStatus "M_L_DQ<62>" )
			)
			( signal "@baseboard_fab2_lib.baseboard_fab2(sch_1):m_l_dq(63)"
				( attribute "CDS_PHYS_NET_NAME" "M_L_DQ<63>"
					( Origin gPackager )
				)
				( attribute "PNN" "M_L_DQ<63>"
					( Origin gPackager )
				)
				( objectStatus "M_L_DQ<63>" )
			)
			( signal "@baseboard_fab2_lib.baseboard_fab2(sch_1):m_l_dqs_dn(0)"
				( attribute "CDS_PHYS_NET_NAME" "M_L_DQS_DN<0>"
					( Origin gPackager )
				)
				( attribute "PNN" "M_L_DQS_DN<0>"
					( Origin gPackager )
				)
				( objectStatus "M_L_DQS_DN<0>" )
			)
			( signal "@baseboard_fab2_lib.baseboard_fab2(sch_1):m_l_dqs_dn(1)"
				( attribute "CDS_PHYS_NET_NAME" "M_L_DQS_DN<1>"
					( Origin gPackager )
				)
				( attribute "PNN" "M_L_DQS_DN<1>"
					( Origin gPackager )
				)
				( objectStatus "M_L_DQS_DN<1>" )
			)
			( signal "@baseboard_fab2_lib.baseboard_fab2(sch_1):m_l_dqs_dn(2)"
				( attribute "CDS_PHYS_NET_NAME" "M_L_DQS_DN<2>"
					( Origin gPackager )
				)
				( attribute "PNN" "M_L_DQS_DN<2>"
					( Origin gPackager )
				)
				( objectStatus "M_L_DQS_DN<2>" )
			)
			( signal "@baseboard_fab2_lib.baseboard_fab2(sch_1):m_l_dqs_dn(3)"
				( attribute "CDS_PHYS_NET_NAME" "M_L_DQS_DN<3>"
					( Origin gPackager )
				)
				( attribute "PNN" "M_L_DQS_DN<3>"
					( Origin gPackager )
				)
				( objectStatus "M_L_DQS_DN<3>" )
			)
			( signal "@baseboard_fab2_lib.baseboard_fab2(sch_1):m_l_dqs_dn(4)"
				( attribute "CDS_PHYS_NET_NAME" "M_L_DQS_DN<4>"
					( Origin gPackager )
				)
				( attribute "PNN" "M_L_DQS_DN<4>"
					( Origin gPackager )
				)
				( objectStatus "M_L_DQS_DN<4>" )
			)
			( signal "@baseboard_fab2_lib.baseboard_fab2(sch_1):m_l_dqs_dn(5)"
				( attribute "CDS_PHYS_NET_NAME" "M_L_DQS_DN<5>"
					( Origin gPackager )
				)
				( attribute "PNN" "M_L_DQS_DN<5>"
					( Origin gPackager )
				)
				( objectStatus "M_L_DQS_DN<5>" )
			)
			( signal "@baseboard_fab2_lib.baseboard_fab2(sch_1):m_l_dqs_dn(6)"
				( attribute "CDS_PHYS_NET_NAME" "M_L_DQS_DN<6>"
					( Origin gPackager )
				)
				( attribute "PNN" "M_L_DQS_DN<6>"
					( Origin gPackager )
				)
				( objectStatus "M_L_DQS_DN<6>" )
			)
			( signal "@baseboard_fab2_lib.baseboard_fab2(sch_1):m_l_dqs_dn(7)"
				( attribute "CDS_PHYS_NET_NAME" "M_L_DQS_DN<7>"
					( Origin gPackager )
				)
				( attribute "PNN" "M_L_DQS_DN<7>"
					( Origin gPackager )
				)
				( objectStatus "M_L_DQS_DN<7>" )
			)
			( signal "@baseboard_fab2_lib.baseboard_fab2(sch_1):m_l_dqs_dn(8)"
				( attribute "CDS_PHYS_NET_NAME" "M_L_DQS_DN<8>"
					( Origin gPackager )
				)
				( attribute "PNN" "M_L_DQS_DN<8>"
					( Origin gPackager )
				)
				( objectStatus "M_L_DQS_DN<8>" )
			)
			( signal "@baseboard_fab2_lib.baseboard_fab2(sch_1):m_l_dqs_dn(9)"
				( attribute "CDS_PHYS_NET_NAME" "M_L_DQS_DN<9>"
					( Origin gPackager )
				)
				( attribute "PNN" "M_L_DQS_DN<9>"
					( Origin gPackager )
				)
				( objectStatus "M_L_DQS_DN<9>" )
			)
			( signal "@baseboard_fab2_lib.baseboard_fab2(sch_1):m_l_dqs_dn(10)"
				( attribute "CDS_PHYS_NET_NAME" "M_L_DQS_DN<10>"
					( Origin gPackager )
				)
				( attribute "PNN" "M_L_DQS_DN<10>"
					( Origin gPackager )
				)
				( objectStatus "M_L_DQS_DN<10>" )
			)
			( signal "@baseboard_fab2_lib.baseboard_fab2(sch_1):m_l_dqs_dn(11)"
				( attribute "CDS_PHYS_NET_NAME" "M_L_DQS_DN<11>"
					( Origin gPackager )
				)
				( attribute "PNN" "M_L_DQS_DN<11>"
					( Origin gPackager )
				)
				( objectStatus "M_L_DQS_DN<11>" )
			)
			( signal "@baseboard_fab2_lib.baseboard_fab2(sch_1):m_l_dqs_dn(12)"
				( attribute "CDS_PHYS_NET_NAME" "M_L_DQS_DN<12>"
					( Origin gPackager )
				)
				( attribute "PNN" "M_L_DQS_DN<12>"
					( Origin gPackager )
				)
				( objectStatus "M_L_DQS_DN<12>" )
			)
			( signal "@baseboard_fab2_lib.baseboard_fab2(sch_1):m_l_dqs_dn(13)"
				( attribute "CDS_PHYS_NET_NAME" "M_L_DQS_DN<13>"
					( Origin gPackager )
				)
				( attribute "PNN" "M_L_DQS_DN<13>"
					( Origin gPackager )
				)
				( objectStatus "M_L_DQS_DN<13>" )
			)
			( signal "@baseboard_fab2_lib.baseboard_fab2(sch_1):m_l_dqs_dn(14)"
				( attribute "CDS_PHYS_NET_NAME" "M_L_DQS_DN<14>"
					( Origin gPackager )
				)
				( attribute "PNN" "M_L_DQS_DN<14>"
					( Origin gPackager )
				)
				( objectStatus "M_L_DQS_DN<14>" )
			)
			( signal "@baseboard_fab2_lib.baseboard_fab2(sch_1):m_l_dqs_dn(15)"
				( attribute "CDS_PHYS_NET_NAME" "M_L_DQS_DN<15>"
					( Origin gPackager )
				)
				( attribute "PNN" "M_L_DQS_DN<15>"
					( Origin gPackager )
				)
				( objectStatus "M_L_DQS_DN<15>" )
			)
			( signal "@baseboard_fab2_lib.baseboard_fab2(sch_1):m_l_dqs_dn(16)"
				( attribute "CDS_PHYS_NET_NAME" "M_L_DQS_DN<16>"
					( Origin gPackager )
				)
				( attribute "PNN" "M_L_DQS_DN<16>"
					( Origin gPackager )
				)
				( objectStatus "M_L_DQS_DN<16>" )
			)
			( signal "@baseboard_fab2_lib.baseboard_fab2(sch_1):m_l_dqs_dn(17)"
				( attribute "CDS_PHYS_NET_NAME" "M_L_DQS_DN<17>"
					( Origin gPackager )
				)
				( attribute "PNN" "M_L_DQS_DN<17>"
					( Origin gPackager )
				)
				( objectStatus "M_L_DQS_DN<17>" )
			)
			( signal "@baseboard_fab2_lib.baseboard_fab2(sch_1):m_l_dqs_dp(0)"
				( attribute "CDS_PHYS_NET_NAME" "M_L_DQS_DP<0>"
					( Origin gPackager )
				)
				( attribute "PNN" "M_L_DQS_DP<0>"
					( Origin gPackager )
				)
				( objectStatus "M_L_DQS_DP<0>" )
			)
			( signal "@baseboard_fab2_lib.baseboard_fab2(sch_1):m_l_dqs_dp(1)"
				( attribute "CDS_PHYS_NET_NAME" "M_L_DQS_DP<1>"
					( Origin gPackager )
				)
				( attribute "PNN" "M_L_DQS_DP<1>"
					( Origin gPackager )
				)
				( objectStatus "M_L_DQS_DP<1>" )
			)
			( signal "@baseboard_fab2_lib.baseboard_fab2(sch_1):m_l_dqs_dp(2)"
				( attribute "CDS_PHYS_NET_NAME" "M_L_DQS_DP<2>"
					( Origin gPackager )
				)
				( attribute "PNN" "M_L_DQS_DP<2>"
					( Origin gPackager )
				)
				( objectStatus "M_L_DQS_DP<2>" )
			)
			( signal "@baseboard_fab2_lib.baseboard_fab2(sch_1):m_l_dqs_dp(3)"
				( attribute "CDS_PHYS_NET_NAME" "M_L_DQS_DP<3>"
					( Origin gPackager )
				)
				( attribute "PNN" "M_L_DQS_DP<3>"
					( Origin gPackager )
				)
				( objectStatus "M_L_DQS_DP<3>" )
			)
			( signal "@baseboard_fab2_lib.baseboard_fab2(sch_1):m_l_dqs_dp(4)"
				( attribute "CDS_PHYS_NET_NAME" "M_L_DQS_DP<4>"
					( Origin gPackager )
				)
				( attribute "PNN" "M_L_DQS_DP<4>"
					( Origin gPackager )
				)
				( objectStatus "M_L_DQS_DP<4>" )
			)
			( signal "@baseboard_fab2_lib.baseboard_fab2(sch_1):m_l_dqs_dp(5)"
				( attribute "CDS_PHYS_NET_NAME" "M_L_DQS_DP<5>"
					( Origin gPackager )
				)
				( attribute "PNN" "M_L_DQS_DP<5>"
					( Origin gPackager )
				)
				( objectStatus "M_L_DQS_DP<5>" )
			)
			( signal "@baseboard_fab2_lib.baseboard_fab2(sch_1):m_l_dqs_dp(6)"
				( attribute "CDS_PHYS_NET_NAME" "M_L_DQS_DP<6>"
					( Origin gPackager )
				)
				( attribute "PNN" "M_L_DQS_DP<6>"
					( Origin gPackager )
				)
				( objectStatus "M_L_DQS_DP<6>" )
			)
			( signal "@baseboard_fab2_lib.baseboard_fab2(sch_1):m_l_dqs_dp(7)"
				( attribute "CDS_PHYS_NET_NAME" "M_L_DQS_DP<7>"
					( Origin gPackager )
				)
				( attribute "PNN" "M_L_DQS_DP<7>"
					( Origin gPackager )
				)
				( objectStatus "M_L_DQS_DP<7>" )
			)
			( signal "@baseboard_fab2_lib.baseboard_fab2(sch_1):m_l_dqs_dp(8)"
				( attribute "CDS_PHYS_NET_NAME" "M_L_DQS_DP<8>"
					( Origin gPackager )
				)
				( attribute "PNN" "M_L_DQS_DP<8>"
					( Origin gPackager )
				)
				( objectStatus "M_L_DQS_DP<8>" )
			)
			( signal "@baseboard_fab2_lib.baseboard_fab2(sch_1):m_l_dqs_dp(9)"
				( attribute "CDS_PHYS_NET_NAME" "M_L_DQS_DP<9>"
					( Origin gPackager )
				)
				( attribute "PNN" "M_L_DQS_DP<9>"
					( Origin gPackager )
				)
				( objectStatus "M_L_DQS_DP<9>" )
			)
			( signal "@baseboard_fab2_lib.baseboard_fab2(sch_1):m_l_dqs_dp(10)"
				( attribute "CDS_PHYS_NET_NAME" "M_L_DQS_DP<10>"
					( Origin gPackager )
				)
				( attribute "PNN" "M_L_DQS_DP<10>"
					( Origin gPackager )
				)
				( objectStatus "M_L_DQS_DP<10>" )
			)
			( signal "@baseboard_fab2_lib.baseboard_fab2(sch_1):m_l_dqs_dp(11)"
				( attribute "CDS_PHYS_NET_NAME" "M_L_DQS_DP<11>"
					( Origin gPackager )
				)
				( attribute "PNN" "M_L_DQS_DP<11>"
					( Origin gPackager )
				)
				( objectStatus "M_L_DQS_DP<11>" )
			)
			( signal "@baseboard_fab2_lib.baseboard_fab2(sch_1):m_l_dqs_dp(12)"
				( attribute "CDS_PHYS_NET_NAME" "M_L_DQS_DP<12>"
					( Origin gPackager )
				)
				( attribute "PNN" "M_L_DQS_DP<12>"
					( Origin gPackager )
				)
				( objectStatus "M_L_DQS_DP<12>" )
			)
			( signal "@baseboard_fab2_lib.baseboard_fab2(sch_1):m_l_dqs_dp(13)"
				( attribute "CDS_PHYS_NET_NAME" "M_L_DQS_DP<13>"
					( Origin gPackager )
				)
				( attribute "PNN" "M_L_DQS_DP<13>"
					( Origin gPackager )
				)
				( objectStatus "M_L_DQS_DP<13>" )
			)
			( signal "@baseboard_fab2_lib.baseboard_fab2(sch_1):m_l_dqs_dp(14)"
				( attribute "CDS_PHYS_NET_NAME" "M_L_DQS_DP<14>"
					( Origin gPackager )
				)
				( attribute "PNN" "M_L_DQS_DP<14>"
					( Origin gPackager )
				)
				( objectStatus "M_L_DQS_DP<14>" )
			)
			( signal "@baseboard_fab2_lib.baseboard_fab2(sch_1):m_l_dqs_dp(15)"
				( attribute "CDS_PHYS_NET_NAME" "M_L_DQS_DP<15>"
					( Origin gPackager )
				)
				( attribute "PNN" "M_L_DQS_DP<15>"
					( Origin gPackager )
				)
				( objectStatus "M_L_DQS_DP<15>" )
			)
			( signal "@baseboard_fab2_lib.baseboard_fab2(sch_1):m_l_dqs_dp(16)"
				( attribute "CDS_PHYS_NET_NAME" "M_L_DQS_DP<16>"
					( Origin gPackager )
				)
				( attribute "PNN" "M_L_DQS_DP<16>"
					( Origin gPackager )
				)
				( objectStatus "M_L_DQS_DP<16>" )
			)
			( signal "@baseboard_fab2_lib.baseboard_fab2(sch_1):m_l_dqs_dp(17)"
				( attribute "CDS_PHYS_NET_NAME" "M_L_DQS_DP<17>"
					( Origin gPackager )
				)
				( attribute "PNN" "M_L_DQS_DP<17>"
					( Origin gPackager )
				)
				( objectStatus "M_L_DQS_DP<17>" )
			)
			( signal "@baseboard_fab2_lib.baseboard_fab2(sch_1):m_l_ecc(0)"
				( attribute "CDS_PHYS_NET_NAME" "M_L_ECC<0>"
					( Origin gPackager )
				)
				( attribute "PNN" "M_L_ECC<0>"
					( Origin gPackager )
				)
				( objectStatus "M_L_ECC<0>" )
			)
			( signal "@baseboard_fab2_lib.baseboard_fab2(sch_1):m_l_ecc(1)"
				( attribute "CDS_PHYS_NET_NAME" "M_L_ECC<1>"
					( Origin gPackager )
				)
				( attribute "PNN" "M_L_ECC<1>"
					( Origin gPackager )
				)
				( objectStatus "M_L_ECC<1>" )
			)
			( signal "@baseboard_fab2_lib.baseboard_fab2(sch_1):m_l_ecc(2)"
				( attribute "CDS_PHYS_NET_NAME" "M_L_ECC<2>"
					( Origin gPackager )
				)
				( attribute "PNN" "M_L_ECC<2>"
					( Origin gPackager )
				)
				( objectStatus "M_L_ECC<2>" )
			)
			( signal "@baseboard_fab2_lib.baseboard_fab2(sch_1):m_l_ecc(3)"
				( attribute "CDS_PHYS_NET_NAME" "M_L_ECC<3>"
					( Origin gPackager )
				)
				( attribute "PNN" "M_L_ECC<3>"
					( Origin gPackager )
				)
				( objectStatus "M_L_ECC<3>" )
			)
			( signal "@baseboard_fab2_lib.baseboard_fab2(sch_1):m_l_ecc(4)"
				( attribute "CDS_PHYS_NET_NAME" "M_L_ECC<4>"
					( Origin gPackager )
				)
				( attribute "PNN" "M_L_ECC<4>"
					( Origin gPackager )
				)
				( objectStatus "M_L_ECC<4>" )
			)
			( signal "@baseboard_fab2_lib.baseboard_fab2(sch_1):m_l_ecc(5)"
				( attribute "CDS_PHYS_NET_NAME" "M_L_ECC<5>"
					( Origin gPackager )
				)
				( attribute "PNN" "M_L_ECC<5>"
					( Origin gPackager )
				)
				( objectStatus "M_L_ECC<5>" )
			)
			( signal "@baseboard_fab2_lib.baseboard_fab2(sch_1):m_l_ecc(6)"
				( attribute "CDS_PHYS_NET_NAME" "M_L_ECC<6>"
					( Origin gPackager )
				)
				( attribute "PNN" "M_L_ECC<6>"
					( Origin gPackager )
				)
				( objectStatus "M_L_ECC<6>" )
			)
			( signal "@baseboard_fab2_lib.baseboard_fab2(sch_1):m_l_ecc(7)"
				( attribute "CDS_PHYS_NET_NAME" "M_L_ECC<7>"
					( Origin gPackager )
				)
				( attribute "PNN" "M_L_ECC<7>"
					( Origin gPackager )
				)
				( objectStatus "M_L_ECC<7>" )
			)
			( signal "@baseboard_fab2_lib.baseboard_fab2(sch_1):m_l_ma(0)"
				( attribute "CDS_PHYS_NET_NAME" "M_L_MA<0>"
					( Origin gPackager )
				)
				( attribute "PNN" "M_L_MA<0>"
					( Origin gPackager )
				)
				( objectStatus "M_L_MA<0>" )
			)
			( signal "@baseboard_fab2_lib.baseboard_fab2(sch_1):m_l_ma(1)"
				( attribute "CDS_PHYS_NET_NAME" "M_L_MA<1>"
					( Origin gPackager )
				)
				( attribute "PNN" "M_L_MA<1>"
					( Origin gPackager )
				)
				( objectStatus "M_L_MA<1>" )
			)
			( signal "@baseboard_fab2_lib.baseboard_fab2(sch_1):m_l_ma(2)"
				( attribute "CDS_PHYS_NET_NAME" "M_L_MA<2>"
					( Origin gPackager )
				)
				( attribute "PNN" "M_L_MA<2>"
					( Origin gPackager )
				)
				( objectStatus "M_L_MA<2>" )
			)
			( signal "@baseboard_fab2_lib.baseboard_fab2(sch_1):m_l_ma(3)"
				( attribute "CDS_PHYS_NET_NAME" "M_L_MA<3>"
					( Origin gPackager )
				)
				( attribute "PNN" "M_L_MA<3>"
					( Origin gPackager )
				)
				( objectStatus "M_L_MA<3>" )
			)
			( signal "@baseboard_fab2_lib.baseboard_fab2(sch_1):m_l_ma(4)"
				( attribute "CDS_PHYS_NET_NAME" "M_L_MA<4>"
					( Origin gPackager )
				)
				( attribute "PNN" "M_L_MA<4>"
					( Origin gPackager )
				)
				( objectStatus "M_L_MA<4>" )
			)
			( signal "@baseboard_fab2_lib.baseboard_fab2(sch_1):m_l_ma(5)"
				( attribute "CDS_PHYS_NET_NAME" "M_L_MA<5>"
					( Origin gPackager )
				)
				( attribute "PNN" "M_L_MA<5>"
					( Origin gPackager )
				)
				( objectStatus "M_L_MA<5>" )
			)
			( signal "@baseboard_fab2_lib.baseboard_fab2(sch_1):m_l_ma(6)"
				( attribute "CDS_PHYS_NET_NAME" "M_L_MA<6>"
					( Origin gPackager )
				)
				( attribute "PNN" "M_L_MA<6>"
					( Origin gPackager )
				)
				( objectStatus "M_L_MA<6>" )
			)
			( signal "@baseboard_fab2_lib.baseboard_fab2(sch_1):m_l_ma(7)"
				( attribute "CDS_PHYS_NET_NAME" "M_L_MA<7>"
					( Origin gPackager )
				)
				( attribute "PNN" "M_L_MA<7>"
					( Origin gPackager )
				)
				( objectStatus "M_L_MA<7>" )
			)
			( signal "@baseboard_fab2_lib.baseboard_fab2(sch_1):m_l_ma(8)"
				( attribute "CDS_PHYS_NET_NAME" "M_L_MA<8>"
					( Origin gPackager )
				)
				( attribute "PNN" "M_L_MA<8>"
					( Origin gPackager )
				)
				( objectStatus "M_L_MA<8>" )
			)
			( signal "@baseboard_fab2_lib.baseboard_fab2(sch_1):m_l_ma(9)"
				( attribute "CDS_PHYS_NET_NAME" "M_L_MA<9>"
					( Origin gPackager )
				)
				( attribute "PNN" "M_L_MA<9>"
					( Origin gPackager )
				)
				( objectStatus "M_L_MA<9>" )
			)
			( signal "@baseboard_fab2_lib.baseboard_fab2(sch_1):m_l_ma(10)"
				( attribute "CDS_PHYS_NET_NAME" "M_L_MA<10>"
					( Origin gPackager )
				)
				( attribute "PNN" "M_L_MA<10>"
					( Origin gPackager )
				)
				( objectStatus "M_L_MA<10>" )
			)
			( signal "@baseboard_fab2_lib.baseboard_fab2(sch_1):m_l_ma(11)"
				( attribute "CDS_PHYS_NET_NAME" "M_L_MA<11>"
					( Origin gPackager )
				)
				( attribute "PNN" "M_L_MA<11>"
					( Origin gPackager )
				)
				( objectStatus "M_L_MA<11>" )
			)
			( signal "@baseboard_fab2_lib.baseboard_fab2(sch_1):m_l_ma(12)"
				( attribute "CDS_PHYS_NET_NAME" "M_L_MA<12>"
					( Origin gPackager )
				)
				( attribute "PNN" "M_L_MA<12>"
					( Origin gPackager )
				)
				( objectStatus "M_L_MA<12>" )
			)
			( signal "@baseboard_fab2_lib.baseboard_fab2(sch_1):m_l_ma(13)"
				( attribute "CDS_PHYS_NET_NAME" "M_L_MA<13>"
					( Origin gPackager )
				)
				( attribute "PNN" "M_L_MA<13>"
					( Origin gPackager )
				)
				( objectStatus "M_L_MA<13>" )
			)
			( signal "@baseboard_fab2_lib.baseboard_fab2(sch_1):m_l_ma(14)"
				( attribute "CDS_PHYS_NET_NAME" "M_L_MA<14>"
					( Origin gPackager )
				)
				( attribute "PNN" "M_L_MA<14>"
					( Origin gPackager )
				)
				( objectStatus "M_L_MA<14>" )
			)
			( signal "@baseboard_fab2_lib.baseboard_fab2(sch_1):m_l_ma(15)"
				( attribute "CDS_PHYS_NET_NAME" "M_L_MA<15>"
					( Origin gPackager )
				)
				( attribute "PNN" "M_L_MA<15>"
					( Origin gPackager )
				)
				( objectStatus "M_L_MA<15>" )
			)
			( signal "@baseboard_fab2_lib.baseboard_fab2(sch_1):m_l_ma(16)"
				( attribute "CDS_PHYS_NET_NAME" "M_L_MA<16>"
					( Origin gPackager )
				)
				( attribute "PNN" "M_L_MA<16>"
					( Origin gPackager )
				)
				( objectStatus "M_L_MA<16>" )
			)
			( signal "@baseboard_fab2_lib.baseboard_fab2(sch_1):m_l_ma(17)"
				( attribute "CDS_PHYS_NET_NAME" "M_L_MA<17>"
					( Origin gPackager )
				)
				( attribute "PNN" "M_L_MA<17>"
					( Origin gPackager )
				)
				( objectStatus "M_L_MA<17>" )
			)
			( signal "@baseboard_fab2_lib.baseboard_fab2(sch_1):m_l_odt(0)"
				( attribute "CDS_PHYS_NET_NAME" "M_L_ODT<0>"
					( Origin gPackager )
				)
				( attribute "PNN" "M_L_ODT<0>"
					( Origin gPackager )
				)
				( objectStatus "M_L_ODT<0>" )
			)
			( signal "@baseboard_fab2_lib.baseboard_fab2(sch_1):m_l_odt(1)"
				( attribute "CDS_PHYS_NET_NAME" "M_L_ODT<1>"
					( Origin gPackager )
				)
				( attribute "PNN" "M_L_ODT<1>"
					( Origin gPackager )
				)
				( objectStatus "M_L_ODT<1>" )
			)
			( signal "@baseboard_fab2_lib.baseboard_fab2(sch_1):m_l_odt(2)"
				( attribute "CDS_PHYS_NET_NAME" "M_L_ODT<2>"
					( Origin gPackager )
				)
				( attribute "PNN" "M_L_ODT<2>"
					( Origin gPackager )
				)
				( objectStatus "M_L_ODT<2>" )
			)
			( signal "@baseboard_fab2_lib.baseboard_fab2(sch_1):m_l_odt(3)"
				( attribute "CDS_PHYS_NET_NAME" "M_L_ODT<3>"
					( Origin gPackager )
				)
				( attribute "PNN" "M_L_ODT<3>"
					( Origin gPackager )
				)
				( objectStatus "M_L_ODT<3>" )
			)
			( signal "@baseboard_fab2_lib.baseboard_fab2(sch_1):m_l_par"
				( attribute "CDS_PHYS_NET_NAME" "M_L_PAR"
					( Origin gPackager )
				)
				( objectStatus "M_L_PAR" )
			)
			( signal "@baseboard_fab2_lib.baseboard_fab2(sch_1):m_m_act_n"
				( attribute "CDS_PHYS_NET_NAME" "M_M_ACT_N"
					( Origin gPackager )
				)
				( objectStatus "M_M_ACT_N" )
			)
			( signal "@baseboard_fab2_lib.baseboard_fab2(sch_1):m_m_alert_n"
				( attribute "CDS_PHYS_NET_NAME" "M_M_ALERT_N"
					( Origin gPackager )
				)
				( objectStatus "M_M_ALERT_N" )
			)
			( signal "@baseboard_fab2_lib.baseboard_fab2(sch_1):m_m_ba(0)"
				( attribute "CDS_PHYS_NET_NAME" "M_M_BA<0>"
					( Origin gPackager )
				)
				( attribute "PNN" "M_M_BA<0>"
					( Origin gPackager )
				)
				( objectStatus "M_M_BA<0>" )
			)
			( signal "@baseboard_fab2_lib.baseboard_fab2(sch_1):m_m_ba(1)"
				( attribute "CDS_PHYS_NET_NAME" "M_M_BA<1>"
					( Origin gPackager )
				)
				( attribute "PNN" "M_M_BA<1>"
					( Origin gPackager )
				)
				( objectStatus "M_M_BA<1>" )
			)
			( signal "@baseboard_fab2_lib.baseboard_fab2(sch_1):m_m_bg(0)"
				( attribute "CDS_PHYS_NET_NAME" "M_M_BG<0>"
					( Origin gPackager )
				)
				( attribute "PNN" "M_M_BG<0>"
					( Origin gPackager )
				)
				( objectStatus "M_M_BG<0>" )
			)
			( signal "@baseboard_fab2_lib.baseboard_fab2(sch_1):m_m_bg(1)"
				( attribute "CDS_PHYS_NET_NAME" "M_M_BG<1>"
					( Origin gPackager )
				)
				( attribute "PNN" "M_M_BG<1>"
					( Origin gPackager )
				)
				( objectStatus "M_M_BG<1>" )
			)
			( signal "@baseboard_fab2_lib.baseboard_fab2(sch_1):m_m_c(2)"
				( attribute "CDS_PHYS_NET_NAME" "M_M_C<2>"
					( Origin gPackager )
				)
				( attribute "PNN" "M_M_C<2>"
					( Origin gPackager )
				)
				( objectStatus "M_M_C<2>" )
			)
			( signal "@baseboard_fab2_lib.baseboard_fab2(sch_1):m_m_cke(0)"
				( attribute "CDS_PHYS_NET_NAME" "M_M_CKE<0>"
					( Origin gPackager )
				)
				( attribute "PNN" "M_M_CKE<0>"
					( Origin gPackager )
				)
				( objectStatus "M_M_CKE<0>" )
			)
			( signal "@baseboard_fab2_lib.baseboard_fab2(sch_1):m_m_cke(1)"
				( attribute "CDS_PHYS_NET_NAME" "M_M_CKE<1>"
					( Origin gPackager )
				)
				( attribute "PNN" "M_M_CKE<1>"
					( Origin gPackager )
				)
				( objectStatus "M_M_CKE<1>" )
			)
			( signal "@baseboard_fab2_lib.baseboard_fab2(sch_1):m_m_cke(2)"
				( attribute "CDS_PHYS_NET_NAME" "M_M_CKE<2>"
					( Origin gPackager )
				)
				( attribute "PNN" "M_M_CKE<2>"
					( Origin gPackager )
				)
				( objectStatus "M_M_CKE<2>" )
			)
			( signal "@baseboard_fab2_lib.baseboard_fab2(sch_1):m_m_cke(3)"
				( attribute "CDS_PHYS_NET_NAME" "M_M_CKE<3>"
					( Origin gPackager )
				)
				( attribute "PNN" "M_M_CKE<3>"
					( Origin gPackager )
				)
				( objectStatus "M_M_CKE<3>" )
			)
			( signal "@baseboard_fab2_lib.baseboard_fab2(sch_1):m_m_clk_dn(0)"
				( attribute "CDS_PHYS_NET_NAME" "M_M_CLK_DN<0>"
					( Origin gPackager )
				)
				( attribute "PNN" "M_M_CLK_DN<0>"
					( Origin gPackager )
				)
				( objectStatus "M_M_CLK_DN<0>" )
			)
			( signal "@baseboard_fab2_lib.baseboard_fab2(sch_1):m_m_clk_dn(1)"
				( attribute "CDS_PHYS_NET_NAME" "M_M_CLK_DN<1>"
					( Origin gPackager )
				)
				( attribute "PNN" "M_M_CLK_DN<1>"
					( Origin gPackager )
				)
				( objectStatus "M_M_CLK_DN<1>" )
			)
			( signal "@baseboard_fab2_lib.baseboard_fab2(sch_1):m_m_clk_dn(2)"
				( attribute "CDS_PHYS_NET_NAME" "M_M_CLK_DN<2>"
					( Origin gPackager )
				)
				( attribute "PNN" "M_M_CLK_DN<2>"
					( Origin gPackager )
				)
				( objectStatus "M_M_CLK_DN<2>" )
			)
			( signal "@baseboard_fab2_lib.baseboard_fab2(sch_1):m_m_clk_dn(3)"
				( attribute "CDS_PHYS_NET_NAME" "M_M_CLK_DN<3>"
					( Origin gPackager )
				)
				( attribute "PNN" "M_M_CLK_DN<3>"
					( Origin gPackager )
				)
				( objectStatus "M_M_CLK_DN<3>" )
			)
			( signal "@baseboard_fab2_lib.baseboard_fab2(sch_1):m_m_clk_dp(0)"
				( attribute "CDS_PHYS_NET_NAME" "M_M_CLK_DP<0>"
					( Origin gPackager )
				)
				( attribute "PNN" "M_M_CLK_DP<0>"
					( Origin gPackager )
				)
				( objectStatus "M_M_CLK_DP<0>" )
			)
			( signal "@baseboard_fab2_lib.baseboard_fab2(sch_1):m_m_clk_dp(1)"
				( attribute "CDS_PHYS_NET_NAME" "M_M_CLK_DP<1>"
					( Origin gPackager )
				)
				( attribute "PNN" "M_M_CLK_DP<1>"
					( Origin gPackager )
				)
				( objectStatus "M_M_CLK_DP<1>" )
			)
			( signal "@baseboard_fab2_lib.baseboard_fab2(sch_1):m_m_clk_dp(2)"
				( attribute "CDS_PHYS_NET_NAME" "M_M_CLK_DP<2>"
					( Origin gPackager )
				)
				( attribute "PNN" "M_M_CLK_DP<2>"
					( Origin gPackager )
				)
				( objectStatus "M_M_CLK_DP<2>" )
			)
			( signal "@baseboard_fab2_lib.baseboard_fab2(sch_1):m_m_clk_dp(3)"
				( attribute "CDS_PHYS_NET_NAME" "M_M_CLK_DP<3>"
					( Origin gPackager )
				)
				( attribute "PNN" "M_M_CLK_DP<3>"
					( Origin gPackager )
				)
				( objectStatus "M_M_CLK_DP<3>" )
			)
			( signal "@baseboard_fab2_lib.baseboard_fab2(sch_1):m_m_cs_n(0)"
				( attribute "CDS_PHYS_NET_NAME" "M_M_CS_N<0>"
					( Origin gPackager )
				)
				( attribute "PNN" "M_M_CS_N<0>"
					( Origin gPackager )
				)
				( objectStatus "M_M_CS_N<0>" )
			)
			( signal "@baseboard_fab2_lib.baseboard_fab2(sch_1):m_m_cs_n(1)"
				( attribute "CDS_PHYS_NET_NAME" "M_M_CS_N<1>"
					( Origin gPackager )
				)
				( attribute "PNN" "M_M_CS_N<1>"
					( Origin gPackager )
				)
				( objectStatus "M_M_CS_N<1>" )
			)
			( signal "@baseboard_fab2_lib.baseboard_fab2(sch_1):m_m_cs_n(2)"
				( attribute "CDS_PHYS_NET_NAME" "M_M_CS_N<2>"
					( Origin gPackager )
				)
				( attribute "PNN" "M_M_CS_N<2>"
					( Origin gPackager )
				)
				( objectStatus "M_M_CS_N<2>" )
			)
			( signal "@baseboard_fab2_lib.baseboard_fab2(sch_1):m_m_cs_n(3)"
				( attribute "CDS_PHYS_NET_NAME" "M_M_CS_N<3>"
					( Origin gPackager )
				)
				( attribute "PNN" "M_M_CS_N<3>"
					( Origin gPackager )
				)
				( objectStatus "M_M_CS_N<3>" )
			)
			( signal "@baseboard_fab2_lib.baseboard_fab2(sch_1):m_m_cs_n(4)"
				( attribute "CDS_PHYS_NET_NAME" "M_M_CS_N<4>"
					( Origin gPackager )
				)
				( attribute "PNN" "M_M_CS_N<4>"
					( Origin gPackager )
				)
				( objectStatus "M_M_CS_N<4>" )
			)
			( signal "@baseboard_fab2_lib.baseboard_fab2(sch_1):m_m_cs_n(5)"
				( attribute "CDS_PHYS_NET_NAME" "M_M_CS_N<5>"
					( Origin gPackager )
				)
				( attribute "PNN" "M_M_CS_N<5>"
					( Origin gPackager )
				)
				( objectStatus "M_M_CS_N<5>" )
			)
			( signal "@baseboard_fab2_lib.baseboard_fab2(sch_1):m_m_cs_n(6)"
				( attribute "CDS_PHYS_NET_NAME" "M_M_CS_N<6>"
					( Origin gPackager )
				)
				( attribute "PNN" "M_M_CS_N<6>"
					( Origin gPackager )
				)
				( objectStatus "M_M_CS_N<6>" )
			)
			( signal "@baseboard_fab2_lib.baseboard_fab2(sch_1):m_m_cs_n(7)"
				( attribute "CDS_PHYS_NET_NAME" "M_M_CS_N<7>"
					( Origin gPackager )
				)
				( attribute "PNN" "M_M_CS_N<7>"
					( Origin gPackager )
				)
				( objectStatus "M_M_CS_N<7>" )
			)
			( signal "@baseboard_fab2_lib.baseboard_fab2(sch_1):m_m_dq(0)"
				( attribute "CDS_PHYS_NET_NAME" "M_M_DQ<0>"
					( Origin gPackager )
				)
				( attribute "PNN" "M_M_DQ<0>"
					( Origin gPackager )
				)
				( objectStatus "M_M_DQ<0>" )
			)
			( signal "@baseboard_fab2_lib.baseboard_fab2(sch_1):m_m_dq(1)"
				( attribute "CDS_PHYS_NET_NAME" "M_M_DQ<1>"
					( Origin gPackager )
				)
				( attribute "PNN" "M_M_DQ<1>"
					( Origin gPackager )
				)
				( objectStatus "M_M_DQ<1>" )
			)
			( signal "@baseboard_fab2_lib.baseboard_fab2(sch_1):m_m_dq(2)"
				( attribute "CDS_PHYS_NET_NAME" "M_M_DQ<2>"
					( Origin gPackager )
				)
				( attribute "PNN" "M_M_DQ<2>"
					( Origin gPackager )
				)
				( objectStatus "M_M_DQ<2>" )
			)
			( signal "@baseboard_fab2_lib.baseboard_fab2(sch_1):m_m_dq(3)"
				( attribute "CDS_PHYS_NET_NAME" "M_M_DQ<3>"
					( Origin gPackager )
				)
				( attribute "PNN" "M_M_DQ<3>"
					( Origin gPackager )
				)
				( objectStatus "M_M_DQ<3>" )
			)
			( signal "@baseboard_fab2_lib.baseboard_fab2(sch_1):m_m_dq(4)"
				( attribute "CDS_PHYS_NET_NAME" "M_M_DQ<4>"
					( Origin gPackager )
				)
				( attribute "PNN" "M_M_DQ<4>"
					( Origin gPackager )
				)
				( objectStatus "M_M_DQ<4>" )
			)
			( signal "@baseboard_fab2_lib.baseboard_fab2(sch_1):m_m_dq(5)"
				( attribute "CDS_PHYS_NET_NAME" "M_M_DQ<5>"
					( Origin gPackager )
				)
				( attribute "PNN" "M_M_DQ<5>"
					( Origin gPackager )
				)
				( objectStatus "M_M_DQ<5>" )
			)
			( signal "@baseboard_fab2_lib.baseboard_fab2(sch_1):m_m_dq(6)"
				( attribute "CDS_PHYS_NET_NAME" "M_M_DQ<6>"
					( Origin gPackager )
				)
				( attribute "PNN" "M_M_DQ<6>"
					( Origin gPackager )
				)
				( objectStatus "M_M_DQ<6>" )
			)
			( signal "@baseboard_fab2_lib.baseboard_fab2(sch_1):m_m_dq(7)"
				( attribute "CDS_PHYS_NET_NAME" "M_M_DQ<7>"
					( Origin gPackager )
				)
				( attribute "PNN" "M_M_DQ<7>"
					( Origin gPackager )
				)
				( objectStatus "M_M_DQ<7>" )
			)
			( signal "@baseboard_fab2_lib.baseboard_fab2(sch_1):m_m_dq(8)"
				( attribute "CDS_PHYS_NET_NAME" "M_M_DQ<8>"
					( Origin gPackager )
				)
				( attribute "PNN" "M_M_DQ<8>"
					( Origin gPackager )
				)
				( objectStatus "M_M_DQ<8>" )
			)
			( signal "@baseboard_fab2_lib.baseboard_fab2(sch_1):m_m_dq(9)"
				( attribute "CDS_PHYS_NET_NAME" "M_M_DQ<9>"
					( Origin gPackager )
				)
				( attribute "PNN" "M_M_DQ<9>"
					( Origin gPackager )
				)
				( objectStatus "M_M_DQ<9>" )
			)
			( signal "@baseboard_fab2_lib.baseboard_fab2(sch_1):m_m_dq(10)"
				( attribute "CDS_PHYS_NET_NAME" "M_M_DQ<10>"
					( Origin gPackager )
				)
				( attribute "PNN" "M_M_DQ<10>"
					( Origin gPackager )
				)
				( objectStatus "M_M_DQ<10>" )
			)
			( signal "@baseboard_fab2_lib.baseboard_fab2(sch_1):m_m_dq(11)"
				( attribute "CDS_PHYS_NET_NAME" "M_M_DQ<11>"
					( Origin gPackager )
				)
				( attribute "PNN" "M_M_DQ<11>"
					( Origin gPackager )
				)
				( objectStatus "M_M_DQ<11>" )
			)
			( signal "@baseboard_fab2_lib.baseboard_fab2(sch_1):m_m_dq(12)"
				( attribute "CDS_PHYS_NET_NAME" "M_M_DQ<12>"
					( Origin gPackager )
				)
				( attribute "PNN" "M_M_DQ<12>"
					( Origin gPackager )
				)
				( objectStatus "M_M_DQ<12>" )
			)
			( signal "@baseboard_fab2_lib.baseboard_fab2(sch_1):m_m_dq(13)"
				( attribute "CDS_PHYS_NET_NAME" "M_M_DQ<13>"
					( Origin gPackager )
				)
				( attribute "PNN" "M_M_DQ<13>"
					( Origin gPackager )
				)
				( objectStatus "M_M_DQ<13>" )
			)
			( signal "@baseboard_fab2_lib.baseboard_fab2(sch_1):m_m_dq(14)"
				( attribute "CDS_PHYS_NET_NAME" "M_M_DQ<14>"
					( Origin gPackager )
				)
				( attribute "PNN" "M_M_DQ<14>"
					( Origin gPackager )
				)
				( objectStatus "M_M_DQ<14>" )
			)
			( signal "@baseboard_fab2_lib.baseboard_fab2(sch_1):m_m_dq(15)"
				( attribute "CDS_PHYS_NET_NAME" "M_M_DQ<15>"
					( Origin gPackager )
				)
				( attribute "PNN" "M_M_DQ<15>"
					( Origin gPackager )
				)
				( objectStatus "M_M_DQ<15>" )
			)
			( signal "@baseboard_fab2_lib.baseboard_fab2(sch_1):m_m_dq(16)"
				( attribute "CDS_PHYS_NET_NAME" "M_M_DQ<16>"
					( Origin gPackager )
				)
				( attribute "PNN" "M_M_DQ<16>"
					( Origin gPackager )
				)
				( objectStatus "M_M_DQ<16>" )
			)
			( signal "@baseboard_fab2_lib.baseboard_fab2(sch_1):m_m_dq(17)"
				( attribute "CDS_PHYS_NET_NAME" "M_M_DQ<17>"
					( Origin gPackager )
				)
				( attribute "PNN" "M_M_DQ<17>"
					( Origin gPackager )
				)
				( objectStatus "M_M_DQ<17>" )
			)
			( signal "@baseboard_fab2_lib.baseboard_fab2(sch_1):m_m_dq(18)"
				( attribute "CDS_PHYS_NET_NAME" "M_M_DQ<18>"
					( Origin gPackager )
				)
				( attribute "PNN" "M_M_DQ<18>"
					( Origin gPackager )
				)
				( objectStatus "M_M_DQ<18>" )
			)
			( signal "@baseboard_fab2_lib.baseboard_fab2(sch_1):m_m_dq(19)"
				( attribute "CDS_PHYS_NET_NAME" "M_M_DQ<19>"
					( Origin gPackager )
				)
				( attribute "PNN" "M_M_DQ<19>"
					( Origin gPackager )
				)
				( objectStatus "M_M_DQ<19>" )
			)
			( signal "@baseboard_fab2_lib.baseboard_fab2(sch_1):m_m_dq(20)"
				( attribute "CDS_PHYS_NET_NAME" "M_M_DQ<20>"
					( Origin gPackager )
				)
				( attribute "PNN" "M_M_DQ<20>"
					( Origin gPackager )
				)
				( objectStatus "M_M_DQ<20>" )
			)
			( signal "@baseboard_fab2_lib.baseboard_fab2(sch_1):m_m_dq(21)"
				( attribute "CDS_PHYS_NET_NAME" "M_M_DQ<21>"
					( Origin gPackager )
				)
				( attribute "PNN" "M_M_DQ<21>"
					( Origin gPackager )
				)
				( objectStatus "M_M_DQ<21>" )
			)
			( signal "@baseboard_fab2_lib.baseboard_fab2(sch_1):m_m_dq(22)"
				( attribute "CDS_PHYS_NET_NAME" "M_M_DQ<22>"
					( Origin gPackager )
				)
				( attribute "PNN" "M_M_DQ<22>"
					( Origin gPackager )
				)
				( objectStatus "M_M_DQ<22>" )
			)
			( signal "@baseboard_fab2_lib.baseboard_fab2(sch_1):m_m_dq(23)"
				( attribute "CDS_PHYS_NET_NAME" "M_M_DQ<23>"
					( Origin gPackager )
				)
				( attribute "PNN" "M_M_DQ<23>"
					( Origin gPackager )
				)
				( objectStatus "M_M_DQ<23>" )
			)
			( signal "@baseboard_fab2_lib.baseboard_fab2(sch_1):m_m_dq(24)"
				( attribute "CDS_PHYS_NET_NAME" "M_M_DQ<24>"
					( Origin gPackager )
				)
				( attribute "PNN" "M_M_DQ<24>"
					( Origin gPackager )
				)
				( objectStatus "M_M_DQ<24>" )
			)
			( signal "@baseboard_fab2_lib.baseboard_fab2(sch_1):m_m_dq(25)"
				( attribute "CDS_PHYS_NET_NAME" "M_M_DQ<25>"
					( Origin gPackager )
				)
				( attribute "PNN" "M_M_DQ<25>"
					( Origin gPackager )
				)
				( objectStatus "M_M_DQ<25>" )
			)
			( signal "@baseboard_fab2_lib.baseboard_fab2(sch_1):m_m_dq(26)"
				( attribute "CDS_PHYS_NET_NAME" "M_M_DQ<26>"
					( Origin gPackager )
				)
				( attribute "PNN" "M_M_DQ<26>"
					( Origin gPackager )
				)
				( objectStatus "M_M_DQ<26>" )
			)
			( signal "@baseboard_fab2_lib.baseboard_fab2(sch_1):m_m_dq(27)"
				( attribute "CDS_PHYS_NET_NAME" "M_M_DQ<27>"
					( Origin gPackager )
				)
				( attribute "PNN" "M_M_DQ<27>"
					( Origin gPackager )
				)
				( objectStatus "M_M_DQ<27>" )
			)
			( signal "@baseboard_fab2_lib.baseboard_fab2(sch_1):m_m_dq(28)"
				( attribute "CDS_PHYS_NET_NAME" "M_M_DQ<28>"
					( Origin gPackager )
				)
				( attribute "PNN" "M_M_DQ<28>"
					( Origin gPackager )
				)
				( objectStatus "M_M_DQ<28>" )
			)
			( signal "@baseboard_fab2_lib.baseboard_fab2(sch_1):m_m_dq(29)"
				( attribute "CDS_PHYS_NET_NAME" "M_M_DQ<29>"
					( Origin gPackager )
				)
				( attribute "PNN" "M_M_DQ<29>"
					( Origin gPackager )
				)
				( objectStatus "M_M_DQ<29>" )
			)
			( signal "@baseboard_fab2_lib.baseboard_fab2(sch_1):m_m_dq(30)"
				( attribute "CDS_PHYS_NET_NAME" "M_M_DQ<30>"
					( Origin gPackager )
				)
				( attribute "PNN" "M_M_DQ<30>"
					( Origin gPackager )
				)
				( objectStatus "M_M_DQ<30>" )
			)
			( signal "@baseboard_fab2_lib.baseboard_fab2(sch_1):m_m_dq(31)"
				( attribute "CDS_PHYS_NET_NAME" "M_M_DQ<31>"
					( Origin gPackager )
				)
				( attribute "PNN" "M_M_DQ<31>"
					( Origin gPackager )
				)
				( objectStatus "M_M_DQ<31>" )
			)
			( signal "@baseboard_fab2_lib.baseboard_fab2(sch_1):m_m_dq(32)"
				( attribute "CDS_PHYS_NET_NAME" "M_M_DQ<32>"
					( Origin gPackager )
				)
				( attribute "PNN" "M_M_DQ<32>"
					( Origin gPackager )
				)
				( objectStatus "M_M_DQ<32>" )
			)
			( signal "@baseboard_fab2_lib.baseboard_fab2(sch_1):m_m_dq(33)"
				( attribute "CDS_PHYS_NET_NAME" "M_M_DQ<33>"
					( Origin gPackager )
				)
				( attribute "PNN" "M_M_DQ<33>"
					( Origin gPackager )
				)
				( objectStatus "M_M_DQ<33>" )
			)
			( signal "@baseboard_fab2_lib.baseboard_fab2(sch_1):m_m_dq(34)"
				( attribute "CDS_PHYS_NET_NAME" "M_M_DQ<34>"
					( Origin gPackager )
				)
				( attribute "PNN" "M_M_DQ<34>"
					( Origin gPackager )
				)
				( objectStatus "M_M_DQ<34>" )
			)
			( signal "@baseboard_fab2_lib.baseboard_fab2(sch_1):m_m_dq(35)"
				( attribute "CDS_PHYS_NET_NAME" "M_M_DQ<35>"
					( Origin gPackager )
				)
				( attribute "PNN" "M_M_DQ<35>"
					( Origin gPackager )
				)
				( objectStatus "M_M_DQ<35>" )
			)
			( signal "@baseboard_fab2_lib.baseboard_fab2(sch_1):m_m_dq(36)"
				( attribute "CDS_PHYS_NET_NAME" "M_M_DQ<36>"
					( Origin gPackager )
				)
				( attribute "PNN" "M_M_DQ<36>"
					( Origin gPackager )
				)
				( objectStatus "M_M_DQ<36>" )
			)
			( signal "@baseboard_fab2_lib.baseboard_fab2(sch_1):m_m_dq(37)"
				( attribute "CDS_PHYS_NET_NAME" "M_M_DQ<37>"
					( Origin gPackager )
				)
				( attribute "PNN" "M_M_DQ<37>"
					( Origin gPackager )
				)
				( objectStatus "M_M_DQ<37>" )
			)
			( signal "@baseboard_fab2_lib.baseboard_fab2(sch_1):m_m_dq(38)"
				( attribute "CDS_PHYS_NET_NAME" "M_M_DQ<38>"
					( Origin gPackager )
				)
				( attribute "PNN" "M_M_DQ<38>"
					( Origin gPackager )
				)
				( objectStatus "M_M_DQ<38>" )
			)
			( signal "@baseboard_fab2_lib.baseboard_fab2(sch_1):m_m_dq(39)"
				( attribute "CDS_PHYS_NET_NAME" "M_M_DQ<39>"
					( Origin gPackager )
				)
				( attribute "PNN" "M_M_DQ<39>"
					( Origin gPackager )
				)
				( objectStatus "M_M_DQ<39>" )
			)
			( signal "@baseboard_fab2_lib.baseboard_fab2(sch_1):m_m_dq(40)"
				( attribute "CDS_PHYS_NET_NAME" "M_M_DQ<40>"
					( Origin gPackager )
				)
				( attribute "PNN" "M_M_DQ<40>"
					( Origin gPackager )
				)
				( objectStatus "M_M_DQ<40>" )
			)
			( signal "@baseboard_fab2_lib.baseboard_fab2(sch_1):m_m_dq(41)"
				( attribute "CDS_PHYS_NET_NAME" "M_M_DQ<41>"
					( Origin gPackager )
				)
				( attribute "PNN" "M_M_DQ<41>"
					( Origin gPackager )
				)
				( objectStatus "M_M_DQ<41>" )
			)
			( signal "@baseboard_fab2_lib.baseboard_fab2(sch_1):m_m_dq(42)"
				( attribute "CDS_PHYS_NET_NAME" "M_M_DQ<42>"
					( Origin gPackager )
				)
				( attribute "PNN" "M_M_DQ<42>"
					( Origin gPackager )
				)
				( objectStatus "M_M_DQ<42>" )
			)
			( signal "@baseboard_fab2_lib.baseboard_fab2(sch_1):m_m_dq(43)"
				( attribute "CDS_PHYS_NET_NAME" "M_M_DQ<43>"
					( Origin gPackager )
				)
				( attribute "PNN" "M_M_DQ<43>"
					( Origin gPackager )
				)
				( objectStatus "M_M_DQ<43>" )
			)
			( signal "@baseboard_fab2_lib.baseboard_fab2(sch_1):m_m_dq(44)"
				( attribute "CDS_PHYS_NET_NAME" "M_M_DQ<44>"
					( Origin gPackager )
				)
				( attribute "PNN" "M_M_DQ<44>"
					( Origin gPackager )
				)
				( objectStatus "M_M_DQ<44>" )
			)
			( signal "@baseboard_fab2_lib.baseboard_fab2(sch_1):m_m_dq(45)"
				( attribute "CDS_PHYS_NET_NAME" "M_M_DQ<45>"
					( Origin gPackager )
				)
				( attribute "PNN" "M_M_DQ<45>"
					( Origin gPackager )
				)
				( objectStatus "M_M_DQ<45>" )
			)
			( signal "@baseboard_fab2_lib.baseboard_fab2(sch_1):m_m_dq(46)"
				( attribute "CDS_PHYS_NET_NAME" "M_M_DQ<46>"
					( Origin gPackager )
				)
				( attribute "PNN" "M_M_DQ<46>"
					( Origin gPackager )
				)
				( objectStatus "M_M_DQ<46>" )
			)
			( signal "@baseboard_fab2_lib.baseboard_fab2(sch_1):m_m_dq(47)"
				( attribute "CDS_PHYS_NET_NAME" "M_M_DQ<47>"
					( Origin gPackager )
				)
				( attribute "PNN" "M_M_DQ<47>"
					( Origin gPackager )
				)
				( objectStatus "M_M_DQ<47>" )
			)
			( signal "@baseboard_fab2_lib.baseboard_fab2(sch_1):m_m_dq(48)"
				( attribute "CDS_PHYS_NET_NAME" "M_M_DQ<48>"
					( Origin gPackager )
				)
				( attribute "PNN" "M_M_DQ<48>"
					( Origin gPackager )
				)
				( objectStatus "M_M_DQ<48>" )
			)
			( signal "@baseboard_fab2_lib.baseboard_fab2(sch_1):m_m_dq(49)"
				( attribute "CDS_PHYS_NET_NAME" "M_M_DQ<49>"
					( Origin gPackager )
				)
				( attribute "PNN" "M_M_DQ<49>"
					( Origin gPackager )
				)
				( objectStatus "M_M_DQ<49>" )
			)
			( signal "@baseboard_fab2_lib.baseboard_fab2(sch_1):m_m_dq(50)"
				( attribute "CDS_PHYS_NET_NAME" "M_M_DQ<50>"
					( Origin gPackager )
				)
				( attribute "PNN" "M_M_DQ<50>"
					( Origin gPackager )
				)
				( objectStatus "M_M_DQ<50>" )
			)
			( signal "@baseboard_fab2_lib.baseboard_fab2(sch_1):m_m_dq(51)"
				( attribute "CDS_PHYS_NET_NAME" "M_M_DQ<51>"
					( Origin gPackager )
				)
				( attribute "PNN" "M_M_DQ<51>"
					( Origin gPackager )
				)
				( objectStatus "M_M_DQ<51>" )
			)
			( signal "@baseboard_fab2_lib.baseboard_fab2(sch_1):m_m_dq(52)"
				( attribute "CDS_PHYS_NET_NAME" "M_M_DQ<52>"
					( Origin gPackager )
				)
				( attribute "PNN" "M_M_DQ<52>"
					( Origin gPackager )
				)
				( objectStatus "M_M_DQ<52>" )
			)
			( signal "@baseboard_fab2_lib.baseboard_fab2(sch_1):m_m_dq(53)"
				( attribute "CDS_PHYS_NET_NAME" "M_M_DQ<53>"
					( Origin gPackager )
				)
				( attribute "PNN" "M_M_DQ<53>"
					( Origin gPackager )
				)
				( objectStatus "M_M_DQ<53>" )
			)
			( signal "@baseboard_fab2_lib.baseboard_fab2(sch_1):m_m_dq(54)"
				( attribute "CDS_PHYS_NET_NAME" "M_M_DQ<54>"
					( Origin gPackager )
				)
				( attribute "PNN" "M_M_DQ<54>"
					( Origin gPackager )
				)
				( objectStatus "M_M_DQ<54>" )
			)
			( signal "@baseboard_fab2_lib.baseboard_fab2(sch_1):m_m_dq(55)"
				( attribute "CDS_PHYS_NET_NAME" "M_M_DQ<55>"
					( Origin gPackager )
				)
				( attribute "PNN" "M_M_DQ<55>"
					( Origin gPackager )
				)
				( objectStatus "M_M_DQ<55>" )
			)
			( signal "@baseboard_fab2_lib.baseboard_fab2(sch_1):m_m_dq(56)"
				( attribute "CDS_PHYS_NET_NAME" "M_M_DQ<56>"
					( Origin gPackager )
				)
				( attribute "PNN" "M_M_DQ<56>"
					( Origin gPackager )
				)
				( objectStatus "M_M_DQ<56>" )
			)
			( signal "@baseboard_fab2_lib.baseboard_fab2(sch_1):m_m_dq(57)"
				( attribute "CDS_PHYS_NET_NAME" "M_M_DQ<57>"
					( Origin gPackager )
				)
				( attribute "PNN" "M_M_DQ<57>"
					( Origin gPackager )
				)
				( objectStatus "M_M_DQ<57>" )
			)
			( signal "@baseboard_fab2_lib.baseboard_fab2(sch_1):m_m_dq(58)"
				( attribute "CDS_PHYS_NET_NAME" "M_M_DQ<58>"
					( Origin gPackager )
				)
				( attribute "PNN" "M_M_DQ<58>"
					( Origin gPackager )
				)
				( objectStatus "M_M_DQ<58>" )
			)
			( signal "@baseboard_fab2_lib.baseboard_fab2(sch_1):m_m_dq(59)"
				( attribute "CDS_PHYS_NET_NAME" "M_M_DQ<59>"
					( Origin gPackager )
				)
				( attribute "PNN" "M_M_DQ<59>"
					( Origin gPackager )
				)
				( objectStatus "M_M_DQ<59>" )
			)
			( signal "@baseboard_fab2_lib.baseboard_fab2(sch_1):m_m_dq(60)"
				( attribute "CDS_PHYS_NET_NAME" "M_M_DQ<60>"
					( Origin gPackager )
				)
				( attribute "PNN" "M_M_DQ<60>"
					( Origin gPackager )
				)
				( objectStatus "M_M_DQ<60>" )
			)
			( signal "@baseboard_fab2_lib.baseboard_fab2(sch_1):m_m_dq(61)"
				( attribute "CDS_PHYS_NET_NAME" "M_M_DQ<61>"
					( Origin gPackager )
				)
				( attribute "PNN" "M_M_DQ<61>"
					( Origin gPackager )
				)
				( objectStatus "M_M_DQ<61>" )
			)
			( signal "@baseboard_fab2_lib.baseboard_fab2(sch_1):m_m_dq(62)"
				( attribute "CDS_PHYS_NET_NAME" "M_M_DQ<62>"
					( Origin gPackager )
				)
				( attribute "PNN" "M_M_DQ<62>"
					( Origin gPackager )
				)
				( objectStatus "M_M_DQ<62>" )
			)
			( signal "@baseboard_fab2_lib.baseboard_fab2(sch_1):m_m_dq(63)"
				( attribute "CDS_PHYS_NET_NAME" "M_M_DQ<63>"
					( Origin gPackager )
				)
				( attribute "PNN" "M_M_DQ<63>"
					( Origin gPackager )
				)
				( objectStatus "M_M_DQ<63>" )
			)
			( signal "@baseboard_fab2_lib.baseboard_fab2(sch_1):m_m_dqs_dn(0)"
				( attribute "CDS_PHYS_NET_NAME" "M_M_DQS_DN<0>"
					( Origin gPackager )
				)
				( attribute "PNN" "M_M_DQS_DN<0>"
					( Origin gPackager )
				)
				( objectStatus "M_M_DQS_DN<0>" )
			)
			( signal "@baseboard_fab2_lib.baseboard_fab2(sch_1):m_m_dqs_dn(1)"
				( attribute "CDS_PHYS_NET_NAME" "M_M_DQS_DN<1>"
					( Origin gPackager )
				)
				( attribute "PNN" "M_M_DQS_DN<1>"
					( Origin gPackager )
				)
				( objectStatus "M_M_DQS_DN<1>" )
			)
			( signal "@baseboard_fab2_lib.baseboard_fab2(sch_1):m_m_dqs_dn(2)"
				( attribute "CDS_PHYS_NET_NAME" "M_M_DQS_DN<2>"
					( Origin gPackager )
				)
				( attribute "PNN" "M_M_DQS_DN<2>"
					( Origin gPackager )
				)
				( objectStatus "M_M_DQS_DN<2>" )
			)
			( signal "@baseboard_fab2_lib.baseboard_fab2(sch_1):m_m_dqs_dn(3)"
				( attribute "CDS_PHYS_NET_NAME" "M_M_DQS_DN<3>"
					( Origin gPackager )
				)
				( attribute "PNN" "M_M_DQS_DN<3>"
					( Origin gPackager )
				)
				( objectStatus "M_M_DQS_DN<3>" )
			)
			( signal "@baseboard_fab2_lib.baseboard_fab2(sch_1):m_m_dqs_dn(4)"
				( attribute "CDS_PHYS_NET_NAME" "M_M_DQS_DN<4>"
					( Origin gPackager )
				)
				( attribute "PNN" "M_M_DQS_DN<4>"
					( Origin gPackager )
				)
				( objectStatus "M_M_DQS_DN<4>" )
			)
			( signal "@baseboard_fab2_lib.baseboard_fab2(sch_1):m_m_dqs_dn(5)"
				( attribute "CDS_PHYS_NET_NAME" "M_M_DQS_DN<5>"
					( Origin gPackager )
				)
				( attribute "PNN" "M_M_DQS_DN<5>"
					( Origin gPackager )
				)
				( objectStatus "M_M_DQS_DN<5>" )
			)
			( signal "@baseboard_fab2_lib.baseboard_fab2(sch_1):m_m_dqs_dn(6)"
				( attribute "CDS_PHYS_NET_NAME" "M_M_DQS_DN<6>"
					( Origin gPackager )
				)
				( attribute "PNN" "M_M_DQS_DN<6>"
					( Origin gPackager )
				)
				( objectStatus "M_M_DQS_DN<6>" )
			)
			( signal "@baseboard_fab2_lib.baseboard_fab2(sch_1):m_m_dqs_dn(7)"
				( attribute "CDS_PHYS_NET_NAME" "M_M_DQS_DN<7>"
					( Origin gPackager )
				)
				( attribute "PNN" "M_M_DQS_DN<7>"
					( Origin gPackager )
				)
				( objectStatus "M_M_DQS_DN<7>" )
			)
			( signal "@baseboard_fab2_lib.baseboard_fab2(sch_1):m_m_dqs_dn(8)"
				( attribute "CDS_PHYS_NET_NAME" "M_M_DQS_DN<8>"
					( Origin gPackager )
				)
				( attribute "PNN" "M_M_DQS_DN<8>"
					( Origin gPackager )
				)
				( objectStatus "M_M_DQS_DN<8>" )
			)
			( signal "@baseboard_fab2_lib.baseboard_fab2(sch_1):m_m_dqs_dn(9)"
				( attribute "CDS_PHYS_NET_NAME" "M_M_DQS_DN<9>"
					( Origin gPackager )
				)
				( attribute "PNN" "M_M_DQS_DN<9>"
					( Origin gPackager )
				)
				( objectStatus "M_M_DQS_DN<9>" )
			)
			( signal "@baseboard_fab2_lib.baseboard_fab2(sch_1):m_m_dqs_dn(10)"
				( attribute "CDS_PHYS_NET_NAME" "M_M_DQS_DN<10>"
					( Origin gPackager )
				)
				( attribute "PNN" "M_M_DQS_DN<10>"
					( Origin gPackager )
				)
				( objectStatus "M_M_DQS_DN<10>" )
			)
			( signal "@baseboard_fab2_lib.baseboard_fab2(sch_1):m_m_dqs_dn(11)"
				( attribute "CDS_PHYS_NET_NAME" "M_M_DQS_DN<11>"
					( Origin gPackager )
				)
				( attribute "PNN" "M_M_DQS_DN<11>"
					( Origin gPackager )
				)
				( objectStatus "M_M_DQS_DN<11>" )
			)
			( signal "@baseboard_fab2_lib.baseboard_fab2(sch_1):m_m_dqs_dn(12)"
				( attribute "CDS_PHYS_NET_NAME" "M_M_DQS_DN<12>"
					( Origin gPackager )
				)
				( attribute "PNN" "M_M_DQS_DN<12>"
					( Origin gPackager )
				)
				( objectStatus "M_M_DQS_DN<12>" )
			)
			( signal "@baseboard_fab2_lib.baseboard_fab2(sch_1):m_m_dqs_dn(13)"
				( attribute "CDS_PHYS_NET_NAME" "M_M_DQS_DN<13>"
					( Origin gPackager )
				)
				( attribute "PNN" "M_M_DQS_DN<13>"
					( Origin gPackager )
				)
				( objectStatus "M_M_DQS_DN<13>" )
			)
			( signal "@baseboard_fab2_lib.baseboard_fab2(sch_1):m_m_dqs_dn(14)"
				( attribute "CDS_PHYS_NET_NAME" "M_M_DQS_DN<14>"
					( Origin gPackager )
				)
				( attribute "PNN" "M_M_DQS_DN<14>"
					( Origin gPackager )
				)
				( objectStatus "M_M_DQS_DN<14>" )
			)
			( signal "@baseboard_fab2_lib.baseboard_fab2(sch_1):m_m_dqs_dn(15)"
				( attribute "CDS_PHYS_NET_NAME" "M_M_DQS_DN<15>"
					( Origin gPackager )
				)
				( attribute "PNN" "M_M_DQS_DN<15>"
					( Origin gPackager )
				)
				( objectStatus "M_M_DQS_DN<15>" )
			)
			( signal "@baseboard_fab2_lib.baseboard_fab2(sch_1):m_m_dqs_dn(16)"
				( attribute "CDS_PHYS_NET_NAME" "M_M_DQS_DN<16>"
					( Origin gPackager )
				)
				( attribute "PNN" "M_M_DQS_DN<16>"
					( Origin gPackager )
				)
				( objectStatus "M_M_DQS_DN<16>" )
			)
			( signal "@baseboard_fab2_lib.baseboard_fab2(sch_1):m_m_dqs_dn(17)"
				( attribute "CDS_PHYS_NET_NAME" "M_M_DQS_DN<17>"
					( Origin gPackager )
				)
				( attribute "PNN" "M_M_DQS_DN<17>"
					( Origin gPackager )
				)
				( objectStatus "M_M_DQS_DN<17>" )
			)
			( signal "@baseboard_fab2_lib.baseboard_fab2(sch_1):m_m_dqs_dp(0)"
				( attribute "CDS_PHYS_NET_NAME" "M_M_DQS_DP<0>"
					( Origin gPackager )
				)
				( attribute "PNN" "M_M_DQS_DP<0>"
					( Origin gPackager )
				)
				( objectStatus "M_M_DQS_DP<0>" )
			)
			( signal "@baseboard_fab2_lib.baseboard_fab2(sch_1):m_m_dqs_dp(1)"
				( attribute "CDS_PHYS_NET_NAME" "M_M_DQS_DP<1>"
					( Origin gPackager )
				)
				( attribute "PNN" "M_M_DQS_DP<1>"
					( Origin gPackager )
				)
				( objectStatus "M_M_DQS_DP<1>" )
			)
			( signal "@baseboard_fab2_lib.baseboard_fab2(sch_1):m_m_dqs_dp(2)"
				( attribute "CDS_PHYS_NET_NAME" "M_M_DQS_DP<2>"
					( Origin gPackager )
				)
				( attribute "PNN" "M_M_DQS_DP<2>"
					( Origin gPackager )
				)
				( objectStatus "M_M_DQS_DP<2>" )
			)
			( signal "@baseboard_fab2_lib.baseboard_fab2(sch_1):m_m_dqs_dp(3)"
				( attribute "CDS_PHYS_NET_NAME" "M_M_DQS_DP<3>"
					( Origin gPackager )
				)
				( attribute "PNN" "M_M_DQS_DP<3>"
					( Origin gPackager )
				)
				( objectStatus "M_M_DQS_DP<3>" )
			)
			( signal "@baseboard_fab2_lib.baseboard_fab2(sch_1):m_m_dqs_dp(4)"
				( attribute "CDS_PHYS_NET_NAME" "M_M_DQS_DP<4>"
					( Origin gPackager )
				)
				( attribute "PNN" "M_M_DQS_DP<4>"
					( Origin gPackager )
				)
				( objectStatus "M_M_DQS_DP<4>" )
			)
			( signal "@baseboard_fab2_lib.baseboard_fab2(sch_1):m_m_dqs_dp(5)"
				( attribute "CDS_PHYS_NET_NAME" "M_M_DQS_DP<5>"
					( Origin gPackager )
				)
				( attribute "PNN" "M_M_DQS_DP<5>"
					( Origin gPackager )
				)
				( objectStatus "M_M_DQS_DP<5>" )
			)
			( signal "@baseboard_fab2_lib.baseboard_fab2(sch_1):m_m_dqs_dp(6)"
				( attribute "CDS_PHYS_NET_NAME" "M_M_DQS_DP<6>"
					( Origin gPackager )
				)
				( attribute "PNN" "M_M_DQS_DP<6>"
					( Origin gPackager )
				)
				( objectStatus "M_M_DQS_DP<6>" )
			)
			( signal "@baseboard_fab2_lib.baseboard_fab2(sch_1):m_m_dqs_dp(7)"
				( attribute "CDS_PHYS_NET_NAME" "M_M_DQS_DP<7>"
					( Origin gPackager )
				)
				( attribute "PNN" "M_M_DQS_DP<7>"
					( Origin gPackager )
				)
				( objectStatus "M_M_DQS_DP<7>" )
			)
			( signal "@baseboard_fab2_lib.baseboard_fab2(sch_1):m_m_dqs_dp(8)"
				( attribute "CDS_PHYS_NET_NAME" "M_M_DQS_DP<8>"
					( Origin gPackager )
				)
				( attribute "PNN" "M_M_DQS_DP<8>"
					( Origin gPackager )
				)
				( objectStatus "M_M_DQS_DP<8>" )
			)
			( signal "@baseboard_fab2_lib.baseboard_fab2(sch_1):m_m_dqs_dp(9)"
				( attribute "CDS_PHYS_NET_NAME" "M_M_DQS_DP<9>"
					( Origin gPackager )
				)
				( attribute "PNN" "M_M_DQS_DP<9>"
					( Origin gPackager )
				)
				( objectStatus "M_M_DQS_DP<9>" )
			)
			( signal "@baseboard_fab2_lib.baseboard_fab2(sch_1):m_m_dqs_dp(10)"
				( attribute "CDS_PHYS_NET_NAME" "M_M_DQS_DP<10>"
					( Origin gPackager )
				)
				( attribute "PNN" "M_M_DQS_DP<10>"
					( Origin gPackager )
				)
				( objectStatus "M_M_DQS_DP<10>" )
			)
			( signal "@baseboard_fab2_lib.baseboard_fab2(sch_1):m_m_dqs_dp(11)"
				( attribute "CDS_PHYS_NET_NAME" "M_M_DQS_DP<11>"
					( Origin gPackager )
				)
				( attribute "PNN" "M_M_DQS_DP<11>"
					( Origin gPackager )
				)
				( objectStatus "M_M_DQS_DP<11>" )
			)
			( signal "@baseboard_fab2_lib.baseboard_fab2(sch_1):m_m_dqs_dp(12)"
				( attribute "CDS_PHYS_NET_NAME" "M_M_DQS_DP<12>"
					( Origin gPackager )
				)
				( attribute "PNN" "M_M_DQS_DP<12>"
					( Origin gPackager )
				)
				( objectStatus "M_M_DQS_DP<12>" )
			)
			( signal "@baseboard_fab2_lib.baseboard_fab2(sch_1):m_m_dqs_dp(13)"
				( attribute "CDS_PHYS_NET_NAME" "M_M_DQS_DP<13>"
					( Origin gPackager )
				)
				( attribute "PNN" "M_M_DQS_DP<13>"
					( Origin gPackager )
				)
				( objectStatus "M_M_DQS_DP<13>" )
			)
			( signal "@baseboard_fab2_lib.baseboard_fab2(sch_1):m_m_dqs_dp(14)"
				( attribute "CDS_PHYS_NET_NAME" "M_M_DQS_DP<14>"
					( Origin gPackager )
				)
				( attribute "PNN" "M_M_DQS_DP<14>"
					( Origin gPackager )
				)
				( objectStatus "M_M_DQS_DP<14>" )
			)
			( signal "@baseboard_fab2_lib.baseboard_fab2(sch_1):m_m_dqs_dp(15)"
				( attribute "CDS_PHYS_NET_NAME" "M_M_DQS_DP<15>"
					( Origin gPackager )
				)
				( attribute "PNN" "M_M_DQS_DP<15>"
					( Origin gPackager )
				)
				( objectStatus "M_M_DQS_DP<15>" )
			)
			( signal "@baseboard_fab2_lib.baseboard_fab2(sch_1):m_m_dqs_dp(16)"
				( attribute "CDS_PHYS_NET_NAME" "M_M_DQS_DP<16>"
					( Origin gPackager )
				)
				( attribute "PNN" "M_M_DQS_DP<16>"
					( Origin gPackager )
				)
				( objectStatus "M_M_DQS_DP<16>" )
			)
			( signal "@baseboard_fab2_lib.baseboard_fab2(sch_1):m_m_dqs_dp(17)"
				( attribute "CDS_PHYS_NET_NAME" "M_M_DQS_DP<17>"
					( Origin gPackager )
				)
				( attribute "PNN" "M_M_DQS_DP<17>"
					( Origin gPackager )
				)
				( objectStatus "M_M_DQS_DP<17>" )
			)
			( signal "@baseboard_fab2_lib.baseboard_fab2(sch_1):m_m_ecc(0)"
				( attribute "CDS_PHYS_NET_NAME" "M_M_ECC<0>"
					( Origin gPackager )
				)
				( attribute "PNN" "M_M_ECC<0>"
					( Origin gPackager )
				)
				( objectStatus "M_M_ECC<0>" )
			)
			( signal "@baseboard_fab2_lib.baseboard_fab2(sch_1):m_m_ecc(1)"
				( attribute "CDS_PHYS_NET_NAME" "M_M_ECC<1>"
					( Origin gPackager )
				)
				( attribute "PNN" "M_M_ECC<1>"
					( Origin gPackager )
				)
				( objectStatus "M_M_ECC<1>" )
			)
			( signal "@baseboard_fab2_lib.baseboard_fab2(sch_1):m_m_ecc(2)"
				( attribute "CDS_PHYS_NET_NAME" "M_M_ECC<2>"
					( Origin gPackager )
				)
				( attribute "PNN" "M_M_ECC<2>"
					( Origin gPackager )
				)
				( objectStatus "M_M_ECC<2>" )
			)
			( signal "@baseboard_fab2_lib.baseboard_fab2(sch_1):m_m_ecc(3)"
				( attribute "CDS_PHYS_NET_NAME" "M_M_ECC<3>"
					( Origin gPackager )
				)
				( attribute "PNN" "M_M_ECC<3>"
					( Origin gPackager )
				)
				( objectStatus "M_M_ECC<3>" )
			)
			( signal "@baseboard_fab2_lib.baseboard_fab2(sch_1):m_m_ecc(4)"
				( attribute "CDS_PHYS_NET_NAME" "M_M_ECC<4>"
					( Origin gPackager )
				)
				( attribute "PNN" "M_M_ECC<4>"
					( Origin gPackager )
				)
				( objectStatus "M_M_ECC<4>" )
			)
			( signal "@baseboard_fab2_lib.baseboard_fab2(sch_1):m_m_ecc(5)"
				( attribute "CDS_PHYS_NET_NAME" "M_M_ECC<5>"
					( Origin gPackager )
				)
				( attribute "PNN" "M_M_ECC<5>"
					( Origin gPackager )
				)
				( objectStatus "M_M_ECC<5>" )
			)
			( signal "@baseboard_fab2_lib.baseboard_fab2(sch_1):m_m_ecc(6)"
				( attribute "CDS_PHYS_NET_NAME" "M_M_ECC<6>"
					( Origin gPackager )
				)
				( attribute "PNN" "M_M_ECC<6>"
					( Origin gPackager )
				)
				( objectStatus "M_M_ECC<6>" )
			)
			( signal "@baseboard_fab2_lib.baseboard_fab2(sch_1):m_m_ecc(7)"
				( attribute "CDS_PHYS_NET_NAME" "M_M_ECC<7>"
					( Origin gPackager )
				)
				( attribute "PNN" "M_M_ECC<7>"
					( Origin gPackager )
				)
				( objectStatus "M_M_ECC<7>" )
			)
			( signal "@baseboard_fab2_lib.baseboard_fab2(sch_1):m_m_ma(0)"
				( attribute "CDS_PHYS_NET_NAME" "M_M_MA<0>"
					( Origin gPackager )
				)
				( attribute "PNN" "M_M_MA<0>"
					( Origin gPackager )
				)
				( objectStatus "M_M_MA<0>" )
			)
			( signal "@baseboard_fab2_lib.baseboard_fab2(sch_1):m_m_ma(1)"
				( attribute "CDS_PHYS_NET_NAME" "M_M_MA<1>"
					( Origin gPackager )
				)
				( attribute "PNN" "M_M_MA<1>"
					( Origin gPackager )
				)
				( objectStatus "M_M_MA<1>" )
			)
			( signal "@baseboard_fab2_lib.baseboard_fab2(sch_1):m_m_ma(2)"
				( attribute "CDS_PHYS_NET_NAME" "M_M_MA<2>"
					( Origin gPackager )
				)
				( attribute "PNN" "M_M_MA<2>"
					( Origin gPackager )
				)
				( objectStatus "M_M_MA<2>" )
			)
			( signal "@baseboard_fab2_lib.baseboard_fab2(sch_1):m_m_ma(3)"
				( attribute "CDS_PHYS_NET_NAME" "M_M_MA<3>"
					( Origin gPackager )
				)
				( attribute "PNN" "M_M_MA<3>"
					( Origin gPackager )
				)
				( objectStatus "M_M_MA<3>" )
			)
			( signal "@baseboard_fab2_lib.baseboard_fab2(sch_1):m_m_ma(4)"
				( attribute "CDS_PHYS_NET_NAME" "M_M_MA<4>"
					( Origin gPackager )
				)
				( attribute "PNN" "M_M_MA<4>"
					( Origin gPackager )
				)
				( objectStatus "M_M_MA<4>" )
			)
			( signal "@baseboard_fab2_lib.baseboard_fab2(sch_1):m_m_ma(5)"
				( attribute "CDS_PHYS_NET_NAME" "M_M_MA<5>"
					( Origin gPackager )
				)
				( attribute "PNN" "M_M_MA<5>"
					( Origin gPackager )
				)
				( objectStatus "M_M_MA<5>" )
			)
			( signal "@baseboard_fab2_lib.baseboard_fab2(sch_1):m_m_ma(6)"
				( attribute "CDS_PHYS_NET_NAME" "M_M_MA<6>"
					( Origin gPackager )
				)
				( attribute "PNN" "M_M_MA<6>"
					( Origin gPackager )
				)
				( objectStatus "M_M_MA<6>" )
			)
			( signal "@baseboard_fab2_lib.baseboard_fab2(sch_1):m_m_ma(7)"
				( attribute "CDS_PHYS_NET_NAME" "M_M_MA<7>"
					( Origin gPackager )
				)
				( attribute "PNN" "M_M_MA<7>"
					( Origin gPackager )
				)
				( objectStatus "M_M_MA<7>" )
			)
			( signal "@baseboard_fab2_lib.baseboard_fab2(sch_1):m_m_ma(8)"
				( attribute "CDS_PHYS_NET_NAME" "M_M_MA<8>"
					( Origin gPackager )
				)
				( attribute "PNN" "M_M_MA<8>"
					( Origin gPackager )
				)
				( objectStatus "M_M_MA<8>" )
			)
			( signal "@baseboard_fab2_lib.baseboard_fab2(sch_1):m_m_ma(9)"
				( attribute "CDS_PHYS_NET_NAME" "M_M_MA<9>"
					( Origin gPackager )
				)
				( attribute "PNN" "M_M_MA<9>"
					( Origin gPackager )
				)
				( objectStatus "M_M_MA<9>" )
			)
			( signal "@baseboard_fab2_lib.baseboard_fab2(sch_1):m_m_ma(10)"
				( attribute "CDS_PHYS_NET_NAME" "M_M_MA<10>"
					( Origin gPackager )
				)
				( attribute "PNN" "M_M_MA<10>"
					( Origin gPackager )
				)
				( objectStatus "M_M_MA<10>" )
			)
			( signal "@baseboard_fab2_lib.baseboard_fab2(sch_1):m_m_ma(11)"
				( attribute "CDS_PHYS_NET_NAME" "M_M_MA<11>"
					( Origin gPackager )
				)
				( attribute "PNN" "M_M_MA<11>"
					( Origin gPackager )
				)
				( objectStatus "M_M_MA<11>" )
			)
			( signal "@baseboard_fab2_lib.baseboard_fab2(sch_1):m_m_ma(12)"
				( attribute "CDS_PHYS_NET_NAME" "M_M_MA<12>"
					( Origin gPackager )
				)
				( attribute "PNN" "M_M_MA<12>"
					( Origin gPackager )
				)
				( objectStatus "M_M_MA<12>" )
			)
			( signal "@baseboard_fab2_lib.baseboard_fab2(sch_1):m_m_ma(13)"
				( attribute "CDS_PHYS_NET_NAME" "M_M_MA<13>"
					( Origin gPackager )
				)
				( attribute "PNN" "M_M_MA<13>"
					( Origin gPackager )
				)
				( objectStatus "M_M_MA<13>" )
			)
			( signal "@baseboard_fab2_lib.baseboard_fab2(sch_1):m_m_ma(14)"
				( attribute "CDS_PHYS_NET_NAME" "M_M_MA<14>"
					( Origin gPackager )
				)
				( attribute "PNN" "M_M_MA<14>"
					( Origin gPackager )
				)
				( objectStatus "M_M_MA<14>" )
			)
			( signal "@baseboard_fab2_lib.baseboard_fab2(sch_1):m_m_ma(15)"
				( attribute "CDS_PHYS_NET_NAME" "M_M_MA<15>"
					( Origin gPackager )
				)
				( attribute "PNN" "M_M_MA<15>"
					( Origin gPackager )
				)
				( objectStatus "M_M_MA<15>" )
			)
			( signal "@baseboard_fab2_lib.baseboard_fab2(sch_1):m_m_ma(16)"
				( attribute "CDS_PHYS_NET_NAME" "M_M_MA<16>"
					( Origin gPackager )
				)
				( attribute "PNN" "M_M_MA<16>"
					( Origin gPackager )
				)
				( objectStatus "M_M_MA<16>" )
			)
			( signal "@baseboard_fab2_lib.baseboard_fab2(sch_1):m_m_ma(17)"
				( attribute "CDS_PHYS_NET_NAME" "M_M_MA<17>"
					( Origin gPackager )
				)
				( attribute "PNN" "M_M_MA<17>"
					( Origin gPackager )
				)
				( objectStatus "M_M_MA<17>" )
			)
			( signal "@baseboard_fab2_lib.baseboard_fab2(sch_1):m_m_odt(0)"
				( attribute "CDS_PHYS_NET_NAME" "M_M_ODT<0>"
					( Origin gPackager )
				)
				( attribute "PNN" "M_M_ODT<0>"
					( Origin gPackager )
				)
				( objectStatus "M_M_ODT<0>" )
			)
			( signal "@baseboard_fab2_lib.baseboard_fab2(sch_1):m_m_odt(1)"
				( attribute "CDS_PHYS_NET_NAME" "M_M_ODT<1>"
					( Origin gPackager )
				)
				( attribute "PNN" "M_M_ODT<1>"
					( Origin gPackager )
				)
				( objectStatus "M_M_ODT<1>" )
			)
			( signal "@baseboard_fab2_lib.baseboard_fab2(sch_1):m_m_odt(2)"
				( attribute "CDS_PHYS_NET_NAME" "M_M_ODT<2>"
					( Origin gPackager )
				)
				( attribute "PNN" "M_M_ODT<2>"
					( Origin gPackager )
				)
				( objectStatus "M_M_ODT<2>" )
			)
			( signal "@baseboard_fab2_lib.baseboard_fab2(sch_1):m_m_odt(3)"
				( attribute "CDS_PHYS_NET_NAME" "M_M_ODT<3>"
					( Origin gPackager )
				)
				( attribute "PNN" "M_M_ODT<3>"
					( Origin gPackager )
				)
				( objectStatus "M_M_ODT<3>" )
			)
			( signal "@baseboard_fab2_lib.baseboard_fab2(sch_1):m_m_par"
				( attribute "CDS_PHYS_NET_NAME" "M_M_PAR"
					( Origin gPackager )
				)
				( objectStatus "M_M_PAR" )
			)
			( signal "@baseboard_fab2_lib.baseboard_fab2(sch_1):clk_100m_cpu1_pe_refclk_dn"
				( attribute "CDS_PHYS_NET_NAME" "CLK_100M_CPU1_PE_REFCLK_DN"
					( Origin gPackager )
				)
				( objectStatus "CLK_100M_CPU1_PE_REFCLK_DN" )
			)
			( signal "@baseboard_fab2_lib.baseboard_fab2(sch_1):clk_100m_cpu1_pe_refclk_dp"
				( attribute "CDS_PHYS_NET_NAME" "CLK_100M_CPU1_PE_REFCLK_DP"
					( Origin gPackager )
				)
				( objectStatus "CLK_100M_CPU1_PE_REFCLK_DP" )
			)
			( signal "@baseboard_fab2_lib.baseboard_fab2(sch_1):clk_156m_osc_cpu1_hfi_dn"
				( attribute "CDS_PHYS_NET_NAME" "CLK_156M_OSC_CPU1_HFI_DN"
					( Origin gPackager )
				)
				( objectStatus "CLK_156M_OSC_CPU1_HFI_DN" )
			)
			( signal "@baseboard_fab2_lib.baseboard_fab2(sch_1):clk_156m_osc_cpu1_hfi_dp"
				( attribute "CDS_PHYS_NET_NAME" "CLK_156M_OSC_CPU1_HFI_DP"
					( Origin gPackager )
				)
				( objectStatus "CLK_156M_OSC_CPU1_HFI_DP" )
			)
			( signal "@baseboard_fab2_lib.baseboard_fab2(sch_1):jtag_mcp_cpu1_tdi"
				( attribute "CDS_PHYS_NET_NAME" "JTAG_MCP_CPU1_TDI"
					( Origin gPackager )
				)
				( objectStatus "JTAG_MCP_CPU1_TDI" )
			)
			( signal "@baseboard_fab2_lib.baseboard_fab2(sch_1):jtag_mcp_cpu1_tdo"
				( attribute "CDS_PHYS_NET_NAME" "JTAG_MCP_CPU1_TDO"
					( Origin gPackager )
				)
				( objectStatus "JTAG_MCP_CPU1_TDO" )
			)
			( signal "@baseboard_fab2_lib.baseboard_fab2(sch_1):rst_cd_cpu1_por_n"
				( attribute "CDS_PHYS_NET_NAME" "RST_CD_CPU1_POR_N"
					( Origin gPackager )
				)
				( objectStatus "RST_CD_CPU1_POR_N" )
			)
			( signal "@baseboard_fab2_lib.baseboard_fab2(sch_1):tp_cd_hfi1_cpu1_i2cdat"
				( attribute "CDS_PHYS_NET_NAME" "TP_CD_HFI1_CPU1_I2CDAT"
					( Origin gPackager )
				)
				( objectStatus "TP_CD_HFI1_CPU1_I2CDAT" )
			)
			( signal "@baseboard_fab2_lib.baseboard_fab2(sch_1):tp_cd_hfi1_cpu1_i2clk"
				( attribute "CDS_PHYS_NET_NAME" "TP_CD_HFI1_CPU1_I2CLK"
					( Origin gPackager )
				)
				( objectStatus "TP_CD_HFI1_CPU1_I2CLK" )
			)
			( signal "@baseboard_fab2_lib.baseboard_fab2(sch_1):tp_cd_hfi1_cpu1_int_n"
				( attribute "CDS_PHYS_NET_NAME" "TP_CD_HFI1_CPU1_INT_N"
					( Origin gPackager )
				)
				( objectStatus "TP_CD_HFI1_CPU1_INT_N" )
			)
			( signal "@baseboard_fab2_lib.baseboard_fab2(sch_1):tp_cd_hfi1_cpu1_led_n"
				( attribute "CDS_PHYS_NET_NAME" "TP_CD_HFI1_CPU1_LED_N"
					( Origin gPackager )
				)
				( objectStatus "TP_CD_HFI1_CPU1_LED_N" )
			)
			( signal "@baseboard_fab2_lib.baseboard_fab2(sch_1):tp_cd_hfi1_cpu1_modprst_n"
				( attribute "CDS_PHYS_NET_NAME" "TP_CD_HFI1_CPU1_MODPRST_N"
					( Origin gPackager )
				)
				( objectStatus "TP_CD_HFI1_CPU1_MODPRST_N" )
			)
			( signal "@baseboard_fab2_lib.baseboard_fab2(sch_1):tp_cd_hfi1_cpu1_reset_n"
				( attribute "CDS_PHYS_NET_NAME" "TP_CD_HFI1_CPU1_RESET_N"
					( Origin gPackager )
				)
				( objectStatus "TP_CD_HFI1_CPU1_RESET_N" )
			)
			( signal "@baseboard_fab2_lib.baseboard_fab2(sch_1):tp_cpu1_dmi_rx_dn0"
				( attribute "CDS_PHYS_NET_NAME" "TP_CPU1_DMI_RX_DN0"
					( Origin gPackager )
				)
				( objectStatus "TP_CPU1_DMI_RX_DN0" )
			)
			( signal "@baseboard_fab2_lib.baseboard_fab2(sch_1):tp_cpu1_dmi_rx_dn1"
				( attribute "CDS_PHYS_NET_NAME" "TP_CPU1_DMI_RX_DN1"
					( Origin gPackager )
				)
				( objectStatus "TP_CPU1_DMI_RX_DN1" )
			)
			( signal "@baseboard_fab2_lib.baseboard_fab2(sch_1):tp_cpu1_dmi_rx_dn2"
				( attribute "CDS_PHYS_NET_NAME" "TP_CPU1_DMI_RX_DN2"
					( Origin gPackager )
				)
				( objectStatus "TP_CPU1_DMI_RX_DN2" )
			)
			( signal "@baseboard_fab2_lib.baseboard_fab2(sch_1):tp_cpu1_dmi_rx_dn3"
				( attribute "CDS_PHYS_NET_NAME" "TP_CPU1_DMI_RX_DN3"
					( Origin gPackager )
				)
				( objectStatus "TP_CPU1_DMI_RX_DN3" )
			)
			( signal "@baseboard_fab2_lib.baseboard_fab2(sch_1):tp_cpu1_dmi_rx_dp0"
				( attribute "CDS_PHYS_NET_NAME" "TP_CPU1_DMI_RX_DP0"
					( Origin gPackager )
				)
				( objectStatus "TP_CPU1_DMI_RX_DP0" )
			)
			( signal "@baseboard_fab2_lib.baseboard_fab2(sch_1):tp_cpu1_dmi_rx_dp1"
				( attribute "CDS_PHYS_NET_NAME" "TP_CPU1_DMI_RX_DP1"
					( Origin gPackager )
				)
				( objectStatus "TP_CPU1_DMI_RX_DP1" )
			)
			( signal "@baseboard_fab2_lib.baseboard_fab2(sch_1):tp_cpu1_dmi_rx_dp2"
				( attribute "CDS_PHYS_NET_NAME" "TP_CPU1_DMI_RX_DP2"
					( Origin gPackager )
				)
				( objectStatus "TP_CPU1_DMI_RX_DP2" )
			)
			( signal "@baseboard_fab2_lib.baseboard_fab2(sch_1):tp_cpu1_dmi_rx_dp3"
				( attribute "CDS_PHYS_NET_NAME" "TP_CPU1_DMI_RX_DP3"
					( Origin gPackager )
				)
				( objectStatus "TP_CPU1_DMI_RX_DP3" )
			)
			( signal "@baseboard_fab2_lib.baseboard_fab2(sch_1):tp_cpu1_dmi_tx_dn0"
				( attribute "CDS_PHYS_NET_NAME" "TP_CPU1_DMI_TX_DN0"
					( Origin gPackager )
				)
				( objectStatus "TP_CPU1_DMI_TX_DN0" )
			)
			( signal "@baseboard_fab2_lib.baseboard_fab2(sch_1):tp_cpu1_dmi_tx_dn1"
				( attribute "CDS_PHYS_NET_NAME" "TP_CPU1_DMI_TX_DN1"
					( Origin gPackager )
				)
				( objectStatus "TP_CPU1_DMI_TX_DN1" )
			)
			( signal "@baseboard_fab2_lib.baseboard_fab2(sch_1):tp_cpu1_dmi_tx_dn2"
				( attribute "CDS_PHYS_NET_NAME" "TP_CPU1_DMI_TX_DN2"
					( Origin gPackager )
				)
				( objectStatus "TP_CPU1_DMI_TX_DN2" )
			)
			( signal "@baseboard_fab2_lib.baseboard_fab2(sch_1):tp_cpu1_dmi_tx_dn3"
				( attribute "CDS_PHYS_NET_NAME" "TP_CPU1_DMI_TX_DN3"
					( Origin gPackager )
				)
				( objectStatus "TP_CPU1_DMI_TX_DN3" )
			)
			( signal "@baseboard_fab2_lib.baseboard_fab2(sch_1):tp_cpu1_dmi_tx_dp0"
				( attribute "CDS_PHYS_NET_NAME" "TP_CPU1_DMI_TX_DP0"
					( Origin gPackager )
				)
				( objectStatus "TP_CPU1_DMI_TX_DP0" )
			)
			( signal "@baseboard_fab2_lib.baseboard_fab2(sch_1):tp_cpu1_dmi_tx_dp1"
				( attribute "CDS_PHYS_NET_NAME" "TP_CPU1_DMI_TX_DP1"
					( Origin gPackager )
				)
				( objectStatus "TP_CPU1_DMI_TX_DP1" )
			)
			( signal "@baseboard_fab2_lib.baseboard_fab2(sch_1):tp_cpu1_dmi_tx_dp2"
				( attribute "CDS_PHYS_NET_NAME" "TP_CPU1_DMI_TX_DP2"
					( Origin gPackager )
				)
				( objectStatus "TP_CPU1_DMI_TX_DP2" )
			)
			( signal "@baseboard_fab2_lib.baseboard_fab2(sch_1):tp_cpu1_dmi_tx_dp3"
				( attribute "CDS_PHYS_NET_NAME" "TP_CPU1_DMI_TX_DP3"
					( Origin gPackager )
				)
				( objectStatus "TP_CPU1_DMI_TX_DP3" )
			)
			( signal "@baseboard_fab2_lib.baseboard_fab2(sch_1):tp_cpu1_rsvd_172"
				( attribute "CDS_PHYS_NET_NAME" "TP_CPU1_RSVD_172"
					( Origin gPackager )
				)
				( objectStatus "TP_CPU1_RSVD_172" )
			)
			( signal "@baseboard_fab2_lib.baseboard_fab2(sch_1):tp_cpu1_rsvd_173"
				( attribute "CDS_PHYS_NET_NAME" "TP_CPU1_RSVD_173"
					( Origin gPackager )
				)
				( objectStatus "TP_CPU1_RSVD_173" )
			)
			( signal "@baseboard_fab2_lib.baseboard_fab2(sch_1):tp_cpu1_rsvd_174"
				( attribute "CDS_PHYS_NET_NAME" "TP_CPU1_RSVD_174"
					( Origin gPackager )
				)
				( objectStatus "TP_CPU1_RSVD_174" )
			)
			( signal "@baseboard_fab2_lib.baseboard_fab2(sch_1):tp_cpu1_rsvd_175"
				( attribute "CDS_PHYS_NET_NAME" "TP_CPU1_RSVD_175"
					( Origin gPackager )
				)
				( objectStatus "TP_CPU1_RSVD_175" )
			)
			( signal "@baseboard_fab2_lib.baseboard_fab2(sch_1):tp_cpu1_rsvd_176"
				( attribute "CDS_PHYS_NET_NAME" "TP_CPU1_RSVD_176"
					( Origin gPackager )
				)
				( objectStatus "TP_CPU1_RSVD_176" )
			)
			( signal "@baseboard_fab2_lib.baseboard_fab2(sch_1):tp_cpu1_rsvd_177"
				( attribute "CDS_PHYS_NET_NAME" "TP_CPU1_RSVD_177"
					( Origin gPackager )
				)
				( objectStatus "TP_CPU1_RSVD_177" )
			)
			( signal "@baseboard_fab2_lib.baseboard_fab2(sch_1):tp_cpu1_rsvd_178"
				( attribute "CDS_PHYS_NET_NAME" "TP_CPU1_RSVD_178"
					( Origin gPackager )
				)
				( objectStatus "TP_CPU1_RSVD_178" )
			)
			( signal "@baseboard_fab2_lib.baseboard_fab2(sch_1):tp_cpu1_rsvd_179"
				( attribute "CDS_PHYS_NET_NAME" "TP_CPU1_RSVD_179"
					( Origin gPackager )
				)
				( objectStatus "TP_CPU1_RSVD_179" )
			)
			( signal "@baseboard_fab2_lib.baseboard_fab2(sch_1):tp_cpu1_rsvd_180"
				( attribute "CDS_PHYS_NET_NAME" "TP_CPU1_RSVD_180"
					( Origin gPackager )
				)
				( objectStatus "TP_CPU1_RSVD_180" )
			)
			( signal "@baseboard_fab2_lib.baseboard_fab2(sch_1):tp_cpu1_rsvd_181"
				( attribute "CDS_PHYS_NET_NAME" "TP_CPU1_RSVD_181"
					( Origin gPackager )
				)
				( objectStatus "TP_CPU1_RSVD_181" )
			)
			( signal "@baseboard_fab2_lib.baseboard_fab2(sch_1):tp_cpu1_rsvd_182"
				( attribute "CDS_PHYS_NET_NAME" "TP_CPU1_RSVD_182"
					( Origin gPackager )
				)
				( objectStatus "TP_CPU1_RSVD_182" )
			)
			( signal "@baseboard_fab2_lib.baseboard_fab2(sch_1):tp_cpu1_rsvd_183"
				( attribute "CDS_PHYS_NET_NAME" "TP_CPU1_RSVD_183"
					( Origin gPackager )
				)
				( objectStatus "TP_CPU1_RSVD_183" )
			)
			( signal "@baseboard_fab2_lib.baseboard_fab2(sch_1):tp_cpu1_rsvd_184"
				( attribute "CDS_PHYS_NET_NAME" "TP_CPU1_RSVD_184"
					( Origin gPackager )
				)
				( objectStatus "TP_CPU1_RSVD_184" )
			)
			( signal "@baseboard_fab2_lib.baseboard_fab2(sch_1):tp_cpu1_rsvd_186"
				( attribute "CDS_PHYS_NET_NAME" "TP_CPU1_RSVD_186"
					( Origin gPackager )
				)
				( objectStatus "TP_CPU1_RSVD_186" )
			)
			( signal "@baseboard_fab2_lib.baseboard_fab2(sch_1):tp_cpu1_rsvd_189"
				( attribute "CDS_PHYS_NET_NAME" "TP_CPU1_RSVD_189"
					( Origin gPackager )
				)
				( objectStatus "TP_CPU1_RSVD_189" )
			)
			( signal "@baseboard_fab2_lib.baseboard_fab2(sch_1):tp_cpu1_rsvd_190"
				( attribute "CDS_PHYS_NET_NAME" "TP_CPU1_RSVD_190"
					( Origin gPackager )
				)
				( objectStatus "TP_CPU1_RSVD_190" )
			)
			( signal "@baseboard_fab2_lib.baseboard_fab2(sch_1):tp_fm_cpu1_cd_hfi0_modprst_n"
				( attribute "CDS_PHYS_NET_NAME" "TP_FM_CPU1_CD_HFI0_MODPRST_N"
					( Origin gPackager )
				)
				( objectStatus "TP_FM_CPU1_CD_HFI0_MODPRST_N" )
			)
			( signal "@baseboard_fab2_lib.baseboard_fab2(sch_1):tp_irq_cpu1_cd_hfi0_n"
				( attribute "CDS_PHYS_NET_NAME" "TP_IRQ_CPU1_CD_HFI0_N"
					( Origin gPackager )
				)
				( objectStatus "TP_IRQ_CPU1_CD_HFI0_N" )
			)
			( signal "@baseboard_fab2_lib.baseboard_fab2(sch_1):tp_led_cpu1_cd_hfi0_n"
				( attribute "CDS_PHYS_NET_NAME" "TP_LED_CPU1_CD_HFI0_N"
					( Origin gPackager )
				)
				( objectStatus "TP_LED_CPU1_CD_HFI0_N" )
			)
			( signal "@baseboard_fab2_lib.baseboard_fab2(sch_1):tp_rst_cpu1_cd_hfi0_n"
				( attribute "CDS_PHYS_NET_NAME" "TP_RST_CPU1_CD_HFI0_N"
					( Origin gPackager )
				)
				( objectStatus "TP_RST_CPU1_CD_HFI0_N" )
			)
			( signal "@baseboard_fab2_lib.baseboard_fab2(sch_1):tp_smb_cpu1_cd_hfi0_i2cclk"
				( attribute "CDS_PHYS_NET_NAME" "TP_SMB_CPU1_CD_HFI0_I2CCLK"
					( Origin gPackager )
				)
				( objectStatus "TP_SMB_CPU1_CD_HFI0_I2CCLK" )
			)
			( signal "@baseboard_fab2_lib.baseboard_fab2(sch_1):tp_smb_cpu1_cd_hfi0_i2cdat"
				( attribute "CDS_PHYS_NET_NAME" "TP_SMB_CPU1_CD_HFI0_I2CDAT"
					( Origin gPackager )
				)
				( objectStatus "TP_SMB_CPU1_CD_HFI0_I2CDAT" )
			)
			( signal "@baseboard_fab2_lib.baseboard_fab2(sch_1):tp_p3e_cpu1_pe1_mp_rxn(0)"
				( attribute "CDS_PHYS_NET_NAME" "TP_P3E_CPU1_PE1_MP_RXN<0>"
					( Origin gPackager )
				)
				( attribute "PNN" "TP_P3E_CPU1_PE1_MP_RXN<0>"
					( Origin gPackager )
				)
				( objectStatus "TP_P3E_CPU1_PE1_MP_RXN<0>" )
			)
			( signal "@baseboard_fab2_lib.baseboard_fab2(sch_1):tp_p3e_cpu1_pe1_mp_rxn(1)"
				( attribute "CDS_PHYS_NET_NAME" "TP_P3E_CPU1_PE1_MP_RXN<1>"
					( Origin gPackager )
				)
				( attribute "PNN" "TP_P3E_CPU1_PE1_MP_RXN<1>"
					( Origin gPackager )
				)
				( objectStatus "TP_P3E_CPU1_PE1_MP_RXN<1>" )
			)
			( signal "@baseboard_fab2_lib.baseboard_fab2(sch_1):tp_p3e_cpu1_pe1_mp_rxn(2)"
				( attribute "CDS_PHYS_NET_NAME" "TP_P3E_CPU1_PE1_MP_RXN<2>"
					( Origin gPackager )
				)
				( attribute "PNN" "TP_P3E_CPU1_PE1_MP_RXN<2>"
					( Origin gPackager )
				)
				( objectStatus "TP_P3E_CPU1_PE1_MP_RXN<2>" )
			)
			( signal "@baseboard_fab2_lib.baseboard_fab2(sch_1):tp_p3e_cpu1_pe1_mp_rxn(3)"
				( attribute "CDS_PHYS_NET_NAME" "TP_P3E_CPU1_PE1_MP_RXN<3>"
					( Origin gPackager )
				)
				( attribute "PNN" "TP_P3E_CPU1_PE1_MP_RXN<3>"
					( Origin gPackager )
				)
				( objectStatus "TP_P3E_CPU1_PE1_MP_RXN<3>" )
			)
			( signal "@baseboard_fab2_lib.baseboard_fab2(sch_1):tp_p3e_cpu1_pe1_mp_rxn(4)"
				( attribute "CDS_PHYS_NET_NAME" "TP_P3E_CPU1_PE1_MP_RXN<4>"
					( Origin gPackager )
				)
				( attribute "PNN" "TP_P3E_CPU1_PE1_MP_RXN<4>"
					( Origin gPackager )
				)
				( objectStatus "TP_P3E_CPU1_PE1_MP_RXN<4>" )
			)
			( signal "@baseboard_fab2_lib.baseboard_fab2(sch_1):tp_p3e_cpu1_pe1_mp_rxn(5)"
				( attribute "CDS_PHYS_NET_NAME" "TP_P3E_CPU1_PE1_MP_RXN<5>"
					( Origin gPackager )
				)
				( attribute "PNN" "TP_P3E_CPU1_PE1_MP_RXN<5>"
					( Origin gPackager )
				)
				( objectStatus "TP_P3E_CPU1_PE1_MP_RXN<5>" )
			)
			( signal "@baseboard_fab2_lib.baseboard_fab2(sch_1):tp_p3e_cpu1_pe1_mp_rxn(6)"
				( attribute "CDS_PHYS_NET_NAME" "TP_P3E_CPU1_PE1_MP_RXN<6>"
					( Origin gPackager )
				)
				( attribute "PNN" "TP_P3E_CPU1_PE1_MP_RXN<6>"
					( Origin gPackager )
				)
				( objectStatus "TP_P3E_CPU1_PE1_MP_RXN<6>" )
			)
			( signal "@baseboard_fab2_lib.baseboard_fab2(sch_1):tp_p3e_cpu1_pe1_mp_rxn(7)"
				( attribute "CDS_PHYS_NET_NAME" "TP_P3E_CPU1_PE1_MP_RXN<7>"
					( Origin gPackager )
				)
				( attribute "PNN" "TP_P3E_CPU1_PE1_MP_RXN<7>"
					( Origin gPackager )
				)
				( objectStatus "TP_P3E_CPU1_PE1_MP_RXN<7>" )
			)
			( signal "@baseboard_fab2_lib.baseboard_fab2(sch_1):tp_p3e_cpu1_pe1_mp_rxp(0)"
				( attribute "CDS_PHYS_NET_NAME" "TP_P3E_CPU1_PE1_MP_RXP<0>"
					( Origin gPackager )
				)
				( attribute "PNN" "TP_P3E_CPU1_PE1_MP_RXP<0>"
					( Origin gPackager )
				)
				( objectStatus "TP_P3E_CPU1_PE1_MP_RXP<0>" )
			)
			( signal "@baseboard_fab2_lib.baseboard_fab2(sch_1):tp_p3e_cpu1_pe1_mp_rxp(1)"
				( attribute "CDS_PHYS_NET_NAME" "TP_P3E_CPU1_PE1_MP_RXP<1>"
					( Origin gPackager )
				)
				( attribute "PNN" "TP_P3E_CPU1_PE1_MP_RXP<1>"
					( Origin gPackager )
				)
				( objectStatus "TP_P3E_CPU1_PE1_MP_RXP<1>" )
			)
			( signal "@baseboard_fab2_lib.baseboard_fab2(sch_1):tp_p3e_cpu1_pe1_mp_rxp(2)"
				( attribute "CDS_PHYS_NET_NAME" "TP_P3E_CPU1_PE1_MP_RXP<2>"
					( Origin gPackager )
				)
				( attribute "PNN" "TP_P3E_CPU1_PE1_MP_RXP<2>"
					( Origin gPackager )
				)
				( objectStatus "TP_P3E_CPU1_PE1_MP_RXP<2>" )
			)
			( signal "@baseboard_fab2_lib.baseboard_fab2(sch_1):tp_p3e_cpu1_pe1_mp_rxp(3)"
				( attribute "CDS_PHYS_NET_NAME" "TP_P3E_CPU1_PE1_MP_RXP<3>"
					( Origin gPackager )
				)
				( attribute "PNN" "TP_P3E_CPU1_PE1_MP_RXP<3>"
					( Origin gPackager )
				)
				( objectStatus "TP_P3E_CPU1_PE1_MP_RXP<3>" )
			)
			( signal "@baseboard_fab2_lib.baseboard_fab2(sch_1):tp_p3e_cpu1_pe1_mp_rxp(4)"
				( attribute "CDS_PHYS_NET_NAME" "TP_P3E_CPU1_PE1_MP_RXP<4>"
					( Origin gPackager )
				)
				( attribute "PNN" "TP_P3E_CPU1_PE1_MP_RXP<4>"
					( Origin gPackager )
				)
				( objectStatus "TP_P3E_CPU1_PE1_MP_RXP<4>" )
			)
			( signal "@baseboard_fab2_lib.baseboard_fab2(sch_1):tp_p3e_cpu1_pe1_mp_rxp(5)"
				( attribute "CDS_PHYS_NET_NAME" "TP_P3E_CPU1_PE1_MP_RXP<5>"
					( Origin gPackager )
				)
				( attribute "PNN" "TP_P3E_CPU1_PE1_MP_RXP<5>"
					( Origin gPackager )
				)
				( objectStatus "TP_P3E_CPU1_PE1_MP_RXP<5>" )
			)
			( signal "@baseboard_fab2_lib.baseboard_fab2(sch_1):tp_p3e_cpu1_pe1_mp_rxp(6)"
				( attribute "CDS_PHYS_NET_NAME" "TP_P3E_CPU1_PE1_MP_RXP<6>"
					( Origin gPackager )
				)
				( attribute "PNN" "TP_P3E_CPU1_PE1_MP_RXP<6>"
					( Origin gPackager )
				)
				( objectStatus "TP_P3E_CPU1_PE1_MP_RXP<6>" )
			)
			( signal "@baseboard_fab2_lib.baseboard_fab2(sch_1):tp_p3e_cpu1_pe1_mp_rxp(7)"
				( attribute "CDS_PHYS_NET_NAME" "TP_P3E_CPU1_PE1_MP_RXP<7>"
					( Origin gPackager )
				)
				( attribute "PNN" "TP_P3E_CPU1_PE1_MP_RXP<7>"
					( Origin gPackager )
				)
				( objectStatus "TP_P3E_CPU1_PE1_MP_RXP<7>" )
			)
			( signal "@baseboard_fab2_lib.baseboard_fab2(sch_1):tp_p3e_cpu1_pe1_mp_txn(0)"
				( attribute "CDS_PHYS_NET_NAME" "TP_P3E_CPU1_PE1_MP_TXN<0>"
					( Origin gPackager )
				)
				( attribute "PNN" "TP_P3E_CPU1_PE1_MP_TXN<0>"
					( Origin gPackager )
				)
				( objectStatus "TP_P3E_CPU1_PE1_MP_TXN<0>" )
			)
			( signal "@baseboard_fab2_lib.baseboard_fab2(sch_1):tp_p3e_cpu1_pe1_mp_txn(1)"
				( attribute "CDS_PHYS_NET_NAME" "TP_P3E_CPU1_PE1_MP_TXN<1>"
					( Origin gPackager )
				)
				( attribute "PNN" "TP_P3E_CPU1_PE1_MP_TXN<1>"
					( Origin gPackager )
				)
				( objectStatus "TP_P3E_CPU1_PE1_MP_TXN<1>" )
			)
			( signal "@baseboard_fab2_lib.baseboard_fab2(sch_1):tp_p3e_cpu1_pe1_mp_txn(2)"
				( attribute "CDS_PHYS_NET_NAME" "TP_P3E_CPU1_PE1_MP_TXN<2>"
					( Origin gPackager )
				)
				( attribute "PNN" "TP_P3E_CPU1_PE1_MP_TXN<2>"
					( Origin gPackager )
				)
				( objectStatus "TP_P3E_CPU1_PE1_MP_TXN<2>" )
			)
			( signal "@baseboard_fab2_lib.baseboard_fab2(sch_1):tp_p3e_cpu1_pe1_mp_txn(3)"
				( attribute "CDS_PHYS_NET_NAME" "TP_P3E_CPU1_PE1_MP_TXN<3>"
					( Origin gPackager )
				)
				( attribute "PNN" "TP_P3E_CPU1_PE1_MP_TXN<3>"
					( Origin gPackager )
				)
				( objectStatus "TP_P3E_CPU1_PE1_MP_TXN<3>" )
			)
			( signal "@baseboard_fab2_lib.baseboard_fab2(sch_1):tp_p3e_cpu1_pe1_mp_txn(4)"
				( attribute "CDS_PHYS_NET_NAME" "TP_P3E_CPU1_PE1_MP_TXN<4>"
					( Origin gPackager )
				)
				( attribute "PNN" "TP_P3E_CPU1_PE1_MP_TXN<4>"
					( Origin gPackager )
				)
				( objectStatus "TP_P3E_CPU1_PE1_MP_TXN<4>" )
			)
			( signal "@baseboard_fab2_lib.baseboard_fab2(sch_1):tp_p3e_cpu1_pe1_mp_txn(5)"
				( attribute "CDS_PHYS_NET_NAME" "TP_P3E_CPU1_PE1_MP_TXN<5>"
					( Origin gPackager )
				)
				( attribute "PNN" "TP_P3E_CPU1_PE1_MP_TXN<5>"
					( Origin gPackager )
				)
				( objectStatus "TP_P3E_CPU1_PE1_MP_TXN<5>" )
			)
			( signal "@baseboard_fab2_lib.baseboard_fab2(sch_1):tp_p3e_cpu1_pe1_mp_txn(6)"
				( attribute "CDS_PHYS_NET_NAME" "TP_P3E_CPU1_PE1_MP_TXN<6>"
					( Origin gPackager )
				)
				( attribute "PNN" "TP_P3E_CPU1_PE1_MP_TXN<6>"
					( Origin gPackager )
				)
				( objectStatus "TP_P3E_CPU1_PE1_MP_TXN<6>" )
			)
			( signal "@baseboard_fab2_lib.baseboard_fab2(sch_1):tp_p3e_cpu1_pe1_mp_txn(7)"
				( attribute "CDS_PHYS_NET_NAME" "TP_P3E_CPU1_PE1_MP_TXN<7>"
					( Origin gPackager )
				)
				( attribute "PNN" "TP_P3E_CPU1_PE1_MP_TXN<7>"
					( Origin gPackager )
				)
				( objectStatus "TP_P3E_CPU1_PE1_MP_TXN<7>" )
			)
			( signal "@baseboard_fab2_lib.baseboard_fab2(sch_1):tp_p3e_cpu1_pe1_mp_txp(0)"
				( attribute "CDS_PHYS_NET_NAME" "TP_P3E_CPU1_PE1_MP_TXP<0>"
					( Origin gPackager )
				)
				( attribute "PNN" "TP_P3E_CPU1_PE1_MP_TXP<0>"
					( Origin gPackager )
				)
				( objectStatus "TP_P3E_CPU1_PE1_MP_TXP<0>" )
			)
			( signal "@baseboard_fab2_lib.baseboard_fab2(sch_1):tp_p3e_cpu1_pe1_mp_txp(1)"
				( attribute "CDS_PHYS_NET_NAME" "TP_P3E_CPU1_PE1_MP_TXP<1>"
					( Origin gPackager )
				)
				( attribute "PNN" "TP_P3E_CPU1_PE1_MP_TXP<1>"
					( Origin gPackager )
				)
				( objectStatus "TP_P3E_CPU1_PE1_MP_TXP<1>" )
			)
			( signal "@baseboard_fab2_lib.baseboard_fab2(sch_1):tp_p3e_cpu1_pe1_mp_txp(2)"
				( attribute "CDS_PHYS_NET_NAME" "TP_P3E_CPU1_PE1_MP_TXP<2>"
					( Origin gPackager )
				)
				( attribute "PNN" "TP_P3E_CPU1_PE1_MP_TXP<2>"
					( Origin gPackager )
				)
				( objectStatus "TP_P3E_CPU1_PE1_MP_TXP<2>" )
			)
			( signal "@baseboard_fab2_lib.baseboard_fab2(sch_1):tp_p3e_cpu1_pe1_mp_txp(3)"
				( attribute "CDS_PHYS_NET_NAME" "TP_P3E_CPU1_PE1_MP_TXP<3>"
					( Origin gPackager )
				)
				( attribute "PNN" "TP_P3E_CPU1_PE1_MP_TXP<3>"
					( Origin gPackager )
				)
				( objectStatus "TP_P3E_CPU1_PE1_MP_TXP<3>" )
			)
			( signal "@baseboard_fab2_lib.baseboard_fab2(sch_1):tp_p3e_cpu1_pe1_mp_txp(4)"
				( attribute "CDS_PHYS_NET_NAME" "TP_P3E_CPU1_PE1_MP_TXP<4>"
					( Origin gPackager )
				)
				( attribute "PNN" "TP_P3E_CPU1_PE1_MP_TXP<4>"
					( Origin gPackager )
				)
				( objectStatus "TP_P3E_CPU1_PE1_MP_TXP<4>" )
			)
			( signal "@baseboard_fab2_lib.baseboard_fab2(sch_1):tp_p3e_cpu1_pe1_mp_txp(5)"
				( attribute "CDS_PHYS_NET_NAME" "TP_P3E_CPU1_PE1_MP_TXP<5>"
					( Origin gPackager )
				)
				( attribute "PNN" "TP_P3E_CPU1_PE1_MP_TXP<5>"
					( Origin gPackager )
				)
				( objectStatus "TP_P3E_CPU1_PE1_MP_TXP<5>" )
			)
			( signal "@baseboard_fab2_lib.baseboard_fab2(sch_1):tp_p3e_cpu1_pe1_mp_txp(6)"
				( attribute "CDS_PHYS_NET_NAME" "TP_P3E_CPU1_PE1_MP_TXP<6>"
					( Origin gPackager )
				)
				( attribute "PNN" "TP_P3E_CPU1_PE1_MP_TXP<6>"
					( Origin gPackager )
				)
				( objectStatus "TP_P3E_CPU1_PE1_MP_TXP<6>" )
			)
			( signal "@baseboard_fab2_lib.baseboard_fab2(sch_1):tp_p3e_cpu1_pe1_mp_txp(7)"
				( attribute "CDS_PHYS_NET_NAME" "TP_P3E_CPU1_PE1_MP_TXP<7>"
					( Origin gPackager )
				)
				( attribute "PNN" "TP_P3E_CPU1_PE1_MP_TXP<7>"
					( Origin gPackager )
				)
				( objectStatus "TP_P3E_CPU1_PE1_MP_TXP<7>" )
			)
			( signal "@baseboard_fab2_lib.baseboard_fab2(sch_1):tp_p3e_cpu1_pe1_rsr3_rxn(8)"
				( attribute "CDS_PHYS_NET_NAME" "TP_P3E_CPU1_PE1_RSR3_RXN<8>"
					( Origin gPackager )
				)
				( attribute "PNN" "TP_P3E_CPU1_PE1_RSR3_RXN<8>"
					( Origin gPackager )
				)
				( objectStatus "TP_P3E_CPU1_PE1_RSR3_RXN<8>" )
			)
			( signal "@baseboard_fab2_lib.baseboard_fab2(sch_1):tp_p3e_cpu1_pe1_rsr3_rxn(9)"
				( attribute "CDS_PHYS_NET_NAME" "TP_P3E_CPU1_PE1_RSR3_RXN<9>"
					( Origin gPackager )
				)
				( attribute "PNN" "TP_P3E_CPU1_PE1_RSR3_RXN<9>"
					( Origin gPackager )
				)
				( objectStatus "TP_P3E_CPU1_PE1_RSR3_RXN<9>" )
			)
			( signal "@baseboard_fab2_lib.baseboard_fab2(sch_1):tp_p3e_cpu1_pe1_rsr3_rxn(10)"
				( attribute "CDS_PHYS_NET_NAME" "TP_P3E_CPU1_PE1_RSR3_RXN<10>"
					( Origin gPackager )
				)
				( attribute "PNN" "TP_P3E_CPU1_PE1_RSR3_RXN<10>"
					( Origin gPackager )
				)
				( objectStatus "TP_P3E_CPU1_PE1_RSR3_RXN<10>" )
			)
			( signal "@baseboard_fab2_lib.baseboard_fab2(sch_1):tp_p3e_cpu1_pe1_rsr3_rxn(11)"
				( attribute "CDS_PHYS_NET_NAME" "TP_P3E_CPU1_PE1_RSR3_RXN<11>"
					( Origin gPackager )
				)
				( attribute "PNN" "TP_P3E_CPU1_PE1_RSR3_RXN<11>"
					( Origin gPackager )
				)
				( objectStatus "TP_P3E_CPU1_PE1_RSR3_RXN<11>" )
			)
			( signal "@baseboard_fab2_lib.baseboard_fab2(sch_1):tp_p3e_cpu1_pe1_rsr3_rxn(12)"
				( attribute "CDS_PHYS_NET_NAME" "TP_P3E_CPU1_PE1_RSR3_RXN<12>"
					( Origin gPackager )
				)
				( attribute "PNN" "TP_P3E_CPU1_PE1_RSR3_RXN<12>"
					( Origin gPackager )
				)
				( objectStatus "TP_P3E_CPU1_PE1_RSR3_RXN<12>" )
			)
			( signal "@baseboard_fab2_lib.baseboard_fab2(sch_1):tp_p3e_cpu1_pe1_rsr3_rxn(13)"
				( attribute "CDS_PHYS_NET_NAME" "TP_P3E_CPU1_PE1_RSR3_RXN<13>"
					( Origin gPackager )
				)
				( attribute "PNN" "TP_P3E_CPU1_PE1_RSR3_RXN<13>"
					( Origin gPackager )
				)
				( objectStatus "TP_P3E_CPU1_PE1_RSR3_RXN<13>" )
			)
			( signal "@baseboard_fab2_lib.baseboard_fab2(sch_1):tp_p3e_cpu1_pe1_rsr3_rxn(14)"
				( attribute "CDS_PHYS_NET_NAME" "TP_P3E_CPU1_PE1_RSR3_RXN<14>"
					( Origin gPackager )
				)
				( attribute "PNN" "TP_P3E_CPU1_PE1_RSR3_RXN<14>"
					( Origin gPackager )
				)
				( objectStatus "TP_P3E_CPU1_PE1_RSR3_RXN<14>" )
			)
			( signal "@baseboard_fab2_lib.baseboard_fab2(sch_1):tp_p3e_cpu1_pe1_rsr3_rxn(15)"
				( attribute "CDS_PHYS_NET_NAME" "TP_P3E_CPU1_PE1_RSR3_RXN<15>"
					( Origin gPackager )
				)
				( attribute "PNN" "TP_P3E_CPU1_PE1_RSR3_RXN<15>"
					( Origin gPackager )
				)
				( objectStatus "TP_P3E_CPU1_PE1_RSR3_RXN<15>" )
			)
			( signal "@baseboard_fab2_lib.baseboard_fab2(sch_1):tp_p3e_cpu1_pe1_rsr3_rxp(8)"
				( attribute "CDS_PHYS_NET_NAME" "TP_P3E_CPU1_PE1_RSR3_RXP<8>"
					( Origin gPackager )
				)
				( attribute "PNN" "TP_P3E_CPU1_PE1_RSR3_RXP<8>"
					( Origin gPackager )
				)
				( objectStatus "TP_P3E_CPU1_PE1_RSR3_RXP<8>" )
			)
			( signal "@baseboard_fab2_lib.baseboard_fab2(sch_1):tp_p3e_cpu1_pe1_rsr3_rxp(9)"
				( attribute "CDS_PHYS_NET_NAME" "TP_P3E_CPU1_PE1_RSR3_RXP<9>"
					( Origin gPackager )
				)
				( attribute "PNN" "TP_P3E_CPU1_PE1_RSR3_RXP<9>"
					( Origin gPackager )
				)
				( objectStatus "TP_P3E_CPU1_PE1_RSR3_RXP<9>" )
			)
			( signal "@baseboard_fab2_lib.baseboard_fab2(sch_1):tp_p3e_cpu1_pe1_rsr3_rxp(10)"
				( attribute "CDS_PHYS_NET_NAME" "TP_P3E_CPU1_PE1_RSR3_RXP<10>"
					( Origin gPackager )
				)
				( attribute "PNN" "TP_P3E_CPU1_PE1_RSR3_RXP<10>"
					( Origin gPackager )
				)
				( objectStatus "TP_P3E_CPU1_PE1_RSR3_RXP<10>" )
			)
			( signal "@baseboard_fab2_lib.baseboard_fab2(sch_1):tp_p3e_cpu1_pe1_rsr3_rxp(11)"
				( attribute "CDS_PHYS_NET_NAME" "TP_P3E_CPU1_PE1_RSR3_RXP<11>"
					( Origin gPackager )
				)
				( attribute "PNN" "TP_P3E_CPU1_PE1_RSR3_RXP<11>"
					( Origin gPackager )
				)
				( objectStatus "TP_P3E_CPU1_PE1_RSR3_RXP<11>" )
			)
			( signal "@baseboard_fab2_lib.baseboard_fab2(sch_1):tp_p3e_cpu1_pe1_rsr3_rxp(12)"
				( attribute "CDS_PHYS_NET_NAME" "TP_P3E_CPU1_PE1_RSR3_RXP<12>"
					( Origin gPackager )
				)
				( attribute "PNN" "TP_P3E_CPU1_PE1_RSR3_RXP<12>"
					( Origin gPackager )
				)
				( objectStatus "TP_P3E_CPU1_PE1_RSR3_RXP<12>" )
			)
			( signal "@baseboard_fab2_lib.baseboard_fab2(sch_1):tp_p3e_cpu1_pe1_rsr3_rxp(13)"
				( attribute "CDS_PHYS_NET_NAME" "TP_P3E_CPU1_PE1_RSR3_RXP<13>"
					( Origin gPackager )
				)
				( attribute "PNN" "TP_P3E_CPU1_PE1_RSR3_RXP<13>"
					( Origin gPackager )
				)
				( objectStatus "TP_P3E_CPU1_PE1_RSR3_RXP<13>" )
			)
			( signal "@baseboard_fab2_lib.baseboard_fab2(sch_1):tp_p3e_cpu1_pe1_rsr3_rxp(14)"
				( attribute "CDS_PHYS_NET_NAME" "TP_P3E_CPU1_PE1_RSR3_RXP<14>"
					( Origin gPackager )
				)
				( attribute "PNN" "TP_P3E_CPU1_PE1_RSR3_RXP<14>"
					( Origin gPackager )
				)
				( objectStatus "TP_P3E_CPU1_PE1_RSR3_RXP<14>" )
			)
			( signal "@baseboard_fab2_lib.baseboard_fab2(sch_1):tp_p3e_cpu1_pe1_rsr3_rxp(15)"
				( attribute "CDS_PHYS_NET_NAME" "TP_P3E_CPU1_PE1_RSR3_RXP<15>"
					( Origin gPackager )
				)
				( attribute "PNN" "TP_P3E_CPU1_PE1_RSR3_RXP<15>"
					( Origin gPackager )
				)
				( objectStatus "TP_P3E_CPU1_PE1_RSR3_RXP<15>" )
			)
			( signal "@baseboard_fab2_lib.baseboard_fab2(sch_1):tp_p3e_cpu1_pe1_rsr3_txn(8)"
				( attribute "CDS_PHYS_NET_NAME" "TP_P3E_CPU1_PE1_RSR3_TXN<8>"
					( Origin gPackager )
				)
				( attribute "PNN" "TP_P3E_CPU1_PE1_RSR3_TXN<8>"
					( Origin gPackager )
				)
				( objectStatus "TP_P3E_CPU1_PE1_RSR3_TXN<8>" )
			)
			( signal "@baseboard_fab2_lib.baseboard_fab2(sch_1):tp_p3e_cpu1_pe1_rsr3_txn(9)"
				( attribute "CDS_PHYS_NET_NAME" "TP_P3E_CPU1_PE1_RSR3_TXN<9>"
					( Origin gPackager )
				)
				( attribute "PNN" "TP_P3E_CPU1_PE1_RSR3_TXN<9>"
					( Origin gPackager )
				)
				( objectStatus "TP_P3E_CPU1_PE1_RSR3_TXN<9>" )
			)
			( signal "@baseboard_fab2_lib.baseboard_fab2(sch_1):tp_p3e_cpu1_pe1_rsr3_txn(10)"
				( attribute "CDS_PHYS_NET_NAME" "TP_P3E_CPU1_PE1_RSR3_TXN<10>"
					( Origin gPackager )
				)
				( attribute "PNN" "TP_P3E_CPU1_PE1_RSR3_TXN<10>"
					( Origin gPackager )
				)
				( objectStatus "TP_P3E_CPU1_PE1_RSR3_TXN<10>" )
			)
			( signal "@baseboard_fab2_lib.baseboard_fab2(sch_1):tp_p3e_cpu1_pe1_rsr3_txn(11)"
				( attribute "CDS_PHYS_NET_NAME" "TP_P3E_CPU1_PE1_RSR3_TXN<11>"
					( Origin gPackager )
				)
				( attribute "PNN" "TP_P3E_CPU1_PE1_RSR3_TXN<11>"
					( Origin gPackager )
				)
				( objectStatus "TP_P3E_CPU1_PE1_RSR3_TXN<11>" )
			)
			( signal "@baseboard_fab2_lib.baseboard_fab2(sch_1):tp_p3e_cpu1_pe1_rsr3_txn(12)"
				( attribute "CDS_PHYS_NET_NAME" "TP_P3E_CPU1_PE1_RSR3_TXN<12>"
					( Origin gPackager )
				)
				( attribute "PNN" "TP_P3E_CPU1_PE1_RSR3_TXN<12>"
					( Origin gPackager )
				)
				( objectStatus "TP_P3E_CPU1_PE1_RSR3_TXN<12>" )
			)
			( signal "@baseboard_fab2_lib.baseboard_fab2(sch_1):tp_p3e_cpu1_pe1_rsr3_txn(13)"
				( attribute "CDS_PHYS_NET_NAME" "TP_P3E_CPU1_PE1_RSR3_TXN<13>"
					( Origin gPackager )
				)
				( attribute "PNN" "TP_P3E_CPU1_PE1_RSR3_TXN<13>"
					( Origin gPackager )
				)
				( objectStatus "TP_P3E_CPU1_PE1_RSR3_TXN<13>" )
			)
			( signal "@baseboard_fab2_lib.baseboard_fab2(sch_1):tp_p3e_cpu1_pe1_rsr3_txn(14)"
				( attribute "CDS_PHYS_NET_NAME" "TP_P3E_CPU1_PE1_RSR3_TXN<14>"
					( Origin gPackager )
				)
				( attribute "PNN" "TP_P3E_CPU1_PE1_RSR3_TXN<14>"
					( Origin gPackager )
				)
				( objectStatus "TP_P3E_CPU1_PE1_RSR3_TXN<14>" )
			)
			( signal "@baseboard_fab2_lib.baseboard_fab2(sch_1):tp_p3e_cpu1_pe1_rsr3_txn(15)"
				( attribute "CDS_PHYS_NET_NAME" "TP_P3E_CPU1_PE1_RSR3_TXN<15>"
					( Origin gPackager )
				)
				( attribute "PNN" "TP_P3E_CPU1_PE1_RSR3_TXN<15>"
					( Origin gPackager )
				)
				( objectStatus "TP_P3E_CPU1_PE1_RSR3_TXN<15>" )
			)
			( signal "@baseboard_fab2_lib.baseboard_fab2(sch_1):tp_p3e_cpu1_pe1_rsr3_txp(8)"
				( attribute "CDS_PHYS_NET_NAME" "TP_P3E_CPU1_PE1_RSR3_TXP<8>"
					( Origin gPackager )
				)
				( attribute "PNN" "TP_P3E_CPU1_PE1_RSR3_TXP<8>"
					( Origin gPackager )
				)
				( objectStatus "TP_P3E_CPU1_PE1_RSR3_TXP<8>" )
			)
			( signal "@baseboard_fab2_lib.baseboard_fab2(sch_1):tp_p3e_cpu1_pe1_rsr3_txp(9)"
				( attribute "CDS_PHYS_NET_NAME" "TP_P3E_CPU1_PE1_RSR3_TXP<9>"
					( Origin gPackager )
				)
				( attribute "PNN" "TP_P3E_CPU1_PE1_RSR3_TXP<9>"
					( Origin gPackager )
				)
				( objectStatus "TP_P3E_CPU1_PE1_RSR3_TXP<9>" )
			)
			( signal "@baseboard_fab2_lib.baseboard_fab2(sch_1):tp_p3e_cpu1_pe1_rsr3_txp(10)"
				( attribute "CDS_PHYS_NET_NAME" "TP_P3E_CPU1_PE1_RSR3_TXP<10>"
					( Origin gPackager )
				)
				( attribute "PNN" "TP_P3E_CPU1_PE1_RSR3_TXP<10>"
					( Origin gPackager )
				)
				( objectStatus "TP_P3E_CPU1_PE1_RSR3_TXP<10>" )
			)
			( signal "@baseboard_fab2_lib.baseboard_fab2(sch_1):tp_p3e_cpu1_pe1_rsr3_txp(11)"
				( attribute "CDS_PHYS_NET_NAME" "TP_P3E_CPU1_PE1_RSR3_TXP<11>"
					( Origin gPackager )
				)
				( attribute "PNN" "TP_P3E_CPU1_PE1_RSR3_TXP<11>"
					( Origin gPackager )
				)
				( objectStatus "TP_P3E_CPU1_PE1_RSR3_TXP<11>" )
			)
			( signal "@baseboard_fab2_lib.baseboard_fab2(sch_1):tp_p3e_cpu1_pe1_rsr3_txp(12)"
				( attribute "CDS_PHYS_NET_NAME" "TP_P3E_CPU1_PE1_RSR3_TXP<12>"
					( Origin gPackager )
				)
				( attribute "PNN" "TP_P3E_CPU1_PE1_RSR3_TXP<12>"
					( Origin gPackager )
				)
				( objectStatus "TP_P3E_CPU1_PE1_RSR3_TXP<12>" )
			)
			( signal "@baseboard_fab2_lib.baseboard_fab2(sch_1):tp_p3e_cpu1_pe1_rsr3_txp(13)"
				( attribute "CDS_PHYS_NET_NAME" "TP_P3E_CPU1_PE1_RSR3_TXP<13>"
					( Origin gPackager )
				)
				( attribute "PNN" "TP_P3E_CPU1_PE1_RSR3_TXP<13>"
					( Origin gPackager )
				)
				( objectStatus "TP_P3E_CPU1_PE1_RSR3_TXP<13>" )
			)
			( signal "@baseboard_fab2_lib.baseboard_fab2(sch_1):tp_p3e_cpu1_pe1_rsr3_txp(14)"
				( attribute "CDS_PHYS_NET_NAME" "TP_P3E_CPU1_PE1_RSR3_TXP<14>"
					( Origin gPackager )
				)
				( attribute "PNN" "TP_P3E_CPU1_PE1_RSR3_TXP<14>"
					( Origin gPackager )
				)
				( objectStatus "TP_P3E_CPU1_PE1_RSR3_TXP<14>" )
			)
			( signal "@baseboard_fab2_lib.baseboard_fab2(sch_1):tp_p3e_cpu1_pe1_rsr3_txp(15)"
				( attribute "CDS_PHYS_NET_NAME" "TP_P3E_CPU1_PE1_RSR3_TXP<15>"
					( Origin gPackager )
				)
				( attribute "PNN" "TP_P3E_CPU1_PE1_RSR3_TXP<15>"
					( Origin gPackager )
				)
				( objectStatus "TP_P3E_CPU1_PE1_RSR3_TXP<15>" )
			)
			( signal "@baseboard_fab2_lib.baseboard_fab2(sch_1):tp_p3e_cpu1_pe2_rsr_rxn(0)"
				( attribute "CDS_PHYS_NET_NAME" "TP_P3E_CPU1_PE2_RSR_RXN<0>"
					( Origin gPackager )
				)
				( attribute "PNN" "TP_P3E_CPU1_PE2_RSR_RXN<0>"
					( Origin gPackager )
				)
				( objectStatus "TP_P3E_CPU1_PE2_RSR_RXN<0>" )
			)
			( signal "@baseboard_fab2_lib.baseboard_fab2(sch_1):tp_p3e_cpu1_pe2_rsr_rxn(1)"
				( attribute "CDS_PHYS_NET_NAME" "TP_P3E_CPU1_PE2_RSR_RXN<1>"
					( Origin gPackager )
				)
				( attribute "PNN" "TP_P3E_CPU1_PE2_RSR_RXN<1>"
					( Origin gPackager )
				)
				( objectStatus "TP_P3E_CPU1_PE2_RSR_RXN<1>" )
			)
			( signal "@baseboard_fab2_lib.baseboard_fab2(sch_1):tp_p3e_cpu1_pe2_rsr_rxn(2)"
				( attribute "CDS_PHYS_NET_NAME" "TP_P3E_CPU1_PE2_RSR_RXN<2>"
					( Origin gPackager )
				)
				( attribute "PNN" "TP_P3E_CPU1_PE2_RSR_RXN<2>"
					( Origin gPackager )
				)
				( objectStatus "TP_P3E_CPU1_PE2_RSR_RXN<2>" )
			)
			( signal "@baseboard_fab2_lib.baseboard_fab2(sch_1):tp_p3e_cpu1_pe2_rsr_rxn(3)"
				( attribute "CDS_PHYS_NET_NAME" "TP_P3E_CPU1_PE2_RSR_RXN<3>"
					( Origin gPackager )
				)
				( attribute "PNN" "TP_P3E_CPU1_PE2_RSR_RXN<3>"
					( Origin gPackager )
				)
				( objectStatus "TP_P3E_CPU1_PE2_RSR_RXN<3>" )
			)
			( signal "@baseboard_fab2_lib.baseboard_fab2(sch_1):tp_p3e_cpu1_pe2_rsr_rxn(4)"
				( attribute "CDS_PHYS_NET_NAME" "TP_P3E_CPU1_PE2_RSR_RXN<4>"
					( Origin gPackager )
				)
				( attribute "PNN" "TP_P3E_CPU1_PE2_RSR_RXN<4>"
					( Origin gPackager )
				)
				( objectStatus "TP_P3E_CPU1_PE2_RSR_RXN<4>" )
			)
			( signal "@baseboard_fab2_lib.baseboard_fab2(sch_1):tp_p3e_cpu1_pe2_rsr_rxn(5)"
				( attribute "CDS_PHYS_NET_NAME" "TP_P3E_CPU1_PE2_RSR_RXN<5>"
					( Origin gPackager )
				)
				( attribute "PNN" "TP_P3E_CPU1_PE2_RSR_RXN<5>"
					( Origin gPackager )
				)
				( objectStatus "TP_P3E_CPU1_PE2_RSR_RXN<5>" )
			)
			( signal "@baseboard_fab2_lib.baseboard_fab2(sch_1):tp_p3e_cpu1_pe2_rsr_rxn(6)"
				( attribute "CDS_PHYS_NET_NAME" "TP_P3E_CPU1_PE2_RSR_RXN<6>"
					( Origin gPackager )
				)
				( attribute "PNN" "TP_P3E_CPU1_PE2_RSR_RXN<6>"
					( Origin gPackager )
				)
				( objectStatus "TP_P3E_CPU1_PE2_RSR_RXN<6>" )
			)
			( signal "@baseboard_fab2_lib.baseboard_fab2(sch_1):tp_p3e_cpu1_pe2_rsr_rxn(7)"
				( attribute "CDS_PHYS_NET_NAME" "TP_P3E_CPU1_PE2_RSR_RXN<7>"
					( Origin gPackager )
				)
				( attribute "PNN" "TP_P3E_CPU1_PE2_RSR_RXN<7>"
					( Origin gPackager )
				)
				( objectStatus "TP_P3E_CPU1_PE2_RSR_RXN<7>" )
			)
			( signal "@baseboard_fab2_lib.baseboard_fab2(sch_1):tp_p3e_cpu1_pe2_rsr_rxn(8)"
				( attribute "CDS_PHYS_NET_NAME" "TP_P3E_CPU1_PE2_RSR_RXN<8>"
					( Origin gPackager )
				)
				( attribute "PNN" "TP_P3E_CPU1_PE2_RSR_RXN<8>"
					( Origin gPackager )
				)
				( objectStatus "TP_P3E_CPU1_PE2_RSR_RXN<8>" )
			)
			( signal "@baseboard_fab2_lib.baseboard_fab2(sch_1):tp_p3e_cpu1_pe2_rsr_rxn(9)"
				( attribute "CDS_PHYS_NET_NAME" "TP_P3E_CPU1_PE2_RSR_RXN<9>"
					( Origin gPackager )
				)
				( attribute "PNN" "TP_P3E_CPU1_PE2_RSR_RXN<9>"
					( Origin gPackager )
				)
				( objectStatus "TP_P3E_CPU1_PE2_RSR_RXN<9>" )
			)
			( signal "@baseboard_fab2_lib.baseboard_fab2(sch_1):tp_p3e_cpu1_pe2_rsr_rxn(10)"
				( attribute "CDS_PHYS_NET_NAME" "TP_P3E_CPU1_PE2_RSR_RXN<10>"
					( Origin gPackager )
				)
				( attribute "PNN" "TP_P3E_CPU1_PE2_RSR_RXN<10>"
					( Origin gPackager )
				)
				( objectStatus "TP_P3E_CPU1_PE2_RSR_RXN<10>" )
			)
			( signal "@baseboard_fab2_lib.baseboard_fab2(sch_1):tp_p3e_cpu1_pe2_rsr_rxn(11)"
				( attribute "CDS_PHYS_NET_NAME" "TP_P3E_CPU1_PE2_RSR_RXN<11>"
					( Origin gPackager )
				)
				( attribute "PNN" "TP_P3E_CPU1_PE2_RSR_RXN<11>"
					( Origin gPackager )
				)
				( objectStatus "TP_P3E_CPU1_PE2_RSR_RXN<11>" )
			)
			( signal "@baseboard_fab2_lib.baseboard_fab2(sch_1):tp_p3e_cpu1_pe2_rsr_rxn(12)"
				( attribute "CDS_PHYS_NET_NAME" "TP_P3E_CPU1_PE2_RSR_RXN<12>"
					( Origin gPackager )
				)
				( attribute "PNN" "TP_P3E_CPU1_PE2_RSR_RXN<12>"
					( Origin gPackager )
				)
				( objectStatus "TP_P3E_CPU1_PE2_RSR_RXN<12>" )
			)
			( signal "@baseboard_fab2_lib.baseboard_fab2(sch_1):tp_p3e_cpu1_pe2_rsr_rxn(13)"
				( attribute "CDS_PHYS_NET_NAME" "TP_P3E_CPU1_PE2_RSR_RXN<13>"
					( Origin gPackager )
				)
				( attribute "PNN" "TP_P3E_CPU1_PE2_RSR_RXN<13>"
					( Origin gPackager )
				)
				( objectStatus "TP_P3E_CPU1_PE2_RSR_RXN<13>" )
			)
			( signal "@baseboard_fab2_lib.baseboard_fab2(sch_1):tp_p3e_cpu1_pe2_rsr_rxn(14)"
				( attribute "CDS_PHYS_NET_NAME" "TP_P3E_CPU1_PE2_RSR_RXN<14>"
					( Origin gPackager )
				)
				( attribute "PNN" "TP_P3E_CPU1_PE2_RSR_RXN<14>"
					( Origin gPackager )
				)
				( objectStatus "TP_P3E_CPU1_PE2_RSR_RXN<14>" )
			)
			( signal "@baseboard_fab2_lib.baseboard_fab2(sch_1):tp_p3e_cpu1_pe2_rsr_rxn(15)"
				( attribute "CDS_PHYS_NET_NAME" "TP_P3E_CPU1_PE2_RSR_RXN<15>"
					( Origin gPackager )
				)
				( attribute "PNN" "TP_P3E_CPU1_PE2_RSR_RXN<15>"
					( Origin gPackager )
				)
				( objectStatus "TP_P3E_CPU1_PE2_RSR_RXN<15>" )
			)
			( signal "@baseboard_fab2_lib.baseboard_fab2(sch_1):tp_p3e_cpu1_pe2_rsr_rxp(0)"
				( attribute "CDS_PHYS_NET_NAME" "TP_P3E_CPU1_PE2_RSR_RXP<0>"
					( Origin gPackager )
				)
				( attribute "PNN" "TP_P3E_CPU1_PE2_RSR_RXP<0>"
					( Origin gPackager )
				)
				( objectStatus "TP_P3E_CPU1_PE2_RSR_RXP<0>" )
			)
			( signal "@baseboard_fab2_lib.baseboard_fab2(sch_1):tp_p3e_cpu1_pe2_rsr_rxp(1)"
				( attribute "CDS_PHYS_NET_NAME" "TP_P3E_CPU1_PE2_RSR_RXP<1>"
					( Origin gPackager )
				)
				( attribute "PNN" "TP_P3E_CPU1_PE2_RSR_RXP<1>"
					( Origin gPackager )
				)
				( objectStatus "TP_P3E_CPU1_PE2_RSR_RXP<1>" )
			)
			( signal "@baseboard_fab2_lib.baseboard_fab2(sch_1):tp_p3e_cpu1_pe2_rsr_rxp(2)"
				( attribute "CDS_PHYS_NET_NAME" "TP_P3E_CPU1_PE2_RSR_RXP<2>"
					( Origin gPackager )
				)
				( attribute "PNN" "TP_P3E_CPU1_PE2_RSR_RXP<2>"
					( Origin gPackager )
				)
				( objectStatus "TP_P3E_CPU1_PE2_RSR_RXP<2>" )
			)
			( signal "@baseboard_fab2_lib.baseboard_fab2(sch_1):tp_p3e_cpu1_pe2_rsr_rxp(3)"
				( attribute "CDS_PHYS_NET_NAME" "TP_P3E_CPU1_PE2_RSR_RXP<3>"
					( Origin gPackager )
				)
				( attribute "PNN" "TP_P3E_CPU1_PE2_RSR_RXP<3>"
					( Origin gPackager )
				)
				( objectStatus "TP_P3E_CPU1_PE2_RSR_RXP<3>" )
			)
			( signal "@baseboard_fab2_lib.baseboard_fab2(sch_1):tp_p3e_cpu1_pe2_rsr_rxp(4)"
				( attribute "CDS_PHYS_NET_NAME" "TP_P3E_CPU1_PE2_RSR_RXP<4>"
					( Origin gPackager )
				)
				( attribute "PNN" "TP_P3E_CPU1_PE2_RSR_RXP<4>"
					( Origin gPackager )
				)
				( objectStatus "TP_P3E_CPU1_PE2_RSR_RXP<4>" )
			)
			( signal "@baseboard_fab2_lib.baseboard_fab2(sch_1):tp_p3e_cpu1_pe2_rsr_rxp(5)"
				( attribute "CDS_PHYS_NET_NAME" "TP_P3E_CPU1_PE2_RSR_RXP<5>"
					( Origin gPackager )
				)
				( attribute "PNN" "TP_P3E_CPU1_PE2_RSR_RXP<5>"
					( Origin gPackager )
				)
				( objectStatus "TP_P3E_CPU1_PE2_RSR_RXP<5>" )
			)
			( signal "@baseboard_fab2_lib.baseboard_fab2(sch_1):tp_p3e_cpu1_pe2_rsr_rxp(6)"
				( attribute "CDS_PHYS_NET_NAME" "TP_P3E_CPU1_PE2_RSR_RXP<6>"
					( Origin gPackager )
				)
				( attribute "PNN" "TP_P3E_CPU1_PE2_RSR_RXP<6>"
					( Origin gPackager )
				)
				( objectStatus "TP_P3E_CPU1_PE2_RSR_RXP<6>" )
			)
			( signal "@baseboard_fab2_lib.baseboard_fab2(sch_1):tp_p3e_cpu1_pe2_rsr_rxp(7)"
				( attribute "CDS_PHYS_NET_NAME" "TP_P3E_CPU1_PE2_RSR_RXP<7>"
					( Origin gPackager )
				)
				( attribute "PNN" "TP_P3E_CPU1_PE2_RSR_RXP<7>"
					( Origin gPackager )
				)
				( objectStatus "TP_P3E_CPU1_PE2_RSR_RXP<7>" )
			)
			( signal "@baseboard_fab2_lib.baseboard_fab2(sch_1):tp_p3e_cpu1_pe2_rsr_rxp(8)"
				( attribute "CDS_PHYS_NET_NAME" "TP_P3E_CPU1_PE2_RSR_RXP<8>"
					( Origin gPackager )
				)
				( attribute "PNN" "TP_P3E_CPU1_PE2_RSR_RXP<8>"
					( Origin gPackager )
				)
				( objectStatus "TP_P3E_CPU1_PE2_RSR_RXP<8>" )
			)
			( signal "@baseboard_fab2_lib.baseboard_fab2(sch_1):tp_p3e_cpu1_pe2_rsr_rxp(9)"
				( attribute "CDS_PHYS_NET_NAME" "TP_P3E_CPU1_PE2_RSR_RXP<9>"
					( Origin gPackager )
				)
				( attribute "PNN" "TP_P3E_CPU1_PE2_RSR_RXP<9>"
					( Origin gPackager )
				)
				( objectStatus "TP_P3E_CPU1_PE2_RSR_RXP<9>" )
			)
			( signal "@baseboard_fab2_lib.baseboard_fab2(sch_1):tp_p3e_cpu1_pe2_rsr_rxp(10)"
				( attribute "CDS_PHYS_NET_NAME" "TP_P3E_CPU1_PE2_RSR_RXP<10>"
					( Origin gPackager )
				)
				( attribute "PNN" "TP_P3E_CPU1_PE2_RSR_RXP<10>"
					( Origin gPackager )
				)
				( objectStatus "TP_P3E_CPU1_PE2_RSR_RXP<10>" )
			)
			( signal "@baseboard_fab2_lib.baseboard_fab2(sch_1):tp_p3e_cpu1_pe2_rsr_rxp(11)"
				( attribute "CDS_PHYS_NET_NAME" "TP_P3E_CPU1_PE2_RSR_RXP<11>"
					( Origin gPackager )
				)
				( attribute "PNN" "TP_P3E_CPU1_PE2_RSR_RXP<11>"
					( Origin gPackager )
				)
				( objectStatus "TP_P3E_CPU1_PE2_RSR_RXP<11>" )
			)
			( signal "@baseboard_fab2_lib.baseboard_fab2(sch_1):tp_p3e_cpu1_pe2_rsr_rxp(12)"
				( attribute "CDS_PHYS_NET_NAME" "TP_P3E_CPU1_PE2_RSR_RXP<12>"
					( Origin gPackager )
				)
				( attribute "PNN" "TP_P3E_CPU1_PE2_RSR_RXP<12>"
					( Origin gPackager )
				)
				( objectStatus "TP_P3E_CPU1_PE2_RSR_RXP<12>" )
			)
			( signal "@baseboard_fab2_lib.baseboard_fab2(sch_1):tp_p3e_cpu1_pe2_rsr_rxp(13)"
				( attribute "CDS_PHYS_NET_NAME" "TP_P3E_CPU1_PE2_RSR_RXP<13>"
					( Origin gPackager )
				)
				( attribute "PNN" "TP_P3E_CPU1_PE2_RSR_RXP<13>"
					( Origin gPackager )
				)
				( objectStatus "TP_P3E_CPU1_PE2_RSR_RXP<13>" )
			)
			( signal "@baseboard_fab2_lib.baseboard_fab2(sch_1):tp_p3e_cpu1_pe2_rsr_rxp(14)"
				( attribute "CDS_PHYS_NET_NAME" "TP_P3E_CPU1_PE2_RSR_RXP<14>"
					( Origin gPackager )
				)
				( attribute "PNN" "TP_P3E_CPU1_PE2_RSR_RXP<14>"
					( Origin gPackager )
				)
				( objectStatus "TP_P3E_CPU1_PE2_RSR_RXP<14>" )
			)
			( signal "@baseboard_fab2_lib.baseboard_fab2(sch_1):tp_p3e_cpu1_pe2_rsr_rxp(15)"
				( attribute "CDS_PHYS_NET_NAME" "TP_P3E_CPU1_PE2_RSR_RXP<15>"
					( Origin gPackager )
				)
				( attribute "PNN" "TP_P3E_CPU1_PE2_RSR_RXP<15>"
					( Origin gPackager )
				)
				( objectStatus "TP_P3E_CPU1_PE2_RSR_RXP<15>" )
			)
			( signal "@baseboard_fab2_lib.baseboard_fab2(sch_1):tp_p3e_cpu1_pe2_rsr_txn(0)"
				( attribute "CDS_PHYS_NET_NAME" "TP_P3E_CPU1_PE2_RSR_TXN<0>"
					( Origin gPackager )
				)
				( attribute "PNN" "TP_P3E_CPU1_PE2_RSR_TXN<0>"
					( Origin gPackager )
				)
				( objectStatus "TP_P3E_CPU1_PE2_RSR_TXN<0>" )
			)
			( signal "@baseboard_fab2_lib.baseboard_fab2(sch_1):tp_p3e_cpu1_pe2_rsr_txn(1)"
				( attribute "CDS_PHYS_NET_NAME" "TP_P3E_CPU1_PE2_RSR_TXN<1>"
					( Origin gPackager )
				)
				( attribute "PNN" "TP_P3E_CPU1_PE2_RSR_TXN<1>"
					( Origin gPackager )
				)
				( objectStatus "TP_P3E_CPU1_PE2_RSR_TXN<1>" )
			)
			( signal "@baseboard_fab2_lib.baseboard_fab2(sch_1):tp_p3e_cpu1_pe2_rsr_txn(2)"
				( attribute "CDS_PHYS_NET_NAME" "TP_P3E_CPU1_PE2_RSR_TXN<2>"
					( Origin gPackager )
				)
				( attribute "PNN" "TP_P3E_CPU1_PE2_RSR_TXN<2>"
					( Origin gPackager )
				)
				( objectStatus "TP_P3E_CPU1_PE2_RSR_TXN<2>" )
			)
			( signal "@baseboard_fab2_lib.baseboard_fab2(sch_1):tp_p3e_cpu1_pe2_rsr_txn(3)"
				( attribute "CDS_PHYS_NET_NAME" "TP_P3E_CPU1_PE2_RSR_TXN<3>"
					( Origin gPackager )
				)
				( attribute "PNN" "TP_P3E_CPU1_PE2_RSR_TXN<3>"
					( Origin gPackager )
				)
				( objectStatus "TP_P3E_CPU1_PE2_RSR_TXN<3>" )
			)
			( signal "@baseboard_fab2_lib.baseboard_fab2(sch_1):tp_p3e_cpu1_pe2_rsr_txn(4)"
				( attribute "CDS_PHYS_NET_NAME" "TP_P3E_CPU1_PE2_RSR_TXN<4>"
					( Origin gPackager )
				)
				( attribute "PNN" "TP_P3E_CPU1_PE2_RSR_TXN<4>"
					( Origin gPackager )
				)
				( objectStatus "TP_P3E_CPU1_PE2_RSR_TXN<4>" )
			)
			( signal "@baseboard_fab2_lib.baseboard_fab2(sch_1):tp_p3e_cpu1_pe2_rsr_txn(5)"
				( attribute "CDS_PHYS_NET_NAME" "TP_P3E_CPU1_PE2_RSR_TXN<5>"
					( Origin gPackager )
				)
				( attribute "PNN" "TP_P3E_CPU1_PE2_RSR_TXN<5>"
					( Origin gPackager )
				)
				( objectStatus "TP_P3E_CPU1_PE2_RSR_TXN<5>" )
			)
			( signal "@baseboard_fab2_lib.baseboard_fab2(sch_1):tp_p3e_cpu1_pe2_rsr_txn(6)"
				( attribute "CDS_PHYS_NET_NAME" "TP_P3E_CPU1_PE2_RSR_TXN<6>"
					( Origin gPackager )
				)
				( attribute "PNN" "TP_P3E_CPU1_PE2_RSR_TXN<6>"
					( Origin gPackager )
				)
				( objectStatus "TP_P3E_CPU1_PE2_RSR_TXN<6>" )
			)
			( signal "@baseboard_fab2_lib.baseboard_fab2(sch_1):tp_p3e_cpu1_pe2_rsr_txn(7)"
				( attribute "CDS_PHYS_NET_NAME" "TP_P3E_CPU1_PE2_RSR_TXN<7>"
					( Origin gPackager )
				)
				( attribute "PNN" "TP_P3E_CPU1_PE2_RSR_TXN<7>"
					( Origin gPackager )
				)
				( objectStatus "TP_P3E_CPU1_PE2_RSR_TXN<7>" )
			)
			( signal "@baseboard_fab2_lib.baseboard_fab2(sch_1):tp_p3e_cpu1_pe2_rsr_txn(8)"
				( attribute "CDS_PHYS_NET_NAME" "TP_P3E_CPU1_PE2_RSR_TXN<8>"
					( Origin gPackager )
				)
				( attribute "PNN" "TP_P3E_CPU1_PE2_RSR_TXN<8>"
					( Origin gPackager )
				)
				( objectStatus "TP_P3E_CPU1_PE2_RSR_TXN<8>" )
			)
			( signal "@baseboard_fab2_lib.baseboard_fab2(sch_1):tp_p3e_cpu1_pe2_rsr_txn(9)"
				( attribute "CDS_PHYS_NET_NAME" "TP_P3E_CPU1_PE2_RSR_TXN<9>"
					( Origin gPackager )
				)
				( attribute "PNN" "TP_P3E_CPU1_PE2_RSR_TXN<9>"
					( Origin gPackager )
				)
				( objectStatus "TP_P3E_CPU1_PE2_RSR_TXN<9>" )
			)
			( signal "@baseboard_fab2_lib.baseboard_fab2(sch_1):tp_p3e_cpu1_pe2_rsr_txn(10)"
				( attribute "CDS_PHYS_NET_NAME" "TP_P3E_CPU1_PE2_RSR_TXN<10>"
					( Origin gPackager )
				)
				( attribute "PNN" "TP_P3E_CPU1_PE2_RSR_TXN<10>"
					( Origin gPackager )
				)
				( objectStatus "TP_P3E_CPU1_PE2_RSR_TXN<10>" )
			)
			( signal "@baseboard_fab2_lib.baseboard_fab2(sch_1):tp_p3e_cpu1_pe2_rsr_txn(11)"
				( attribute "CDS_PHYS_NET_NAME" "TP_P3E_CPU1_PE2_RSR_TXN<11>"
					( Origin gPackager )
				)
				( attribute "PNN" "TP_P3E_CPU1_PE2_RSR_TXN<11>"
					( Origin gPackager )
				)
				( objectStatus "TP_P3E_CPU1_PE2_RSR_TXN<11>" )
			)
			( signal "@baseboard_fab2_lib.baseboard_fab2(sch_1):tp_p3e_cpu1_pe2_rsr_txn(12)"
				( attribute "CDS_PHYS_NET_NAME" "TP_P3E_CPU1_PE2_RSR_TXN<12>"
					( Origin gPackager )
				)
				( attribute "PNN" "TP_P3E_CPU1_PE2_RSR_TXN<12>"
					( Origin gPackager )
				)
				( objectStatus "TP_P3E_CPU1_PE2_RSR_TXN<12>" )
			)
			( signal "@baseboard_fab2_lib.baseboard_fab2(sch_1):tp_p3e_cpu1_pe2_rsr_txn(13)"
				( attribute "CDS_PHYS_NET_NAME" "TP_P3E_CPU1_PE2_RSR_TXN<13>"
					( Origin gPackager )
				)
				( attribute "PNN" "TP_P3E_CPU1_PE2_RSR_TXN<13>"
					( Origin gPackager )
				)
				( objectStatus "TP_P3E_CPU1_PE2_RSR_TXN<13>" )
			)
			( signal "@baseboard_fab2_lib.baseboard_fab2(sch_1):tp_p3e_cpu1_pe2_rsr_txn(14)"
				( attribute "CDS_PHYS_NET_NAME" "TP_P3E_CPU1_PE2_RSR_TXN<14>"
					( Origin gPackager )
				)
				( attribute "PNN" "TP_P3E_CPU1_PE2_RSR_TXN<14>"
					( Origin gPackager )
				)
				( objectStatus "TP_P3E_CPU1_PE2_RSR_TXN<14>" )
			)
			( signal "@baseboard_fab2_lib.baseboard_fab2(sch_1):tp_p3e_cpu1_pe2_rsr_txn(15)"
				( attribute "CDS_PHYS_NET_NAME" "TP_P3E_CPU1_PE2_RSR_TXN<15>"
					( Origin gPackager )
				)
				( attribute "PNN" "TP_P3E_CPU1_PE2_RSR_TXN<15>"
					( Origin gPackager )
				)
				( objectStatus "TP_P3E_CPU1_PE2_RSR_TXN<15>" )
			)
			( signal "@baseboard_fab2_lib.baseboard_fab2(sch_1):tp_p3e_cpu1_pe2_rsr_txp(0)"
				( attribute "CDS_PHYS_NET_NAME" "TP_P3E_CPU1_PE2_RSR_TXP<0>"
					( Origin gPackager )
				)
				( attribute "PNN" "TP_P3E_CPU1_PE2_RSR_TXP<0>"
					( Origin gPackager )
				)
				( objectStatus "TP_P3E_CPU1_PE2_RSR_TXP<0>" )
			)
			( signal "@baseboard_fab2_lib.baseboard_fab2(sch_1):tp_p3e_cpu1_pe2_rsr_txp(1)"
				( attribute "CDS_PHYS_NET_NAME" "TP_P3E_CPU1_PE2_RSR_TXP<1>"
					( Origin gPackager )
				)
				( attribute "PNN" "TP_P3E_CPU1_PE2_RSR_TXP<1>"
					( Origin gPackager )
				)
				( objectStatus "TP_P3E_CPU1_PE2_RSR_TXP<1>" )
			)
			( signal "@baseboard_fab2_lib.baseboard_fab2(sch_1):tp_p3e_cpu1_pe2_rsr_txp(2)"
				( attribute "CDS_PHYS_NET_NAME" "TP_P3E_CPU1_PE2_RSR_TXP<2>"
					( Origin gPackager )
				)
				( attribute "PNN" "TP_P3E_CPU1_PE2_RSR_TXP<2>"
					( Origin gPackager )
				)
				( objectStatus "TP_P3E_CPU1_PE2_RSR_TXP<2>" )
			)
			( signal "@baseboard_fab2_lib.baseboard_fab2(sch_1):tp_p3e_cpu1_pe2_rsr_txp(3)"
				( attribute "CDS_PHYS_NET_NAME" "TP_P3E_CPU1_PE2_RSR_TXP<3>"
					( Origin gPackager )
				)
				( attribute "PNN" "TP_P3E_CPU1_PE2_RSR_TXP<3>"
					( Origin gPackager )
				)
				( objectStatus "TP_P3E_CPU1_PE2_RSR_TXP<3>" )
			)
			( signal "@baseboard_fab2_lib.baseboard_fab2(sch_1):tp_p3e_cpu1_pe2_rsr_txp(4)"
				( attribute "CDS_PHYS_NET_NAME" "TP_P3E_CPU1_PE2_RSR_TXP<4>"
					( Origin gPackager )
				)
				( attribute "PNN" "TP_P3E_CPU1_PE2_RSR_TXP<4>"
					( Origin gPackager )
				)
				( objectStatus "TP_P3E_CPU1_PE2_RSR_TXP<4>" )
			)
			( signal "@baseboard_fab2_lib.baseboard_fab2(sch_1):tp_p3e_cpu1_pe2_rsr_txp(5)"
				( attribute "CDS_PHYS_NET_NAME" "TP_P3E_CPU1_PE2_RSR_TXP<5>"
					( Origin gPackager )
				)
				( attribute "PNN" "TP_P3E_CPU1_PE2_RSR_TXP<5>"
					( Origin gPackager )
				)
				( objectStatus "TP_P3E_CPU1_PE2_RSR_TXP<5>" )
			)
			( signal "@baseboard_fab2_lib.baseboard_fab2(sch_1):tp_p3e_cpu1_pe2_rsr_txp(6)"
				( attribute "CDS_PHYS_NET_NAME" "TP_P3E_CPU1_PE2_RSR_TXP<6>"
					( Origin gPackager )
				)
				( attribute "PNN" "TP_P3E_CPU1_PE2_RSR_TXP<6>"
					( Origin gPackager )
				)
				( objectStatus "TP_P3E_CPU1_PE2_RSR_TXP<6>" )
			)
			( signal "@baseboard_fab2_lib.baseboard_fab2(sch_1):tp_p3e_cpu1_pe2_rsr_txp(7)"
				( attribute "CDS_PHYS_NET_NAME" "TP_P3E_CPU1_PE2_RSR_TXP<7>"
					( Origin gPackager )
				)
				( attribute "PNN" "TP_P3E_CPU1_PE2_RSR_TXP<7>"
					( Origin gPackager )
				)
				( objectStatus "TP_P3E_CPU1_PE2_RSR_TXP<7>" )
			)
			( signal "@baseboard_fab2_lib.baseboard_fab2(sch_1):tp_p3e_cpu1_pe2_rsr_txp(8)"
				( attribute "CDS_PHYS_NET_NAME" "TP_P3E_CPU1_PE2_RSR_TXP<8>"
					( Origin gPackager )
				)
				( attribute "PNN" "TP_P3E_CPU1_PE2_RSR_TXP<8>"
					( Origin gPackager )
				)
				( objectStatus "TP_P3E_CPU1_PE2_RSR_TXP<8>" )
			)
			( signal "@baseboard_fab2_lib.baseboard_fab2(sch_1):tp_p3e_cpu1_pe2_rsr_txp(9)"
				( attribute "CDS_PHYS_NET_NAME" "TP_P3E_CPU1_PE2_RSR_TXP<9>"
					( Origin gPackager )
				)
				( attribute "PNN" "TP_P3E_CPU1_PE2_RSR_TXP<9>"
					( Origin gPackager )
				)
				( objectStatus "TP_P3E_CPU1_PE2_RSR_TXP<9>" )
			)
			( signal "@baseboard_fab2_lib.baseboard_fab2(sch_1):tp_p3e_cpu1_pe2_rsr_txp(10)"
				( attribute "CDS_PHYS_NET_NAME" "TP_P3E_CPU1_PE2_RSR_TXP<10>"
					( Origin gPackager )
				)
				( attribute "PNN" "TP_P3E_CPU1_PE2_RSR_TXP<10>"
					( Origin gPackager )
				)
				( objectStatus "TP_P3E_CPU1_PE2_RSR_TXP<10>" )
			)
			( signal "@baseboard_fab2_lib.baseboard_fab2(sch_1):tp_p3e_cpu1_pe2_rsr_txp(11)"
				( attribute "CDS_PHYS_NET_NAME" "TP_P3E_CPU1_PE2_RSR_TXP<11>"
					( Origin gPackager )
				)
				( attribute "PNN" "TP_P3E_CPU1_PE2_RSR_TXP<11>"
					( Origin gPackager )
				)
				( objectStatus "TP_P3E_CPU1_PE2_RSR_TXP<11>" )
			)
			( signal "@baseboard_fab2_lib.baseboard_fab2(sch_1):tp_p3e_cpu1_pe2_rsr_txp(12)"
				( attribute "CDS_PHYS_NET_NAME" "TP_P3E_CPU1_PE2_RSR_TXP<12>"
					( Origin gPackager )
				)
				( attribute "PNN" "TP_P3E_CPU1_PE2_RSR_TXP<12>"
					( Origin gPackager )
				)
				( objectStatus "TP_P3E_CPU1_PE2_RSR_TXP<12>" )
			)
			( signal "@baseboard_fab2_lib.baseboard_fab2(sch_1):tp_p3e_cpu1_pe2_rsr_txp(13)"
				( attribute "CDS_PHYS_NET_NAME" "TP_P3E_CPU1_PE2_RSR_TXP<13>"
					( Origin gPackager )
				)
				( attribute "PNN" "TP_P3E_CPU1_PE2_RSR_TXP<13>"
					( Origin gPackager )
				)
				( objectStatus "TP_P3E_CPU1_PE2_RSR_TXP<13>" )
			)
			( signal "@baseboard_fab2_lib.baseboard_fab2(sch_1):tp_p3e_cpu1_pe2_rsr_txp(14)"
				( attribute "CDS_PHYS_NET_NAME" "TP_P3E_CPU1_PE2_RSR_TXP<14>"
					( Origin gPackager )
				)
				( attribute "PNN" "TP_P3E_CPU1_PE2_RSR_TXP<14>"
					( Origin gPackager )
				)
				( objectStatus "TP_P3E_CPU1_PE2_RSR_TXP<14>" )
			)
			( signal "@baseboard_fab2_lib.baseboard_fab2(sch_1):tp_p3e_cpu1_pe2_rsr_txp(15)"
				( attribute "CDS_PHYS_NET_NAME" "TP_P3E_CPU1_PE2_RSR_TXP<15>"
					( Origin gPackager )
				)
				( attribute "PNN" "TP_P3E_CPU1_PE2_RSR_TXP<15>"
					( Origin gPackager )
				)
				( objectStatus "TP_P3E_CPU1_PE2_RSR_TXP<15>" )
			)
			( signal "@baseboard_fab2_lib.baseboard_fab2(sch_1):p3e_cpu1_pe3_mp_rxn(0)"
				( attribute "CDS_PHYS_NET_NAME" "P3E_CPU1_PE3_MP_RXN<0>"
					( Origin gPackager )
				)
				( attribute "PNN" "P3E_CPU1_PE3_MP_RXN<0>"
					( Origin gPackager )
				)
				( objectStatus "P3E_CPU1_PE3_MP_RXN<0>" )
			)
			( signal "@baseboard_fab2_lib.baseboard_fab2(sch_1):p3e_cpu1_pe3_mp_rxn(1)"
				( attribute "CDS_PHYS_NET_NAME" "P3E_CPU1_PE3_MP_RXN<1>"
					( Origin gPackager )
				)
				( attribute "PNN" "P3E_CPU1_PE3_MP_RXN<1>"
					( Origin gPackager )
				)
				( objectStatus "P3E_CPU1_PE3_MP_RXN<1>" )
			)
			( signal "@baseboard_fab2_lib.baseboard_fab2(sch_1):p3e_cpu1_pe3_mp_rxn(2)"
				( attribute "CDS_PHYS_NET_NAME" "P3E_CPU1_PE3_MP_RXN<2>"
					( Origin gPackager )
				)
				( attribute "PNN" "P3E_CPU1_PE3_MP_RXN<2>"
					( Origin gPackager )
				)
				( objectStatus "P3E_CPU1_PE3_MP_RXN<2>" )
			)
			( signal "@baseboard_fab2_lib.baseboard_fab2(sch_1):p3e_cpu1_pe3_mp_rxn(3)"
				( attribute "CDS_PHYS_NET_NAME" "P3E_CPU1_PE3_MP_RXN<3>"
					( Origin gPackager )
				)
				( attribute "PNN" "P3E_CPU1_PE3_MP_RXN<3>"
					( Origin gPackager )
				)
				( objectStatus "P3E_CPU1_PE3_MP_RXN<3>" )
			)
			( signal "@baseboard_fab2_lib.baseboard_fab2(sch_1):p3e_cpu1_pe3_mp_rxn(4)"
				( attribute "CDS_PHYS_NET_NAME" "P3E_CPU1_PE3_MP_RXN<4>"
					( Origin gPackager )
				)
				( attribute "PNN" "P3E_CPU1_PE3_MP_RXN<4>"
					( Origin gPackager )
				)
				( objectStatus "P3E_CPU1_PE3_MP_RXN<4>" )
			)
			( signal "@baseboard_fab2_lib.baseboard_fab2(sch_1):p3e_cpu1_pe3_mp_rxn(5)"
				( attribute "CDS_PHYS_NET_NAME" "P3E_CPU1_PE3_MP_RXN<5>"
					( Origin gPackager )
				)
				( attribute "PNN" "P3E_CPU1_PE3_MP_RXN<5>"
					( Origin gPackager )
				)
				( objectStatus "P3E_CPU1_PE3_MP_RXN<5>" )
			)
			( signal "@baseboard_fab2_lib.baseboard_fab2(sch_1):p3e_cpu1_pe3_mp_rxn(6)"
				( attribute "CDS_PHYS_NET_NAME" "P3E_CPU1_PE3_MP_RXN<6>"
					( Origin gPackager )
				)
				( attribute "PNN" "P3E_CPU1_PE3_MP_RXN<6>"
					( Origin gPackager )
				)
				( objectStatus "P3E_CPU1_PE3_MP_RXN<6>" )
			)
			( signal "@baseboard_fab2_lib.baseboard_fab2(sch_1):p3e_cpu1_pe3_mp_rxn(7)"
				( attribute "CDS_PHYS_NET_NAME" "P3E_CPU1_PE3_MP_RXN<7>"
					( Origin gPackager )
				)
				( attribute "PNN" "P3E_CPU1_PE3_MP_RXN<7>"
					( Origin gPackager )
				)
				( objectStatus "P3E_CPU1_PE3_MP_RXN<7>" )
			)
			( signal "@baseboard_fab2_lib.baseboard_fab2(sch_1):p3e_cpu1_pe3_mp_rxn(8)"
				( attribute "CDS_PHYS_NET_NAME" "P3E_CPU1_PE3_MP_RXN<8>"
					( Origin gPackager )
				)
				( attribute "PNN" "P3E_CPU1_PE3_MP_RXN<8>"
					( Origin gPackager )
				)
				( objectStatus "P3E_CPU1_PE3_MP_RXN<8>" )
			)
			( signal "@baseboard_fab2_lib.baseboard_fab2(sch_1):p3e_cpu1_pe3_mp_rxn(9)"
				( attribute "CDS_PHYS_NET_NAME" "P3E_CPU1_PE3_MP_RXN<9>"
					( Origin gPackager )
				)
				( attribute "PNN" "P3E_CPU1_PE3_MP_RXN<9>"
					( Origin gPackager )
				)
				( objectStatus "P3E_CPU1_PE3_MP_RXN<9>" )
			)
			( signal "@baseboard_fab2_lib.baseboard_fab2(sch_1):p3e_cpu1_pe3_mp_rxn(10)"
				( attribute "CDS_PHYS_NET_NAME" "P3E_CPU1_PE3_MP_RXN<10>"
					( Origin gPackager )
				)
				( attribute "PNN" "P3E_CPU1_PE3_MP_RXN<10>"
					( Origin gPackager )
				)
				( objectStatus "P3E_CPU1_PE3_MP_RXN<10>" )
			)
			( signal "@baseboard_fab2_lib.baseboard_fab2(sch_1):p3e_cpu1_pe3_mp_rxn(11)"
				( attribute "CDS_PHYS_NET_NAME" "P3E_CPU1_PE3_MP_RXN<11>"
					( Origin gPackager )
				)
				( attribute "PNN" "P3E_CPU1_PE3_MP_RXN<11>"
					( Origin gPackager )
				)
				( objectStatus "P3E_CPU1_PE3_MP_RXN<11>" )
			)
			( signal "@baseboard_fab2_lib.baseboard_fab2(sch_1):p3e_cpu1_pe3_mp_rxn(12)"
				( attribute "CDS_PHYS_NET_NAME" "P3E_CPU1_PE3_MP_RXN<12>"
					( Origin gPackager )
				)
				( attribute "PNN" "P3E_CPU1_PE3_MP_RXN<12>"
					( Origin gPackager )
				)
				( objectStatus "P3E_CPU1_PE3_MP_RXN<12>" )
			)
			( signal "@baseboard_fab2_lib.baseboard_fab2(sch_1):p3e_cpu1_pe3_mp_rxn(13)"
				( attribute "CDS_PHYS_NET_NAME" "P3E_CPU1_PE3_MP_RXN<13>"
					( Origin gPackager )
				)
				( attribute "PNN" "P3E_CPU1_PE3_MP_RXN<13>"
					( Origin gPackager )
				)
				( objectStatus "P3E_CPU1_PE3_MP_RXN<13>" )
			)
			( signal "@baseboard_fab2_lib.baseboard_fab2(sch_1):p3e_cpu1_pe3_mp_rxn(14)"
				( attribute "CDS_PHYS_NET_NAME" "P3E_CPU1_PE3_MP_RXN<14>"
					( Origin gPackager )
				)
				( attribute "PNN" "P3E_CPU1_PE3_MP_RXN<14>"
					( Origin gPackager )
				)
				( objectStatus "P3E_CPU1_PE3_MP_RXN<14>" )
			)
			( signal "@baseboard_fab2_lib.baseboard_fab2(sch_1):p3e_cpu1_pe3_mp_rxn(15)"
				( attribute "CDS_PHYS_NET_NAME" "P3E_CPU1_PE3_MP_RXN<15>"
					( Origin gPackager )
				)
				( attribute "PNN" "P3E_CPU1_PE3_MP_RXN<15>"
					( Origin gPackager )
				)
				( objectStatus "P3E_CPU1_PE3_MP_RXN<15>" )
			)
			( signal "@baseboard_fab2_lib.baseboard_fab2(sch_1):p3e_cpu1_pe3_mp_rxp(0)"
				( attribute "CDS_PHYS_NET_NAME" "P3E_CPU1_PE3_MP_RXP<0>"
					( Origin gPackager )
				)
				( attribute "PNN" "P3E_CPU1_PE3_MP_RXP<0>"
					( Origin gPackager )
				)
				( objectStatus "P3E_CPU1_PE3_MP_RXP<0>" )
			)
			( signal "@baseboard_fab2_lib.baseboard_fab2(sch_1):p3e_cpu1_pe3_mp_rxp(1)"
				( attribute "CDS_PHYS_NET_NAME" "P3E_CPU1_PE3_MP_RXP<1>"
					( Origin gPackager )
				)
				( attribute "PNN" "P3E_CPU1_PE3_MP_RXP<1>"
					( Origin gPackager )
				)
				( objectStatus "P3E_CPU1_PE3_MP_RXP<1>" )
			)
			( signal "@baseboard_fab2_lib.baseboard_fab2(sch_1):p3e_cpu1_pe3_mp_rxp(2)"
				( attribute "CDS_PHYS_NET_NAME" "P3E_CPU1_PE3_MP_RXP<2>"
					( Origin gPackager )
				)
				( attribute "PNN" "P3E_CPU1_PE3_MP_RXP<2>"
					( Origin gPackager )
				)
				( objectStatus "P3E_CPU1_PE3_MP_RXP<2>" )
			)
			( signal "@baseboard_fab2_lib.baseboard_fab2(sch_1):p3e_cpu1_pe3_mp_rxp(3)"
				( attribute "CDS_PHYS_NET_NAME" "P3E_CPU1_PE3_MP_RXP<3>"
					( Origin gPackager )
				)
				( attribute "PNN" "P3E_CPU1_PE3_MP_RXP<3>"
					( Origin gPackager )
				)
				( objectStatus "P3E_CPU1_PE3_MP_RXP<3>" )
			)
			( signal "@baseboard_fab2_lib.baseboard_fab2(sch_1):p3e_cpu1_pe3_mp_rxp(4)"
				( attribute "CDS_PHYS_NET_NAME" "P3E_CPU1_PE3_MP_RXP<4>"
					( Origin gPackager )
				)
				( attribute "PNN" "P3E_CPU1_PE3_MP_RXP<4>"
					( Origin gPackager )
				)
				( objectStatus "P3E_CPU1_PE3_MP_RXP<4>" )
			)
			( signal "@baseboard_fab2_lib.baseboard_fab2(sch_1):p3e_cpu1_pe3_mp_rxp(5)"
				( attribute "CDS_PHYS_NET_NAME" "P3E_CPU1_PE3_MP_RXP<5>"
					( Origin gPackager )
				)
				( attribute "PNN" "P3E_CPU1_PE3_MP_RXP<5>"
					( Origin gPackager )
				)
				( objectStatus "P3E_CPU1_PE3_MP_RXP<5>" )
			)
			( signal "@baseboard_fab2_lib.baseboard_fab2(sch_1):p3e_cpu1_pe3_mp_rxp(6)"
				( attribute "CDS_PHYS_NET_NAME" "P3E_CPU1_PE3_MP_RXP<6>"
					( Origin gPackager )
				)
				( attribute "PNN" "P3E_CPU1_PE3_MP_RXP<6>"
					( Origin gPackager )
				)
				( objectStatus "P3E_CPU1_PE3_MP_RXP<6>" )
			)
			( signal "@baseboard_fab2_lib.baseboard_fab2(sch_1):p3e_cpu1_pe3_mp_rxp(7)"
				( attribute "CDS_PHYS_NET_NAME" "P3E_CPU1_PE3_MP_RXP<7>"
					( Origin gPackager )
				)
				( attribute "PNN" "P3E_CPU1_PE3_MP_RXP<7>"
					( Origin gPackager )
				)
				( objectStatus "P3E_CPU1_PE3_MP_RXP<7>" )
			)
			( signal "@baseboard_fab2_lib.baseboard_fab2(sch_1):p3e_cpu1_pe3_mp_rxp(8)"
				( attribute "CDS_PHYS_NET_NAME" "P3E_CPU1_PE3_MP_RXP<8>"
					( Origin gPackager )
				)
				( attribute "PNN" "P3E_CPU1_PE3_MP_RXP<8>"
					( Origin gPackager )
				)
				( objectStatus "P3E_CPU1_PE3_MP_RXP<8>" )
			)
			( signal "@baseboard_fab2_lib.baseboard_fab2(sch_1):p3e_cpu1_pe3_mp_rxp(9)"
				( attribute "CDS_PHYS_NET_NAME" "P3E_CPU1_PE3_MP_RXP<9>"
					( Origin gPackager )
				)
				( attribute "PNN" "P3E_CPU1_PE3_MP_RXP<9>"
					( Origin gPackager )
				)
				( objectStatus "P3E_CPU1_PE3_MP_RXP<9>" )
			)
			( signal "@baseboard_fab2_lib.baseboard_fab2(sch_1):p3e_cpu1_pe3_mp_rxp(10)"
				( attribute "CDS_PHYS_NET_NAME" "P3E_CPU1_PE3_MP_RXP<10>"
					( Origin gPackager )
				)
				( attribute "PNN" "P3E_CPU1_PE3_MP_RXP<10>"
					( Origin gPackager )
				)
				( objectStatus "P3E_CPU1_PE3_MP_RXP<10>" )
			)
			( signal "@baseboard_fab2_lib.baseboard_fab2(sch_1):p3e_cpu1_pe3_mp_rxp(11)"
				( attribute "CDS_PHYS_NET_NAME" "P3E_CPU1_PE3_MP_RXP<11>"
					( Origin gPackager )
				)
				( attribute "PNN" "P3E_CPU1_PE3_MP_RXP<11>"
					( Origin gPackager )
				)
				( objectStatus "P3E_CPU1_PE3_MP_RXP<11>" )
			)
			( signal "@baseboard_fab2_lib.baseboard_fab2(sch_1):p3e_cpu1_pe3_mp_rxp(12)"
				( attribute "CDS_PHYS_NET_NAME" "P3E_CPU1_PE3_MP_RXP<12>"
					( Origin gPackager )
				)
				( attribute "PNN" "P3E_CPU1_PE3_MP_RXP<12>"
					( Origin gPackager )
				)
				( objectStatus "P3E_CPU1_PE3_MP_RXP<12>" )
			)
			( signal "@baseboard_fab2_lib.baseboard_fab2(sch_1):p3e_cpu1_pe3_mp_rxp(13)"
				( attribute "CDS_PHYS_NET_NAME" "P3E_CPU1_PE3_MP_RXP<13>"
					( Origin gPackager )
				)
				( attribute "PNN" "P3E_CPU1_PE3_MP_RXP<13>"
					( Origin gPackager )
				)
				( objectStatus "P3E_CPU1_PE3_MP_RXP<13>" )
			)
			( signal "@baseboard_fab2_lib.baseboard_fab2(sch_1):p3e_cpu1_pe3_mp_rxp(14)"
				( attribute "CDS_PHYS_NET_NAME" "P3E_CPU1_PE3_MP_RXP<14>"
					( Origin gPackager )
				)
				( attribute "PNN" "P3E_CPU1_PE3_MP_RXP<14>"
					( Origin gPackager )
				)
				( objectStatus "P3E_CPU1_PE3_MP_RXP<14>" )
			)
			( signal "@baseboard_fab2_lib.baseboard_fab2(sch_1):p3e_cpu1_pe3_mp_rxp(15)"
				( attribute "CDS_PHYS_NET_NAME" "P3E_CPU1_PE3_MP_RXP<15>"
					( Origin gPackager )
				)
				( attribute "PNN" "P3E_CPU1_PE3_MP_RXP<15>"
					( Origin gPackager )
				)
				( objectStatus "P3E_CPU1_PE3_MP_RXP<15>" )
			)
			( signal "@baseboard_fab2_lib.baseboard_fab2(sch_1):p3e_cpu1_pe3_mp_txn(0)"
				( attribute "CDS_PHYS_NET_NAME" "P3E_CPU1_PE3_MP_TXN<0>"
					( Origin gPackager )
				)
				( attribute "PNN" "P3E_CPU1_PE3_MP_TXN<0>"
					( Origin gPackager )
				)
				( objectStatus "P3E_CPU1_PE3_MP_TXN<0>" )
			)
			( signal "@baseboard_fab2_lib.baseboard_fab2(sch_1):p3e_cpu1_pe3_mp_txn(1)"
				( attribute "CDS_PHYS_NET_NAME" "P3E_CPU1_PE3_MP_TXN<1>"
					( Origin gPackager )
				)
				( attribute "PNN" "P3E_CPU1_PE3_MP_TXN<1>"
					( Origin gPackager )
				)
				( objectStatus "P3E_CPU1_PE3_MP_TXN<1>" )
			)
			( signal "@baseboard_fab2_lib.baseboard_fab2(sch_1):p3e_cpu1_pe3_mp_txn(2)"
				( attribute "CDS_PHYS_NET_NAME" "P3E_CPU1_PE3_MP_TXN<2>"
					( Origin gPackager )
				)
				( attribute "PNN" "P3E_CPU1_PE3_MP_TXN<2>"
					( Origin gPackager )
				)
				( objectStatus "P3E_CPU1_PE3_MP_TXN<2>" )
			)
			( signal "@baseboard_fab2_lib.baseboard_fab2(sch_1):p3e_cpu1_pe3_mp_txn(3)"
				( attribute "CDS_PHYS_NET_NAME" "P3E_CPU1_PE3_MP_TXN<3>"
					( Origin gPackager )
				)
				( attribute "PNN" "P3E_CPU1_PE3_MP_TXN<3>"
					( Origin gPackager )
				)
				( objectStatus "P3E_CPU1_PE3_MP_TXN<3>" )
			)
			( signal "@baseboard_fab2_lib.baseboard_fab2(sch_1):p3e_cpu1_pe3_mp_txn(4)"
				( attribute "CDS_PHYS_NET_NAME" "P3E_CPU1_PE3_MP_TXN<4>"
					( Origin gPackager )
				)
				( attribute "PNN" "P3E_CPU1_PE3_MP_TXN<4>"
					( Origin gPackager )
				)
				( objectStatus "P3E_CPU1_PE3_MP_TXN<4>" )
			)
			( signal "@baseboard_fab2_lib.baseboard_fab2(sch_1):p3e_cpu1_pe3_mp_txn(5)"
				( attribute "CDS_PHYS_NET_NAME" "P3E_CPU1_PE3_MP_TXN<5>"
					( Origin gPackager )
				)
				( attribute "PNN" "P3E_CPU1_PE3_MP_TXN<5>"
					( Origin gPackager )
				)
				( objectStatus "P3E_CPU1_PE3_MP_TXN<5>" )
			)
			( signal "@baseboard_fab2_lib.baseboard_fab2(sch_1):p3e_cpu1_pe3_mp_txn(6)"
				( attribute "CDS_PHYS_NET_NAME" "P3E_CPU1_PE3_MP_TXN<6>"
					( Origin gPackager )
				)
				( attribute "PNN" "P3E_CPU1_PE3_MP_TXN<6>"
					( Origin gPackager )
				)
				( objectStatus "P3E_CPU1_PE3_MP_TXN<6>" )
			)
			( signal "@baseboard_fab2_lib.baseboard_fab2(sch_1):p3e_cpu1_pe3_mp_txn(7)"
				( attribute "CDS_PHYS_NET_NAME" "P3E_CPU1_PE3_MP_TXN<7>"
					( Origin gPackager )
				)
				( attribute "PNN" "P3E_CPU1_PE3_MP_TXN<7>"
					( Origin gPackager )
				)
				( objectStatus "P3E_CPU1_PE3_MP_TXN<7>" )
			)
			( signal "@baseboard_fab2_lib.baseboard_fab2(sch_1):p3e_cpu1_pe3_mp_txn(8)"
				( attribute "CDS_PHYS_NET_NAME" "P3E_CPU1_PE3_MP_TXN<8>"
					( Origin gPackager )
				)
				( attribute "PNN" "P3E_CPU1_PE3_MP_TXN<8>"
					( Origin gPackager )
				)
				( objectStatus "P3E_CPU1_PE3_MP_TXN<8>" )
			)
			( signal "@baseboard_fab2_lib.baseboard_fab2(sch_1):p3e_cpu1_pe3_mp_txn(9)"
				( attribute "CDS_PHYS_NET_NAME" "P3E_CPU1_PE3_MP_TXN<9>"
					( Origin gPackager )
				)
				( attribute "PNN" "P3E_CPU1_PE3_MP_TXN<9>"
					( Origin gPackager )
				)
				( objectStatus "P3E_CPU1_PE3_MP_TXN<9>" )
			)
			( signal "@baseboard_fab2_lib.baseboard_fab2(sch_1):p3e_cpu1_pe3_mp_txn(10)"
				( attribute "CDS_PHYS_NET_NAME" "P3E_CPU1_PE3_MP_TXN<10>"
					( Origin gPackager )
				)
				( attribute "PNN" "P3E_CPU1_PE3_MP_TXN<10>"
					( Origin gPackager )
				)
				( objectStatus "P3E_CPU1_PE3_MP_TXN<10>" )
			)
			( signal "@baseboard_fab2_lib.baseboard_fab2(sch_1):p3e_cpu1_pe3_mp_txn(11)"
				( attribute "CDS_PHYS_NET_NAME" "P3E_CPU1_PE3_MP_TXN<11>"
					( Origin gPackager )
				)
				( attribute "PNN" "P3E_CPU1_PE3_MP_TXN<11>"
					( Origin gPackager )
				)
				( objectStatus "P3E_CPU1_PE3_MP_TXN<11>" )
			)
			( signal "@baseboard_fab2_lib.baseboard_fab2(sch_1):p3e_cpu1_pe3_mp_txn(12)"
				( attribute "CDS_PHYS_NET_NAME" "P3E_CPU1_PE3_MP_TXN<12>"
					( Origin gPackager )
				)
				( attribute "PNN" "P3E_CPU1_PE3_MP_TXN<12>"
					( Origin gPackager )
				)
				( objectStatus "P3E_CPU1_PE3_MP_TXN<12>" )
			)
			( signal "@baseboard_fab2_lib.baseboard_fab2(sch_1):p3e_cpu1_pe3_mp_txn(13)"
				( attribute "CDS_PHYS_NET_NAME" "P3E_CPU1_PE3_MP_TXN<13>"
					( Origin gPackager )
				)
				( attribute "PNN" "P3E_CPU1_PE3_MP_TXN<13>"
					( Origin gPackager )
				)
				( objectStatus "P3E_CPU1_PE3_MP_TXN<13>" )
			)
			( signal "@baseboard_fab2_lib.baseboard_fab2(sch_1):p3e_cpu1_pe3_mp_txn(14)"
				( attribute "CDS_PHYS_NET_NAME" "P3E_CPU1_PE3_MP_TXN<14>"
					( Origin gPackager )
				)
				( attribute "PNN" "P3E_CPU1_PE3_MP_TXN<14>"
					( Origin gPackager )
				)
				( objectStatus "P3E_CPU1_PE3_MP_TXN<14>" )
			)
			( signal "@baseboard_fab2_lib.baseboard_fab2(sch_1):p3e_cpu1_pe3_mp_txn(15)"
				( attribute "CDS_PHYS_NET_NAME" "P3E_CPU1_PE3_MP_TXN<15>"
					( Origin gPackager )
				)
				( attribute "PNN" "P3E_CPU1_PE3_MP_TXN<15>"
					( Origin gPackager )
				)
				( objectStatus "P3E_CPU1_PE3_MP_TXN<15>" )
			)
			( signal "@baseboard_fab2_lib.baseboard_fab2(sch_1):p3e_cpu1_pe3_mp_txp(0)"
				( attribute "CDS_PHYS_NET_NAME" "P3E_CPU1_PE3_MP_TXP<0>"
					( Origin gPackager )
				)
				( attribute "PNN" "P3E_CPU1_PE3_MP_TXP<0>"
					( Origin gPackager )
				)
				( objectStatus "P3E_CPU1_PE3_MP_TXP<0>" )
			)
			( signal "@baseboard_fab2_lib.baseboard_fab2(sch_1):p3e_cpu1_pe3_mp_txp(1)"
				( attribute "CDS_PHYS_NET_NAME" "P3E_CPU1_PE3_MP_TXP<1>"
					( Origin gPackager )
				)
				( attribute "PNN" "P3E_CPU1_PE3_MP_TXP<1>"
					( Origin gPackager )
				)
				( objectStatus "P3E_CPU1_PE3_MP_TXP<1>" )
			)
			( signal "@baseboard_fab2_lib.baseboard_fab2(sch_1):p3e_cpu1_pe3_mp_txp(2)"
				( attribute "CDS_PHYS_NET_NAME" "P3E_CPU1_PE3_MP_TXP<2>"
					( Origin gPackager )
				)
				( attribute "PNN" "P3E_CPU1_PE3_MP_TXP<2>"
					( Origin gPackager )
				)
				( objectStatus "P3E_CPU1_PE3_MP_TXP<2>" )
			)
			( signal "@baseboard_fab2_lib.baseboard_fab2(sch_1):p3e_cpu1_pe3_mp_txp(3)"
				( attribute "CDS_PHYS_NET_NAME" "P3E_CPU1_PE3_MP_TXP<3>"
					( Origin gPackager )
				)
				( attribute "PNN" "P3E_CPU1_PE3_MP_TXP<3>"
					( Origin gPackager )
				)
				( objectStatus "P3E_CPU1_PE3_MP_TXP<3>" )
			)
			( signal "@baseboard_fab2_lib.baseboard_fab2(sch_1):p3e_cpu1_pe3_mp_txp(4)"
				( attribute "CDS_PHYS_NET_NAME" "P3E_CPU1_PE3_MP_TXP<4>"
					( Origin gPackager )
				)
				( attribute "PNN" "P3E_CPU1_PE3_MP_TXP<4>"
					( Origin gPackager )
				)
				( objectStatus "P3E_CPU1_PE3_MP_TXP<4>" )
			)
			( signal "@baseboard_fab2_lib.baseboard_fab2(sch_1):p3e_cpu1_pe3_mp_txp(5)"
				( attribute "CDS_PHYS_NET_NAME" "P3E_CPU1_PE3_MP_TXP<5>"
					( Origin gPackager )
				)
				( attribute "PNN" "P3E_CPU1_PE3_MP_TXP<5>"
					( Origin gPackager )
				)
				( objectStatus "P3E_CPU1_PE3_MP_TXP<5>" )
			)
			( signal "@baseboard_fab2_lib.baseboard_fab2(sch_1):p3e_cpu1_pe3_mp_txp(6)"
				( attribute "CDS_PHYS_NET_NAME" "P3E_CPU1_PE3_MP_TXP<6>"
					( Origin gPackager )
				)
				( attribute "PNN" "P3E_CPU1_PE3_MP_TXP<6>"
					( Origin gPackager )
				)
				( objectStatus "P3E_CPU1_PE3_MP_TXP<6>" )
			)
			( signal "@baseboard_fab2_lib.baseboard_fab2(sch_1):p3e_cpu1_pe3_mp_txp(7)"
				( attribute "CDS_PHYS_NET_NAME" "P3E_CPU1_PE3_MP_TXP<7>"
					( Origin gPackager )
				)
				( attribute "PNN" "P3E_CPU1_PE3_MP_TXP<7>"
					( Origin gPackager )
				)
				( objectStatus "P3E_CPU1_PE3_MP_TXP<7>" )
			)
			( signal "@baseboard_fab2_lib.baseboard_fab2(sch_1):p3e_cpu1_pe3_mp_txp(8)"
				( attribute "CDS_PHYS_NET_NAME" "P3E_CPU1_PE3_MP_TXP<8>"
					( Origin gPackager )
				)
				( attribute "PNN" "P3E_CPU1_PE3_MP_TXP<8>"
					( Origin gPackager )
				)
				( objectStatus "P3E_CPU1_PE3_MP_TXP<8>" )
			)
			( signal "@baseboard_fab2_lib.baseboard_fab2(sch_1):p3e_cpu1_pe3_mp_txp(9)"
				( attribute "CDS_PHYS_NET_NAME" "P3E_CPU1_PE3_MP_TXP<9>"
					( Origin gPackager )
				)
				( attribute "PNN" "P3E_CPU1_PE3_MP_TXP<9>"
					( Origin gPackager )
				)
				( objectStatus "P3E_CPU1_PE3_MP_TXP<9>" )
			)
			( signal "@baseboard_fab2_lib.baseboard_fab2(sch_1):p3e_cpu1_pe3_mp_txp(10)"
				( attribute "CDS_PHYS_NET_NAME" "P3E_CPU1_PE3_MP_TXP<10>"
					( Origin gPackager )
				)
				( attribute "PNN" "P3E_CPU1_PE3_MP_TXP<10>"
					( Origin gPackager )
				)
				( objectStatus "P3E_CPU1_PE3_MP_TXP<10>" )
			)
			( signal "@baseboard_fab2_lib.baseboard_fab2(sch_1):p3e_cpu1_pe3_mp_txp(11)"
				( attribute "CDS_PHYS_NET_NAME" "P3E_CPU1_PE3_MP_TXP<11>"
					( Origin gPackager )
				)
				( attribute "PNN" "P3E_CPU1_PE3_MP_TXP<11>"
					( Origin gPackager )
				)
				( objectStatus "P3E_CPU1_PE3_MP_TXP<11>" )
			)
			( signal "@baseboard_fab2_lib.baseboard_fab2(sch_1):p3e_cpu1_pe3_mp_txp(12)"
				( attribute "CDS_PHYS_NET_NAME" "P3E_CPU1_PE3_MP_TXP<12>"
					( Origin gPackager )
				)
				( attribute "PNN" "P3E_CPU1_PE3_MP_TXP<12>"
					( Origin gPackager )
				)
				( objectStatus "P3E_CPU1_PE3_MP_TXP<12>" )
			)
			( signal "@baseboard_fab2_lib.baseboard_fab2(sch_1):p3e_cpu1_pe3_mp_txp(13)"
				( attribute "CDS_PHYS_NET_NAME" "P3E_CPU1_PE3_MP_TXP<13>"
					( Origin gPackager )
				)
				( attribute "PNN" "P3E_CPU1_PE3_MP_TXP<13>"
					( Origin gPackager )
				)
				( objectStatus "P3E_CPU1_PE3_MP_TXP<13>" )
			)
			( signal "@baseboard_fab2_lib.baseboard_fab2(sch_1):p3e_cpu1_pe3_mp_txp(14)"
				( attribute "CDS_PHYS_NET_NAME" "P3E_CPU1_PE3_MP_TXP<14>"
					( Origin gPackager )
				)
				( attribute "PNN" "P3E_CPU1_PE3_MP_TXP<14>"
					( Origin gPackager )
				)
				( objectStatus "P3E_CPU1_PE3_MP_TXP<14>" )
			)
			( signal "@baseboard_fab2_lib.baseboard_fab2(sch_1):p3e_cpu1_pe3_mp_txp(15)"
				( attribute "CDS_PHYS_NET_NAME" "P3E_CPU1_PE3_MP_TXP<15>"
					( Origin gPackager )
				)
				( attribute "PNN" "P3E_CPU1_PE3_MP_TXP<15>"
					( Origin gPackager )
				)
				( objectStatus "P3E_CPU1_PE3_MP_TXP<15>" )
			)
			( signal "@baseboard_fab2_lib.baseboard_fab2(sch_1):tp_cpu1_upi2_rsvd_ca12"
				( attribute "CDS_PHYS_NET_NAME" "TP_CPU1_UPI2_RSVD_CA12"
					( Origin gPackager )
				)
				( objectStatus "TP_CPU1_UPI2_RSVD_CA12" )
			)
			( signal "@baseboard_fab2_lib.baseboard_fab2(sch_1):tp_cpu1_upi2_rsvd_cb11"
				( attribute "CDS_PHYS_NET_NAME" "TP_CPU1_UPI2_RSVD_CB11"
					( Origin gPackager )
				)
				( objectStatus "TP_CPU1_UPI2_RSVD_CB11" )
			)
			( signal "@baseboard_fab2_lib.baseboard_fab2(sch_1):tp_cpu1_upi2_rsvd_cc10"
				( attribute "CDS_PHYS_NET_NAME" "TP_CPU1_UPI2_RSVD_CC10"
					( Origin gPackager )
				)
				( objectStatus "TP_CPU1_UPI2_RSVD_CC10" )
			)
			( signal "@baseboard_fab2_lib.baseboard_fab2(sch_1):tp_cpu1_upi2_rsvd_cc12"
				( attribute "CDS_PHYS_NET_NAME" "TP_CPU1_UPI2_RSVD_CC12"
					( Origin gPackager )
				)
				( objectStatus "TP_CPU1_UPI2_RSVD_CC12" )
			)
			( signal "@baseboard_fab2_lib.baseboard_fab2(sch_1):tp_cpu1_upi2_rsvd_cd11"
				( attribute "CDS_PHYS_NET_NAME" "TP_CPU1_UPI2_RSVD_CD11"
					( Origin gPackager )
				)
				( objectStatus "TP_CPU1_UPI2_RSVD_CD11" )
			)
			( signal "@baseboard_fab2_lib.baseboard_fab2(sch_1):tp_cpu1_upi2_rsvd_ce12"
				( attribute "CDS_PHYS_NET_NAME" "TP_CPU1_UPI2_RSVD_CE12"
					( Origin gPackager )
				)
				( objectStatus "TP_CPU1_UPI2_RSVD_CE12" )
			)
			( signal "@baseboard_fab2_lib.baseboard_fab2(sch_1):tp_cpu1_upi2_rsvd_cf11"
				( attribute "CDS_PHYS_NET_NAME" "TP_CPU1_UPI2_RSVD_CF11"
					( Origin gPackager )
				)
				( objectStatus "TP_CPU1_UPI2_RSVD_CF11" )
			)
			( signal "@baseboard_fab2_lib.baseboard_fab2(sch_1):tp_cpu1_upi2_rsvd_cf13"
				( attribute "CDS_PHYS_NET_NAME" "TP_CPU1_UPI2_RSVD_CF13"
					( Origin gPackager )
				)
				( objectStatus "TP_CPU1_UPI2_RSVD_CF13" )
			)
			( signal "@baseboard_fab2_lib.baseboard_fab2(sch_1):tp_cpu1_upi2_rsvd_cg12"
				( attribute "CDS_PHYS_NET_NAME" "TP_CPU1_UPI2_RSVD_CG12"
					( Origin gPackager )
				)
				( objectStatus "TP_CPU1_UPI2_RSVD_CG12" )
			)
			( signal "@baseboard_fab2_lib.baseboard_fab2(sch_1):tp_cpu1_upi2_rsvd_ch11"
				( attribute "CDS_PHYS_NET_NAME" "TP_CPU1_UPI2_RSVD_CH11"
					( Origin gPackager )
				)
				( objectStatus "TP_CPU1_UPI2_RSVD_CH11" )
			)
			( signal "@baseboard_fab2_lib.baseboard_fab2(sch_1):tp_cpu1_upi2_rsvd_ch13"
				( attribute "CDS_PHYS_NET_NAME" "TP_CPU1_UPI2_RSVD_CH13"
					( Origin gPackager )
				)
				( objectStatus "TP_CPU1_UPI2_RSVD_CH13" )
			)
			( signal "@baseboard_fab2_lib.baseboard_fab2(sch_1):tp_cpu1_upi2_rsvd_cj14"
				( attribute "CDS_PHYS_NET_NAME" "TP_CPU1_UPI2_RSVD_CJ14"
					( Origin gPackager )
				)
				( objectStatus "TP_CPU1_UPI2_RSVD_CJ14" )
			)
			( signal "@baseboard_fab2_lib.baseboard_fab2(sch_1):tp_cpu1_upi2_rsvd_ck13"
				( attribute "CDS_PHYS_NET_NAME" "TP_CPU1_UPI2_RSVD_CK13"
					( Origin gPackager )
				)
				( objectStatus "TP_CPU1_UPI2_RSVD_CK13" )
			)
			( signal "@baseboard_fab2_lib.baseboard_fab2(sch_1):tp_cpu1_upi2_rsvd_cm13"
				( attribute "CDS_PHYS_NET_NAME" "TP_CPU1_UPI2_RSVD_CM13"
					( Origin gPackager )
				)
				( objectStatus "TP_CPU1_UPI2_RSVD_CM13" )
			)
			( signal "@baseboard_fab2_lib.baseboard_fab2(sch_1):tp_cpu1_upi2_rsvd_cr14"
				( attribute "CDS_PHYS_NET_NAME" "TP_CPU1_UPI2_RSVD_CR14"
					( Origin gPackager )
				)
				( objectStatus "TP_CPU1_UPI2_RSVD_CR14" )
			)
			( signal "@baseboard_fab2_lib.baseboard_fab2(sch_1):tp_cpu1_upi2_rsvd_cu14"
				( attribute "CDS_PHYS_NET_NAME" "TP_CPU1_UPI2_RSVD_CU14"
					( Origin gPackager )
				)
				( objectStatus "TP_CPU1_UPI2_RSVD_CU14" )
			)
			( signal "@baseboard_fab2_lib.baseboard_fab2(sch_1):tp_cpu1_upi2_rsvd_cv13"
				( attribute "CDS_PHYS_NET_NAME" "TP_CPU1_UPI2_RSVD_CV13"
					( Origin gPackager )
				)
				( objectStatus "TP_CPU1_UPI2_RSVD_CV13" )
			)
			( signal "@baseboard_fab2_lib.baseboard_fab2(sch_1):tp_cpu1_upi2_rsvd_cw14"
				( attribute "CDS_PHYS_NET_NAME" "TP_CPU1_UPI2_RSVD_CW14"
					( Origin gPackager )
				)
				( objectStatus "TP_CPU1_UPI2_RSVD_CW14" )
			)
			( signal "@baseboard_fab2_lib.baseboard_fab2(sch_1):tp_cpu1_upi2_rsvd_cw16"
				( attribute "CDS_PHYS_NET_NAME" "TP_CPU1_UPI2_RSVD_CW16"
					( Origin gPackager )
				)
				( objectStatus "TP_CPU1_UPI2_RSVD_CW16" )
			)
			( signal "@baseboard_fab2_lib.baseboard_fab2(sch_1):tp_cpu1_upi2_rsvd_da16"
				( attribute "CDS_PHYS_NET_NAME" "TP_CPU1_UPI2_RSVD_DA16"
					( Origin gPackager )
				)
				( objectStatus "TP_CPU1_UPI2_RSVD_DA16" )
			)
			( signal "@baseboard_fab2_lib.baseboard_fab2(sch_1):tp_cpu1_upi2_rsvd_db15"
				( attribute "CDS_PHYS_NET_NAME" "TP_CPU1_UPI2_RSVD_DB15"
					( Origin gPackager )
				)
				( objectStatus "TP_CPU1_UPI2_RSVD_DB15" )
			)
			( signal "@baseboard_fab2_lib.baseboard_fab2(sch_1):tp_cpu1_upi2_rsvd_dc16"
				( attribute "CDS_PHYS_NET_NAME" "TP_CPU1_UPI2_RSVD_DC16"
					( Origin gPackager )
				)
				( objectStatus "TP_CPU1_UPI2_RSVD_DC16" )
			)
			( signal "@baseboard_fab2_lib.baseboard_fab2(sch_1):tp_cpu1_upi2_rsvd_dd15"
				( attribute "CDS_PHYS_NET_NAME" "TP_CPU1_UPI2_RSVD_DD15"
					( Origin gPackager )
				)
				( objectStatus "TP_CPU1_UPI2_RSVD_DD15" )
			)
			( signal "@baseboard_fab2_lib.baseboard_fab2(sch_1):tp_cpu1_upi2_rsvd_dd17"
				( attribute "CDS_PHYS_NET_NAME" "TP_CPU1_UPI2_RSVD_DD17"
					( Origin gPackager )
				)
				( objectStatus "TP_CPU1_UPI2_RSVD_DD17" )
			)
			( signal "@baseboard_fab2_lib.baseboard_fab2(sch_1):tp_cpu1_upi2_rsvd_de16"
				( attribute "CDS_PHYS_NET_NAME" "TP_CPU1_UPI2_RSVD_DE16"
					( Origin gPackager )
				)
				( objectStatus "TP_CPU1_UPI2_RSVD_DE16" )
			)
			( signal "@baseboard_fab2_lib.baseboard_fab2(sch_1):tp_cpu1_upi2_rsvd_df15"
				( attribute "CDS_PHYS_NET_NAME" "TP_CPU1_UPI2_RSVD_DF15"
					( Origin gPackager )
				)
				( objectStatus "TP_CPU1_UPI2_RSVD_DF15" )
			)
			( signal "@baseboard_fab2_lib.baseboard_fab2(sch_1):tp_cpu1_upi2_rsvd_df17"
				( attribute "CDS_PHYS_NET_NAME" "TP_CPU1_UPI2_RSVD_DF17"
					( Origin gPackager )
				)
				( objectStatus "TP_CPU1_UPI2_RSVD_DF17" )
			)
			( signal "@baseboard_fab2_lib.baseboard_fab2(sch_1):tp_cpu1_upi2_rsvd_dg18"
				( attribute "CDS_PHYS_NET_NAME" "TP_CPU1_UPI2_RSVD_DG18"
					( Origin gPackager )
				)
				( objectStatus "TP_CPU1_UPI2_RSVD_DG18" )
			)
			( signal "@baseboard_fab2_lib.baseboard_fab2(sch_1):tp_cpu1_upi2_rsvd_dg20"
				( attribute "CDS_PHYS_NET_NAME" "TP_CPU1_UPI2_RSVD_DG20"
					( Origin gPackager )
				)
				( objectStatus "TP_CPU1_UPI2_RSVD_DG20" )
			)
			( signal "@baseboard_fab2_lib.baseboard_fab2(sch_1):tp_cpu1_upi2_rsvd_dh17"
				( attribute "CDS_PHYS_NET_NAME" "TP_CPU1_UPI2_RSVD_DH17"
					( Origin gPackager )
				)
				( objectStatus "TP_CPU1_UPI2_RSVD_DH17" )
			)
			( signal "@baseboard_fab2_lib.baseboard_fab2(sch_1):tp_cpu1_upi2_rsvd_dh19"
				( attribute "CDS_PHYS_NET_NAME" "TP_CPU1_UPI2_RSVD_DH19"
					( Origin gPackager )
				)
				( objectStatus "TP_CPU1_UPI2_RSVD_DH19" )
			)
			( signal "@baseboard_fab2_lib.baseboard_fab2(sch_1):tp_cpu1_upi2_rsvd_dj18"
				( attribute "CDS_PHYS_NET_NAME" "TP_CPU1_UPI2_RSVD_DJ18"
					( Origin gPackager )
				)
				( objectStatus "TP_CPU1_UPI2_RSVD_DJ18" )
			)
			( signal "@baseboard_fab2_lib.baseboard_fab2(sch_1):tp_cpu1_upi2_rsvd_dj20"
				( attribute "CDS_PHYS_NET_NAME" "TP_CPU1_UPI2_RSVD_DJ20"
					( Origin gPackager )
				)
				( objectStatus "TP_CPU1_UPI2_RSVD_DJ20" )
			)
			( signal "@baseboard_fab2_lib.baseboard_fab2(sch_1):tp_cpu1_upi2_rsvd_dk17"
				( attribute "CDS_PHYS_NET_NAME" "TP_CPU1_UPI2_RSVD_DK17"
					( Origin gPackager )
				)
				( objectStatus "TP_CPU1_UPI2_RSVD_DK17" )
			)
			( signal "@baseboard_fab2_lib.baseboard_fab2(sch_1):tp_cpu1_upi2_rsvd_dk19"
				( attribute "CDS_PHYS_NET_NAME" "TP_CPU1_UPI2_RSVD_DK19"
					( Origin gPackager )
				)
				( objectStatus "TP_CPU1_UPI2_RSVD_DK19" )
			)
			( signal "@baseboard_fab2_lib.baseboard_fab2(sch_1):tp_cpu1_upi2_rsvd_dl20"
				( attribute "CDS_PHYS_NET_NAME" "TP_CPU1_UPI2_RSVD_DL20"
					( Origin gPackager )
				)
				( objectStatus "TP_CPU1_UPI2_RSVD_DL20" )
			)
			( signal "@baseboard_fab2_lib.baseboard_fab2(sch_1):tp_cpu1_upi2_rsvd_dm21"
				( attribute "CDS_PHYS_NET_NAME" "TP_CPU1_UPI2_RSVD_DM21"
					( Origin gPackager )
				)
				( objectStatus "TP_CPU1_UPI2_RSVD_DM21" )
			)
			( signal "@baseboard_fab2_lib.baseboard_fab2(sch_1):tp_cpu1_upi2_rsvd_dn20"
				( attribute "CDS_PHYS_NET_NAME" "TP_CPU1_UPI2_RSVD_DN20"
					( Origin gPackager )
				)
				( objectStatus "TP_CPU1_UPI2_RSVD_DN20" )
			)
			( signal "@baseboard_fab2_lib.baseboard_fab2(sch_1):tp_cpu1_upi2_rsvd_dp21"
				( attribute "CDS_PHYS_NET_NAME" "TP_CPU1_UPI2_RSVD_DP21"
					( Origin gPackager )
				)
				( objectStatus "TP_CPU1_UPI2_RSVD_DP21" )
			)
			( signal "@baseboard_fab2_lib.baseboard_fab2(sch_1):tp_cpu1_upi2_rsvd_dt21"
				( attribute "CDS_PHYS_NET_NAME" "TP_CPU1_UPI2_RSVD_DT21"
					( Origin gPackager )
				)
				( objectStatus "TP_CPU1_UPI2_RSVD_DT21" )
			)
			( signal "@baseboard_fab2_lib.baseboard_fab2(sch_1):clk_100m_cpu1_rc_refclk1_dn"
				( attribute "CDS_PHYS_NET_NAME" "CLK_100M_CPU1_RC_REFCLK1_DN"
					( Origin gPackager )
				)
				( objectStatus "CLK_100M_CPU1_RC_REFCLK1_DN" )
			)
			( signal "@baseboard_fab2_lib.baseboard_fab2(sch_1):clk_100m_cpu1_rc_refclk1_dp"
				( attribute "CDS_PHYS_NET_NAME" "CLK_100M_CPU1_RC_REFCLK1_DP"
					( Origin gPackager )
				)
				( objectStatus "CLK_100M_CPU1_RC_REFCLK1_DP" )
			)
			( signal "@baseboard_fab2_lib.baseboard_fab2(sch_1):tp_cpu1_rsvd_100"
				( attribute "CDS_PHYS_NET_NAME" "TP_CPU1_RSVD_100"
					( Origin gPackager )
				)
				( objectStatus "TP_CPU1_RSVD_100" )
			)
			( signal "@baseboard_fab2_lib.baseboard_fab2(sch_1):tp_cpu1_rsvd_101"
				( attribute "CDS_PHYS_NET_NAME" "TP_CPU1_RSVD_101"
					( Origin gPackager )
				)
				( objectStatus "TP_CPU1_RSVD_101" )
			)
			( signal "@baseboard_fab2_lib.baseboard_fab2(sch_1):tp_cpu1_rsvd_105"
				( attribute "CDS_PHYS_NET_NAME" "TP_CPU1_RSVD_105"
					( Origin gPackager )
				)
				( objectStatus "TP_CPU1_RSVD_105" )
			)
			( signal "@baseboard_fab2_lib.baseboard_fab2(sch_1):tp_cpu1_rsvd_106"
				( attribute "CDS_PHYS_NET_NAME" "TP_CPU1_RSVD_106"
					( Origin gPackager )
				)
				( objectStatus "TP_CPU1_RSVD_106" )
			)
			( signal "@baseboard_fab2_lib.baseboard_fab2(sch_1):tp_cpu1_rsvd_108"
				( attribute "CDS_PHYS_NET_NAME" "TP_CPU1_RSVD_108"
					( Origin gPackager )
				)
				( objectStatus "TP_CPU1_RSVD_108" )
			)
			( signal "@baseboard_fab2_lib.baseboard_fab2(sch_1):tp_cpu1_rsvd_111"
				( attribute "CDS_PHYS_NET_NAME" "TP_CPU1_RSVD_111"
					( Origin gPackager )
				)
				( objectStatus "TP_CPU1_RSVD_111" )
			)
			( signal "@baseboard_fab2_lib.baseboard_fab2(sch_1):tp_cpu1_rsvd_113"
				( attribute "CDS_PHYS_NET_NAME" "TP_CPU1_RSVD_113"
					( Origin gPackager )
				)
				( objectStatus "TP_CPU1_RSVD_113" )
			)
			( signal "@baseboard_fab2_lib.baseboard_fab2(sch_1):tp_cpu1_rsvd_114"
				( attribute "CDS_PHYS_NET_NAME" "TP_CPU1_RSVD_114"
					( Origin gPackager )
				)
				( objectStatus "TP_CPU1_RSVD_114" )
			)
			( signal "@baseboard_fab2_lib.baseboard_fab2(sch_1):tp_cpu1_rsvd_117"
				( attribute "CDS_PHYS_NET_NAME" "TP_CPU1_RSVD_117"
					( Origin gPackager )
				)
				( objectStatus "TP_CPU1_RSVD_117" )
			)
			( signal "@baseboard_fab2_lib.baseboard_fab2(sch_1):tp_cpu1_rsvd_119"
				( attribute "CDS_PHYS_NET_NAME" "TP_CPU1_RSVD_119"
					( Origin gPackager )
				)
				( objectStatus "TP_CPU1_RSVD_119" )
			)
			( signal "@baseboard_fab2_lib.baseboard_fab2(sch_1):tp_cpu1_rsvd_121"
				( attribute "CDS_PHYS_NET_NAME" "TP_CPU1_RSVD_121"
					( Origin gPackager )
				)
				( objectStatus "TP_CPU1_RSVD_121" )
			)
			( signal "@baseboard_fab2_lib.baseboard_fab2(sch_1):tp_cpu1_rsvd_123"
				( attribute "CDS_PHYS_NET_NAME" "TP_CPU1_RSVD_123"
					( Origin gPackager )
				)
				( objectStatus "TP_CPU1_RSVD_123" )
			)
			( signal "@baseboard_fab2_lib.baseboard_fab2(sch_1):tp_cpu1_rsvd_124"
				( attribute "CDS_PHYS_NET_NAME" "TP_CPU1_RSVD_124"
					( Origin gPackager )
				)
				( objectStatus "TP_CPU1_RSVD_124" )
			)
			( signal "@baseboard_fab2_lib.baseboard_fab2(sch_1):tp_cpu1_rsvd_144"
				( attribute "CDS_PHYS_NET_NAME" "TP_CPU1_RSVD_144"
					( Origin gPackager )
				)
				( objectStatus "TP_CPU1_RSVD_144" )
			)
			( signal "@baseboard_fab2_lib.baseboard_fab2(sch_1):tp_cpu1_rsvd_145"
				( attribute "CDS_PHYS_NET_NAME" "TP_CPU1_RSVD_145"
					( Origin gPackager )
				)
				( objectStatus "TP_CPU1_RSVD_145" )
			)
			( signal "@baseboard_fab2_lib.baseboard_fab2(sch_1):tp_cpu1_rsvd_146"
				( attribute "CDS_PHYS_NET_NAME" "TP_CPU1_RSVD_146"
					( Origin gPackager )
				)
				( objectStatus "TP_CPU1_RSVD_146" )
			)
			( signal "@baseboard_fab2_lib.baseboard_fab2(sch_1):tp_cpu1_rsvd_147"
				( attribute "CDS_PHYS_NET_NAME" "TP_CPU1_RSVD_147"
					( Origin gPackager )
				)
				( objectStatus "TP_CPU1_RSVD_147" )
			)
			( signal "@baseboard_fab2_lib.baseboard_fab2(sch_1):tp_cpu1_rsvd_148"
				( attribute "CDS_PHYS_NET_NAME" "TP_CPU1_RSVD_148"
					( Origin gPackager )
				)
				( objectStatus "TP_CPU1_RSVD_148" )
			)
			( signal "@baseboard_fab2_lib.baseboard_fab2(sch_1):tp_cpu1_rsvd_149"
				( attribute "CDS_PHYS_NET_NAME" "TP_CPU1_RSVD_149"
					( Origin gPackager )
				)
				( objectStatus "TP_CPU1_RSVD_149" )
			)
			( signal "@baseboard_fab2_lib.baseboard_fab2(sch_1):tp_cpu1_rsvd_150"
				( attribute "CDS_PHYS_NET_NAME" "TP_CPU1_RSVD_150"
					( Origin gPackager )
				)
				( objectStatus "TP_CPU1_RSVD_150" )
			)
			( signal "@baseboard_fab2_lib.baseboard_fab2(sch_1):tp_cpu1_rsvd_151"
				( attribute "CDS_PHYS_NET_NAME" "TP_CPU1_RSVD_151"
					( Origin gPackager )
				)
				( objectStatus "TP_CPU1_RSVD_151" )
			)
			( signal "@baseboard_fab2_lib.baseboard_fab2(sch_1):tp_cpu1_rsvd_152"
				( attribute "CDS_PHYS_NET_NAME" "TP_CPU1_RSVD_152"
					( Origin gPackager )
				)
				( objectStatus "TP_CPU1_RSVD_152" )
			)
			( signal "@baseboard_fab2_lib.baseboard_fab2(sch_1):tp_cpu1_rsvd_154"
				( attribute "CDS_PHYS_NET_NAME" "TP_CPU1_RSVD_154"
					( Origin gPackager )
				)
				( objectStatus "TP_CPU1_RSVD_154" )
			)
			( signal "@baseboard_fab2_lib.baseboard_fab2(sch_1):tp_cpu1_rsvd_155"
				( attribute "CDS_PHYS_NET_NAME" "TP_CPU1_RSVD_155"
					( Origin gPackager )
				)
				( objectStatus "TP_CPU1_RSVD_155" )
			)
			( signal "@baseboard_fab2_lib.baseboard_fab2(sch_1):tp_cpu1_rsvd_156"
				( attribute "CDS_PHYS_NET_NAME" "TP_CPU1_RSVD_156"
					( Origin gPackager )
				)
				( objectStatus "TP_CPU1_RSVD_156" )
			)
			( signal "@baseboard_fab2_lib.baseboard_fab2(sch_1):tp_cpu1_rsvd_157"
				( attribute "CDS_PHYS_NET_NAME" "TP_CPU1_RSVD_157"
					( Origin gPackager )
				)
				( objectStatus "TP_CPU1_RSVD_157" )
			)
			( signal "@baseboard_fab2_lib.baseboard_fab2(sch_1):tp_cpu1_rsvd_158"
				( attribute "CDS_PHYS_NET_NAME" "TP_CPU1_RSVD_158"
					( Origin gPackager )
				)
				( objectStatus "TP_CPU1_RSVD_158" )
			)
			( signal "@baseboard_fab2_lib.baseboard_fab2(sch_1):tp_cpu1_rsvd_159"
				( attribute "CDS_PHYS_NET_NAME" "TP_CPU1_RSVD_159"
					( Origin gPackager )
				)
				( objectStatus "TP_CPU1_RSVD_159" )
			)
			( signal "@baseboard_fab2_lib.baseboard_fab2(sch_1):tp_cpu1_rsvd_160"
				( attribute "CDS_PHYS_NET_NAME" "TP_CPU1_RSVD_160"
					( Origin gPackager )
				)
				( objectStatus "TP_CPU1_RSVD_160" )
			)
			( signal "@baseboard_fab2_lib.baseboard_fab2(sch_1):tp_cpu1_rsvd_161"
				( attribute "CDS_PHYS_NET_NAME" "TP_CPU1_RSVD_161"
					( Origin gPackager )
				)
				( objectStatus "TP_CPU1_RSVD_161" )
			)
			( signal "@baseboard_fab2_lib.baseboard_fab2(sch_1):tp_cpu1_rsvd_162"
				( attribute "CDS_PHYS_NET_NAME" "TP_CPU1_RSVD_162"
					( Origin gPackager )
				)
				( objectStatus "TP_CPU1_RSVD_162" )
			)
			( signal "@baseboard_fab2_lib.baseboard_fab2(sch_1):tp_cpu1_rsvd_163"
				( attribute "CDS_PHYS_NET_NAME" "TP_CPU1_RSVD_163"
					( Origin gPackager )
				)
				( objectStatus "TP_CPU1_RSVD_163" )
			)
			( signal "@baseboard_fab2_lib.baseboard_fab2(sch_1):tp_cpu1_rsvd_164"
				( attribute "CDS_PHYS_NET_NAME" "TP_CPU1_RSVD_164"
					( Origin gPackager )
				)
				( objectStatus "TP_CPU1_RSVD_164" )
			)
			( signal "@baseboard_fab2_lib.baseboard_fab2(sch_1):tp_cpu1_rsvd_166"
				( attribute "CDS_PHYS_NET_NAME" "TP_CPU1_RSVD_166"
					( Origin gPackager )
				)
				( objectStatus "TP_CPU1_RSVD_166" )
			)
			( signal "@baseboard_fab2_lib.baseboard_fab2(sch_1):tp_cpu1_rsvd_167"
				( attribute "CDS_PHYS_NET_NAME" "TP_CPU1_RSVD_167"
					( Origin gPackager )
				)
				( objectStatus "TP_CPU1_RSVD_167" )
			)
			( signal "@baseboard_fab2_lib.baseboard_fab2(sch_1):tp_cpu1_rsvd_168"
				( attribute "CDS_PHYS_NET_NAME" "TP_CPU1_RSVD_168"
					( Origin gPackager )
				)
				( objectStatus "TP_CPU1_RSVD_168" )
			)
			( signal "@baseboard_fab2_lib.baseboard_fab2(sch_1):tp_cpu1_rsvd_169"
				( attribute "CDS_PHYS_NET_NAME" "TP_CPU1_RSVD_169"
					( Origin gPackager )
				)
				( objectStatus "TP_CPU1_RSVD_169" )
			)
			( signal "@baseboard_fab2_lib.baseboard_fab2(sch_1):tp_cpu1_rsvd_170"
				( attribute "CDS_PHYS_NET_NAME" "TP_CPU1_RSVD_170"
					( Origin gPackager )
				)
				( objectStatus "TP_CPU1_RSVD_170" )
			)
			( signal "@baseboard_fab2_lib.baseboard_fab2(sch_1):tp_cpu1_rsvd_171"
				( attribute "CDS_PHYS_NET_NAME" "TP_CPU1_RSVD_171"
					( Origin gPackager )
				)
				( objectStatus "TP_CPU1_RSVD_171" )
			)
			( signal "@baseboard_fab2_lib.baseboard_fab2(sch_1):tp_cpu1_rsvd_255"
				( attribute "CDS_PHYS_NET_NAME" "TP_CPU1_RSVD_255"
					( Origin gPackager )
				)
				( objectStatus "TP_CPU1_RSVD_255" )
			)
			( signal "@baseboard_fab2_lib.baseboard_fab2(sch_1):tp_cpu1_rsvd_82"
				( attribute "CDS_PHYS_NET_NAME" "TP_CPU1_RSVD_82"
					( Origin gPackager )
				)
				( objectStatus "TP_CPU1_RSVD_82" )
			)
			( signal "@baseboard_fab2_lib.baseboard_fab2(sch_1):tp_cpu1_rsvd_85"
				( attribute "CDS_PHYS_NET_NAME" "TP_CPU1_RSVD_85"
					( Origin gPackager )
				)
				( objectStatus "TP_CPU1_RSVD_85" )
			)
			( signal "@baseboard_fab2_lib.baseboard_fab2(sch_1):tp_cpu1_rsvd_90"
				( attribute "CDS_PHYS_NET_NAME" "TP_CPU1_RSVD_90"
					( Origin gPackager )
				)
				( objectStatus "TP_CPU1_RSVD_90" )
			)
			( signal "@baseboard_fab2_lib.baseboard_fab2(sch_1):tp_cpu1_rsvd_91"
				( attribute "CDS_PHYS_NET_NAME" "TP_CPU1_RSVD_91"
					( Origin gPackager )
				)
				( objectStatus "TP_CPU1_RSVD_91" )
			)
			( signal "@baseboard_fab2_lib.baseboard_fab2(sch_1):tp_cpu1_rsvd_94"
				( attribute "CDS_PHYS_NET_NAME" "TP_CPU1_RSVD_94"
					( Origin gPackager )
				)
				( objectStatus "TP_CPU1_RSVD_94" )
			)
			( signal "@baseboard_fab2_lib.baseboard_fab2(sch_1):tp_cpu1_rsvd_95"
				( attribute "CDS_PHYS_NET_NAME" "TP_CPU1_RSVD_95"
					( Origin gPackager )
				)
				( objectStatus "TP_CPU1_RSVD_95" )
			)
			( signal "@baseboard_fab2_lib.baseboard_fab2(sch_1):tp_cpu1_rsvd_97"
				( attribute "CDS_PHYS_NET_NAME" "TP_CPU1_RSVD_97"
					( Origin gPackager )
				)
				( objectStatus "TP_CPU1_RSVD_97" )
			)
			( signal "@baseboard_fab2_lib.baseboard_fab2(sch_1):tp_cpu1_rsvd_99"
				( attribute "CDS_PHYS_NET_NAME" "TP_CPU1_RSVD_99"
					( Origin gPackager )
				)
				( objectStatus "TP_CPU1_RSVD_99" )
			)
			( signal "@baseboard_fab2_lib.baseboard_fab2(sch_1):tp_cpu1_test_10"
				( attribute "CDS_PHYS_NET_NAME" "TP_CPU1_TEST_10"
					( Origin gPackager )
				)
				( objectStatus "TP_CPU1_TEST_10" )
			)
			( signal "@baseboard_fab2_lib.baseboard_fab2(sch_1):tp_cpu1_test_6"
				( attribute "CDS_PHYS_NET_NAME" "TP_CPU1_TEST_6"
					( Origin gPackager )
				)
				( objectStatus "TP_CPU1_TEST_6" )
			)
			( signal "@baseboard_fab2_lib.baseboard_fab2(sch_1):tp_cpu1_test_7"
				( attribute "CDS_PHYS_NET_NAME" "TP_CPU1_TEST_7"
					( Origin gPackager )
				)
				( objectStatus "TP_CPU1_TEST_7" )
			)
			( signal "@baseboard_fab2_lib.baseboard_fab2(sch_1):tp_cpu1_test_8"
				( attribute "CDS_PHYS_NET_NAME" "TP_CPU1_TEST_8"
					( Origin gPackager )
				)
				( objectStatus "TP_CPU1_TEST_8" )
			)
			( signal "@baseboard_fab2_lib.baseboard_fab2(sch_1):tp_cpu1_test_9"
				( attribute "CDS_PHYS_NET_NAME" "TP_CPU1_TEST_9"
					( Origin gPackager )
				)
				( objectStatus "TP_CPU1_TEST_9" )
			)
			( signal "@baseboard_fab2_lib.baseboard_fab2(sch_1):pvccin_cpu1"
				( alias ( signalRef "@baseboard_fab2_lib.baseboard_fab2(sch_1):page71_pvccin_cpu1") )
				( alias ( signalRef "@baseboard_fab2_lib.baseboard_fab2(sch_1):page76_pvccin_cpu1") )
				( alias ( signalRef "@baseboard_fab2_lib.baseboard_fab2(sch_1):page207_pvccin_cpu1") )
				( alias ( signalRef "@baseboard_fab2_lib.baseboard_fab2(sch_1):page208_pvccin_cpu1") )
				( alias ( signalRef "@baseboard_fab2_lib.baseboard_fab2(sch_1):page209_pvccin_cpu1") )
				( attribute "VOLTAGE" "2.0V"
					( Units "uVoltage" "V" 1.000000)
					( Status sAliasFlattened )
					( Origin gFrontEnd )
				)
				( attribute "CDS_PHYS_NET_NAME" "PVCCIN_CPU1"
					( Origin gPackager )
				)
				( objectStatus "PVCCIN_CPU1" )
			)
			( signal "@baseboard_fab2_lib.baseboard_fab2(sch_1):page71_pvccin_cpu1"
				( attribute "VOLTAGE" "2.0V"
					( Units "uVoltage" "V" 1.000000)
					( Origin gFrontEnd )
				)
				( objectFlag fObjectAlias )
				( objectStatus "page71_pvccin_cpu1" )
			)
			( signal "@baseboard_fab2_lib.baseboard_fab2(sch_1):page76_pvccin_cpu1"
				( attribute "VOLTAGE" "2.0V"
					( Units "uVoltage" "V" 1.000000)
					( Origin gFrontEnd )
				)
				( objectFlag fObjectAlias )
				( objectStatus "page76_pvccin_cpu1" )
			)
			( signal "@baseboard_fab2_lib.baseboard_fab2(sch_1):page207_pvccin_cpu1"
				( attribute "VOLTAGE" "2.0V"
					( Units "uVoltage" "V" 1.000000)
					( Origin gFrontEnd )
				)
				( objectFlag fObjectAlias )
				( objectStatus "page207_pvccin_cpu1" )
			)
			( signal "@baseboard_fab2_lib.baseboard_fab2(sch_1):page208_pvccin_cpu1"
				( attribute "VOLTAGE" "2.0V"
					( Units "uVoltage" "V" 1.000000)
					( Origin gFrontEnd )
				)
				( objectFlag fObjectAlias )
				( objectStatus "page208_pvccin_cpu1" )
			)
			( signal "@baseboard_fab2_lib.baseboard_fab2(sch_1):page209_pvccin_cpu1"
				( attribute "VOLTAGE" "2.0V"
					( Units "uVoltage" "V" 1.000000)
					( Origin gFrontEnd )
				)
				( objectFlag fObjectAlias )
				( objectStatus "page209_pvccin_cpu1" )
			)
			( signal "@baseboard_fab2_lib.baseboard_fab2(sch_1):vsense_pmax_cpu1"
				( attribute "CDS_PHYS_NET_NAME" "VSENSE_PMAX_CPU1"
					( Origin gPackager )
				)
				( objectStatus "VSENSE_PMAX_CPU1" )
			)
			( signal "@baseboard_fab2_lib.baseboard_fab2(sch_1):vsense_pvccin_cpu1_skt_vrtn"
				( attribute "CDS_PHYS_NET_NAME" "VSENSE_PVCCIN_CPU1_SKT_VRTN"
					( Origin gPackager )
				)
				( objectStatus "VSENSE_PVCCIN_CPU1_SKT_VRTN" )
			)
			( signal "@baseboard_fab2_lib.baseboard_fab2(sch_1):vsense_pvccin_cpu1_skt_vsen"
				( attribute "CDS_PHYS_NET_NAME" "VSENSE_PVCCIN_CPU1_SKT_VSEN"
					( Origin gPackager )
				)
				( objectStatus "VSENSE_PVCCIN_CPU1_SKT_VSEN" )
			)
			( signal "@baseboard_fab2_lib.baseboard_fab2(sch_1):vsense_vccinr2pmax_cpu1"
				( attribute "CDS_PHYS_NET_NAME" "VSENSE_VCCINR2PMAX_CPU1"
					( Origin gPackager )
				)
				( objectStatus "VSENSE_VCCINR2PMAX_CPU1" )
			)
			( signal "@baseboard_fab2_lib.baseboard_fab2(sch_1):pvcciomcp_cpu1"
				( alias ( signalRef "@baseboard_fab2_lib.baseboard_fab2(sch_1):page72_pvcciomcp_cpu1") )
				( alias ( signalRef "@baseboard_fab2_lib.baseboard_fab2(sch_1):page193_pvcciomcp_cpu1") )
				( alias ( signalRef "@baseboard_fab2_lib.baseboard_fab2(sch_1):page70_pvcciomcp_cpu1") )
				( attribute "CDS_PHYS_NET_NAME" "PVCCIOMCP_CPU1"
					( Origin gPackager )
				)
				( attribute "VOLTAGE" "+0.95V"
					( Units "uVoltage" "V" 1.000000)
					( Status sAliasFlattened )
					( Status sAliasConflict )
					( Origin gFrontEnd )
				)
				( objectStatus "PVCCIOMCP_CPU1" )
			)
			( signal "@baseboard_fab2_lib.baseboard_fab2(sch_1):page72_pvcciomcp_cpu1"
				( attribute "VOLTAGE" "+0.95V"
					( Units "uVoltage" "V" 1.000000)
					( Origin gFrontEnd )
				)
				( objectFlag fObjectAlias )
				( objectStatus "page72_pvcciomcp_cpu1" )
			)
			( signal "@baseboard_fab2_lib.baseboard_fab2(sch_1):page193_pvcciomcp_cpu1"
				( attribute "VOLTAGE" "+0.95"
					( Units "uVoltage" "V" 1.000000)
					( Origin gFrontEnd )
				)
				( objectFlag fObjectAlias )
				( objectStatus "page193_pvcciomcp_cpu1" )
			)
			( signal "@baseboard_fab2_lib.baseboard_fab2(sch_1):page70_pvcciomcp_cpu1"
				( attribute "VOLTAGE" "+0.95V"
					( Units "uVoltage" "V" 1.000000)
					( Origin gFrontEnd )
				)
				( objectFlag fObjectAlias )
				( objectStatus "page70_pvcciomcp_cpu1" )
			)
			( signal "@baseboard_fab2_lib.baseboard_fab2(sch_1):pvddq_ghj"
				( alias ( signalRef "@baseboard_fab2_lib.baseboard_fab2(sch_1):page72_pvddq_ghj") )
				( alias ( signalRef "@baseboard_fab2_lib.baseboard_fab2(sch_1):page77_pvddq_ghj") )
				( alias ( signalRef "@baseboard_fab2_lib.baseboard_fab2(sch_1):page78_pvddq_ghj") )
				( alias ( signalRef "@baseboard_fab2_lib.baseboard_fab2(sch_1):page79_pvddq_ghj") )
				( alias ( signalRef "@baseboard_fab2_lib.baseboard_fab2(sch_1):page80_pvddq_ghj") )
				( alias ( signalRef "@baseboard_fab2_lib.baseboard_fab2(sch_1):page81_pvddq_ghj") )
				( alias ( signalRef "@baseboard_fab2_lib.baseboard_fab2(sch_1):page82_pvddq_ghj") )
				( alias ( signalRef "@baseboard_fab2_lib.baseboard_fab2(sch_1):page96_pvddq_ghj") )
				( alias ( signalRef "@baseboard_fab2_lib.baseboard_fab2(sch_1):page100_pvddq_ghj") )
				( alias ( signalRef "@baseboard_fab2_lib.baseboard_fab2(sch_1):page224_pvddq_ghj") )
				( alias ( signalRef "@baseboard_fab2_lib.baseboard_fab2(sch_1):page225_pvddq_ghj") )
				( alias ( signalRef "@baseboard_fab2_lib.baseboard_fab2(sch_1):page229_pvddq_ghj") )
				( alias ( signalRef "@baseboard_fab2_lib.baseboard_fab2(sch_1):page243_pvddq_ghj") )
				( attribute "CDS_PHYS_NET_NAME" "PVDDQ_GHJ"
					( Origin gPackager )
				)
				( attribute "VOLTAGE" "1.2V"
					( Units "uVoltage" "V" 1.000000)
					( Status sAliasFlattened )
					( Origin gFrontEnd )
				)
				( objectStatus "PVDDQ_GHJ" )
			)
			( signal "@baseboard_fab2_lib.baseboard_fab2(sch_1):page72_pvddq_ghj"
				( attribute "VOLTAGE" "1.2V"
					( Units "uVoltage" "V" 1.000000)
					( Origin gFrontEnd )
				)
				( objectFlag fObjectAlias )
				( objectStatus "page72_pvddq_ghj" )
			)
			( signal "@baseboard_fab2_lib.baseboard_fab2(sch_1):page77_pvddq_ghj"
				( attribute "VOLTAGE" "1.2V"
					( Units "uVoltage" "V" 1.000000)
					( Origin gFrontEnd )
				)
				( objectFlag fObjectAlias )
				( objectStatus "page77_pvddq_ghj" )
			)
			( signal "@baseboard_fab2_lib.baseboard_fab2(sch_1):page78_pvddq_ghj"
				( attribute "VOLTAGE" "1.2V"
					( Units "uVoltage" "V" 1.000000)
					( Origin gFrontEnd )
				)
				( objectFlag fObjectAlias )
				( objectStatus "page78_pvddq_ghj" )
			)
			( signal "@baseboard_fab2_lib.baseboard_fab2(sch_1):page79_pvddq_ghj"
				( attribute "VOLTAGE" "1.2V"
					( Units "uVoltage" "V" 1.000000)
					( Origin gFrontEnd )
				)
				( objectFlag fObjectAlias )
				( objectStatus "page79_pvddq_ghj" )
			)
			( signal "@baseboard_fab2_lib.baseboard_fab2(sch_1):page80_pvddq_ghj"
				( attribute "VOLTAGE" "1.2V"
					( Units "uVoltage" "V" 1.000000)
					( Origin gFrontEnd )
				)
				( objectFlag fObjectAlias )
				( objectStatus "page80_pvddq_ghj" )
			)
			( signal "@baseboard_fab2_lib.baseboard_fab2(sch_1):page81_pvddq_ghj"
				( attribute "VOLTAGE" "1.2V"
					( Units "uVoltage" "V" 1.000000)
					( Origin gFrontEnd )
				)
				( objectFlag fObjectAlias )
				( objectStatus "page81_pvddq_ghj" )
			)
			( signal "@baseboard_fab2_lib.baseboard_fab2(sch_1):page82_pvddq_ghj"
				( attribute "VOLTAGE" "1.2V"
					( Units "uVoltage" "V" 1.000000)
					( Origin gFrontEnd )
				)
				( objectFlag fObjectAlias )
				( objectStatus "page82_pvddq_ghj" )
			)
			( signal "@baseboard_fab2_lib.baseboard_fab2(sch_1):page96_pvddq_ghj"
				( attribute "VOLTAGE" "1.2V"
					( Units "uVoltage" "V" 1.000000)
					( Origin gFrontEnd )
				)
				( objectFlag fObjectAlias )
				( objectStatus "page96_pvddq_ghj" )
			)
			( signal "@baseboard_fab2_lib.baseboard_fab2(sch_1):page100_pvddq_ghj"
				( attribute "VOLTAGE" "1.2V"
					( Units "uVoltage" "V" 1.000000)
					( Origin gFrontEnd )
				)
				( objectFlag fObjectAlias )
				( objectStatus "page100_pvddq_ghj" )
			)
			( signal "@baseboard_fab2_lib.baseboard_fab2(sch_1):page224_pvddq_ghj"
				( attribute "VOLTAGE" "1.2V"
					( Units "uVoltage" "V" 1.000000)
					( Origin gFrontEnd )
				)
				( objectFlag fObjectAlias )
				( objectStatus "page224_pvddq_ghj" )
			)
			( signal "@baseboard_fab2_lib.baseboard_fab2(sch_1):page225_pvddq_ghj"
				( attribute "VOLTAGE" "1.2V"
					( Units "uVoltage" "V" 1.000000)
					( Origin gFrontEnd )
				)
				( objectFlag fObjectAlias )
				( objectStatus "page225_pvddq_ghj" )
			)
			( signal "@baseboard_fab2_lib.baseboard_fab2(sch_1):page229_pvddq_ghj"
				( attribute "VOLTAGE" "1.2V"
					( Units "uVoltage" "V" 1.000000)
					( Origin gFrontEnd )
				)
				( objectFlag fObjectAlias )
				( objectStatus "page229_pvddq_ghj" )
			)
			( signal "@baseboard_fab2_lib.baseboard_fab2(sch_1):page243_pvddq_ghj"
				( attribute "VOLTAGE" "1.2V"
					( Units "uVoltage" "V" 1.000000)
					( Origin gFrontEnd )
				)
				( objectFlag fObjectAlias )
				( objectStatus "page243_pvddq_ghj" )
			)
			( signal "@baseboard_fab2_lib.baseboard_fab2(sch_1):pvddq_klm"
				( alias ( signalRef "@baseboard_fab2_lib.baseboard_fab2(sch_1):page72_pvddq_klm") )
				( alias ( signalRef "@baseboard_fab2_lib.baseboard_fab2(sch_1):page83_pvddq_klm") )
				( alias ( signalRef "@baseboard_fab2_lib.baseboard_fab2(sch_1):page84_pvddq_klm") )
				( alias ( signalRef "@baseboard_fab2_lib.baseboard_fab2(sch_1):page85_pvddq_klm") )
				( alias ( signalRef "@baseboard_fab2_lib.baseboard_fab2(sch_1):page86_pvddq_klm") )
				( alias ( signalRef "@baseboard_fab2_lib.baseboard_fab2(sch_1):page87_pvddq_klm") )
				( alias ( signalRef "@baseboard_fab2_lib.baseboard_fab2(sch_1):page88_pvddq_klm") )
				( alias ( signalRef "@baseboard_fab2_lib.baseboard_fab2(sch_1):page96_pvddq_klm") )
				( alias ( signalRef "@baseboard_fab2_lib.baseboard_fab2(sch_1):page100_pvddq_klm") )
				( alias ( signalRef "@baseboard_fab2_lib.baseboard_fab2(sch_1):page227_pvddq_klm") )
				( alias ( signalRef "@baseboard_fab2_lib.baseboard_fab2(sch_1):page228_pvddq_klm") )
				( alias ( signalRef "@baseboard_fab2_lib.baseboard_fab2(sch_1):page230_pvddq_klm") )
				( alias ( signalRef "@baseboard_fab2_lib.baseboard_fab2(sch_1):page243_pvddq_klm") )
				( attribute "CDS_PHYS_NET_NAME" "PVDDQ_KLM"
					( Origin gPackager )
				)
				( attribute "VOLTAGE" "1.2V"
					( Units "uVoltage" "V" 1.000000)
					( Status sAliasFlattened )
					( Origin gFrontEnd )
				)
				( objectStatus "PVDDQ_KLM" )
			)
			( signal "@baseboard_fab2_lib.baseboard_fab2(sch_1):page72_pvddq_klm"
				( attribute "VOLTAGE" "1.2V"
					( Units "uVoltage" "V" 1.000000)
					( Origin gFrontEnd )
				)
				( objectFlag fObjectAlias )
				( objectStatus "page72_pvddq_klm" )
			)
			( signal "@baseboard_fab2_lib.baseboard_fab2(sch_1):page83_pvddq_klm"
				( attribute "VOLTAGE" "1.2V"
					( Units "uVoltage" "V" 1.000000)
					( Origin gFrontEnd )
				)
				( objectFlag fObjectAlias )
				( objectStatus "page83_pvddq_klm" )
			)
			( signal "@baseboard_fab2_lib.baseboard_fab2(sch_1):page84_pvddq_klm"
				( attribute "VOLTAGE" "1.2V"
					( Units "uVoltage" "V" 1.000000)
					( Origin gFrontEnd )
				)
				( objectFlag fObjectAlias )
				( objectStatus "page84_pvddq_klm" )
			)
			( signal "@baseboard_fab2_lib.baseboard_fab2(sch_1):page85_pvddq_klm"
				( attribute "VOLTAGE" "1.2V"
					( Units "uVoltage" "V" 1.000000)
					( Origin gFrontEnd )
				)
				( objectFlag fObjectAlias )
				( objectStatus "page85_pvddq_klm" )
			)
			( signal "@baseboard_fab2_lib.baseboard_fab2(sch_1):page86_pvddq_klm"
				( attribute "VOLTAGE" "1.2V"
					( Units "uVoltage" "V" 1.000000)
					( Origin gFrontEnd )
				)
				( objectFlag fObjectAlias )
				( objectStatus "page86_pvddq_klm" )
			)
			( signal "@baseboard_fab2_lib.baseboard_fab2(sch_1):page87_pvddq_klm"
				( attribute "VOLTAGE" "1.2V"
					( Units "uVoltage" "V" 1.000000)
					( Origin gFrontEnd )
				)
				( objectFlag fObjectAlias )
				( objectStatus "page87_pvddq_klm" )
			)
			( signal "@baseboard_fab2_lib.baseboard_fab2(sch_1):page88_pvddq_klm"
				( attribute "VOLTAGE" "1.2V"
					( Units "uVoltage" "V" 1.000000)
					( Origin gFrontEnd )
				)
				( objectFlag fObjectAlias )
				( objectStatus "page88_pvddq_klm" )
			)
			( signal "@baseboard_fab2_lib.baseboard_fab2(sch_1):page96_pvddq_klm"
				( attribute "VOLTAGE" "1.2V"
					( Units "uVoltage" "V" 1.000000)
					( Origin gFrontEnd )
				)
				( objectFlag fObjectAlias )
				( objectStatus "page96_pvddq_klm" )
			)
			( signal "@baseboard_fab2_lib.baseboard_fab2(sch_1):page100_pvddq_klm"
				( attribute "VOLTAGE" "1.2V"
					( Units "uVoltage" "V" 1.000000)
					( Origin gFrontEnd )
				)
				( objectFlag fObjectAlias )
				( objectStatus "page100_pvddq_klm" )
			)
			( signal "@baseboard_fab2_lib.baseboard_fab2(sch_1):page227_pvddq_klm"
				( attribute "VOLTAGE" "1.2V"
					( Units "uVoltage" "V" 1.000000)
					( Origin gFrontEnd )
				)
				( objectFlag fObjectAlias )
				( objectStatus "page227_pvddq_klm" )
			)
			( signal "@baseboard_fab2_lib.baseboard_fab2(sch_1):page228_pvddq_klm"
				( attribute "VOLTAGE" "1.2V"
					( Units "uVoltage" "V" 1.000000)
					( Origin gFrontEnd )
				)
				( objectFlag fObjectAlias )
				( objectStatus "page228_pvddq_klm" )
			)
			( signal "@baseboard_fab2_lib.baseboard_fab2(sch_1):page230_pvddq_klm"
				( attribute "VOLTAGE" "1.2V"
					( Units "uVoltage" "V" 1.000000)
					( Origin gFrontEnd )
				)
				( objectFlag fObjectAlias )
				( objectStatus "page230_pvddq_klm" )
			)
			( signal "@baseboard_fab2_lib.baseboard_fab2(sch_1):page243_pvddq_klm"
				( attribute "VOLTAGE" "1.2V"
					( Units "uVoltage" "V" 1.000000)
					( Origin gFrontEnd )
				)
				( objectFlag fObjectAlias )
				( objectStatus "page243_pvddq_klm" )
			)
			( signal "@baseboard_fab2_lib.baseboard_fab2(sch_1):peci_sel"
				( attribute "CDS_PHYS_NET_NAME" "PECI_SEL"
					( Origin gPackager )
				)
				( objectStatus "PECI_SEL" )
			)
			( signal "@baseboard_fab2_lib.baseboard_fab2(sch_1):pvpp_ghj"
				( alias ( signalRef "@baseboard_fab2_lib.baseboard_fab2(sch_1):page72_pvpp_ghj") )
				( alias ( signalRef "@baseboard_fab2_lib.baseboard_fab2(sch_1):page77_pvpp_ghj") )
				( alias ( signalRef "@baseboard_fab2_lib.baseboard_fab2(sch_1):page78_pvpp_ghj") )
				( alias ( signalRef "@baseboard_fab2_lib.baseboard_fab2(sch_1):page79_pvpp_ghj") )
				( alias ( signalRef "@baseboard_fab2_lib.baseboard_fab2(sch_1):page80_pvpp_ghj") )
				( alias ( signalRef "@baseboard_fab2_lib.baseboard_fab2(sch_1):page81_pvpp_ghj") )
				( alias ( signalRef "@baseboard_fab2_lib.baseboard_fab2(sch_1):page82_pvpp_ghj") )
				( alias ( signalRef "@baseboard_fab2_lib.baseboard_fab2(sch_1):page99_pvpp_ghj") )
				( alias ( signalRef "@baseboard_fab2_lib.baseboard_fab2(sch_1):page233_pvpp_ghj") )
				( attribute "VOLTAGE" "2.5V"
					( Units "uVoltage" "V" 1.000000)
					( Status sAliasFlattened )
					( Origin gFrontEnd )
				)
				( attribute "CDS_PHYS_NET_NAME" "PVPP_GHJ"
					( Origin gPackager )
				)
				( objectStatus "PVPP_GHJ" )
			)
			( signal "@baseboard_fab2_lib.baseboard_fab2(sch_1):page72_pvpp_ghj"
				( attribute "VOLTAGE" "2.5V"
					( Units "uVoltage" "V" 1.000000)
					( Origin gFrontEnd )
				)
				( objectFlag fObjectAlias )
				( objectStatus "page72_pvpp_ghj" )
			)
			( signal "@baseboard_fab2_lib.baseboard_fab2(sch_1):page77_pvpp_ghj"
				( attribute "VOLTAGE" "2.5V"
					( Units "uVoltage" "V" 1.000000)
					( Origin gFrontEnd )
				)
				( objectFlag fObjectAlias )
				( objectStatus "page77_pvpp_ghj" )
			)
			( signal "@baseboard_fab2_lib.baseboard_fab2(sch_1):page78_pvpp_ghj"
				( attribute "VOLTAGE" "2.5V"
					( Units "uVoltage" "V" 1.000000)
					( Origin gFrontEnd )
				)
				( objectFlag fObjectAlias )
				( objectStatus "page78_pvpp_ghj" )
			)
			( signal "@baseboard_fab2_lib.baseboard_fab2(sch_1):page79_pvpp_ghj"
				( attribute "VOLTAGE" "2.5V"
					( Units "uVoltage" "V" 1.000000)
					( Origin gFrontEnd )
				)
				( objectFlag fObjectAlias )
				( objectStatus "page79_pvpp_ghj" )
			)
			( signal "@baseboard_fab2_lib.baseboard_fab2(sch_1):page80_pvpp_ghj"
				( attribute "VOLTAGE" "2.5V"
					( Units "uVoltage" "V" 1.000000)
					( Origin gFrontEnd )
				)
				( objectFlag fObjectAlias )
				( objectStatus "page80_pvpp_ghj" )
			)
			( signal "@baseboard_fab2_lib.baseboard_fab2(sch_1):page81_pvpp_ghj"
				( attribute "VOLTAGE" "2.5V"
					( Units "uVoltage" "V" 1.000000)
					( Origin gFrontEnd )
				)
				( objectFlag fObjectAlias )
				( objectStatus "page81_pvpp_ghj" )
			)
			( signal "@baseboard_fab2_lib.baseboard_fab2(sch_1):page82_pvpp_ghj"
				( attribute "VOLTAGE" "2.5V"
					( Units "uVoltage" "V" 1.000000)
					( Origin gFrontEnd )
				)
				( objectFlag fObjectAlias )
				( objectStatus "page82_pvpp_ghj" )
			)
			( signal "@baseboard_fab2_lib.baseboard_fab2(sch_1):page99_pvpp_ghj"
				( attribute "VOLTAGE" "2.5V"
					( Units "uVoltage" "V" 1.000000)
					( Origin gFrontEnd )
				)
				( objectFlag fObjectAlias )
				( objectStatus "page99_pvpp_ghj" )
			)
			( signal "@baseboard_fab2_lib.baseboard_fab2(sch_1):page233_pvpp_ghj"
				( attribute "VOLTAGE" "2.5V"
					( Units "uVoltage" "V" 1.000000)
					( Origin gFrontEnd )
				)
				( objectFlag fObjectAlias )
				( objectStatus "page233_pvpp_ghj" )
			)
			( signal "@baseboard_fab2_lib.baseboard_fab2(sch_1):pvsa_cpu1"
				( alias ( signalRef "@baseboard_fab2_lib.baseboard_fab2(sch_1):page72_pvsa_cpu1") )
				( alias ( signalRef "@baseboard_fab2_lib.baseboard_fab2(sch_1):page76_pvsa_cpu1") )
				( alias ( signalRef "@baseboard_fab2_lib.baseboard_fab2(sch_1):page210_pvsa_cpu1") )
				( attribute "VOLTAGE" "1.1V"
					( Units "uVoltage" "V" 1.000000)
					( Status sAliasFlattened )
					( Origin gFrontEnd )
				)
				( attribute "CDS_PHYS_NET_NAME" "PVSA_CPU1"
					( Origin gPackager )
				)
				( objectStatus "PVSA_CPU1" )
			)
			( signal "@baseboard_fab2_lib.baseboard_fab2(sch_1):page72_pvsa_cpu1"
				( attribute "VOLTAGE" "1.1V"
					( Units "uVoltage" "V" 1.000000)
					( Origin gFrontEnd )
				)
				( objectFlag fObjectAlias )
				( objectStatus "page72_pvsa_cpu1" )
			)
			( signal "@baseboard_fab2_lib.baseboard_fab2(sch_1):page76_pvsa_cpu1"
				( attribute "VOLTAGE" "1.1V"
					( Units "uVoltage" "V" 1.000000)
					( Origin gFrontEnd )
				)
				( objectFlag fObjectAlias )
				( objectStatus "page76_pvsa_cpu1" )
			)
			( signal "@baseboard_fab2_lib.baseboard_fab2(sch_1):page210_pvsa_cpu1"
				( attribute "VOLTAGE" "1.1V"
					( Units "uVoltage" "V" 1.000000)
					( Origin gFrontEnd )
				)
				( objectFlag fObjectAlias )
				( objectStatus "page210_pvsa_cpu1" )
			)
			( signal "@baseboard_fab2_lib.baseboard_fab2(sch_1):pd_cpu1_mcp01_dmon"
				( attribute "CDS_PHYS_NET_NAME" "PD_CPU1_MCP01_DMON"
					( Origin gPackager )
				)
				( objectStatus "PD_CPU1_MCP01_DMON" )
			)
			( signal "@baseboard_fab2_lib.baseboard_fab2(sch_1):tp_cpu1_kti2_amonv"
				( attribute "CDS_PHYS_NET_NAME" "TP_CPU1_KTI2_AMONV"
					( Origin gPackager )
				)
				( objectStatus "TP_CPU1_KTI2_AMONV" )
			)
			( signal "@baseboard_fab2_lib.baseboard_fab2(sch_1):tp_cpu1_kti2_dfx_dn"
				( attribute "CDS_PHYS_NET_NAME" "TP_CPU1_KTI2_DFX_DN"
					( Origin gPackager )
				)
				( objectStatus "TP_CPU1_KTI2_DFX_DN" )
			)
			( signal "@baseboard_fab2_lib.baseboard_fab2(sch_1):tp_cpu1_rsvd_0"
				( attribute "CDS_PHYS_NET_NAME" "TP_CPU1_RSVD_0"
					( Origin gPackager )
				)
				( objectStatus "TP_CPU1_RSVD_0" )
			)
			( signal "@baseboard_fab2_lib.baseboard_fab2(sch_1):tp_cpu1_rsvd_1"
				( attribute "CDS_PHYS_NET_NAME" "TP_CPU1_RSVD_1"
					( Origin gPackager )
				)
				( objectStatus "TP_CPU1_RSVD_1" )
			)
			( signal "@baseboard_fab2_lib.baseboard_fab2(sch_1):tp_cpu1_rsvd_10"
				( attribute "CDS_PHYS_NET_NAME" "TP_CPU1_RSVD_10"
					( Origin gPackager )
				)
				( objectStatus "TP_CPU1_RSVD_10" )
			)
			( signal "@baseboard_fab2_lib.baseboard_fab2(sch_1):tp_cpu1_rsvd_11"
				( attribute "CDS_PHYS_NET_NAME" "TP_CPU1_RSVD_11"
					( Origin gPackager )
				)
				( objectStatus "TP_CPU1_RSVD_11" )
			)
			( signal "@baseboard_fab2_lib.baseboard_fab2(sch_1):tp_cpu1_rsvd_12"
				( attribute "CDS_PHYS_NET_NAME" "TP_CPU1_RSVD_12"
					( Origin gPackager )
				)
				( objectStatus "TP_CPU1_RSVD_12" )
			)
			( signal "@baseboard_fab2_lib.baseboard_fab2(sch_1):tp_cpu1_rsvd_13"
				( attribute "CDS_PHYS_NET_NAME" "TP_CPU1_RSVD_13"
					( Origin gPackager )
				)
				( objectStatus "TP_CPU1_RSVD_13" )
			)
			( signal "@baseboard_fab2_lib.baseboard_fab2(sch_1):tp_cpu1_rsvd_14"
				( attribute "CDS_PHYS_NET_NAME" "TP_CPU1_RSVD_14"
					( Origin gPackager )
				)
				( objectStatus "TP_CPU1_RSVD_14" )
			)
			( signal "@baseboard_fab2_lib.baseboard_fab2(sch_1):tp_cpu1_rsvd_15"
				( attribute "CDS_PHYS_NET_NAME" "TP_CPU1_RSVD_15"
					( Origin gPackager )
				)
				( objectStatus "TP_CPU1_RSVD_15" )
			)
			( signal "@baseboard_fab2_lib.baseboard_fab2(sch_1):tp_cpu1_rsvd_16"
				( attribute "CDS_PHYS_NET_NAME" "TP_CPU1_RSVD_16"
					( Origin gPackager )
				)
				( objectStatus "TP_CPU1_RSVD_16" )
			)
			( signal "@baseboard_fab2_lib.baseboard_fab2(sch_1):tp_cpu1_rsvd_17"
				( attribute "CDS_PHYS_NET_NAME" "TP_CPU1_RSVD_17"
					( Origin gPackager )
				)
				( objectStatus "TP_CPU1_RSVD_17" )
			)
			( signal "@baseboard_fab2_lib.baseboard_fab2(sch_1):tp_cpu1_rsvd_18"
				( attribute "CDS_PHYS_NET_NAME" "TP_CPU1_RSVD_18"
					( Origin gPackager )
				)
				( objectStatus "TP_CPU1_RSVD_18" )
			)
			( signal "@baseboard_fab2_lib.baseboard_fab2(sch_1):tp_cpu1_rsvd_19"
				( attribute "CDS_PHYS_NET_NAME" "TP_CPU1_RSVD_19"
					( Origin gPackager )
				)
				( objectStatus "TP_CPU1_RSVD_19" )
			)
			( signal "@baseboard_fab2_lib.baseboard_fab2(sch_1):tp_cpu1_rsvd_2"
				( attribute "CDS_PHYS_NET_NAME" "TP_CPU1_RSVD_2"
					( Origin gPackager )
				)
				( objectStatus "TP_CPU1_RSVD_2" )
			)
			( signal "@baseboard_fab2_lib.baseboard_fab2(sch_1):tp_cpu1_rsvd_20"
				( attribute "CDS_PHYS_NET_NAME" "TP_CPU1_RSVD_20"
					( Origin gPackager )
				)
				( objectStatus "TP_CPU1_RSVD_20" )
			)
			( signal "@baseboard_fab2_lib.baseboard_fab2(sch_1):tp_cpu1_rsvd_21"
				( attribute "CDS_PHYS_NET_NAME" "TP_CPU1_RSVD_21"
					( Origin gPackager )
				)
				( objectStatus "TP_CPU1_RSVD_21" )
			)
			( signal "@baseboard_fab2_lib.baseboard_fab2(sch_1):tp_cpu1_rsvd_22"
				( attribute "CDS_PHYS_NET_NAME" "TP_CPU1_RSVD_22"
					( Origin gPackager )
				)
				( objectStatus "TP_CPU1_RSVD_22" )
			)
			( signal "@baseboard_fab2_lib.baseboard_fab2(sch_1):tp_cpu1_rsvd_23"
				( attribute "CDS_PHYS_NET_NAME" "TP_CPU1_RSVD_23"
					( Origin gPackager )
				)
				( objectStatus "TP_CPU1_RSVD_23" )
			)
			( signal "@baseboard_fab2_lib.baseboard_fab2(sch_1):tp_cpu1_rsvd_24"
				( attribute "CDS_PHYS_NET_NAME" "TP_CPU1_RSVD_24"
					( Origin gPackager )
				)
				( objectStatus "TP_CPU1_RSVD_24" )
			)
			( signal "@baseboard_fab2_lib.baseboard_fab2(sch_1):tp_cpu1_rsvd_25"
				( attribute "CDS_PHYS_NET_NAME" "TP_CPU1_RSVD_25"
					( Origin gPackager )
				)
				( objectStatus "TP_CPU1_RSVD_25" )
			)
			( signal "@baseboard_fab2_lib.baseboard_fab2(sch_1):tp_cpu1_rsvd_26"
				( attribute "CDS_PHYS_NET_NAME" "TP_CPU1_RSVD_26"
					( Origin gPackager )
				)
				( objectStatus "TP_CPU1_RSVD_26" )
			)
			( signal "@baseboard_fab2_lib.baseboard_fab2(sch_1):tp_cpu1_rsvd_27"
				( attribute "CDS_PHYS_NET_NAME" "TP_CPU1_RSVD_27"
					( Origin gPackager )
				)
				( objectStatus "TP_CPU1_RSVD_27" )
			)
			( signal "@baseboard_fab2_lib.baseboard_fab2(sch_1):tp_cpu1_rsvd_28"
				( attribute "CDS_PHYS_NET_NAME" "TP_CPU1_RSVD_28"
					( Origin gPackager )
				)
				( objectStatus "TP_CPU1_RSVD_28" )
			)
			( signal "@baseboard_fab2_lib.baseboard_fab2(sch_1):tp_cpu1_rsvd_29"
				( attribute "CDS_PHYS_NET_NAME" "TP_CPU1_RSVD_29"
					( Origin gPackager )
				)
				( objectStatus "TP_CPU1_RSVD_29" )
			)
			( signal "@baseboard_fab2_lib.baseboard_fab2(sch_1):tp_cpu1_rsvd_3"
				( attribute "CDS_PHYS_NET_NAME" "TP_CPU1_RSVD_3"
					( Origin gPackager )
				)
				( objectStatus "TP_CPU1_RSVD_3" )
			)
			( signal "@baseboard_fab2_lib.baseboard_fab2(sch_1):tp_cpu1_rsvd_30"
				( attribute "CDS_PHYS_NET_NAME" "TP_CPU1_RSVD_30"
					( Origin gPackager )
				)
				( objectStatus "TP_CPU1_RSVD_30" )
			)
			( signal "@baseboard_fab2_lib.baseboard_fab2(sch_1):tp_cpu1_rsvd_31"
				( attribute "CDS_PHYS_NET_NAME" "TP_CPU1_RSVD_31"
					( Origin gPackager )
				)
				( objectStatus "TP_CPU1_RSVD_31" )
			)
			( signal "@baseboard_fab2_lib.baseboard_fab2(sch_1):tp_cpu1_rsvd_32"
				( attribute "CDS_PHYS_NET_NAME" "TP_CPU1_RSVD_32"
					( Origin gPackager )
				)
				( objectStatus "TP_CPU1_RSVD_32" )
			)
			( signal "@baseboard_fab2_lib.baseboard_fab2(sch_1):tp_cpu1_rsvd_33"
				( attribute "CDS_PHYS_NET_NAME" "TP_CPU1_RSVD_33"
					( Origin gPackager )
				)
				( objectStatus "TP_CPU1_RSVD_33" )
			)
			( signal "@baseboard_fab2_lib.baseboard_fab2(sch_1):tp_cpu1_rsvd_34"
				( attribute "CDS_PHYS_NET_NAME" "TP_CPU1_RSVD_34"
					( Origin gPackager )
				)
				( objectStatus "TP_CPU1_RSVD_34" )
			)
			( signal "@baseboard_fab2_lib.baseboard_fab2(sch_1):tp_cpu1_rsvd_35"
				( attribute "CDS_PHYS_NET_NAME" "TP_CPU1_RSVD_35"
					( Origin gPackager )
				)
				( objectStatus "TP_CPU1_RSVD_35" )
			)
			( signal "@baseboard_fab2_lib.baseboard_fab2(sch_1):tp_cpu1_rsvd_36"
				( attribute "CDS_PHYS_NET_NAME" "TP_CPU1_RSVD_36"
					( Origin gPackager )
				)
				( objectStatus "TP_CPU1_RSVD_36" )
			)
			( signal "@baseboard_fab2_lib.baseboard_fab2(sch_1):tp_cpu1_rsvd_37"
				( attribute "CDS_PHYS_NET_NAME" "TP_CPU1_RSVD_37"
					( Origin gPackager )
				)
				( objectStatus "TP_CPU1_RSVD_37" )
			)
			( signal "@baseboard_fab2_lib.baseboard_fab2(sch_1):tp_cpu1_rsvd_38"
				( attribute "CDS_PHYS_NET_NAME" "TP_CPU1_RSVD_38"
					( Origin gPackager )
				)
				( objectStatus "TP_CPU1_RSVD_38" )
			)
			( signal "@baseboard_fab2_lib.baseboard_fab2(sch_1):tp_cpu1_rsvd_39"
				( attribute "CDS_PHYS_NET_NAME" "TP_CPU1_RSVD_39"
					( Origin gPackager )
				)
				( objectStatus "TP_CPU1_RSVD_39" )
			)
			( signal "@baseboard_fab2_lib.baseboard_fab2(sch_1):tp_cpu1_rsvd_4"
				( attribute "CDS_PHYS_NET_NAME" "TP_CPU1_RSVD_4"
					( Origin gPackager )
				)
				( objectStatus "TP_CPU1_RSVD_4" )
			)
			( signal "@baseboard_fab2_lib.baseboard_fab2(sch_1):tp_cpu1_rsvd_40"
				( attribute "CDS_PHYS_NET_NAME" "TP_CPU1_RSVD_40"
					( Origin gPackager )
				)
				( objectStatus "TP_CPU1_RSVD_40" )
			)
			( signal "@baseboard_fab2_lib.baseboard_fab2(sch_1):tp_cpu1_rsvd_41"
				( attribute "CDS_PHYS_NET_NAME" "TP_CPU1_RSVD_41"
					( Origin gPackager )
				)
				( objectStatus "TP_CPU1_RSVD_41" )
			)
			( signal "@baseboard_fab2_lib.baseboard_fab2(sch_1):tp_cpu1_rsvd_42"
				( attribute "CDS_PHYS_NET_NAME" "TP_CPU1_RSVD_42"
					( Origin gPackager )
				)
				( objectStatus "TP_CPU1_RSVD_42" )
			)
			( signal "@baseboard_fab2_lib.baseboard_fab2(sch_1):tp_cpu1_rsvd_43"
				( attribute "CDS_PHYS_NET_NAME" "TP_CPU1_RSVD_43"
					( Origin gPackager )
				)
				( objectStatus "TP_CPU1_RSVD_43" )
			)
			( signal "@baseboard_fab2_lib.baseboard_fab2(sch_1):tp_cpu1_rsvd_44"
				( attribute "CDS_PHYS_NET_NAME" "TP_CPU1_RSVD_44"
					( Origin gPackager )
				)
				( objectStatus "TP_CPU1_RSVD_44" )
			)
			( signal "@baseboard_fab2_lib.baseboard_fab2(sch_1):tp_cpu1_rsvd_45"
				( attribute "CDS_PHYS_NET_NAME" "TP_CPU1_RSVD_45"
					( Origin gPackager )
				)
				( objectStatus "TP_CPU1_RSVD_45" )
			)
			( signal "@baseboard_fab2_lib.baseboard_fab2(sch_1):tp_cpu1_rsvd_46"
				( attribute "CDS_PHYS_NET_NAME" "TP_CPU1_RSVD_46"
					( Origin gPackager )
				)
				( objectStatus "TP_CPU1_RSVD_46" )
			)
			( signal "@baseboard_fab2_lib.baseboard_fab2(sch_1):tp_cpu1_rsvd_47"
				( attribute "CDS_PHYS_NET_NAME" "TP_CPU1_RSVD_47"
					( Origin gPackager )
				)
				( objectStatus "TP_CPU1_RSVD_47" )
			)
			( signal "@baseboard_fab2_lib.baseboard_fab2(sch_1):tp_cpu1_rsvd_48"
				( attribute "CDS_PHYS_NET_NAME" "TP_CPU1_RSVD_48"
					( Origin gPackager )
				)
				( objectStatus "TP_CPU1_RSVD_48" )
			)
			( signal "@baseboard_fab2_lib.baseboard_fab2(sch_1):tp_cpu1_rsvd_49"
				( attribute "CDS_PHYS_NET_NAME" "TP_CPU1_RSVD_49"
					( Origin gPackager )
				)
				( objectStatus "TP_CPU1_RSVD_49" )
			)
			( signal "@baseboard_fab2_lib.baseboard_fab2(sch_1):tp_cpu1_rsvd_5"
				( attribute "CDS_PHYS_NET_NAME" "TP_CPU1_RSVD_5"
					( Origin gPackager )
				)
				( objectStatus "TP_CPU1_RSVD_5" )
			)
			( signal "@baseboard_fab2_lib.baseboard_fab2(sch_1):tp_cpu1_rsvd_50"
				( attribute "CDS_PHYS_NET_NAME" "TP_CPU1_RSVD_50"
					( Origin gPackager )
				)
				( objectStatus "TP_CPU1_RSVD_50" )
			)
			( signal "@baseboard_fab2_lib.baseboard_fab2(sch_1):tp_cpu1_rsvd_51"
				( attribute "CDS_PHYS_NET_NAME" "TP_CPU1_RSVD_51"
					( Origin gPackager )
				)
				( objectStatus "TP_CPU1_RSVD_51" )
			)
			( signal "@baseboard_fab2_lib.baseboard_fab2(sch_1):tp_cpu1_rsvd_53"
				( attribute "CDS_PHYS_NET_NAME" "TP_CPU1_RSVD_53"
					( Origin gPackager )
				)
				( objectStatus "TP_CPU1_RSVD_53" )
			)
			( signal "@baseboard_fab2_lib.baseboard_fab2(sch_1):tp_cpu1_rsvd_54"
				( attribute "CDS_PHYS_NET_NAME" "TP_CPU1_RSVD_54"
					( Origin gPackager )
				)
				( objectStatus "TP_CPU1_RSVD_54" )
			)
			( signal "@baseboard_fab2_lib.baseboard_fab2(sch_1):tp_cpu1_rsvd_55"
				( attribute "CDS_PHYS_NET_NAME" "TP_CPU1_RSVD_55"
					( Origin gPackager )
				)
				( objectStatus "TP_CPU1_RSVD_55" )
			)
			( signal "@baseboard_fab2_lib.baseboard_fab2(sch_1):tp_cpu1_rsvd_56"
				( attribute "CDS_PHYS_NET_NAME" "TP_CPU1_RSVD_56"
					( Origin gPackager )
				)
				( objectStatus "TP_CPU1_RSVD_56" )
			)
			( signal "@baseboard_fab2_lib.baseboard_fab2(sch_1):tp_cpu1_rsvd_57"
				( attribute "CDS_PHYS_NET_NAME" "TP_CPU1_RSVD_57"
					( Origin gPackager )
				)
				( objectStatus "TP_CPU1_RSVD_57" )
			)
			( signal "@baseboard_fab2_lib.baseboard_fab2(sch_1):tp_cpu1_rsvd_59"
				( attribute "CDS_PHYS_NET_NAME" "TP_CPU1_RSVD_59"
					( Origin gPackager )
				)
				( objectStatus "TP_CPU1_RSVD_59" )
			)
			( signal "@baseboard_fab2_lib.baseboard_fab2(sch_1):tp_cpu1_rsvd_6"
				( attribute "CDS_PHYS_NET_NAME" "TP_CPU1_RSVD_6"
					( Origin gPackager )
				)
				( objectStatus "TP_CPU1_RSVD_6" )
			)
			( signal "@baseboard_fab2_lib.baseboard_fab2(sch_1):tp_cpu1_rsvd_60"
				( attribute "CDS_PHYS_NET_NAME" "TP_CPU1_RSVD_60"
					( Origin gPackager )
				)
				( objectStatus "TP_CPU1_RSVD_60" )
			)
			( signal "@baseboard_fab2_lib.baseboard_fab2(sch_1):tp_cpu1_rsvd_61"
				( attribute "CDS_PHYS_NET_NAME" "TP_CPU1_RSVD_61"
					( Origin gPackager )
				)
				( objectStatus "TP_CPU1_RSVD_61" )
			)
			( signal "@baseboard_fab2_lib.baseboard_fab2(sch_1):tp_cpu1_rsvd_64"
				( attribute "CDS_PHYS_NET_NAME" "TP_CPU1_RSVD_64"
					( Origin gPackager )
				)
				( objectStatus "TP_CPU1_RSVD_64" )
			)
			( signal "@baseboard_fab2_lib.baseboard_fab2(sch_1):tp_cpu1_rsvd_66"
				( attribute "CDS_PHYS_NET_NAME" "TP_CPU1_RSVD_66"
					( Origin gPackager )
				)
				( objectStatus "TP_CPU1_RSVD_66" )
			)
			( signal "@baseboard_fab2_lib.baseboard_fab2(sch_1):tp_cpu1_rsvd_67"
				( attribute "CDS_PHYS_NET_NAME" "TP_CPU1_RSVD_67"
					( Origin gPackager )
				)
				( objectStatus "TP_CPU1_RSVD_67" )
			)
			( signal "@baseboard_fab2_lib.baseboard_fab2(sch_1):tp_cpu1_rsvd_69"
				( attribute "CDS_PHYS_NET_NAME" "TP_CPU1_RSVD_69"
					( Origin gPackager )
				)
				( objectStatus "TP_CPU1_RSVD_69" )
			)
			( signal "@baseboard_fab2_lib.baseboard_fab2(sch_1):tp_cpu1_rsvd_7"
				( attribute "CDS_PHYS_NET_NAME" "TP_CPU1_RSVD_7"
					( Origin gPackager )
				)
				( objectStatus "TP_CPU1_RSVD_7" )
			)
			( signal "@baseboard_fab2_lib.baseboard_fab2(sch_1):tp_cpu1_rsvd_70"
				( attribute "CDS_PHYS_NET_NAME" "TP_CPU1_RSVD_70"
					( Origin gPackager )
				)
				( objectStatus "TP_CPU1_RSVD_70" )
			)
			( signal "@baseboard_fab2_lib.baseboard_fab2(sch_1):tp_cpu1_rsvd_72"
				( attribute "CDS_PHYS_NET_NAME" "TP_CPU1_RSVD_72"
					( Origin gPackager )
				)
				( objectStatus "TP_CPU1_RSVD_72" )
			)
			( signal "@baseboard_fab2_lib.baseboard_fab2(sch_1):tp_cpu1_rsvd_73"
				( attribute "CDS_PHYS_NET_NAME" "TP_CPU1_RSVD_73"
					( Origin gPackager )
				)
				( objectStatus "TP_CPU1_RSVD_73" )
			)
			( signal "@baseboard_fab2_lib.baseboard_fab2(sch_1):tp_cpu1_rsvd_8"
				( attribute "CDS_PHYS_NET_NAME" "TP_CPU1_RSVD_8"
					( Origin gPackager )
				)
				( objectStatus "TP_CPU1_RSVD_8" )
			)
			( signal "@baseboard_fab2_lib.baseboard_fab2(sch_1):tp_cpu1_rsvd_9"
				( attribute "CDS_PHYS_NET_NAME" "TP_CPU1_RSVD_9"
					( Origin gPackager )
				)
				( objectStatus "TP_CPU1_RSVD_9" )
			)
			( signal "@baseboard_fab2_lib.baseboard_fab2(sch_1):vsense_pvccio_cpu1_skt_vrtn"
				( attribute "CDS_PHYS_NET_NAME" "VSENSE_PVCCIO_CPU1_SKT_VRTN"
					( Origin gPackager )
				)
				( objectStatus "VSENSE_PVCCIO_CPU1_SKT_VRTN" )
			)
			( signal "@baseboard_fab2_lib.baseboard_fab2(sch_1):vsense_pvccio_cpu1_skt_vsen"
				( attribute "CDS_PHYS_NET_NAME" "VSENSE_PVCCIO_CPU1_SKT_VSEN"
					( Origin gPackager )
				)
				( objectStatus "VSENSE_PVCCIO_CPU1_SKT_VSEN" )
			)
			( signal "@baseboard_fab2_lib.baseboard_fab2(sch_1):vsense_pvcciomcp_cpu1_skt_vrtn"
				( attribute "CDS_PHYS_NET_NAME" "VSENSE_PVCCIOMCP_CPU1_SKT_VRTN"
					( Origin gPackager )
				)
				( objectStatus "VSENSE_PVCCIOMCP_CPU1_SKT_VRTN" )
			)
			( signal "@baseboard_fab2_lib.baseboard_fab2(sch_1):vsense_pvcciomcp_cpu1_skt_vsen"
				( attribute "CDS_PHYS_NET_NAME" "VSENSE_PVCCIOMCP_CPU1_SKT_VSEN"
					( Origin gPackager )
				)
				( objectStatus "VSENSE_PVCCIOMCP_CPU1_SKT_VSEN" )
			)
			( signal "@baseboard_fab2_lib.baseboard_fab2(sch_1):vsense_pvccmcp_cpu1_skt_vrtn"
				( attribute "CDS_PHYS_NET_NAME" "VSENSE_PVCCMCP_CPU1_SKT_VRTN"
					( Origin gPackager )
				)
				( objectStatus "VSENSE_PVCCMCP_CPU1_SKT_VRTN" )
			)
			( signal "@baseboard_fab2_lib.baseboard_fab2(sch_1):vsense_pvccmcp_cpu1_skt_vsen"
				( attribute "CDS_PHYS_NET_NAME" "VSENSE_PVCCMCP_CPU1_SKT_VSEN"
					( Origin gPackager )
				)
				( objectStatus "VSENSE_PVCCMCP_CPU1_SKT_VSEN" )
			)
			( signal "@baseboard_fab2_lib.baseboard_fab2(sch_1):vsense_pvsa_cpu1_skt_vrtn"
				( attribute "CDS_PHYS_NET_NAME" "VSENSE_PVSA_CPU1_SKT_VRTN"
					( Origin gPackager )
				)
				( objectStatus "VSENSE_PVSA_CPU1_SKT_VRTN" )
			)
			( signal "@baseboard_fab2_lib.baseboard_fab2(sch_1):vsense_pvsa_cpu1_skt_vsen"
				( attribute "CDS_PHYS_NET_NAME" "VSENSE_PVSA_CPU1_SKT_VSEN"
					( Origin gPackager )
				)
				( objectStatus "VSENSE_PVSA_CPU1_SKT_VSEN" )
			)
			( signal "@baseboard_fab2_lib.baseboard_fab2(sch_1):fm_adr_complete_ghj_n"
				( attribute "CDS_PHYS_NET_NAME" "FM_ADR_COMPLETE_GHJ_N"
					( Origin gPackager )
				)
				( objectStatus "FM_ADR_COMPLETE_GHJ_N" )
			)
			( signal "@baseboard_fab2_lib.baseboard_fab2(sch_1):m_g_vref"
				( attribute "CDS_PHYS_NET_NAME" "M_G_VREF"
					( Origin gPackager )
				)
				( objectStatus "M_G_VREF" )
			)
			( signal "@baseboard_fab2_lib.baseboard_fab2(sch_1):p12v_nvdimm_ghj"
				( alias ( signalRef "@baseboard_fab2_lib.baseboard_fab2(sch_1):page77_p12v_nvdimm_ghj") )
				( alias ( signalRef "@baseboard_fab2_lib.baseboard_fab2(sch_1):page78_p12v_nvdimm_ghj") )
				( alias ( signalRef "@baseboard_fab2_lib.baseboard_fab2(sch_1):page79_p12v_nvdimm_ghj") )
				( alias ( signalRef "@baseboard_fab2_lib.baseboard_fab2(sch_1):page80_p12v_nvdimm_ghj") )
				( alias ( signalRef "@baseboard_fab2_lib.baseboard_fab2(sch_1):page81_p12v_nvdimm_ghj") )
				( alias ( signalRef "@baseboard_fab2_lib.baseboard_fab2(sch_1):page82_p12v_nvdimm_ghj") )
				( alias ( signalRef "@baseboard_fab2_lib.baseboard_fab2(sch_1):page197_p12v_nvdimm_ghj") )
				( attribute "VOLTAGE" "12.0"
					( Units "uVoltage" "V" 1.000000)
					( Status sAliasFlattened )
					( Origin gFrontEnd )
				)
				( attribute "CDS_PHYS_NET_NAME" "P12V_NVDIMM_GHJ"
					( Origin gPackager )
				)
				( objectStatus "P12V_NVDIMM_GHJ" )
			)
			( signal "@baseboard_fab2_lib.baseboard_fab2(sch_1):page77_p12v_nvdimm_ghj"
				( attribute "VOLTAGE" "12.0"
					( Units "uVoltage" "V" 1.000000)
					( Origin gFrontEnd )
				)
				( objectFlag fObjectAlias )
				( objectStatus "page77_p12v_nvdimm_ghj" )
			)
			( signal "@baseboard_fab2_lib.baseboard_fab2(sch_1):page78_p12v_nvdimm_ghj"
				( attribute "VOLTAGE" "12.0"
					( Units "uVoltage" "V" 1.000000)
					( Origin gFrontEnd )
				)
				( objectFlag fObjectAlias )
				( objectStatus "page78_p12v_nvdimm_ghj" )
			)
			( signal "@baseboard_fab2_lib.baseboard_fab2(sch_1):page79_p12v_nvdimm_ghj"
				( attribute "VOLTAGE" "12.0"
					( Units "uVoltage" "V" 1.000000)
					( Origin gFrontEnd )
				)
				( objectFlag fObjectAlias )
				( objectStatus "page79_p12v_nvdimm_ghj" )
			)
			( signal "@baseboard_fab2_lib.baseboard_fab2(sch_1):page80_p12v_nvdimm_ghj"
				( attribute "VOLTAGE" "12.0"
					( Units "uVoltage" "V" 1.000000)
					( Origin gFrontEnd )
				)
				( objectFlag fObjectAlias )
				( objectStatus "page80_p12v_nvdimm_ghj" )
			)
			( signal "@baseboard_fab2_lib.baseboard_fab2(sch_1):page81_p12v_nvdimm_ghj"
				( attribute "VOLTAGE" "12.0"
					( Units "uVoltage" "V" 1.000000)
					( Origin gFrontEnd )
				)
				( objectFlag fObjectAlias )
				( objectStatus "page81_p12v_nvdimm_ghj" )
			)
			( signal "@baseboard_fab2_lib.baseboard_fab2(sch_1):page82_p12v_nvdimm_ghj"
				( attribute "VOLTAGE" "12.0"
					( Units "uVoltage" "V" 1.000000)
					( Origin gFrontEnd )
				)
				( objectFlag fObjectAlias )
				( objectStatus "page82_p12v_nvdimm_ghj" )
			)
			( signal "@baseboard_fab2_lib.baseboard_fab2(sch_1):page197_p12v_nvdimm_ghj"
				( attribute "VOLTAGE" "12.0"
					( Units "uVoltage" "V" 1.000000)
					( Origin gFrontEnd )
				)
				( objectFlag fObjectAlias )
				( objectStatus "page197_p12v_nvdimm_ghj" )
			)
			( signal "@baseboard_fab2_lib.baseboard_fab2(sch_1):pvtt_ghj"
				( alias ( signalRef "@baseboard_fab2_lib.baseboard_fab2(sch_1):page77_pvtt_ghj") )
				( alias ( signalRef "@baseboard_fab2_lib.baseboard_fab2(sch_1):page78_pvtt_ghj") )
				( alias ( signalRef "@baseboard_fab2_lib.baseboard_fab2(sch_1):page79_pvtt_ghj") )
				( alias ( signalRef "@baseboard_fab2_lib.baseboard_fab2(sch_1):page80_pvtt_ghj") )
				( alias ( signalRef "@baseboard_fab2_lib.baseboard_fab2(sch_1):page81_pvtt_ghj") )
				( alias ( signalRef "@baseboard_fab2_lib.baseboard_fab2(sch_1):page82_pvtt_ghj") )
				( alias ( signalRef "@baseboard_fab2_lib.baseboard_fab2(sch_1):page229_pvtt_ghj") )
				( attribute "VOLTAGE" "0.6V"
					( Units "uVoltage" "V" 1.000000)
					( Status sAliasFlattened )
					( Origin gFrontEnd )
				)
				( attribute "CDS_PHYS_NET_NAME" "PVTT_GHJ"
					( Origin gPackager )
				)
				( objectStatus "PVTT_GHJ" )
			)
			( signal "@baseboard_fab2_lib.baseboard_fab2(sch_1):page77_pvtt_ghj"
				( attribute "VOLTAGE" "0.6V"
					( Units "uVoltage" "V" 1.000000)
					( Origin gFrontEnd )
				)
				( objectFlag fObjectAlias )
				( objectStatus "page77_pvtt_ghj" )
			)
			( signal "@baseboard_fab2_lib.baseboard_fab2(sch_1):page78_pvtt_ghj"
				( attribute "VOLTAGE" "0.6V"
					( Units "uVoltage" "V" 1.000000)
					( Origin gFrontEnd )
				)
				( objectFlag fObjectAlias )
				( objectStatus "page78_pvtt_ghj" )
			)
			( signal "@baseboard_fab2_lib.baseboard_fab2(sch_1):page79_pvtt_ghj"
				( attribute "VOLTAGE" "0.6V"
					( Units "uVoltage" "V" 1.000000)
					( Origin gFrontEnd )
				)
				( objectFlag fObjectAlias )
				( objectStatus "page79_pvtt_ghj" )
			)
			( signal "@baseboard_fab2_lib.baseboard_fab2(sch_1):page80_pvtt_ghj"
				( attribute "VOLTAGE" "0.6V"
					( Units "uVoltage" "V" 1.000000)
					( Origin gFrontEnd )
				)
				( objectFlag fObjectAlias )
				( objectStatus "page80_pvtt_ghj" )
			)
			( signal "@baseboard_fab2_lib.baseboard_fab2(sch_1):page81_pvtt_ghj"
				( attribute "VOLTAGE" "0.6V"
					( Units "uVoltage" "V" 1.000000)
					( Origin gFrontEnd )
				)
				( objectFlag fObjectAlias )
				( objectStatus "page81_pvtt_ghj" )
			)
			( signal "@baseboard_fab2_lib.baseboard_fab2(sch_1):page82_pvtt_ghj"
				( attribute "VOLTAGE" "0.6V"
					( Units "uVoltage" "V" 1.000000)
					( Origin gFrontEnd )
				)
				( objectFlag fObjectAlias )
				( objectStatus "page82_pvtt_ghj" )
			)
			( signal "@baseboard_fab2_lib.baseboard_fab2(sch_1):page229_pvtt_ghj"
				( attribute "VOLTAGE" "0.6V"
					( Units "uVoltage" "V" 1.000000)
					( Origin gFrontEnd )
				)
				( objectFlag fObjectAlias )
				( objectStatus "page229_pvtt_ghj" )
			)
			( signal "@baseboard_fab2_lib.baseboard_fab2(sch_1):smb_ddr_ghj_vpp_scl"
				( attribute "CDS_PHYS_NET_NAME" "SMB_DDR_GHJ_VPP_SCL"
					( Origin gPackager )
				)
				( objectStatus "SMB_DDR_GHJ_VPP_SCL" )
			)
			( signal "@baseboard_fab2_lib.baseboard_fab2(sch_1):smb_ddr_ghj_vpp_sda"
				( attribute "CDS_PHYS_NET_NAME" "SMB_DDR_GHJ_VPP_SDA"
					( Origin gPackager )
				)
				( objectStatus "SMB_DDR_GHJ_VPP_SDA" )
			)
			( signal "@baseboard_fab2_lib.baseboard_fab2(sch_1):tp_ch_g_dimm_g0_rfu_0"
				( attribute "CDS_PHYS_NET_NAME" "TP_CH_G_DIMM_G0_RFU_0"
					( Origin gPackager )
				)
				( objectStatus "TP_CH_G_DIMM_G0_RFU_0" )
			)
			( signal "@baseboard_fab2_lib.baseboard_fab2(sch_1):tp_ch_g_dimm_g0_rfu_1"
				( attribute "CDS_PHYS_NET_NAME" "TP_CH_G_DIMM_G0_RFU_1"
					( Origin gPackager )
				)
				( objectStatus "TP_CH_G_DIMM_G0_RFU_1" )
			)
			( signal "@baseboard_fab2_lib.baseboard_fab2(sch_1):tp_ch_g_dimm_g0_rfu_2"
				( attribute "CDS_PHYS_NET_NAME" "TP_CH_G_DIMM_G0_RFU_2"
					( Origin gPackager )
				)
				( objectStatus "TP_CH_G_DIMM_G0_RFU_2" )
			)
			( signal "@baseboard_fab2_lib.baseboard_fab2(sch_1):tp_ch_g_dimm0_rfu_0"
				( attribute "CDS_PHYS_NET_NAME" "TP_CH_G_DIMM0_RFU_0"
					( Origin gPackager )
				)
				( objectStatus "TP_CH_G_DIMM0_RFU_0" )
			)
			( signal "@baseboard_fab2_lib.baseboard_fab2(sch_1):tp_ch_g_dimm0_rfu_1"
				( attribute "CDS_PHYS_NET_NAME" "TP_CH_G_DIMM0_RFU_1"
					( Origin gPackager )
				)
				( objectStatus "TP_CH_G_DIMM0_RFU_1" )
			)
			( signal "@baseboard_fab2_lib.baseboard_fab2(sch_1):tp_ch_g_dimm0_rfu_2"
				( attribute "CDS_PHYS_NET_NAME" "TP_CH_G_DIMM0_RFU_2"
					( Origin gPackager )
				)
				( objectStatus "TP_CH_G_DIMM0_RFU_2" )
			)
			( signal "@baseboard_fab2_lib.baseboard_fab2(sch_1):m_h_vref"
				( attribute "CDS_PHYS_NET_NAME" "M_H_VREF"
					( Origin gPackager )
				)
				( objectStatus "M_H_VREF" )
			)
			( signal "@baseboard_fab2_lib.baseboard_fab2(sch_1):tp_ch_h_dimm_h0_rfu_0"
				( attribute "CDS_PHYS_NET_NAME" "TP_CH_H_DIMM_H0_RFU_0"
					( Origin gPackager )
				)
				( objectStatus "TP_CH_H_DIMM_H0_RFU_0" )
			)
			( signal "@baseboard_fab2_lib.baseboard_fab2(sch_1):tp_ch_h_dimm_h0_rfu_1"
				( attribute "CDS_PHYS_NET_NAME" "TP_CH_H_DIMM_H0_RFU_1"
					( Origin gPackager )
				)
				( objectStatus "TP_CH_H_DIMM_H0_RFU_1" )
			)
			( signal "@baseboard_fab2_lib.baseboard_fab2(sch_1):tp_ch_h_dimm_h0_rfu_2"
				( attribute "CDS_PHYS_NET_NAME" "TP_CH_H_DIMM_H0_RFU_2"
					( Origin gPackager )
				)
				( objectStatus "TP_CH_H_DIMM_H0_RFU_2" )
			)
			( signal "@baseboard_fab2_lib.baseboard_fab2(sch_1):tp_ch_h_dimm0_rfu_0"
				( attribute "CDS_PHYS_NET_NAME" "TP_CH_H_DIMM0_RFU_0"
					( Origin gPackager )
				)
				( objectStatus "TP_CH_H_DIMM0_RFU_0" )
			)
			( signal "@baseboard_fab2_lib.baseboard_fab2(sch_1):tp_ch_h_dimm0_rfu_1"
				( attribute "CDS_PHYS_NET_NAME" "TP_CH_H_DIMM0_RFU_1"
					( Origin gPackager )
				)
				( objectStatus "TP_CH_H_DIMM0_RFU_1" )
			)
			( signal "@baseboard_fab2_lib.baseboard_fab2(sch_1):tp_ch_h_dimm0_rfu_2"
				( attribute "CDS_PHYS_NET_NAME" "TP_CH_H_DIMM0_RFU_2"
					( Origin gPackager )
				)
				( objectStatus "TP_CH_H_DIMM0_RFU_2" )
			)
			( signal "@baseboard_fab2_lib.baseboard_fab2(sch_1):m_j_vref"
				( attribute "CDS_PHYS_NET_NAME" "M_J_VREF"
					( Origin gPackager )
				)
				( objectStatus "M_J_VREF" )
			)
			( signal "@baseboard_fab2_lib.baseboard_fab2(sch_1):tp_ch_j_dimm_j0_rfu_0"
				( attribute "CDS_PHYS_NET_NAME" "TP_CH_J_DIMM_J0_RFU_0"
					( Origin gPackager )
				)
				( objectStatus "TP_CH_J_DIMM_J0_RFU_0" )
			)
			( signal "@baseboard_fab2_lib.baseboard_fab2(sch_1):tp_ch_j_dimm_j0_rfu_1"
				( attribute "CDS_PHYS_NET_NAME" "TP_CH_J_DIMM_J0_RFU_1"
					( Origin gPackager )
				)
				( objectStatus "TP_CH_J_DIMM_J0_RFU_1" )
			)
			( signal "@baseboard_fab2_lib.baseboard_fab2(sch_1):tp_ch_j_dimm_j0_rfu_2"
				( attribute "CDS_PHYS_NET_NAME" "TP_CH_J_DIMM_J0_RFU_2"
					( Origin gPackager )
				)
				( objectStatus "TP_CH_J_DIMM_J0_RFU_2" )
			)
			( signal "@baseboard_fab2_lib.baseboard_fab2(sch_1):tp_ch_j_dimm_j1_rfu_0"
				( attribute "CDS_PHYS_NET_NAME" "TP_CH_J_DIMM_J1_RFU_0"
					( Origin gPackager )
				)
				( objectStatus "TP_CH_J_DIMM_J1_RFU_0" )
			)
			( signal "@baseboard_fab2_lib.baseboard_fab2(sch_1):tp_ch_j_dimm_j1_rfu_1"
				( attribute "CDS_PHYS_NET_NAME" "TP_CH_J_DIMM_J1_RFU_1"
					( Origin gPackager )
				)
				( objectStatus "TP_CH_J_DIMM_J1_RFU_1" )
			)
			( signal "@baseboard_fab2_lib.baseboard_fab2(sch_1):tp_ch_j_dimm_j1_rfu_2"
				( attribute "CDS_PHYS_NET_NAME" "TP_CH_J_DIMM_J1_RFU_2"
					( Origin gPackager )
				)
				( objectStatus "TP_CH_J_DIMM_J1_RFU_2" )
			)
			( signal "@baseboard_fab2_lib.baseboard_fab2(sch_1):fm_adr_complete_klm_n"
				( attribute "CDS_PHYS_NET_NAME" "FM_ADR_COMPLETE_KLM_N"
					( Origin gPackager )
				)
				( objectStatus "FM_ADR_COMPLETE_KLM_N" )
			)
			( signal "@baseboard_fab2_lib.baseboard_fab2(sch_1):m_k_vref"
				( attribute "CDS_PHYS_NET_NAME" "M_K_VREF"
					( Origin gPackager )
				)
				( objectStatus "M_K_VREF" )
			)
			( signal "@baseboard_fab2_lib.baseboard_fab2(sch_1):p12v_nvdimm_klm"
				( alias ( signalRef "@baseboard_fab2_lib.baseboard_fab2(sch_1):page83_p12v_nvdimm_klm") )
				( alias ( signalRef "@baseboard_fab2_lib.baseboard_fab2(sch_1):page84_p12v_nvdimm_klm") )
				( alias ( signalRef "@baseboard_fab2_lib.baseboard_fab2(sch_1):page85_p12v_nvdimm_klm") )
				( alias ( signalRef "@baseboard_fab2_lib.baseboard_fab2(sch_1):page86_p12v_nvdimm_klm") )
				( alias ( signalRef "@baseboard_fab2_lib.baseboard_fab2(sch_1):page87_p12v_nvdimm_klm") )
				( alias ( signalRef "@baseboard_fab2_lib.baseboard_fab2(sch_1):page88_p12v_nvdimm_klm") )
				( alias ( signalRef "@baseboard_fab2_lib.baseboard_fab2(sch_1):page197_p12v_nvdimm_klm") )
				( attribute "VOLTAGE" "12.0"
					( Units "uVoltage" "V" 1.000000)
					( Status sAliasFlattened )
					( Origin gFrontEnd )
				)
				( attribute "CDS_PHYS_NET_NAME" "P12V_NVDIMM_KLM"
					( Origin gPackager )
				)
				( objectStatus "P12V_NVDIMM_KLM" )
			)
			( signal "@baseboard_fab2_lib.baseboard_fab2(sch_1):page83_p12v_nvdimm_klm"
				( attribute "VOLTAGE" "12.0"
					( Units "uVoltage" "V" 1.000000)
					( Origin gFrontEnd )
				)
				( objectFlag fObjectAlias )
				( objectStatus "page83_p12v_nvdimm_klm" )
			)
			( signal "@baseboard_fab2_lib.baseboard_fab2(sch_1):page84_p12v_nvdimm_klm"
				( attribute "VOLTAGE" "12.0"
					( Units "uVoltage" "V" 1.000000)
					( Origin gFrontEnd )
				)
				( objectFlag fObjectAlias )
				( objectStatus "page84_p12v_nvdimm_klm" )
			)
			( signal "@baseboard_fab2_lib.baseboard_fab2(sch_1):page85_p12v_nvdimm_klm"
				( attribute "VOLTAGE" "12.0"
					( Units "uVoltage" "V" 1.000000)
					( Origin gFrontEnd )
				)
				( objectFlag fObjectAlias )
				( objectStatus "page85_p12v_nvdimm_klm" )
			)
			( signal "@baseboard_fab2_lib.baseboard_fab2(sch_1):page86_p12v_nvdimm_klm"
				( attribute "VOLTAGE" "12.0"
					( Units "uVoltage" "V" 1.000000)
					( Origin gFrontEnd )
				)
				( objectFlag fObjectAlias )
				( objectStatus "page86_p12v_nvdimm_klm" )
			)
			( signal "@baseboard_fab2_lib.baseboard_fab2(sch_1):page87_p12v_nvdimm_klm"
				( attribute "VOLTAGE" "12.0"
					( Units "uVoltage" "V" 1.000000)
					( Origin gFrontEnd )
				)
				( objectFlag fObjectAlias )
				( objectStatus "page87_p12v_nvdimm_klm" )
			)
			( signal "@baseboard_fab2_lib.baseboard_fab2(sch_1):page88_p12v_nvdimm_klm"
				( attribute "VOLTAGE" "12.0"
					( Units "uVoltage" "V" 1.000000)
					( Origin gFrontEnd )
				)
				( objectFlag fObjectAlias )
				( objectStatus "page88_p12v_nvdimm_klm" )
			)
			( signal "@baseboard_fab2_lib.baseboard_fab2(sch_1):page197_p12v_nvdimm_klm"
				( attribute "VOLTAGE" "12.0"
					( Units "uVoltage" "V" 1.000000)
					( Origin gFrontEnd )
				)
				( objectFlag fObjectAlias )
				( objectStatus "page197_p12v_nvdimm_klm" )
			)
			( signal "@baseboard_fab2_lib.baseboard_fab2(sch_1):pvpp_klm"
				( alias ( signalRef "@baseboard_fab2_lib.baseboard_fab2(sch_1):page83_pvpp_klm") )
				( alias ( signalRef "@baseboard_fab2_lib.baseboard_fab2(sch_1):page84_pvpp_klm") )
				( alias ( signalRef "@baseboard_fab2_lib.baseboard_fab2(sch_1):page85_pvpp_klm") )
				( alias ( signalRef "@baseboard_fab2_lib.baseboard_fab2(sch_1):page86_pvpp_klm") )
				( alias ( signalRef "@baseboard_fab2_lib.baseboard_fab2(sch_1):page87_pvpp_klm") )
				( alias ( signalRef "@baseboard_fab2_lib.baseboard_fab2(sch_1):page88_pvpp_klm") )
				( alias ( signalRef "@baseboard_fab2_lib.baseboard_fab2(sch_1):page99_pvpp_klm") )
				( alias ( signalRef "@baseboard_fab2_lib.baseboard_fab2(sch_1):page192_pvpp_klm") )
				( alias ( signalRef "@baseboard_fab2_lib.baseboard_fab2(sch_1):page234_pvpp_klm") )
				( attribute "VOLTAGE" "2.5V"
					( Units "uVoltage" "V" 1.000000)
					( Status sAliasFlattened )
					( Origin gFrontEnd )
				)
				( attribute "CDS_PHYS_NET_NAME" "PVPP_KLM"
					( Origin gPackager )
				)
				( objectStatus "PVPP_KLM" )
			)
			( signal "@baseboard_fab2_lib.baseboard_fab2(sch_1):page83_pvpp_klm"
				( attribute "VOLTAGE" "2.5V"
					( Units "uVoltage" "V" 1.000000)
					( Origin gFrontEnd )
				)
				( objectFlag fObjectAlias )
				( objectStatus "page83_pvpp_klm" )
			)
			( signal "@baseboard_fab2_lib.baseboard_fab2(sch_1):page84_pvpp_klm"
				( attribute "VOLTAGE" "2.5V"
					( Units "uVoltage" "V" 1.000000)
					( Origin gFrontEnd )
				)
				( objectFlag fObjectAlias )
				( objectStatus "page84_pvpp_klm" )
			)
			( signal "@baseboard_fab2_lib.baseboard_fab2(sch_1):page85_pvpp_klm"
				( attribute "VOLTAGE" "2.5V"
					( Units "uVoltage" "V" 1.000000)
					( Origin gFrontEnd )
				)
				( objectFlag fObjectAlias )
				( objectStatus "page85_pvpp_klm" )
			)
			( signal "@baseboard_fab2_lib.baseboard_fab2(sch_1):page86_pvpp_klm"
				( attribute "VOLTAGE" "2.5V"
					( Units "uVoltage" "V" 1.000000)
					( Origin gFrontEnd )
				)
				( objectFlag fObjectAlias )
				( objectStatus "page86_pvpp_klm" )
			)
			( signal "@baseboard_fab2_lib.baseboard_fab2(sch_1):page87_pvpp_klm"
				( attribute "VOLTAGE" "2.5V"
					( Units "uVoltage" "V" 1.000000)
					( Origin gFrontEnd )
				)
				( objectFlag fObjectAlias )
				( objectStatus "page87_pvpp_klm" )
			)
			( signal "@baseboard_fab2_lib.baseboard_fab2(sch_1):page88_pvpp_klm"
				( attribute "VOLTAGE" "2.5V"
					( Units "uVoltage" "V" 1.000000)
					( Origin gFrontEnd )
				)
				( objectFlag fObjectAlias )
				( objectStatus "page88_pvpp_klm" )
			)
			( signal "@baseboard_fab2_lib.baseboard_fab2(sch_1):page99_pvpp_klm"
				( attribute "VOLTAGE" "2.5V"
					( Units "uVoltage" "V" 1.000000)
					( Origin gFrontEnd )
				)
				( objectFlag fObjectAlias )
				( objectStatus "page99_pvpp_klm" )
			)
			( signal "@baseboard_fab2_lib.baseboard_fab2(sch_1):page192_pvpp_klm"
				( attribute "VOLTAGE" "2.5V"
					( Units "uVoltage" "V" 1.000000)
					( Origin gFrontEnd )
				)
				( objectFlag fObjectAlias )
				( objectStatus "page192_pvpp_klm" )
			)
			( signal "@baseboard_fab2_lib.baseboard_fab2(sch_1):page234_pvpp_klm"
				( attribute "VOLTAGE" "2.5V"
					( Units "uVoltage" "V" 1.000000)
					( Origin gFrontEnd )
				)
				( objectFlag fObjectAlias )
				( objectStatus "page234_pvpp_klm" )
			)
			( signal "@baseboard_fab2_lib.baseboard_fab2(sch_1):pvtt_klm"
				( alias ( signalRef "@baseboard_fab2_lib.baseboard_fab2(sch_1):page83_pvtt_klm") )
				( alias ( signalRef "@baseboard_fab2_lib.baseboard_fab2(sch_1):page84_pvtt_klm") )
				( alias ( signalRef "@baseboard_fab2_lib.baseboard_fab2(sch_1):page85_pvtt_klm") )
				( alias ( signalRef "@baseboard_fab2_lib.baseboard_fab2(sch_1):page86_pvtt_klm") )
				( alias ( signalRef "@baseboard_fab2_lib.baseboard_fab2(sch_1):page87_pvtt_klm") )
				( alias ( signalRef "@baseboard_fab2_lib.baseboard_fab2(sch_1):page88_pvtt_klm") )
				( alias ( signalRef "@baseboard_fab2_lib.baseboard_fab2(sch_1):page230_pvtt_klm") )
				( attribute "VOLTAGE" "0.6V"
					( Units "uVoltage" "V" 1.000000)
					( Status sAliasFlattened )
					( Origin gFrontEnd )
				)
				( attribute "CDS_PHYS_NET_NAME" "PVTT_KLM"
					( Origin gPackager )
				)
				( objectStatus "PVTT_KLM" )
			)
			( signal "@baseboard_fab2_lib.baseboard_fab2(sch_1):page83_pvtt_klm"
				( attribute "VOLTAGE" "0.6V"
					( Units "uVoltage" "V" 1.000000)
					( Origin gFrontEnd )
				)
				( objectFlag fObjectAlias )
				( objectStatus "page83_pvtt_klm" )
			)
			( signal "@baseboard_fab2_lib.baseboard_fab2(sch_1):page84_pvtt_klm"
				( attribute "VOLTAGE" "0.6V"
					( Units "uVoltage" "V" 1.000000)
					( Origin gFrontEnd )
				)
				( objectFlag fObjectAlias )
				( objectStatus "page84_pvtt_klm" )
			)
			( signal "@baseboard_fab2_lib.baseboard_fab2(sch_1):page85_pvtt_klm"
				( attribute "VOLTAGE" "0.6V"
					( Units "uVoltage" "V" 1.000000)
					( Origin gFrontEnd )
				)
				( objectFlag fObjectAlias )
				( objectStatus "page85_pvtt_klm" )
			)
			( signal "@baseboard_fab2_lib.baseboard_fab2(sch_1):page86_pvtt_klm"
				( attribute "VOLTAGE" "0.6V"
					( Units "uVoltage" "V" 1.000000)
					( Origin gFrontEnd )
				)
				( objectFlag fObjectAlias )
				( objectStatus "page86_pvtt_klm" )
			)
			( signal "@baseboard_fab2_lib.baseboard_fab2(sch_1):page87_pvtt_klm"
				( attribute "VOLTAGE" "0.6V"
					( Units "uVoltage" "V" 1.000000)
					( Origin gFrontEnd )
				)
				( objectFlag fObjectAlias )
				( objectStatus "page87_pvtt_klm" )
			)
			( signal "@baseboard_fab2_lib.baseboard_fab2(sch_1):page88_pvtt_klm"
				( attribute "VOLTAGE" "0.6V"
					( Units "uVoltage" "V" 1.000000)
					( Origin gFrontEnd )
				)
				( objectFlag fObjectAlias )
				( objectStatus "page88_pvtt_klm" )
			)
			( signal "@baseboard_fab2_lib.baseboard_fab2(sch_1):page230_pvtt_klm"
				( attribute "VOLTAGE" "0.6V"
					( Units "uVoltage" "V" 1.000000)
					( Origin gFrontEnd )
				)
				( objectFlag fObjectAlias )
				( objectStatus "page230_pvtt_klm" )
			)
			( signal "@baseboard_fab2_lib.baseboard_fab2(sch_1):smb_ddr_klm_vpp_scl"
				( attribute "CDS_PHYS_NET_NAME" "SMB_DDR_KLM_VPP_SCL"
					( Origin gPackager )
				)
				( objectStatus "SMB_DDR_KLM_VPP_SCL" )
			)
			( signal "@baseboard_fab2_lib.baseboard_fab2(sch_1):smb_ddr_klm_vpp_sda"
				( attribute "CDS_PHYS_NET_NAME" "SMB_DDR_KLM_VPP_SDA"
					( Origin gPackager )
				)
				( objectStatus "SMB_DDR_KLM_VPP_SDA" )
			)
			( signal "@baseboard_fab2_lib.baseboard_fab2(sch_1):tp_ch_k_dimm_k0_rfu_0"
				( attribute "CDS_PHYS_NET_NAME" "TP_CH_K_DIMM_K0_RFU_0"
					( Origin gPackager )
				)
				( objectStatus "TP_CH_K_DIMM_K0_RFU_0" )
			)
			( signal "@baseboard_fab2_lib.baseboard_fab2(sch_1):tp_ch_k_dimm_k0_rfu_1"
				( attribute "CDS_PHYS_NET_NAME" "TP_CH_K_DIMM_K0_RFU_1"
					( Origin gPackager )
				)
				( objectStatus "TP_CH_K_DIMM_K0_RFU_1" )
			)
			( signal "@baseboard_fab2_lib.baseboard_fab2(sch_1):tp_ch_k_dimm_k0_rfu_2"
				( attribute "CDS_PHYS_NET_NAME" "TP_CH_K_DIMM_K0_RFU_2"
					( Origin gPackager )
				)
				( objectStatus "TP_CH_K_DIMM_K0_RFU_2" )
			)
			( signal "@baseboard_fab2_lib.baseboard_fab2(sch_1):tp_ch_k_dimm0_rfu_0"
				( attribute "CDS_PHYS_NET_NAME" "TP_CH_K_DIMM0_RFU_0"
					( Origin gPackager )
				)
				( objectStatus "TP_CH_K_DIMM0_RFU_0" )
			)
			( signal "@baseboard_fab2_lib.baseboard_fab2(sch_1):tp_ch_k_dimm0_rfu_1"
				( attribute "CDS_PHYS_NET_NAME" "TP_CH_K_DIMM0_RFU_1"
					( Origin gPackager )
				)
				( objectStatus "TP_CH_K_DIMM0_RFU_1" )
			)
			( signal "@baseboard_fab2_lib.baseboard_fab2(sch_1):tp_ch_k_dimm0_rfu_2"
				( attribute "CDS_PHYS_NET_NAME" "TP_CH_K_DIMM0_RFU_2"
					( Origin gPackager )
				)
				( objectStatus "TP_CH_K_DIMM0_RFU_2" )
			)
			( signal "@baseboard_fab2_lib.baseboard_fab2(sch_1):m_l_vref"
				( attribute "CDS_PHYS_NET_NAME" "M_L_VREF"
					( Origin gPackager )
				)
				( objectStatus "M_L_VREF" )
			)
			( signal "@baseboard_fab2_lib.baseboard_fab2(sch_1):tp_ch_l_dimm_l0_rfu_0"
				( attribute "CDS_PHYS_NET_NAME" "TP_CH_L_DIMM_L0_RFU_0"
					( Origin gPackager )
				)
				( objectStatus "TP_CH_L_DIMM_L0_RFU_0" )
			)
			( signal "@baseboard_fab2_lib.baseboard_fab2(sch_1):tp_ch_l_dimm_l0_rfu_1"
				( attribute "CDS_PHYS_NET_NAME" "TP_CH_L_DIMM_L0_RFU_1"
					( Origin gPackager )
				)
				( objectStatus "TP_CH_L_DIMM_L0_RFU_1" )
			)
			( signal "@baseboard_fab2_lib.baseboard_fab2(sch_1):tp_ch_l_dimm_l0_rfu_2"
				( attribute "CDS_PHYS_NET_NAME" "TP_CH_L_DIMM_L0_RFU_2"
					( Origin gPackager )
				)
				( objectStatus "TP_CH_L_DIMM_L0_RFU_2" )
			)
			( signal "@baseboard_fab2_lib.baseboard_fab2(sch_1):tp_ch_l_dimm0_rfu_0"
				( attribute "CDS_PHYS_NET_NAME" "TP_CH_L_DIMM0_RFU_0"
					( Origin gPackager )
				)
				( objectStatus "TP_CH_L_DIMM0_RFU_0" )
			)
			( signal "@baseboard_fab2_lib.baseboard_fab2(sch_1):tp_ch_l_dimm0_rfu_1"
				( attribute "CDS_PHYS_NET_NAME" "TP_CH_L_DIMM0_RFU_1"
					( Origin gPackager )
				)
				( objectStatus "TP_CH_L_DIMM0_RFU_1" )
			)
			( signal "@baseboard_fab2_lib.baseboard_fab2(sch_1):tp_ch_l_dimm0_rfu_2"
				( attribute "CDS_PHYS_NET_NAME" "TP_CH_L_DIMM0_RFU_2"
					( Origin gPackager )
				)
				( objectStatus "TP_CH_L_DIMM0_RFU_2" )
			)
			( signal "@baseboard_fab2_lib.baseboard_fab2(sch_1):m_m_vref"
				( attribute "CDS_PHYS_NET_NAME" "M_M_VREF"
					( Origin gPackager )
				)
				( objectStatus "M_M_VREF" )
			)
			( signal "@baseboard_fab2_lib.baseboard_fab2(sch_1):tp_ch_m_dimm_m0_rfu_0"
				( attribute "CDS_PHYS_NET_NAME" "TP_CH_M_DIMM_M0_RFU_0"
					( Origin gPackager )
				)
				( objectStatus "TP_CH_M_DIMM_M0_RFU_0" )
			)
			( signal "@baseboard_fab2_lib.baseboard_fab2(sch_1):tp_ch_m_dimm_m0_rfu_1"
				( attribute "CDS_PHYS_NET_NAME" "TP_CH_M_DIMM_M0_RFU_1"
					( Origin gPackager )
				)
				( objectStatus "TP_CH_M_DIMM_M0_RFU_1" )
			)
			( signal "@baseboard_fab2_lib.baseboard_fab2(sch_1):tp_ch_m_dimm_m0_rfu_2"
				( attribute "CDS_PHYS_NET_NAME" "TP_CH_M_DIMM_M0_RFU_2"
					( Origin gPackager )
				)
				( objectStatus "TP_CH_M_DIMM_M0_RFU_2" )
			)
			( signal "@baseboard_fab2_lib.baseboard_fab2(sch_1):tp_ch_m_dimm_m1_rfu_0"
				( attribute "CDS_PHYS_NET_NAME" "TP_CH_M_DIMM_M1_RFU_0"
					( Origin gPackager )
				)
				( objectStatus "TP_CH_M_DIMM_M1_RFU_0" )
			)
			( signal "@baseboard_fab2_lib.baseboard_fab2(sch_1):tp_ch_m_dimm_m1_rfu_1"
				( attribute "CDS_PHYS_NET_NAME" "TP_CH_M_DIMM_M1_RFU_1"
					( Origin gPackager )
				)
				( objectStatus "TP_CH_M_DIMM_M1_RFU_1" )
			)
			( signal "@baseboard_fab2_lib.baseboard_fab2(sch_1):tp_ch_m_dimm_m1_rfu_2"
				( attribute "CDS_PHYS_NET_NAME" "TP_CH_M_DIMM_M1_RFU_2"
					( Origin gPackager )
				)
				( objectStatus "TP_CH_M_DIMM_M1_RFU_2" )
			)
			( signal "@baseboard_fab2_lib.baseboard_fab2(sch_1):fm_adr_complete"
				( attribute "CDS_PHYS_NET_NAME" "FM_ADR_COMPLETE"
					( Origin gPackager )
				)
				( objectStatus "FM_ADR_COMPLETE" )
			)
			( signal "@baseboard_fab2_lib.baseboard_fab2(sch_1):fm_adr_complete_dly"
				( attribute "CDS_PHYS_NET_NAME" "FM_ADR_COMPLETE_DLY"
					( Origin gPackager )
				)
				( objectStatus "FM_ADR_COMPLETE_DLY" )
			)
			( signal "@baseboard_fab2_lib.baseboard_fab2(sch_1):fm_adr_complete_r"
				( attribute "CDS_PHYS_NET_NAME" "FM_ADR_COMPLETE_R"
					( Origin gPackager )
				)
				( objectStatus "FM_ADR_COMPLETE_R" )
			)
			( signal "@baseboard_fab2_lib.baseboard_fab2(sch_1):fan_pwm_out_sys0"
				( attribute "CDS_PHYS_NET_NAME" "FAN_PWM_OUT_SYS0"
					( Origin gPackager )
				)
				( attribute "PHYS_NET_NAME" "FAN_PWM_OUT_SYS0"
					( Origin gPackager )
				)
				( objectStatus "FAN_PWM_OUT_SYS0" )
			)
			( signal "@baseboard_fab2_lib.baseboard_fab2(sch_1):irq_dimm_save_lvt3"
				( attribute "CDS_PHYS_NET_NAME" "IRQ_DIMM_SAVE_LVT3"
					( Origin gPackager )
				)
				( objectStatus "IRQ_DIMM_SAVE_LVT3" )
			)
			( signal "@baseboard_fab2_lib.baseboard_fab2(sch_1):fan_pwm_out_sys1"
				( attribute "CDS_PHYS_NET_NAME" "FAN_PWM_OUT_SYS1"
					( Origin gPackager )
				)
				( attribute "PHYS_NET_NAME" "FAN_PWM_OUT_SYS1"
					( Origin gPackager )
				)
				( objectStatus "FAN_PWM_OUT_SYS1" )
			)
			( signal "@baseboard_fab2_lib.baseboard_fab2(sch_1):rmii_bmc_pch_sprngvlle_txd0_r"
				( attribute "CDS_PHYS_NET_NAME" "RMII_BMC_PCH_SPRNGVLLE_TXD0_R"
					( Origin gPackager )
				)
				( objectStatus "RMII_BMC_PCH_SPRNGVLLE_TXD0_R" )
			)
			( signal "@baseboard_fab2_lib.baseboard_fab2(sch_1):rmii_bmc_sprngvlle_txen_r"
				( attribute "CDS_PHYS_NET_NAME" "RMII_BMC_SPRNGVLLE_TXEN_R"
					( Origin gPackager )
				)
				( objectStatus "RMII_BMC_SPRNGVLLE_TXEN_R" )
			)
			( signal "@baseboard_fab2_lib.baseboard_fab2(sch_1):rmii_bmc_ocp_txd0_r"
				( attribute "CDS_PHYS_NET_NAME" "RMII_BMC_OCP_TXD0_R"
					( Origin gPackager )
				)
				( objectStatus "RMII_BMC_OCP_TXD0_R" )
			)
			( signal "@baseboard_fab2_lib.baseboard_fab2(sch_1):rmii_bmc_ocp_crsdv"
				( attribute "CDS_PHYS_NET_NAME" "RMII_BMC_OCP_CRSDV"
					( Origin gPackager )
				)
				( attribute "PHYS_NET_NAME" "RMII_BMC_OCP_CRSDV"
					( Origin gPackager )
				)
				( objectStatus "RMII_BMC_OCP_CRSDV" )
			)
			( signal "@baseboard_fab2_lib.baseboard_fab2(sch_1):page145_fm_bios_mrc_debug_msg_dis_n"
				( attribute "CDS_PHYS_NET_NAME" "FM_BIOS_MRC_DEBUG_MSG_DIS_N"
					( Origin gPackager )
				)
				( attribute "PHYS_NET_NAME" "FM_BIOS_MRC_DEBUG_MSG_DIS_N"
					( Origin gFrontEnd )
				)
				( objectFlag fObjectAlias )
				( objectStatus "page145_fm_bios_mrc_debug_msg_dis_n" )
			)
			( signal "@baseboard_fab2_lib.baseboard_fab2(sch_1):fm_bmc_sys_throttle_r_n"
				( alias ( signalRef "@baseboard_fab2_lib.baseboard_fab2(sch_1):page145_fm_bmc_sys_throttle_r_n") )
				( attribute "CDS_PHYS_NET_NAME" "FM_BMC_SYS_THROTTLE_R_N"
					( Origin gPackager )
				)
				( objectStatus "FM_BMC_SYS_THROTTLE_R_N" )
			)
			( signal "@baseboard_fab2_lib.baseboard_fab2(sch_1):page145_fm_bmc_sys_throttle_r_n"
				( attribute "CDS_PHYS_NET_NAME" "FM_BMC_SYS_THROTTLE_R_N"
					( Origin gPackager )
				)
				( objectFlag fObjectAlias )
				( objectStatus "page145_fm_bmc_sys_throttle_r_n" )
			)
			( signal "@baseboard_fab2_lib.baseboard_fab2(sch_1):spi_bmc_bt_cs0_n"
				( alias ( signalRef "@baseboard_fab2_lib.baseboard_fab2(sch_1):page146_spi_bmc_bt_cs0_n") )
				( attribute "CDS_PHYS_NET_NAME" "SPI_BMC_BT_CS0_N"
					( Origin gPackager )
				)
				( objectStatus "SPI_BMC_BT_CS0_N" )
			)
			( signal "@baseboard_fab2_lib.baseboard_fab2(sch_1):page146_spi_bmc_bt_cs0_n"
				( objectFlag fObjectAlias )
				( objectStatus "page146_spi_bmc_bt_cs0_n" )
			)
			( signal "@baseboard_fab2_lib.baseboard_fab2(sch_1):irq_dimm_save_n"
				( attribute "CDS_PHYS_NET_NAME" "IRQ_DIMM_SAVE_N"
					( Origin gPackager )
				)
				( objectStatus "IRQ_DIMM_SAVE_N" )
			)
			( signal "@baseboard_fab2_lib.baseboard_fab2(sch_1):irq_dimm_save_r_n"
				( attribute "CDS_PHYS_NET_NAME" "IRQ_DIMM_SAVE_R_N"
					( Origin gPackager )
				)
				( objectStatus "IRQ_DIMM_SAVE_R_N" )
			)
			( signal "@baseboard_fab2_lib.baseboard_fab2(sch_1):p3v3"
				( alias ( signalRef "@baseboard_fab2_lib.baseboard_fab2(sch_1):page91_p3v3") )
				( alias ( signalRef "@baseboard_fab2_lib.baseboard_fab2(sch_1):page92_p3v3") )
				( alias ( signalRef "@baseboard_fab2_lib.baseboard_fab2(sch_1):page93_p3v3") )
				( alias ( signalRef "@baseboard_fab2_lib.baseboard_fab2(sch_1):page94_p3v3") )
				( alias ( signalRef "@baseboard_fab2_lib.baseboard_fab2(sch_1):page95_p3v3") )
				( alias ( signalRef "@baseboard_fab2_lib.baseboard_fab2(sch_1):page102_p3v3") )
				( alias ( signalRef "@baseboard_fab2_lib.baseboard_fab2(sch_1):page104_p3v3") )
				( alias ( signalRef "@baseboard_fab2_lib.baseboard_fab2(sch_1):page108_p3v3") )
				( alias ( signalRef "@baseboard_fab2_lib.baseboard_fab2(sch_1):page111_p3v3") )
				( alias ( signalRef "@baseboard_fab2_lib.baseboard_fab2(sch_1):page152_p3v3") )
				( alias ( signalRef "@baseboard_fab2_lib.baseboard_fab2(sch_1):page157_p3v3") )
				( alias ( signalRef "@baseboard_fab2_lib.baseboard_fab2(sch_1):page169_p3v3") )
				( alias ( signalRef "@baseboard_fab2_lib.baseboard_fab2(sch_1):page173_p3v3") )
				( alias ( signalRef "@baseboard_fab2_lib.baseboard_fab2(sch_1):page177_p3v3") )
				( alias ( signalRef "@baseboard_fab2_lib.baseboard_fab2(sch_1):page185_p3v3") )
				( alias ( signalRef "@baseboard_fab2_lib.baseboard_fab2(sch_1):page186_p3v3") )
				( alias ( signalRef "@baseboard_fab2_lib.baseboard_fab2(sch_1):page193_p3v3") )
				( alias ( signalRef "@baseboard_fab2_lib.baseboard_fab2(sch_1):page194_p3v3") )
				( alias ( signalRef "@baseboard_fab2_lib.baseboard_fab2(sch_1):page196_p3v3") )
				( alias ( signalRef "@baseboard_fab2_lib.baseboard_fab2(sch_1):page198_p3v3") )
				( alias ( signalRef "@baseboard_fab2_lib.baseboard_fab2(sch_1):page221_p3v3") )
				( alias ( signalRef "@baseboard_fab2_lib.baseboard_fab2(sch_1):page222_p3v3") )
				( alias ( signalRef "@baseboard_fab2_lib.baseboard_fab2(sch_1):page229_p3v3") )
				( alias ( signalRef "@baseboard_fab2_lib.baseboard_fab2(sch_1):page230_p3v3") )
				( alias ( signalRef "@baseboard_fab2_lib.baseboard_fab2(sch_1):page248_p3v3") )
				( alias ( signalRef "@baseboard_fab2_lib.baseboard_fab2(sch_1):page255_p3v3") )
				( alias ( signalRef "@baseboard_fab2_lib.baseboard_fab2(sch_1):page146_p3v3") )
				( attribute "CDS_PHYS_NET_NAME" "P3V3"
					( Origin gPackager )
				)
				( attribute "VOLTAGE" "3.3V"
					( Units "uVoltage" "V" 1.000000)
					( Status sAliasFlattened )
					( Status sAliasConflict )
					( Origin gFrontEnd )
				)
				( objectStatus "P3V3" )
			)
			( signal "@baseboard_fab2_lib.baseboard_fab2(sch_1):page91_p3v3"
				( attribute "VOLTAGE" "3.3V"
					( Units "uVoltage" "V" 1.000000)
					( Origin gFrontEnd )
				)
				( objectFlag fObjectAlias )
				( objectStatus "page91_p3v3" )
			)
			( signal "@baseboard_fab2_lib.baseboard_fab2(sch_1):page92_p3v3"
				( attribute "VOLTAGE" "3.3V"
					( Units "uVoltage" "V" 1.000000)
					( Origin gFrontEnd )
				)
				( objectFlag fObjectAlias )
				( objectStatus "page92_p3v3" )
			)
			( signal "@baseboard_fab2_lib.baseboard_fab2(sch_1):page93_p3v3"
				( attribute "VOLTAGE" "3.3V"
					( Units "uVoltage" "V" 1.000000)
					( Origin gFrontEnd )
				)
				( objectFlag fObjectAlias )
				( objectStatus "page93_p3v3" )
			)
			( signal "@baseboard_fab2_lib.baseboard_fab2(sch_1):page94_p3v3"
				( attribute "VOLTAGE" "+3.3"
					( Units "uVoltage" "V" 1.000000)
					( Origin gFrontEnd )
				)
				( objectFlag fObjectAlias )
				( objectStatus "page94_p3v3" )
			)
			( signal "@baseboard_fab2_lib.baseboard_fab2(sch_1):page95_p3v3"
				( attribute "VOLTAGE" "3.3V"
					( Units "uVoltage" "V" 1.000000)
					( Origin gFrontEnd )
				)
				( objectFlag fObjectAlias )
				( objectStatus "page95_p3v3" )
			)
			( signal "@baseboard_fab2_lib.baseboard_fab2(sch_1):page102_p3v3"
				( attribute "VOLTAGE" "3.3V"
					( Units "uVoltage" "V" 1.000000)
					( Origin gFrontEnd )
				)
				( objectFlag fObjectAlias )
				( objectStatus "page102_p3v3" )
			)
			( signal "@baseboard_fab2_lib.baseboard_fab2(sch_1):page104_p3v3"
				( attribute "VOLTAGE" "3.3V"
					( Units "uVoltage" "V" 1.000000)
					( Origin gFrontEnd )
				)
				( objectFlag fObjectAlias )
				( objectStatus "page104_p3v3" )
			)
			( signal "@baseboard_fab2_lib.baseboard_fab2(sch_1):page108_p3v3"
				( attribute "VOLTAGE" "3.3V"
					( Units "uVoltage" "V" 1.000000)
					( Origin gFrontEnd )
				)
				( objectFlag fObjectAlias )
				( objectStatus "page108_p3v3" )
			)
			( signal "@baseboard_fab2_lib.baseboard_fab2(sch_1):page111_p3v3"
				( attribute "VOLTAGE" "3.3V"
					( Units "uVoltage" "V" 1.000000)
					( Origin gFrontEnd )
				)
				( objectFlag fObjectAlias )
				( objectStatus "page111_p3v3" )
			)
			( signal "@baseboard_fab2_lib.baseboard_fab2(sch_1):page152_p3v3"
				( attribute "VOLTAGE" "3.3V"
					( Units "uVoltage" "V" 1.000000)
					( Origin gFrontEnd )
				)
				( objectFlag fObjectAlias )
				( objectStatus "page152_p3v3" )
			)
			( signal "@baseboard_fab2_lib.baseboard_fab2(sch_1):page157_p3v3"
				( attribute "VOLTAGE" "3.3V"
					( Units "uVoltage" "V" 1.000000)
					( Origin gFrontEnd )
				)
				( objectFlag fObjectAlias )
				( objectStatus "page157_p3v3" )
			)
			( signal "@baseboard_fab2_lib.baseboard_fab2(sch_1):page169_p3v3"
				( attribute "VOLTAGE" "3.3V"
					( Units "uVoltage" "V" 1.000000)
					( Origin gFrontEnd )
				)
				( objectFlag fObjectAlias )
				( objectStatus "page169_p3v3" )
			)
			( signal "@baseboard_fab2_lib.baseboard_fab2(sch_1):page173_p3v3"
				( attribute "VOLTAGE" "3.3V"
					( Units "uVoltage" "V" 1.000000)
					( Origin gFrontEnd )
				)
				( objectFlag fObjectAlias )
				( objectStatus "page173_p3v3" )
			)
			( signal "@baseboard_fab2_lib.baseboard_fab2(sch_1):page177_p3v3"
				( attribute "VOLTAGE" "+3.3"
					( Units "uVoltage" "V" 1.000000)
					( Origin gFrontEnd )
				)
				( objectFlag fObjectAlias )
				( objectStatus "page177_p3v3" )
			)
			( signal "@baseboard_fab2_lib.baseboard_fab2(sch_1):page185_p3v3"
				( attribute "VOLTAGE" "3.3V"
					( Units "uVoltage" "V" 1.000000)
					( Origin gFrontEnd )
				)
				( objectFlag fObjectAlias )
				( objectStatus "page185_p3v3" )
			)
			( signal "@baseboard_fab2_lib.baseboard_fab2(sch_1):page186_p3v3"
				( attribute "VOLTAGE" "+3.3"
					( Units "uVoltage" "V" 1.000000)
					( Origin gFrontEnd )
				)
				( objectFlag fObjectAlias )
				( objectStatus "page186_p3v3" )
			)
			( signal "@baseboard_fab2_lib.baseboard_fab2(sch_1):page193_p3v3"
				( attribute "VOLTAGE" "+3.3V"
					( Units "uVoltage" "V" 1.000000)
					( Origin gFrontEnd )
				)
				( objectFlag fObjectAlias )
				( objectStatus "page193_p3v3" )
			)
			( signal "@baseboard_fab2_lib.baseboard_fab2(sch_1):page194_p3v3"
				( attribute "VOLTAGE" "+3.3V"
					( Units "uVoltage" "V" 1.000000)
					( Origin gFrontEnd )
				)
				( objectFlag fObjectAlias )
				( objectStatus "page194_p3v3" )
			)
			( signal "@baseboard_fab2_lib.baseboard_fab2(sch_1):page196_p3v3"
				( attribute "VOLTAGE" "3.3V"
					( Units "uVoltage" "V" 1.000000)
					( Origin gFrontEnd )
				)
				( objectFlag fObjectAlias )
				( objectStatus "page196_p3v3" )
			)
			( signal "@baseboard_fab2_lib.baseboard_fab2(sch_1):page198_p3v3"
				( attribute "VOLTAGE" "+3.3V"
					( Units "uVoltage" "V" 1.000000)
					( Origin gFrontEnd )
				)
				( objectFlag fObjectAlias )
				( objectStatus "page198_p3v3" )
			)
			( signal "@baseboard_fab2_lib.baseboard_fab2(sch_1):page221_p3v3"
				( attribute "VOLTAGE" "3.3V"
					( Units "uVoltage" "V" 1.000000)
					( Origin gFrontEnd )
				)
				( objectFlag fObjectAlias )
				( objectStatus "page221_p3v3" )
			)
			( signal "@baseboard_fab2_lib.baseboard_fab2(sch_1):page222_p3v3"
				( attribute "VOLTAGE" "3.3V"
					( Units "uVoltage" "V" 1.000000)
					( Origin gFrontEnd )
				)
				( objectFlag fObjectAlias )
				( objectStatus "page222_p3v3" )
			)
			( signal "@baseboard_fab2_lib.baseboard_fab2(sch_1):page229_p3v3"
				( attribute "VOLTAGE" "3.3V"
					( Units "uVoltage" "V" 1.000000)
					( Origin gFrontEnd )
				)
				( objectFlag fObjectAlias )
				( objectStatus "page229_p3v3" )
			)
			( signal "@baseboard_fab2_lib.baseboard_fab2(sch_1):page230_p3v3"
				( attribute "VOLTAGE" "3.3V"
					( Units "uVoltage" "V" 1.000000)
					( Origin gFrontEnd )
				)
				( objectFlag fObjectAlias )
				( objectStatus "page230_p3v3" )
			)
			( signal "@baseboard_fab2_lib.baseboard_fab2(sch_1):page248_p3v3"
				( attribute "VOLTAGE" "3.3V"
					( Units "uVoltage" "V" 1.000000)
					( Origin gFrontEnd )
				)
				( objectFlag fObjectAlias )
				( objectStatus "page248_p3v3" )
			)
			( signal "@baseboard_fab2_lib.baseboard_fab2(sch_1):page255_p3v3"
				( attribute "VOLTAGE" "3.3V"
					( Units "uVoltage" "V" 1.000000)
					( Origin gFrontEnd )
				)
				( objectFlag fObjectAlias )
				( objectStatus "page255_p3v3" )
			)
			( signal "@baseboard_fab2_lib.baseboard_fab2(sch_1):page146_p3v3"
				( attribute "VOLTAGE" "3.3V"
					( Units "uVoltage" "V" 1.000000)
					( Origin gFrontEnd )
				)
				( objectFlag fObjectAlias )
				( objectStatus "page146_p3v3" )
			)
			( signal "@baseboard_fab2_lib.baseboard_fab2(sch_1):pwrgd_pvpp_abc"
				( attribute "CDS_PHYS_NET_NAME" "PWRGD_PVPP_ABC"
					( Origin gPackager )
				)
				( objectStatus "PWRGD_PVPP_ABC" )
			)
			( signal "@baseboard_fab2_lib.baseboard_fab2(sch_1):smb_ocp_fru_stby_lvc3_scl"
				( attribute "CDS_PHYS_NET_NAME" "SMB_OCP_FRU_STBY_LVC3_SCL"
					( Origin gPackager )
				)
				( objectStatus "SMB_OCP_FRU_STBY_LVC3_SCL" )
			)
			( signal "@baseboard_fab2_lib.baseboard_fab2(sch_1):smb_ocp_fru_stby_lvc3_sda"
				( attribute "CDS_PHYS_NET_NAME" "SMB_OCP_FRU_STBY_LVC3_SDA"
					( Origin gPackager )
				)
				( objectStatus "SMB_OCP_FRU_STBY_LVC3_SDA" )
			)
			( signal "@baseboard_fab2_lib.baseboard_fab2(sch_1):tp_hfi_io_conn0_rsvd_17"
				( attribute "CDS_PHYS_NET_NAME" "TP_HFI_IO_CONN0_RSVD_17"
					( Origin gPackager )
				)
				( objectStatus "TP_HFI_IO_CONN0_RSVD_17" )
			)
			( signal "@baseboard_fab2_lib.baseboard_fab2(sch_1):fm_cpu0_fivr_fault_lvt3"
				( attribute "CDS_PHYS_NET_NAME" "FM_CPU0_FIVR_FAULT_LVT3"
					( Origin gPackager )
				)
				( objectStatus "FM_CPU0_FIVR_FAULT_LVT3" )
			)
			( signal "@baseboard_fab2_lib.baseboard_fab2(sch_1):fm_cpu0_fivr_fault_r_lvt3"
				( attribute "CDS_PHYS_NET_NAME" "FM_CPU0_FIVR_FAULT_R_LVT3"
					( Origin gPackager )
				)
				( objectStatus "FM_CPU0_FIVR_FAULT_R_LVT3" )
			)
			( signal "@baseboard_fab2_lib.baseboard_fab2(sch_1):fm_cpu0_thermtrip_lvt3_n"
				( attribute "CDS_PHYS_NET_NAME" "FM_CPU0_THERMTRIP_LVT3_N"
					( Origin gPackager )
				)
				( objectStatus "FM_CPU0_THERMTRIP_LVT3_N" )
			)
			( signal "@baseboard_fab2_lib.baseboard_fab2(sch_1):fm_cpu0_thermtrip_lvt3_r_n"
				( attribute "CDS_PHYS_NET_NAME" "FM_CPU0_THERMTRIP_LVT3_R_N"
					( Origin gPackager )
				)
				( objectStatus "FM_CPU0_THERMTRIP_LVT3_R_N" )
			)
			( signal "@baseboard_fab2_lib.baseboard_fab2(sch_1):fm_cpu1_fivr_fault_lvt3"
				( attribute "CDS_PHYS_NET_NAME" "FM_CPU1_FIVR_FAULT_LVT3"
					( Origin gPackager )
				)
				( objectStatus "FM_CPU1_FIVR_FAULT_LVT3" )
			)
			( signal "@baseboard_fab2_lib.baseboard_fab2(sch_1):fm_cpu1_fivr_fault_r_lvt3"
				( attribute "CDS_PHYS_NET_NAME" "FM_CPU1_FIVR_FAULT_R_LVT3"
					( Origin gPackager )
				)
				( objectStatus "FM_CPU1_FIVR_FAULT_R_LVT3" )
			)
			( signal "@baseboard_fab2_lib.baseboard_fab2(sch_1):fm_cpu1_thermtrip_lvt3_n"
				( attribute "CDS_PHYS_NET_NAME" "FM_CPU1_THERMTRIP_LVT3_N"
					( Origin gPackager )
				)
				( objectStatus "FM_CPU1_THERMTRIP_LVT3_N" )
			)
			( signal "@baseboard_fab2_lib.baseboard_fab2(sch_1):fm_cpu1_thermtrip_lvt3_r_n"
				( attribute "CDS_PHYS_NET_NAME" "FM_CPU1_THERMTRIP_LVT3_R_N"
					( Origin gPackager )
				)
				( objectStatus "FM_CPU1_THERMTRIP_LVT3_R_N" )
			)
			( signal "@baseboard_fab2_lib.baseboard_fab2(sch_1):fm_cpu_caterr_lvt3_n"
				( attribute "CDS_PHYS_NET_NAME" "FM_CPU_CATERR_LVT3_N"
					( Origin gPackager )
				)
				( attribute "PHYS_NET_NAME" "FM_CPU_CATERR_LVT3_N"
					( Origin gPackager )
				)
				( objectStatus "FM_CPU_CATERR_LVT3_N" )
			)
			( signal "@baseboard_fab2_lib.baseboard_fab2(sch_1):fm_cpu_caterr_lvt3_r2_n"
				( attribute "CDS_PHYS_NET_NAME" "FM_CPU_CATERR_LVT3_R2_N"
					( Origin gPackager )
				)
				( objectStatus "FM_CPU_CATERR_LVT3_R2_N" )
			)
			( signal "@baseboard_fab2_lib.baseboard_fab2(sch_1):fm_cpu_err2_lvt3_n"
				( attribute "CDS_PHYS_NET_NAME" "FM_CPU_ERR2_LVT3_N"
					( Origin gPackager )
				)
				( attribute "PHYS_NET_NAME" "FM_CPU_ERR2_LVT3_N"
					( Origin gPackager )
				)
				( objectStatus "FM_CPU_ERR2_LVT3_N" )
			)
			( signal "@baseboard_fab2_lib.baseboard_fab2(sch_1):fm_cpu_err2_lvt3_r_n"
				( attribute "CDS_PHYS_NET_NAME" "FM_CPU_ERR2_LVT3_R_N"
					( Origin gPackager )
				)
				( objectStatus "FM_CPU_ERR2_LVT3_R_N" )
			)
			( signal "@baseboard_fab2_lib.baseboard_fab2(sch_1):fm_cpu_msmi_lvt3_n"
				( attribute "CDS_PHYS_NET_NAME" "FM_CPU_MSMI_LVT3_N"
					( Origin gPackager )
				)
				( attribute "PHYS_NET_NAME" "FM_CPU_MSMI_LVT3_N"
					( Origin gPackager )
				)
				( objectStatus "FM_CPU_MSMI_LVT3_N" )
			)
			( signal "@baseboard_fab2_lib.baseboard_fab2(sch_1):fm_cpu_msmi_lvt3_r_n"
				( attribute "CDS_PHYS_NET_NAME" "FM_CPU_MSMI_LVT3_R_N"
					( Origin gPackager )
				)
				( objectStatus "FM_CPU_MSMI_LVT3_R_N" )
			)
			( signal "@baseboard_fab2_lib.baseboard_fab2(sch_1):h_cpu_caterr_g_n"
				( attribute "CDS_PHYS_NET_NAME" "H_CPU_CATERR_G_N"
					( Origin gPackager )
				)
				( objectStatus "H_CPU_CATERR_G_N" )
			)
			( signal "@baseboard_fab2_lib.baseboard_fab2(sch_1):h_cpu_err2_g_r_n"
				( attribute "CDS_PHYS_NET_NAME" "H_CPU_ERR2_G_R_N"
					( Origin gPackager )
				)
				( objectStatus "H_CPU_ERR2_G_R_N" )
			)
			( signal "@baseboard_fab2_lib.baseboard_fab2(sch_1):h_cpu_err2_gtl_n"
				( attribute "CDS_PHYS_NET_NAME" "H_CPU_ERR2_GTL_N"
					( Origin gPackager )
				)
				( objectStatus "H_CPU_ERR2_GTL_N" )
			)
			( signal "@baseboard_fab2_lib.baseboard_fab2(sch_1):h_cpu_msmi_g_n"
				( attribute "CDS_PHYS_NET_NAME" "H_CPU_MSMI_G_N"
					( Origin gPackager )
				)
				( objectStatus "H_CPU_MSMI_G_N" )
			)
			( signal "@baseboard_fab2_lib.baseboard_fab2(sch_1):p0v7_gtl2104_vref_0"
				( alias ( signalRef "@baseboard_fab2_lib.baseboard_fab2(sch_1):page92_p0v7_gtl2104_vref_0") )
				( attribute "VOLTAGE" "+0.7 V"
					( Units "uVoltage" "V" 1.000000)
					( Status sAliasFlattened )
					( Origin gFrontEnd )
				)
				( attribute "CDS_PHYS_NET_NAME" "P0V7_GTL2104_VREF_0"
					( Origin gPackager )
				)
				( objectStatus "P0V7_GTL2104_VREF_0" )
			)
			( signal "@baseboard_fab2_lib.baseboard_fab2(sch_1):page92_p0v7_gtl2104_vref_0"
				( attribute "VOLTAGE" "+0.7 V"
					( Units "uVoltage" "V" 1.000000)
					( Origin gFrontEnd )
				)
				( objectFlag fObjectAlias )
				( objectStatus "page92_p0v7_gtl2104_vref_0" )
			)
			( signal "@baseboard_fab2_lib.baseboard_fab2(sch_1):p0v7_gtl2104_vref_1"
				( alias ( signalRef "@baseboard_fab2_lib.baseboard_fab2(sch_1):page92_p0v7_gtl2104_vref_1") )
				( attribute "VOLTAGE" "+0.7 V"
					( Units "uVoltage" "V" 1.000000)
					( Status sAliasFlattened )
					( Origin gFrontEnd )
				)
				( attribute "CDS_PHYS_NET_NAME" "P0V7_GTL2104_VREF_1"
					( Origin gPackager )
				)
				( objectStatus "P0V7_GTL2104_VREF_1" )
			)
			( signal "@baseboard_fab2_lib.baseboard_fab2(sch_1):page92_p0v7_gtl2104_vref_1"
				( attribute "VOLTAGE" "+0.7 V"
					( Units "uVoltage" "V" 1.000000)
					( Origin gFrontEnd )
				)
				( objectFlag fObjectAlias )
				( objectStatus "page92_p0v7_gtl2104_vref_1" )
			)
			( signal "@baseboard_fab2_lib.baseboard_fab2(sch_1):pd_gtl2104_dir_0"
				( attribute "CDS_PHYS_NET_NAME" "PD_GTL2104_DIR_0"
					( Origin gPackager )
				)
				( objectStatus "PD_GTL2104_DIR_0" )
			)
			( signal "@baseboard_fab2_lib.baseboard_fab2(sch_1):pd_gtl2104_dir_1"
				( attribute "CDS_PHYS_NET_NAME" "PD_GTL2104_DIR_1"
					( Origin gPackager )
				)
				( objectStatus "PD_GTL2104_DIR_1" )
			)
			( signal "@baseboard_fab2_lib.baseboard_fab2(sch_1):pwrgd_cpupwrgd"
				( attribute "CDS_PHYS_NET_NAME" "PWRGD_CPUPWRGD"
					( Origin gPackager )
				)
				( objectStatus "PWRGD_CPUPWRGD" )
			)
			( signal "@baseboard_fab2_lib.baseboard_fab2(sch_1):pwrgd_cpupwrgd_gtl"
				( attribute "CDS_PHYS_NET_NAME" "PWRGD_CPUPWRGD_GTL"
					( Origin gPackager )
				)
				( objectStatus "PWRGD_CPUPWRGD_GTL" )
			)
			( signal "@baseboard_fab2_lib.baseboard_fab2(sch_1):pwrgd_cpupwrgd_r1"
				( attribute "CDS_PHYS_NET_NAME" "PWRGD_CPUPWRGD_R1"
					( Origin gPackager )
				)
				( objectStatus "PWRGD_CPUPWRGD_R1" )
			)
			( signal "@baseboard_fab2_lib.baseboard_fab2(sch_1):fm_cpu0_prochot_lvt3_bmc_n"
				( attribute "CDS_PHYS_NET_NAME" "FM_CPU0_PROCHOT_LVT3_BMC_N"
					( Origin gPackager )
				)
				( attribute "PHYS_NET_NAME" "FM_CPU0_PROCHOT_LVT3_BMC_N"
					( Origin gPackager )
				)
				( objectStatus "FM_CPU0_PROCHOT_LVT3_BMC_N" )
			)
			( signal "@baseboard_fab2_lib.baseboard_fab2(sch_1):fm_cpu0_prochot_lvt3_k_n"
				( attribute "CDS_PHYS_NET_NAME" "FM_CPU0_PROCHOT_LVT3_K_N"
					( Origin gPackager )
				)
				( objectStatus "FM_CPU0_PROCHOT_LVT3_K_N" )
			)
			( signal "@baseboard_fab2_lib.baseboard_fab2(sch_1):fm_cpu0_prochot_lvt3_n"
				( attribute "CDS_PHYS_NET_NAME" "FM_CPU0_PROCHOT_LVT3_N"
					( Origin gPackager )
				)
				( objectStatus "FM_CPU0_PROCHOT_LVT3_N" )
			)
			( signal "@baseboard_fab2_lib.baseboard_fab2(sch_1):fm_cpu0_prochot_lvt3_r_n"
				( attribute "CDS_PHYS_NET_NAME" "FM_CPU0_PROCHOT_LVT3_R_N"
					( Origin gPackager )
				)
				( objectStatus "FM_CPU0_PROCHOT_LVT3_R_N" )
			)
			( signal "@baseboard_fab2_lib.baseboard_fab2(sch_1):fm_cpu0_prochot_pch_n"
				( attribute "CDS_PHYS_NET_NAME" "FM_CPU0_PROCHOT_PCH_N"
					( Origin gPackager )
				)
				( objectStatus "FM_CPU0_PROCHOT_PCH_N" )
			)
			( signal "@baseboard_fab2_lib.baseboard_fab2(sch_1):fm_cpu1_prochot_lvt3_bmc_n"
				( attribute "CDS_PHYS_NET_NAME" "FM_CPU1_PROCHOT_LVT3_BMC_N"
					( Origin gPackager )
				)
				( attribute "PHYS_NET_NAME" "FM_CPU1_PROCHOT_LVT3_BMC_N"
					( Origin gPackager )
				)
				( objectStatus "FM_CPU1_PROCHOT_LVT3_BMC_N" )
			)
			( signal "@baseboard_fab2_lib.baseboard_fab2(sch_1):fm_cpu1_prochot_lvt3_k_n"
				( attribute "CDS_PHYS_NET_NAME" "FM_CPU1_PROCHOT_LVT3_K_N"
					( Origin gPackager )
				)
				( objectStatus "FM_CPU1_PROCHOT_LVT3_K_N" )
			)
			( signal "@baseboard_fab2_lib.baseboard_fab2(sch_1):fm_cpu1_prochot_lvt3_n"
				( attribute "CDS_PHYS_NET_NAME" "FM_CPU1_PROCHOT_LVT3_N"
					( Origin gPackager )
				)
				( objectStatus "FM_CPU1_PROCHOT_LVT3_N" )
			)
			( signal "@baseboard_fab2_lib.baseboard_fab2(sch_1):fm_cpu1_prochot_lvt3_r_n"
				( attribute "CDS_PHYS_NET_NAME" "FM_CPU1_PROCHOT_LVT3_R_N"
					( Origin gPackager )
				)
				( objectStatus "FM_CPU1_PROCHOT_LVT3_R_N" )
			)
			( signal "@baseboard_fab2_lib.baseboard_fab2(sch_1):fm_cpu1_prochot_pch_n"
				( attribute "CDS_PHYS_NET_NAME" "FM_CPU1_PROCHOT_PCH_N"
					( Origin gPackager )
				)
				( objectStatus "FM_CPU1_PROCHOT_PCH_N" )
			)
			( signal "@baseboard_fab2_lib.baseboard_fab2(sch_1):fm_cpu_err0_lvt3_bmc_n"
				( attribute "CDS_PHYS_NET_NAME" "FM_CPU_ERR0_LVT3_BMC_N"
					( Origin gPackager )
				)
				( attribute "PHYS_NET_NAME" "FM_CPU_ERR0_LVT3_BMC_N"
					( Origin gPackager )
				)
				( objectStatus "FM_CPU_ERR0_LVT3_BMC_N" )
			)
			( signal "@baseboard_fab2_lib.baseboard_fab2(sch_1):fm_cpu_err0_lvt3_k_n"
				( attribute "CDS_PHYS_NET_NAME" "FM_CPU_ERR0_LVT3_K_N"
					( Origin gPackager )
				)
				( objectStatus "FM_CPU_ERR0_LVT3_K_N" )
			)
			( signal "@baseboard_fab2_lib.baseboard_fab2(sch_1):fm_cpu_err0_lvt3_n"
				( attribute "CDS_PHYS_NET_NAME" "FM_CPU_ERR0_LVT3_N"
					( Origin gPackager )
				)
				( objectStatus "FM_CPU_ERR0_LVT3_N" )
			)
			( signal "@baseboard_fab2_lib.baseboard_fab2(sch_1):fm_cpu_err0_lvt3_r_n"
				( attribute "CDS_PHYS_NET_NAME" "FM_CPU_ERR0_LVT3_R_N"
					( Origin gPackager )
				)
				( objectStatus "FM_CPU_ERR0_LVT3_R_N" )
			)
			( signal "@baseboard_fab2_lib.baseboard_fab2(sch_1):fm_cpu_err0_pch_n"
				( attribute "CDS_PHYS_NET_NAME" "FM_CPU_ERR0_PCH_N"
					( Origin gPackager )
				)
				( objectStatus "FM_CPU_ERR0_PCH_N" )
			)
			( signal "@baseboard_fab2_lib.baseboard_fab2(sch_1):fm_cpu_err1_lvt3_bmc_n"
				( attribute "CDS_PHYS_NET_NAME" "FM_CPU_ERR1_LVT3_BMC_N"
					( Origin gPackager )
				)
				( attribute "PHYS_NET_NAME" "FM_CPU_ERR1_LVT3_BMC_N"
					( Origin gPackager )
				)
				( objectStatus "FM_CPU_ERR1_LVT3_BMC_N" )
			)
			( signal "@baseboard_fab2_lib.baseboard_fab2(sch_1):fm_cpu_err1_lvt3_k_n"
				( attribute "CDS_PHYS_NET_NAME" "FM_CPU_ERR1_LVT3_K_N"
					( Origin gPackager )
				)
				( objectStatus "FM_CPU_ERR1_LVT3_K_N" )
			)
			( signal "@baseboard_fab2_lib.baseboard_fab2(sch_1):fm_cpu_err1_lvt3_n"
				( attribute "CDS_PHYS_NET_NAME" "FM_CPU_ERR1_LVT3_N"
					( Origin gPackager )
				)
				( objectStatus "FM_CPU_ERR1_LVT3_N" )
			)
			( signal "@baseboard_fab2_lib.baseboard_fab2(sch_1):fm_cpu_err1_lvt3_r_n"
				( attribute "CDS_PHYS_NET_NAME" "FM_CPU_ERR1_LVT3_R_N"
					( Origin gPackager )
				)
				( objectStatus "FM_CPU_ERR1_LVT3_R_N" )
			)
			( signal "@baseboard_fab2_lib.baseboard_fab2(sch_1):fm_cpu_err1_pch_n"
				( attribute "CDS_PHYS_NET_NAME" "FM_CPU_ERR1_PCH_N"
					( Origin gPackager )
				)
				( objectStatus "FM_CPU_ERR1_PCH_N" )
			)
			( signal "@baseboard_fab2_lib.baseboard_fab2(sch_1):h_cpu0_prochot_g_pch_n"
				( attribute "CDS_PHYS_NET_NAME" "H_CPU0_PROCHOT_G_PCH_N"
					( Origin gPackager )
				)
				( objectStatus "H_CPU0_PROCHOT_G_PCH_N" )
			)
			( signal "@baseboard_fab2_lib.baseboard_fab2(sch_1):h_cpu0_prochot_g_r_n"
				( attribute "CDS_PHYS_NET_NAME" "H_CPU0_PROCHOT_G_R_N"
					( Origin gPackager )
				)
				( objectStatus "H_CPU0_PROCHOT_G_R_N" )
			)
			( signal "@baseboard_fab2_lib.baseboard_fab2(sch_1):h_cpu1_prochot_g_pch_n"
				( attribute "CDS_PHYS_NET_NAME" "H_CPU1_PROCHOT_G_PCH_N"
					( Origin gPackager )
				)
				( objectStatus "H_CPU1_PROCHOT_G_PCH_N" )
			)
			( signal "@baseboard_fab2_lib.baseboard_fab2(sch_1):h_cpu1_prochot_g_r_n"
				( attribute "CDS_PHYS_NET_NAME" "H_CPU1_PROCHOT_G_R_N"
					( Origin gPackager )
				)
				( objectStatus "H_CPU1_PROCHOT_G_R_N" )
			)
			( signal "@baseboard_fab2_lib.baseboard_fab2(sch_1):h_cpu_err0_gtl_n"
				( attribute "CDS_PHYS_NET_NAME" "H_CPU_ERR0_GTL_N"
					( Origin gPackager )
				)
				( objectStatus "H_CPU_ERR0_GTL_N" )
			)
			( signal "@baseboard_fab2_lib.baseboard_fab2(sch_1):h_cpu_err0_gtl_r_n"
				( attribute "CDS_PHYS_NET_NAME" "H_CPU_ERR0_GTL_R_N"
					( Origin gPackager )
				)
				( objectStatus "H_CPU_ERR0_GTL_R_N" )
			)
			( signal "@baseboard_fab2_lib.baseboard_fab2(sch_1):h_cpu_err0_pch_n"
				( attribute "CDS_PHYS_NET_NAME" "H_CPU_ERR0_PCH_N"
					( Origin gPackager )
				)
				( objectStatus "H_CPU_ERR0_PCH_N" )
			)
			( signal "@baseboard_fab2_lib.baseboard_fab2(sch_1):h_cpu_err1_gtl_n"
				( attribute "CDS_PHYS_NET_NAME" "H_CPU_ERR1_GTL_N"
					( Origin gPackager )
				)
				( objectStatus "H_CPU_ERR1_GTL_N" )
			)
			( signal "@baseboard_fab2_lib.baseboard_fab2(sch_1):h_cpu_err1_gtl_r_n"
				( attribute "CDS_PHYS_NET_NAME" "H_CPU_ERR1_GTL_R_N"
					( Origin gPackager )
				)
				( objectStatus "H_CPU_ERR1_GTL_R_N" )
			)
			( signal "@baseboard_fab2_lib.baseboard_fab2(sch_1):h_cpu_err1_pch_n"
				( attribute "CDS_PHYS_NET_NAME" "H_CPU_ERR1_PCH_N"
					( Origin gPackager )
				)
				( objectStatus "H_CPU_ERR1_PCH_N" )
			)
			( signal "@baseboard_fab2_lib.baseboard_fab2(sch_1):p0v7_gtl2104_5_vref"
				( alias ( signalRef "@baseboard_fab2_lib.baseboard_fab2(sch_1):page93_p0v7_gtl2104_5_vref") )
				( attribute "VOLTAGE" "0.734"
					( Units "uVoltage" "V" 1.000000)
					( Status sAliasFlattened )
					( Origin gFrontEnd )
				)
				( attribute "CDS_PHYS_NET_NAME" "P0V7_GTL2104_5_VREF"
					( Origin gPackager )
				)
				( objectStatus "P0V7_GTL2104_5_VREF" )
			)
			( signal "@baseboard_fab2_lib.baseboard_fab2(sch_1):page93_p0v7_gtl2104_5_vref"
				( attribute "VOLTAGE" "0.734"
					( Units "uVoltage" "V" 1.000000)
					( Origin gFrontEnd )
				)
				( objectFlag fObjectAlias )
				( objectStatus "page93_p0v7_gtl2104_5_vref" )
			)
			( signal "@baseboard_fab2_lib.baseboard_fab2(sch_1):pd_gtl2104_4_dir"
				( attribute "CDS_PHYS_NET_NAME" "PD_GTL2104_4_DIR"
					( Origin gPackager )
				)
				( objectStatus "PD_GTL2104_4_DIR" )
			)
			( signal "@baseboard_fab2_lib.baseboard_fab2(sch_1):fm_dimm_event_fet"
				( attribute "CDS_PHYS_NET_NAME" "FM_DIMM_EVENT_FET"
					( Origin gPackager )
				)
				( objectStatus "FM_DIMM_EVENT_FET" )
			)
			( signal "@baseboard_fab2_lib.baseboard_fab2(sch_1):fm_mem_therm_event_lvt3_n"
				( attribute "CDS_PHYS_NET_NAME" "FM_MEM_THERM_EVENT_LVT3_N"
					( Origin gPackager )
				)
				( objectStatus "FM_MEM_THERM_EVENT_LVT3_N" )
			)
			( signal "@baseboard_fab2_lib.baseboard_fab2(sch_1):h_cpu0_memabc_memhot"
				( attribute "CDS_PHYS_NET_NAME" "H_CPU0_MEMABC_MEMHOT"
					( Origin gPackager )
				)
				( objectStatus "H_CPU0_MEMABC_MEMHOT" )
			)
			( signal "@baseboard_fab2_lib.baseboard_fab2(sch_1):h_cpu0_memdef_memhot"
				( attribute "CDS_PHYS_NET_NAME" "H_CPU0_MEMDEF_MEMHOT"
					( Origin gPackager )
				)
				( objectStatus "H_CPU0_MEMDEF_MEMHOT" )
			)
			( signal "@baseboard_fab2_lib.baseboard_fab2(sch_1):h_cpu1_memghj_memhot"
				( attribute "CDS_PHYS_NET_NAME" "H_CPU1_MEMGHJ_MEMHOT"
					( Origin gPackager )
				)
				( objectStatus "H_CPU1_MEMGHJ_MEMHOT" )
			)
			( signal "@baseboard_fab2_lib.baseboard_fab2(sch_1):h_cpu1_memklm_memhot"
				( attribute "CDS_PHYS_NET_NAME" "H_CPU1_MEMKLM_MEMHOT"
					( Origin gPackager )
				)
				( objectStatus "H_CPU1_MEMKLM_MEMHOT" )
			)
			( signal "@baseboard_fab2_lib.baseboard_fab2(sch_1):irq_pvddq_abc_vrhot_lvt3_n"
				( attribute "CDS_PHYS_NET_NAME" "IRQ_PVDDQ_ABC_VRHOT_LVT3_N"
					( Origin gPackager )
				)
				( attribute "PHYS_NET_NAME" "IRQ_PVDDQ_ABC_VRHOT_LVT3_N"
					( Origin gPackager )
				)
				( objectStatus "IRQ_PVDDQ_ABC_VRHOT_LVT3_N" )
			)
			( signal "@baseboard_fab2_lib.baseboard_fab2(sch_1):irq_pvddq_def_vrhot_lvt3_n"
				( alias ( signalRef "@baseboard_fab2_lib.baseboard_fab2(sch_1):page146_irq_pvddq_def_vrhot_lvt3_n") )
				( attribute "CDS_PHYS_NET_NAME" "IRQ_PVDDQ_DEF_VRHOT_LVT3_N"
					( Origin gPackager )
				)
				( attribute "PHYS_NET_NAME" "IRQ_PVDDQ_DEF_VRHOT_LVT3_N"
					( Origin gPackager )
				)
				( objectStatus "IRQ_PVDDQ_DEF_VRHOT_LVT3_N" )
			)
			( signal "@baseboard_fab2_lib.baseboard_fab2(sch_1):page146_irq_pvddq_def_vrhot_lvt3_n"
				( attribute "CDS_PHYS_NET_NAME" "IRQ_PVDDQ_DEF_VRHOT_LVT3_N"
					( Origin gPackager )
				)
				( attribute "PHYS_NET_NAME" "IRQ_PVDDQ_DEF_VRHOT_LVT3_N"
					( Origin gPackager )
				)
				( objectFlag fObjectAlias )
				( objectStatus "page146_irq_pvddq_def_vrhot_lvt3_n" )
			)
			( signal "@baseboard_fab2_lib.baseboard_fab2(sch_1):sp1_bmc_host_uart_rx"
				( attribute "CDS_PHYS_NET_NAME" "SP1_BMC_HOST_UART_RX"
					( Origin gPackager )
				)
				( attribute "PHYS_NET_NAME" "SP1_BMC_HOST_UART_RX"
					( Origin gPackager )
				)
				( objectStatus "SP1_BMC_HOST_UART_RX" )
			)
			( signal "@baseboard_fab2_lib.baseboard_fab2(sch_1):fm_bmc_nmi_n_r"
				( attribute "CDS_PHYS_NET_NAME" "FM_BMC_NMI_N_R"
					( Origin gPackager )
				)
				( objectStatus "FM_BMC_NMI_N_R" )
			)
			( signal "@baseboard_fab2_lib.baseboard_fab2(sch_1):irq_pvddq_ghj_vrhot_lvt3_n"
				( attribute "CDS_PHYS_NET_NAME" "IRQ_PVDDQ_GHJ_VRHOT_LVT3_N"
					( Origin gPackager )
				)
				( attribute "PHYS_NET_NAME" "IRQ_PVDDQ_GHJ_VRHOT_LVT3_N"
					( Origin gPackager )
				)
				( objectStatus "IRQ_PVDDQ_GHJ_VRHOT_LVT3_N" )
			)
			( signal "@baseboard_fab2_lib.baseboard_fab2(sch_1):pd_sp_entest"
				( attribute "CDS_PHYS_NET_NAME" "PD_SP_ENTEST"
					( Origin gPackager )
				)
				( objectStatus "PD_SP_ENTEST" )
			)
			( signal "@baseboard_fab2_lib.baseboard_fab2(sch_1):sp1_bmc_host_uart_tx"
				( attribute "CDS_PHYS_NET_NAME" "SP1_BMC_HOST_UART_TX"
					( Origin gPackager )
				)
				( attribute "PHYS_NET_NAME" "SP1_BMC_HOST_UART_TX"
					( Origin gPackager )
				)
				( objectStatus "SP1_BMC_HOST_UART_TX" )
			)
			( signal "@baseboard_fab2_lib.baseboard_fab2(sch_1):p2e_ssb_bmc_rx_dp"
				( attribute "CDS_PHYS_NET_NAME" "P2E_SSB_BMC_RX_DP"
					( Origin gPackager )
				)
				( objectStatus "P2E_SSB_BMC_RX_DP" )
			)
			( signal "@baseboard_fab2_lib.baseboard_fab2(sch_1):peci_bmc"
				( attribute "CDS_PHYS_NET_NAME" "PECI_BMC"
					( Origin gPackager )
				)
				( objectStatus "PECI_BMC" )
			)
			( signal "@baseboard_fab2_lib.baseboard_fab2(sch_1):tp_tpm_spi_6"
				( attribute "CDS_PHYS_NET_NAME" "TP_TPM_SPI_6"
					( Origin gPackager )
				)
				( objectStatus "TP_TPM_SPI_6" )
			)
			( signal "@baseboard_fab2_lib.baseboard_fab2(sch_1):tp_tpm_spi_3"
				( attribute "CDS_PHYS_NET_NAME" "TP_TPM_SPI_3"
					( Origin gPackager )
				)
				( objectStatus "TP_TPM_SPI_3" )
			)
			( signal "@baseboard_fab2_lib.baseboard_fab2(sch_1):irq_pvddq_klm_vrhot_lvt3_n"
				( attribute "CDS_PHYS_NET_NAME" "IRQ_PVDDQ_KLM_VRHOT_LVT3_N"
					( Origin gPackager )
				)
				( attribute "PHYS_NET_NAME" "IRQ_PVDDQ_KLM_VRHOT_LVT3_N"
					( Origin gPackager )
				)
				( objectStatus "IRQ_PVDDQ_KLM_VRHOT_LVT3_N" )
			)
			( signal "@baseboard_fab2_lib.baseboard_fab2(sch_1):page148_p3v3_usb2a_alg"
				( objectFlag fObjectAlias )
				( objectStatus "page148_p3v3_usb2a_alg" )
			)
			( signal "@baseboard_fab2_lib.baseboard_fab2(sch_1):fm_pvccin_cpu0_pwr_in_alert_n"
				( attribute "CDS_PHYS_NET_NAME" "FM_PVCCIN_CPU0_PWR_IN_ALERT_N"
					( Origin gPackager )
				)
				( objectStatus "FM_PVCCIN_CPU0_PWR_IN_ALERT_N" )
			)
			( signal "@baseboard_fab2_lib.baseboard_fab2(sch_1):fm_pvccin_cpu1_pwr_in_alert_n"
				( attribute "CDS_PHYS_NET_NAME" "FM_PVCCIN_CPU1_PWR_IN_ALERT_N"
					( Origin gPackager )
				)
				( objectStatus "FM_PVCCIN_CPU1_PWR_IN_ALERT_N" )
			)
			( signal "@baseboard_fab2_lib.baseboard_fab2(sch_1):fm_pwrbrk_n"
				( attribute "CDS_PHYS_NET_NAME" "FM_PWRBRK_N"
					( Origin gPackager )
				)
				( objectStatus "FM_PWRBRK_N" )
			)
			( signal "@baseboard_fab2_lib.baseboard_fab2(sch_1):fm_sys_throttle_lvc3"
				( attribute "CDS_PHYS_NET_NAME" "FM_SYS_THROTTLE_LVC3"
					( Origin gPackager )
				)
				( objectStatus "FM_SYS_THROTTLE_LVC3" )
			)
			( signal "@baseboard_fab2_lib.baseboard_fab2(sch_1):fm_throttle_n"
				( attribute "CDS_PHYS_NET_NAME" "FM_THROTTLE_N"
					( Origin gPackager )
				)
				( attribute "PHYS_NET_NAME" "FM_THROTTLE_N"
					( Origin gPackager )
				)
				( objectStatus "FM_THROTTLE_N" )
			)
			( signal "@baseboard_fab2_lib.baseboard_fab2(sch_1):fm_throttle_r_n"
				( attribute "CDS_PHYS_NET_NAME" "FM_THROTTLE_R_N"
					( Origin gPackager )
				)
				( objectStatus "FM_THROTTLE_R_N" )
			)
			( signal "@baseboard_fab2_lib.baseboard_fab2(sch_1):irq_cpu0_prochot_g_n"
				( attribute "CDS_PHYS_NET_NAME" "IRQ_CPU0_PROCHOT_G_N"
					( Origin gPackager )
				)
				( objectStatus "IRQ_CPU0_PROCHOT_G_N" )
			)
			( signal "@baseboard_fab2_lib.baseboard_fab2(sch_1):irq_cpu0_vrhot"
				( attribute "CDS_PHYS_NET_NAME" "IRQ_CPU0_VRHOT"
					( Origin gPackager )
				)
				( objectStatus "IRQ_CPU0_VRHOT" )
			)
			( signal "@baseboard_fab2_lib.baseboard_fab2(sch_1):irq_cpu1_prochot_g_n"
				( attribute "CDS_PHYS_NET_NAME" "IRQ_CPU1_PROCHOT_G_N"
					( Origin gPackager )
				)
				( objectStatus "IRQ_CPU1_PROCHOT_G_N" )
			)
			( signal "@baseboard_fab2_lib.baseboard_fab2(sch_1):irq_cpu1_vrhot"
				( attribute "CDS_PHYS_NET_NAME" "IRQ_CPU1_VRHOT"
					( Origin gPackager )
				)
				( objectStatus "IRQ_CPU1_VRHOT" )
			)
			( signal "@baseboard_fab2_lib.baseboard_fab2(sch_1):irq_pvccin_cpu0_vrhot_lvc3_n"
				( attribute "CDS_PHYS_NET_NAME" "IRQ_PVCCIN_CPU0_VRHOT_LVC3_N"
					( Origin gPackager )
				)
				( attribute "PHYS_NET_NAME" "IRQ_PVCCIN_CPU0_VRHOT_LVC3_N"
					( Origin gPackager )
				)
				( objectStatus "IRQ_PVCCIN_CPU0_VRHOT_LVC3_N" )
			)
			( signal "@baseboard_fab2_lib.baseboard_fab2(sch_1):irq_pvccin_cpu1_vrhot_lvc3_n"
				( attribute "CDS_PHYS_NET_NAME" "IRQ_PVCCIN_CPU1_VRHOT_LVC3_N"
					( Origin gPackager )
				)
				( attribute "PHYS_NET_NAME" "IRQ_PVCCIN_CPU1_VRHOT_LVC3_N"
					( Origin gPackager )
				)
				( objectStatus "IRQ_PVCCIN_CPU1_VRHOT_LVC3_N" )
			)
			( signal "@baseboard_fab2_lib.baseboard_fab2(sch_1):pd_gtl2014_1_vref"
				( attribute "CDS_PHYS_NET_NAME" "PD_GTL2014_1_VREF"
					( Origin gPackager )
				)
				( objectStatus "PD_GTL2014_1_VREF" )
			)
			( signal "@baseboard_fab2_lib.baseboard_fab2(sch_1):pd_gtl2014_2_vref"
				( attribute "CDS_PHYS_NET_NAME" "PD_GTL2014_2_VREF"
					( Origin gPackager )
				)
				( objectStatus "PD_GTL2014_2_VREF" )
			)
			( signal "@baseboard_fab2_lib.baseboard_fab2(sch_1):pu_gtl2014_1_dir"
				( attribute "CDS_PHYS_NET_NAME" "PU_GTL2014_1_DIR"
					( Origin gPackager )
				)
				( objectStatus "PU_GTL2014_1_DIR" )
			)
			( signal "@baseboard_fab2_lib.baseboard_fab2(sch_1):pu_gtl2014_2_dir"
				( attribute "CDS_PHYS_NET_NAME" "PU_GTL2014_2_DIR"
					( Origin gPackager )
				)
				( objectStatus "PU_GTL2014_2_DIR" )
			)
			( signal "@baseboard_fab2_lib.baseboard_fab2(sch_1):pwrgd_cpu0_lvc3"
				( attribute "CDS_PHYS_NET_NAME" "PWRGD_CPU0_LVC3"
					( Origin gPackager )
				)
				( objectStatus "PWRGD_CPU0_LVC3" )
			)
			( signal "@baseboard_fab2_lib.baseboard_fab2(sch_1):pwrgd_cpu1_lvc3"
				( attribute "CDS_PHYS_NET_NAME" "PWRGD_CPU1_LVC3"
					( Origin gPackager )
				)
				( objectStatus "PWRGD_CPU1_LVC3" )
			)
			( signal "@baseboard_fab2_lib.baseboard_fab2(sch_1):pwrgd_drampwrgd"
				( attribute "CDS_PHYS_NET_NAME" "PWRGD_DRAMPWRGD"
					( Origin gPackager )
				)
				( objectStatus "PWRGD_DRAMPWRGD" )
			)
			( signal "@baseboard_fab2_lib.baseboard_fab2(sch_1):rst_cpu0_lvc3_n"
				( attribute "CDS_PHYS_NET_NAME" "RST_CPU0_LVC3_N"
					( Origin gPackager )
				)
				( objectStatus "RST_CPU0_LVC3_N" )
			)
			( signal "@baseboard_fab2_lib.baseboard_fab2(sch_1):rst_cpu1_lvc3_n"
				( attribute "CDS_PHYS_NET_NAME" "RST_CPU1_LVC3_N"
					( Origin gPackager )
				)
				( objectStatus "RST_CPU1_LVC3_N" )
			)
			( signal "@baseboard_fab2_lib.baseboard_fab2(sch_1):smb_ddr_abc_scl_g"
				( attribute "CDS_PHYS_NET_NAME" "SMB_DDR_ABC_SCL_G"
					( Origin gPackager )
				)
				( objectStatus "SMB_DDR_ABC_SCL_G" )
			)
			( signal "@baseboard_fab2_lib.baseboard_fab2(sch_1):smb_ddr_abc_sda_g"
				( attribute "CDS_PHYS_NET_NAME" "SMB_DDR_ABC_SDA_G"
					( Origin gPackager )
				)
				( objectStatus "SMB_DDR_ABC_SDA_G" )
			)
			( signal "@baseboard_fab2_lib.baseboard_fab2(sch_1):smb_ddr_abc_vpp_scl_r"
				( attribute "CDS_PHYS_NET_NAME" "SMB_DDR_ABC_VPP_SCL_R"
					( Origin gPackager )
				)
				( objectStatus "SMB_DDR_ABC_VPP_SCL_R" )
			)
			( signal "@baseboard_fab2_lib.baseboard_fab2(sch_1):smb_ddr_abc_vpp_sda_r"
				( attribute "CDS_PHYS_NET_NAME" "SMB_DDR_ABC_VPP_SDA_R"
					( Origin gPackager )
				)
				( objectStatus "SMB_DDR_ABC_VPP_SDA_R" )
			)
			( signal "@baseboard_fab2_lib.baseboard_fab2(sch_1):smb_ddr_def_scl_g"
				( attribute "CDS_PHYS_NET_NAME" "SMB_DDR_DEF_SCL_G"
					( Origin gPackager )
				)
				( objectStatus "SMB_DDR_DEF_SCL_G" )
			)
			( signal "@baseboard_fab2_lib.baseboard_fab2(sch_1):smb_ddr_def_sda_g"
				( attribute "CDS_PHYS_NET_NAME" "SMB_DDR_DEF_SDA_G"
					( Origin gPackager )
				)
				( objectStatus "SMB_DDR_DEF_SDA_G" )
			)
			( signal "@baseboard_fab2_lib.baseboard_fab2(sch_1):smb_ddr_def_vpp_scl_r"
				( attribute "CDS_PHYS_NET_NAME" "SMB_DDR_DEF_VPP_SCL_R"
					( Origin gPackager )
				)
				( objectStatus "SMB_DDR_DEF_VPP_SCL_R" )
			)
			( signal "@baseboard_fab2_lib.baseboard_fab2(sch_1):smb_ddr_def_vpp_sda_r"
				( attribute "CDS_PHYS_NET_NAME" "SMB_DDR_DEF_VPP_SDA_R"
					( Origin gPackager )
				)
				( objectStatus "SMB_DDR_DEF_VPP_SDA_R" )
			)
			( signal "@baseboard_fab2_lib.baseboard_fab2(sch_1):smb_ddr_ghj_scl_g"
				( attribute "CDS_PHYS_NET_NAME" "SMB_DDR_GHJ_SCL_G"
					( Origin gPackager )
				)
				( objectStatus "SMB_DDR_GHJ_SCL_G" )
			)
			( signal "@baseboard_fab2_lib.baseboard_fab2(sch_1):smb_ddr_ghj_sda_g"
				( attribute "CDS_PHYS_NET_NAME" "SMB_DDR_GHJ_SDA_G"
					( Origin gPackager )
				)
				( objectStatus "SMB_DDR_GHJ_SDA_G" )
			)
			( signal "@baseboard_fab2_lib.baseboard_fab2(sch_1):smb_ddr_ghj_vpp_scl_r"
				( attribute "CDS_PHYS_NET_NAME" "SMB_DDR_GHJ_VPP_SCL_R"
					( Origin gPackager )
				)
				( objectStatus "SMB_DDR_GHJ_VPP_SCL_R" )
			)
			( signal "@baseboard_fab2_lib.baseboard_fab2(sch_1):smb_ddr_ghj_vpp_sda_r"
				( attribute "CDS_PHYS_NET_NAME" "SMB_DDR_GHJ_VPP_SDA_R"
					( Origin gPackager )
				)
				( objectStatus "SMB_DDR_GHJ_VPP_SDA_R" )
			)
			( signal "@baseboard_fab2_lib.baseboard_fab2(sch_1):smb_ddr_klm_scl_g"
				( attribute "CDS_PHYS_NET_NAME" "SMB_DDR_KLM_SCL_G"
					( Origin gPackager )
				)
				( objectStatus "SMB_DDR_KLM_SCL_G" )
			)
			( signal "@baseboard_fab2_lib.baseboard_fab2(sch_1):smb_ddr_klm_sda_g"
				( attribute "CDS_PHYS_NET_NAME" "SMB_DDR_KLM_SDA_G"
					( Origin gPackager )
				)
				( objectStatus "SMB_DDR_KLM_SDA_G" )
			)
			( signal "@baseboard_fab2_lib.baseboard_fab2(sch_1):smb_ddr_klm_vpp_scl_r"
				( attribute "CDS_PHYS_NET_NAME" "SMB_DDR_KLM_VPP_SCL_R"
					( Origin gPackager )
				)
				( objectStatus "SMB_DDR_KLM_VPP_SCL_R" )
			)
			( signal "@baseboard_fab2_lib.baseboard_fab2(sch_1):smb_ddr_klm_vpp_sda_r"
				( attribute "CDS_PHYS_NET_NAME" "SMB_DDR_KLM_VPP_SDA_R"
					( Origin gPackager )
				)
				( objectStatus "SMB_DDR_KLM_VPP_SDA_R" )
			)
			( signal "@baseboard_fab2_lib.baseboard_fab2(sch_1):tp_smb_ddr_abc_en"
				( attribute "CDS_PHYS_NET_NAME" "TP_SMB_DDR_ABC_EN"
					( Origin gPackager )
				)
				( objectStatus "TP_SMB_DDR_ABC_EN" )
			)
			( signal "@baseboard_fab2_lib.baseboard_fab2(sch_1):tp_smb_ddr_def_en"
				( attribute "CDS_PHYS_NET_NAME" "TP_SMB_DDR_DEF_EN"
					( Origin gPackager )
				)
				( objectStatus "TP_SMB_DDR_DEF_EN" )
			)
			( signal "@baseboard_fab2_lib.baseboard_fab2(sch_1):tp_smb_ddr_ghj_en"
				( attribute "CDS_PHYS_NET_NAME" "TP_SMB_DDR_GHJ_EN"
					( Origin gPackager )
				)
				( objectStatus "TP_SMB_DDR_GHJ_EN" )
			)
			( signal "@baseboard_fab2_lib.baseboard_fab2(sch_1):tp_smb_ddr_klm_en"
				( attribute "CDS_PHYS_NET_NAME" "TP_SMB_DDR_KLM_EN"
					( Origin gPackager )
				)
				( objectStatus "TP_SMB_DDR_KLM_EN" )
			)
			( signal "@baseboard_fab2_lib.baseboard_fab2(sch_1):a_comp_ckmng"
				( attribute "CDS_PHYS_NET_NAME" "A_COMP_CKMNG"
					( Origin gPackager )
				)
				( objectStatus "A_COMP_CKMNG" )
			)
			( signal "@baseboard_fab2_lib.baseboard_fab2(sch_1):clk_25m_bmc"
				( attribute "CDS_PHYS_NET_NAME" "CLK_25M_BMC"
					( Origin gPackager )
				)
				( objectStatus "CLK_25M_BMC" )
			)
			( signal "@baseboard_fab2_lib.baseboard_fab2(sch_1):clk_25m_bmc_r"
				( attribute "CDS_PHYS_NET_NAME" "CLK_25M_BMC_R"
					( Origin gPackager )
				)
				( objectStatus "CLK_25M_BMC_R" )
			)
			( signal "@baseboard_fab2_lib.baseboard_fab2(sch_1):clk_25m_cpld"
				( attribute "CDS_PHYS_NET_NAME" "CLK_25M_CPLD"
					( Origin gPackager )
				)
				( objectStatus "CLK_25M_CPLD" )
			)
			( signal "@baseboard_fab2_lib.baseboard_fab2(sch_1):clk_25m_cpld_r"
				( attribute "CDS_PHYS_NET_NAME" "CLK_25M_CPLD_R"
					( Origin gPackager )
				)
				( objectStatus "CLK_25M_CPLD_R" )
			)
			( signal "@baseboard_fab2_lib.baseboard_fab2(sch_1):clk_32k_susclk_pld"
				( attribute "CDS_PHYS_NET_NAME" "CLK_32K_SUSCLK_PLD"
					( Origin gPackager )
				)
				( objectStatus "CLK_32K_SUSCLK_PLD" )
			)
			( signal "@baseboard_fab2_lib.baseboard_fab2(sch_1):clk_32k_susclk_pld_r"
				( attribute "CDS_PHYS_NET_NAME" "CLK_32K_SUSCLK_PLD_R"
					( Origin gPackager )
				)
				( objectStatus "CLK_32K_SUSCLK_PLD_R" )
			)
			( signal "@baseboard_fab2_lib.baseboard_fab2(sch_1):clk_50m_ckmng_bmc_1"
				( alias ( signalRef "@baseboard_fab2_lib.baseboard_fab2(sch_1):page147_clk_50m_ckmng_bmc_1") )
				( attribute "CDS_PHYS_NET_NAME" "CLK_50M_CKMNG_BMC_1"
					( Origin gPackager )
				)
				( attribute "PHYS_NET_NAME" "CLK_50M_CKMNG_BMC_1"
					( Origin gPackager )
				)
				( objectStatus "CLK_50M_CKMNG_BMC_1" )
			)
			( signal "@baseboard_fab2_lib.baseboard_fab2(sch_1):page147_clk_50m_ckmng_bmc_1"
				( attribute "CDS_PHYS_NET_NAME" "CLK_50M_CKMNG_BMC_1"
					( Origin gPackager )
				)
				( attribute "PHYS_NET_NAME" "CLK_50M_CKMNG_BMC_1"
					( Origin gPackager )
				)
				( objectFlag fObjectAlias )
				( objectStatus "page147_clk_50m_ckmng_bmc_1" )
			)
			( signal "@baseboard_fab2_lib.baseboard_fab2(sch_1):clk_50m_ckmng_bmc_1_r"
				( attribute "CDS_PHYS_NET_NAME" "CLK_50M_CKMNG_BMC_1_R"
					( Origin gPackager )
				)
				( objectStatus "CLK_50M_CKMNG_BMC_1_R" )
			)
			( signal "@baseboard_fab2_lib.baseboard_fab2(sch_1):clk_50m_ckmng_bmc_2"
				( alias ( signalRef "@baseboard_fab2_lib.baseboard_fab2(sch_1):page147_clk_50m_ckmng_bmc_2") )
				( attribute "CDS_PHYS_NET_NAME" "CLK_50M_CKMNG_BMC_2"
					( Origin gPackager )
				)
				( attribute "PHYS_NET_NAME" "CLK_50M_CKMNG_BMC_2"
					( Origin gPackager )
				)
				( objectStatus "CLK_50M_CKMNG_BMC_2" )
			)
			( signal "@baseboard_fab2_lib.baseboard_fab2(sch_1):page147_clk_50m_ckmng_bmc_2"
				( attribute "CDS_PHYS_NET_NAME" "CLK_50M_CKMNG_BMC_2"
					( Origin gPackager )
				)
				( attribute "PHYS_NET_NAME" "CLK_50M_CKMNG_BMC_2"
					( Origin gPackager )
				)
				( objectFlag fObjectAlias )
				( objectStatus "page147_clk_50m_ckmng_bmc_2" )
			)
			( signal "@baseboard_fab2_lib.baseboard_fab2(sch_1):clk_50m_ckmng_bmc_2_r"
				( attribute "CDS_PHYS_NET_NAME" "CLK_50M_CKMNG_BMC_2_R"
					( Origin gPackager )
				)
				( objectStatus "CLK_50M_CKMNG_BMC_2_R" )
			)
			( signal "@baseboard_fab2_lib.baseboard_fab2(sch_1):clk_50m_ckmng_ocp"
				( attribute "CDS_PHYS_NET_NAME" "CLK_50M_CKMNG_OCP"
					( Origin gPackager )
				)
				( objectStatus "CLK_50M_CKMNG_OCP" )
			)
			( signal "@baseboard_fab2_lib.baseboard_fab2(sch_1):clk_50m_ckmng_ocp_r"
				( attribute "CDS_PHYS_NET_NAME" "CLK_50M_CKMNG_OCP_R"
					( Origin gPackager )
				)
				( objectStatus "CLK_50M_CKMNG_OCP_R" )
			)
			( signal "@baseboard_fab2_lib.baseboard_fab2(sch_1):clk_50m_ckmng_pch_10gbe"
				( attribute "CDS_PHYS_NET_NAME" "CLK_50M_CKMNG_PCH_10GBE"
					( Origin gPackager )
				)
				( objectStatus "CLK_50M_CKMNG_PCH_10GBE" )
			)
			( signal "@baseboard_fab2_lib.baseboard_fab2(sch_1):clk_50m_ckmng_pch_10gbe_r"
				( attribute "CDS_PHYS_NET_NAME" "CLK_50M_CKMNG_PCH_10GBE_R"
					( Origin gPackager )
				)
				( objectStatus "CLK_50M_CKMNG_PCH_10GBE_R" )
			)
			( signal "@baseboard_fab2_lib.baseboard_fab2(sch_1):clk_50m_ckmng_sprvlle"
				( attribute "CDS_PHYS_NET_NAME" "CLK_50M_CKMNG_SPRVLLE"
					( Origin gPackager )
				)
				( objectStatus "CLK_50M_CKMNG_SPRVLLE" )
			)
			( signal "@baseboard_fab2_lib.baseboard_fab2(sch_1):clk_50m_ckmng_sprvlle_r"
				( attribute "CDS_PHYS_NET_NAME" "CLK_50M_CKMNG_SPRVLLE_R"
					( Origin gPackager )
				)
				( objectStatus "CLK_50M_CKMNG_SPRVLLE_R" )
			)
			( signal "@baseboard_fab2_lib.baseboard_fab2(sch_1):p3v3_stby_mng"
				( alias ( signalRef "@baseboard_fab2_lib.baseboard_fab2(sch_1):page101_p3v3_stby_mng") )
				( attribute "VOLTAGE" "5"
					( Units "uVoltage" "V" 1.000000)
					( Status sAliasFlattened )
					( Origin gFrontEnd )
				)
				( attribute "CDS_PHYS_NET_NAME" "P3V3_STBY_MNG"
					( Origin gPackager )
				)
				( objectStatus "P3V3_STBY_MNG" )
			)
			( signal "@baseboard_fab2_lib.baseboard_fab2(sch_1):page101_p3v3_stby_mng"
				( attribute "VOLTAGE" "5"
					( Units "uVoltage" "V" 1.000000)
					( Origin gFrontEnd )
				)
				( objectFlag fObjectAlias )
				( objectStatus "page101_p3v3_stby_mng" )
			)
			( signal "@baseboard_fab2_lib.baseboard_fab2(sch_1):p3v3_stby_mng_cpu"
				( alias ( signalRef "@baseboard_fab2_lib.baseboard_fab2(sch_1):page101_p3v3_stby_mng_cpu") )
				( attribute "VOLTAGE" "3.3"
					( Units "uVoltage" "V" 1.000000)
					( Status sAliasFlattened )
					( Origin gFrontEnd )
				)
				( attribute "CDS_PHYS_NET_NAME" "P3V3_STBY_MNG_CPU"
					( Origin gPackager )
				)
				( objectStatus "P3V3_STBY_MNG_CPU" )
			)
			( signal "@baseboard_fab2_lib.baseboard_fab2(sch_1):page101_p3v3_stby_mng_cpu"
				( attribute "VOLTAGE" "3.3"
					( Units "uVoltage" "V" 1.000000)
					( Origin gFrontEnd )
				)
				( objectFlag fObjectAlias )
				( objectStatus "page101_p3v3_stby_mng_cpu" )
			)
			( signal "@baseboard_fab2_lib.baseboard_fab2(sch_1):p3v3_stby_mng_rgmii"
				( alias ( signalRef "@baseboard_fab2_lib.baseboard_fab2(sch_1):page101_p3v3_stby_mng_rgmii") )
				( attribute "VOLTAGE" "3.3"
					( Units "uVoltage" "V" 1.000000)
					( Status sAliasFlattened )
					( Origin gFrontEnd )
				)
				( attribute "CDS_PHYS_NET_NAME" "P3V3_STBY_MNG_RGMII"
					( Origin gPackager )
				)
				( objectStatus "P3V3_STBY_MNG_RGMII" )
			)
			( signal "@baseboard_fab2_lib.baseboard_fab2(sch_1):page101_p3v3_stby_mng_rgmii"
				( attribute "VOLTAGE" "3.3"
					( Units "uVoltage" "V" 1.000000)
					( Origin gFrontEnd )
				)
				( objectFlag fObjectAlias )
				( objectStatus "page101_p3v3_stby_mng_rgmii" )
			)
			( signal "@baseboard_fab2_lib.baseboard_fab2(sch_1):p3v3_stby_mng_rmii"
				( alias ( signalRef "@baseboard_fab2_lib.baseboard_fab2(sch_1):page101_p3v3_stby_mng_rmii") )
				( attribute "VOLTAGE" "3.3"
					( Units "uVoltage" "V" 1.000000)
					( Status sAliasFlattened )
					( Origin gFrontEnd )
				)
				( attribute "CDS_PHYS_NET_NAME" "P3V3_STBY_MNG_RMII"
					( Origin gPackager )
				)
				( objectStatus "P3V3_STBY_MNG_RMII" )
			)
			( signal "@baseboard_fab2_lib.baseboard_fab2(sch_1):page101_p3v3_stby_mng_rmii"
				( attribute "VOLTAGE" "3.3"
					( Units "uVoltage" "V" 1.000000)
					( Origin gFrontEnd )
				)
				( objectFlag fObjectAlias )
				( objectStatus "page101_p3v3_stby_mng_rmii" )
			)
			( signal "@baseboard_fab2_lib.baseboard_fab2(sch_1):pd_ckmng_oe"
				( attribute "CDS_PHYS_NET_NAME" "PD_CKMNG_OE"
					( Origin gPackager )
				)
				( objectStatus "PD_CKMNG_OE" )
			)
			( signal "@baseboard_fab2_lib.baseboard_fab2(sch_1):pwrgd_p3v3_stby"
				( attribute "CDS_PHYS_NET_NAME" "PWRGD_P3V3_STBY"
					( Origin gPackager )
				)
				( objectStatus "PWRGD_P3V3_STBY" )
			)
			( signal "@baseboard_fab2_lib.baseboard_fab2(sch_1):smb_host_stby_lvc3_scl"
				( attribute "CDS_PHYS_NET_NAME" "SMB_HOST_STBY_LVC3_SCL"
					( Origin gPackager )
				)
				( objectStatus "SMB_HOST_STBY_LVC3_SCL" )
			)
			( signal "@baseboard_fab2_lib.baseboard_fab2(sch_1):smb_host_stby_lvc3_sda"
				( attribute "CDS_PHYS_NET_NAME" "SMB_HOST_STBY_LVC3_SDA"
					( Origin gPackager )
				)
				( attribute "PHYS_NET_NAME" "SMB_HOST_STBY_LVC3_SDA"
					( Origin gPackager )
				)
				( objectStatus "SMB_HOST_STBY_LVC3_SDA" )
			)
			( signal "@baseboard_fab2_lib.baseboard_fab2(sch_1):tp_clk5_50m_ckmng"
				( attribute "CDS_PHYS_NET_NAME" "TP_CLK5_50M_CKMNG"
					( Origin gPackager )
				)
				( objectStatus "TP_CLK5_50M_CKMNG" )
			)
			( signal "@baseboard_fab2_lib.baseboard_fab2(sch_1):tp_clk_100m_r_dn"
				( attribute "CDS_PHYS_NET_NAME" "TP_CLK_100M_R_DN"
					( Origin gPackager )
				)
				( objectStatus "TP_CLK_100M_R_DN" )
			)
			( signal "@baseboard_fab2_lib.baseboard_fab2(sch_1):tp_clk_100m_r_dp"
				( attribute "CDS_PHYS_NET_NAME" "TP_CLK_100M_R_DP"
					( Origin gPackager )
				)
				( objectStatus "TP_CLK_100M_R_DP" )
			)
			( signal "@baseboard_fab2_lib.baseboard_fab2(sch_1):tp_clk_125m"
				( attribute "CDS_PHYS_NET_NAME" "TP_CLK_125M"
					( Origin gPackager )
				)
				( objectStatus "TP_CLK_125M" )
			)
			( signal "@baseboard_fab2_lib.baseboard_fab2(sch_1):tp_clk_125m_bmca"
				( attribute "CDS_PHYS_NET_NAME" "TP_CLK_125M_BMCA"
					( Origin gPackager )
				)
				( objectStatus "TP_CLK_125M_BMCA" )
			)
			( signal "@baseboard_fab2_lib.baseboard_fab2(sch_1):tp_clk_96m_ckmng_n"
				( attribute "CDS_PHYS_NET_NAME" "TP_CLK_96M_CKMNG_N"
					( Origin gPackager )
				)
				( objectStatus "TP_CLK_96M_CKMNG_N" )
			)
			( signal "@baseboard_fab2_lib.baseboard_fab2(sch_1):tp_clk_96m_ckmng_p"
				( attribute "CDS_PHYS_NET_NAME" "TP_CLK_96M_CKMNG_P"
					( Origin gPackager )
				)
				( objectStatus "TP_CLK_96M_CKMNG_P" )
			)
			( signal "@baseboard_fab2_lib.baseboard_fab2(sch_1):xtal_ck_mng_in"
				( attribute "CDS_PHYS_NET_NAME" "XTAL_CK_MNG_IN"
					( Origin gPackager )
				)
				( objectStatus "XTAL_CK_MNG_IN" )
			)
			( signal "@baseboard_fab2_lib.baseboard_fab2(sch_1):xtal_ck_mng_out"
				( attribute "CDS_PHYS_NET_NAME" "XTAL_CK_MNG_OUT"
					( Origin gPackager )
				)
				( objectStatus "XTAL_CK_MNG_OUT" )
			)
			( signal "@baseboard_fab2_lib.baseboard_fab2(sch_1):clk_100m_cpu0_bclk0_r_dn"
				( attribute "CDS_PHYS_NET_NAME" "CLK_100M_CPU0_BCLK0_R_DN"
					( Origin gPackager )
				)
				( objectStatus "CLK_100M_CPU0_BCLK0_R_DN" )
			)
			( signal "@baseboard_fab2_lib.baseboard_fab2(sch_1):clk_100m_cpu0_bclk0_r_dp"
				( attribute "CDS_PHYS_NET_NAME" "CLK_100M_CPU0_BCLK0_R_DP"
					( Origin gPackager )
				)
				( objectStatus "CLK_100M_CPU0_BCLK0_R_DP" )
			)
			( signal "@baseboard_fab2_lib.baseboard_fab2(sch_1):clk_100m_cpu0_bclk1_r_dn"
				( attribute "CDS_PHYS_NET_NAME" "CLK_100M_CPU0_BCLK1_R_DN"
					( Origin gPackager )
				)
				( objectStatus "CLK_100M_CPU0_BCLK1_R_DN" )
			)
			( signal "@baseboard_fab2_lib.baseboard_fab2(sch_1):clk_100m_cpu0_bclk1_r_dp"
				( attribute "CDS_PHYS_NET_NAME" "CLK_100M_CPU0_BCLK1_R_DP"
					( Origin gPackager )
				)
				( objectStatus "CLK_100M_CPU0_BCLK1_R_DP" )
			)
			( signal "@baseboard_fab2_lib.baseboard_fab2(sch_1):clk_100m_cpu0_bclk2_r_dn"
				( attribute "CDS_PHYS_NET_NAME" "CLK_100M_CPU0_BCLK2_R_DN"
					( Origin gPackager )
				)
				( objectStatus "CLK_100M_CPU0_BCLK2_R_DN" )
			)
			( signal "@baseboard_fab2_lib.baseboard_fab2(sch_1):clk_100m_cpu0_bclk2_r_dp"
				( attribute "CDS_PHYS_NET_NAME" "CLK_100M_CPU0_BCLK2_R_DP"
					( Origin gPackager )
				)
				( objectStatus "CLK_100M_CPU0_BCLK2_R_DP" )
			)
			( signal "@baseboard_fab2_lib.baseboard_fab2(sch_1):clk_100m_cpu0_pe_refclk_r_dn"
				( attribute "CDS_PHYS_NET_NAME" "CLK_100M_CPU0_PE_REFCLK_R_DN"
					( Origin gPackager )
				)
				( objectStatus "CLK_100M_CPU0_PE_REFCLK_R_DN" )
			)
			( signal "@baseboard_fab2_lib.baseboard_fab2(sch_1):clk_100m_cpu0_pe_refclk_r_dp"
				( attribute "CDS_PHYS_NET_NAME" "CLK_100M_CPU0_PE_REFCLK_R_DP"
					( Origin gPackager )
				)
				( objectStatus "CLK_100M_CPU0_PE_REFCLK_R_DP" )
			)
			( signal "@baseboard_fab2_lib.baseboard_fab2(sch_1):clk_100m_cpu0_rc_refclk0_r_dn"
				( attribute "CDS_PHYS_NET_NAME" "CLK_100M_CPU0_RC_REFCLK0_R_DN"
					( Origin gPackager )
				)
				( objectStatus "CLK_100M_CPU0_RC_REFCLK0_R_DN" )
			)
			( signal "@baseboard_fab2_lib.baseboard_fab2(sch_1):clk_100m_cpu0_rc_refclk0_r_dp"
				( attribute "CDS_PHYS_NET_NAME" "CLK_100M_CPU0_RC_REFCLK0_R_DP"
					( Origin gPackager )
				)
				( objectStatus "CLK_100M_CPU0_RC_REFCLK0_R_DP" )
			)
			( signal "@baseboard_fab2_lib.baseboard_fab2(sch_1):clk_100m_cpu0_rc_refclk1_r_dn"
				( attribute "CDS_PHYS_NET_NAME" "CLK_100M_CPU0_RC_REFCLK1_R_DN"
					( Origin gPackager )
				)
				( objectStatus "CLK_100M_CPU0_RC_REFCLK1_R_DN" )
			)
			( signal "@baseboard_fab2_lib.baseboard_fab2(sch_1):clk_100m_cpu0_rc_refclk1_r_dp"
				( attribute "CDS_PHYS_NET_NAME" "CLK_100M_CPU0_RC_REFCLK1_R_DP"
					( Origin gPackager )
				)
				( objectStatus "CLK_100M_CPU0_RC_REFCLK1_R_DP" )
			)
			( signal "@baseboard_fab2_lib.baseboard_fab2(sch_1):clk_100m_cpu1_bclk0_r_dn"
				( attribute "CDS_PHYS_NET_NAME" "CLK_100M_CPU1_BCLK0_R_DN"
					( Origin gPackager )
				)
				( objectStatus "CLK_100M_CPU1_BCLK0_R_DN" )
			)
			( signal "@baseboard_fab2_lib.baseboard_fab2(sch_1):clk_100m_cpu1_bclk0_r_dp"
				( attribute "CDS_PHYS_NET_NAME" "CLK_100M_CPU1_BCLK0_R_DP"
					( Origin gPackager )
				)
				( objectStatus "CLK_100M_CPU1_BCLK0_R_DP" )
			)
			( signal "@baseboard_fab2_lib.baseboard_fab2(sch_1):clk_100m_cpu1_bclk1_r_dn"
				( attribute "CDS_PHYS_NET_NAME" "CLK_100M_CPU1_BCLK1_R_DN"
					( Origin gPackager )
				)
				( objectStatus "CLK_100M_CPU1_BCLK1_R_DN" )
			)
			( signal "@baseboard_fab2_lib.baseboard_fab2(sch_1):clk_100m_cpu1_bclk1_r_dp"
				( attribute "CDS_PHYS_NET_NAME" "CLK_100M_CPU1_BCLK1_R_DP"
					( Origin gPackager )
				)
				( objectStatus "CLK_100M_CPU1_BCLK1_R_DP" )
			)
			( signal "@baseboard_fab2_lib.baseboard_fab2(sch_1):clk_100m_cpu1_bclk2_r_dn"
				( attribute "CDS_PHYS_NET_NAME" "CLK_100M_CPU1_BCLK2_R_DN"
					( Origin gPackager )
				)
				( objectStatus "CLK_100M_CPU1_BCLK2_R_DN" )
			)
			( signal "@baseboard_fab2_lib.baseboard_fab2(sch_1):clk_100m_cpu1_bclk2_r_dp"
				( attribute "CDS_PHYS_NET_NAME" "CLK_100M_CPU1_BCLK2_R_DP"
					( Origin gPackager )
				)
				( objectStatus "CLK_100M_CPU1_BCLK2_R_DP" )
			)
			( signal "@baseboard_fab2_lib.baseboard_fab2(sch_1):clk_100m_cpu1_pe_refclk_r_dn"
				( attribute "CDS_PHYS_NET_NAME" "CLK_100M_CPU1_PE_REFCLK_R_DN"
					( Origin gPackager )
				)
				( objectStatus "CLK_100M_CPU1_PE_REFCLK_R_DN" )
			)
			( signal "@baseboard_fab2_lib.baseboard_fab2(sch_1):clk_100m_cpu1_pe_refclk_r_dp"
				( attribute "CDS_PHYS_NET_NAME" "CLK_100M_CPU1_PE_REFCLK_R_DP"
					( Origin gPackager )
				)
				( objectStatus "CLK_100M_CPU1_PE_REFCLK_R_DP" )
			)
			( signal "@baseboard_fab2_lib.baseboard_fab2(sch_1):clk_100m_cpu1_rc_refclk0_r_dn"
				( attribute "CDS_PHYS_NET_NAME" "CLK_100M_CPU1_RC_REFCLK0_R_DN"
					( Origin gPackager )
				)
				( objectStatus "CLK_100M_CPU1_RC_REFCLK0_R_DN" )
			)
			( signal "@baseboard_fab2_lib.baseboard_fab2(sch_1):clk_100m_cpu1_rc_refclk0_r_dp"
				( attribute "CDS_PHYS_NET_NAME" "CLK_100M_CPU1_RC_REFCLK0_R_DP"
					( Origin gPackager )
				)
				( objectStatus "CLK_100M_CPU1_RC_REFCLK0_R_DP" )
			)
			( signal "@baseboard_fab2_lib.baseboard_fab2(sch_1):clk_100m_cpu1_rc_refclk1_r_dn"
				( attribute "CDS_PHYS_NET_NAME" "CLK_100M_CPU1_RC_REFCLK1_R_DN"
					( Origin gPackager )
				)
				( objectStatus "CLK_100M_CPU1_RC_REFCLK1_R_DN" )
			)
			( signal "@baseboard_fab2_lib.baseboard_fab2(sch_1):clk_100m_cpu1_rc_refclk1_r_dp"
				( attribute "CDS_PHYS_NET_NAME" "CLK_100M_CPU1_RC_REFCLK1_R_DP"
					( Origin gPackager )
				)
				( objectStatus "CLK_100M_CPU1_RC_REFCLK1_R_DP" )
			)
			( signal "@baseboard_fab2_lib.baseboard_fab2(sch_1):clk_100m_db1200_dn"
				( attribute "CDS_PHYS_NET_NAME" "CLK_100M_DB1200_DN"
					( Origin gPackager )
				)
				( objectStatus "CLK_100M_DB1200_DN" )
			)
			( signal "@baseboard_fab2_lib.baseboard_fab2(sch_1):clk_100m_db1200_dp"
				( attribute "CDS_PHYS_NET_NAME" "CLK_100M_DB1200_DP"
					( Origin gPackager )
				)
				( objectStatus "CLK_100M_DB1200_DP" )
			)
			( signal "@baseboard_fab2_lib.baseboard_fab2(sch_1):fm_100m_n"
				( attribute "CDS_PHYS_NET_NAME" "FM_100M_N"
					( Origin gPackager )
				)
				( objectStatus "FM_100M_N" )
			)
			( signal "@baseboard_fab2_lib.baseboard_fab2(sch_1):fm_cpu0_mcp_clk_en_n"
				( attribute "CDS_PHYS_NET_NAME" "FM_CPU0_MCP_CLK_EN_N"
					( Origin gPackager )
				)
				( objectStatus "FM_CPU0_MCP_CLK_EN_N" )
			)
			( signal "@baseboard_fab2_lib.baseboard_fab2(sch_1):fm_cpu1_mcp_clk_en_n"
				( attribute "CDS_PHYS_NET_NAME" "FM_CPU1_MCP_CLK_EN_N"
					( Origin gPackager )
				)
				( objectStatus "FM_CPU1_MCP_CLK_EN_N" )
			)
			( signal "@baseboard_fab2_lib.baseboard_fab2(sch_1):fm_db1200_pwrgd"
				( attribute "CDS_PHYS_NET_NAME" "FM_DB1200_PWRGD"
					( Origin gPackager )
				)
				( attribute "PHYS_NET_NAME" "FM_DB1200_PWRGD"
					( Origin gPackager )
				)
				( objectStatus "FM_DB1200_PWRGD" )
			)
			( signal "@baseboard_fab2_lib.baseboard_fab2(sch_1):fm_db1200_smb_sa0"
				( attribute "CDS_PHYS_NET_NAME" "FM_DB1200_SMB_SA0"
					( Origin gPackager )
				)
				( objectStatus "FM_DB1200_SMB_SA0" )
			)
			( signal "@baseboard_fab2_lib.baseboard_fab2(sch_1):fm_db1200_smb_sa1"
				( attribute "CDS_PHYS_NET_NAME" "FM_DB1200_SMB_SA1"
					( Origin gPackager )
				)
				( objectStatus "FM_DB1200_SMB_SA1" )
			)
			( signal "@baseboard_fab2_lib.baseboard_fab2(sch_1):fm_db1200zl_bclks_en_n"
				( attribute "CDS_PHYS_NET_NAME" "FM_DB1200ZL_BCLKS_EN_N"
					( Origin gPackager )
				)
				( objectStatus "FM_DB1200ZL_BCLKS_EN_N" )
			)
			( signal "@baseboard_fab2_lib.baseboard_fab2(sch_1):fm_hbw_bypass_lowbw_n"
				( attribute "CDS_PHYS_NET_NAME" "FM_HBW_BYPASS_LOWBW_N"
					( Origin gPackager )
				)
				( objectStatus "FM_HBW_BYPASS_LOWBW_N" )
			)
			( signal "@baseboard_fab2_lib.baseboard_fab2(sch_1):p3v3_db1200"
				( alias ( signalRef "@baseboard_fab2_lib.baseboard_fab2(sch_1):page102_p3v3_db1200") )
				( attribute "VOLTAGE" "5"
					( Units "uVoltage" "V" 1.000000)
					( Status sAliasFlattened )
					( Origin gFrontEnd )
				)
				( attribute "CDS_PHYS_NET_NAME" "P3V3_DB1200"
					( Origin gPackager )
				)
				( objectStatus "P3V3_DB1200" )
			)
			( signal "@baseboard_fab2_lib.baseboard_fab2(sch_1):page102_p3v3_db1200"
				( attribute "VOLTAGE" "5"
					( Units "uVoltage" "V" 1.000000)
					( Origin gFrontEnd )
				)
				( objectFlag fObjectAlias )
				( objectStatus "page102_p3v3_db1200" )
			)
			( signal "@baseboard_fab2_lib.baseboard_fab2(sch_1):p3v3_db1200_a"
				( alias ( signalRef "@baseboard_fab2_lib.baseboard_fab2(sch_1):page102_p3v3_db1200_a") )
				( attribute "VOLTAGE" "+3.3V"
					( Units "uVoltage" "V" 1.000000)
					( Status sAliasFlattened )
					( Origin gFrontEnd )
				)
				( attribute "CDS_PHYS_NET_NAME" "P3V3_DB1200_A"
					( Origin gPackager )
				)
				( objectStatus "P3V3_DB1200_A" )
			)
			( signal "@baseboard_fab2_lib.baseboard_fab2(sch_1):page102_p3v3_db1200_a"
				( attribute "VOLTAGE" "+3.3V"
					( Units "uVoltage" "V" 1.000000)
					( Origin gFrontEnd )
				)
				( objectFlag fObjectAlias )
				( objectStatus "page102_p3v3_db1200_a" )
			)
			( signal "@baseboard_fab2_lib.baseboard_fab2(sch_1):p3v3_db1200_r"
				( alias ( signalRef "@baseboard_fab2_lib.baseboard_fab2(sch_1):page102_p3v3_db1200_r") )
				( attribute "VOLTAGE" "+3.3V"
					( Units "uVoltage" "V" 1.000000)
					( Status sAliasFlattened )
					( Origin gFrontEnd )
				)
				( attribute "CDS_PHYS_NET_NAME" "P3V3_DB1200_R"
					( Origin gPackager )
				)
				( objectStatus "P3V3_DB1200_R" )
			)
			( signal "@baseboard_fab2_lib.baseboard_fab2(sch_1):page102_p3v3_db1200_r"
				( attribute "VOLTAGE" "+3.3V"
					( Units "uVoltage" "V" 1.000000)
					( Origin gFrontEnd )
				)
				( objectFlag fObjectAlias )
				( objectStatus "page102_p3v3_db1200_r" )
			)
			( signal "@baseboard_fab2_lib.baseboard_fab2(sch_1):smb_host_stby_lvc3_scl_r2"
				( attribute "CDS_PHYS_NET_NAME" "SMB_HOST_STBY_LVC3_SCL_R2"
					( Origin gPackager )
				)
				( objectStatus "SMB_HOST_STBY_LVC3_SCL_R2" )
			)
			( signal "@baseboard_fab2_lib.baseboard_fab2(sch_1):smb_host_stby_lvc3_sda_r2"
				( attribute "CDS_PHYS_NET_NAME" "SMB_HOST_STBY_LVC3_SDA_R2"
					( Origin gPackager )
				)
				( attribute "PHYS_NET_NAME" "SMB_HOST_STBY_LVC3_SDA_R2"
					( Origin gPackager )
				)
				( objectStatus "SMB_HOST_STBY_LVC3_SDA_R2" )
			)
			( signal "@baseboard_fab2_lib.baseboard_fab2(sch_1):clk_156m_osc_brd_cpu0_dn"
				( attribute "CDS_PHYS_NET_NAME" "CLK_156M_OSC_BRD_CPU0_DN"
					( Origin gPackager )
				)
				( objectStatus "CLK_156M_OSC_BRD_CPU0_DN" )
			)
			( signal "@baseboard_fab2_lib.baseboard_fab2(sch_1):clk_156m_osc_brd_cpu0_dp"
				( attribute "CDS_PHYS_NET_NAME" "CLK_156M_OSC_BRD_CPU0_DP"
					( Origin gPackager )
				)
				( objectStatus "CLK_156M_OSC_BRD_CPU0_DP" )
			)
			( signal "@baseboard_fab2_lib.baseboard_fab2(sch_1):clk_156m_osc_brd_cpu1_dn"
				( attribute "CDS_PHYS_NET_NAME" "CLK_156M_OSC_BRD_CPU1_DN"
					( Origin gPackager )
				)
				( objectStatus "CLK_156M_OSC_BRD_CPU1_DN" )
			)
			( signal "@baseboard_fab2_lib.baseboard_fab2(sch_1):clk_156m_osc_brd_cpu1_dp"
				( attribute "CDS_PHYS_NET_NAME" "CLK_156M_OSC_BRD_CPU1_DP"
					( Origin gPackager )
				)
				( objectStatus "CLK_156M_OSC_BRD_CPU1_DP" )
			)
			( signal "@baseboard_fab2_lib.baseboard_fab2(sch_1):clk_322m_156m_cpu0_osc_vrm_dn"
				( attribute "CDS_PHYS_NET_NAME" "CLK_322M_156M_CPU0_OSC_VRM_DN"
					( Origin gPackager )
				)
				( objectStatus "CLK_322M_156M_CPU0_OSC_VRM_DN" )
			)
			( signal "@baseboard_fab2_lib.baseboard_fab2(sch_1):clk_322m_156m_cpu0_osc_vrm_dp"
				( attribute "CDS_PHYS_NET_NAME" "CLK_322M_156M_CPU0_OSC_VRM_DP"
					( Origin gPackager )
				)
				( objectStatus "CLK_322M_156M_CPU0_OSC_VRM_DP" )
			)
			( signal "@baseboard_fab2_lib.baseboard_fab2(sch_1):clk_322m_156m_cpu1_osc_vrm_dn"
				( attribute "CDS_PHYS_NET_NAME" "CLK_322M_156M_CPU1_OSC_VRM_DN"
					( Origin gPackager )
				)
				( objectStatus "CLK_322M_156M_CPU1_OSC_VRM_DN" )
			)
			( signal "@baseboard_fab2_lib.baseboard_fab2(sch_1):clk_322m_156m_cpu1_osc_vrm_dp"
				( attribute "CDS_PHYS_NET_NAME" "CLK_322M_156M_CPU1_OSC_VRM_DP"
					( Origin gPackager )
				)
				( objectStatus "CLK_322M_156M_CPU1_OSC_VRM_DP" )
			)
			( signal "@baseboard_fab2_lib.baseboard_fab2(sch_1):fm_156m_cpu0_brd_osc_en"
				( attribute "CDS_PHYS_NET_NAME" "FM_156M_CPU0_BRD_OSC_EN"
					( Origin gPackager )
				)
				( objectStatus "FM_156M_CPU0_BRD_OSC_EN" )
			)
			( signal "@baseboard_fab2_lib.baseboard_fab2(sch_1):fm_156m_cpu1_brd_osc_en"
				( attribute "CDS_PHYS_NET_NAME" "FM_156M_CPU1_BRD_OSC_EN"
					( Origin gPackager )
				)
				( objectStatus "FM_156M_CPU1_BRD_OSC_EN" )
			)
			( signal "@baseboard_fab2_lib.baseboard_fab2(sch_1):fm_cpu0_stl_brd_osc_en"
				( attribute "CDS_PHYS_NET_NAME" "FM_CPU0_STL_BRD_OSC_EN"
					( Origin gPackager )
				)
				( objectStatus "FM_CPU0_STL_BRD_OSC_EN" )
			)
			( signal "@baseboard_fab2_lib.baseboard_fab2(sch_1):fm_cpu0_vrm_322m_156m_osc_en"
				( attribute "CDS_PHYS_NET_NAME" "FM_CPU0_VRM_322M_156M_OSC_EN"
					( Origin gPackager )
				)
				( objectStatus "FM_CPU0_VRM_322M_156M_OSC_EN" )
			)
			( signal "@baseboard_fab2_lib.baseboard_fab2(sch_1):fm_cpu0_vrm_osc_en"
				( attribute "CDS_PHYS_NET_NAME" "FM_CPU0_VRM_OSC_EN"
					( Origin gPackager )
				)
				( objectStatus "FM_CPU0_VRM_OSC_EN" )
			)
			( signal "@baseboard_fab2_lib.baseboard_fab2(sch_1):fm_cpu1_stl_brd_osc_en"
				( attribute "CDS_PHYS_NET_NAME" "FM_CPU1_STL_BRD_OSC_EN"
					( Origin gPackager )
				)
				( objectStatus "FM_CPU1_STL_BRD_OSC_EN" )
			)
			( signal "@baseboard_fab2_lib.baseboard_fab2(sch_1):fm_cpu1_vrm_322m_156m_osc_en"
				( attribute "CDS_PHYS_NET_NAME" "FM_CPU1_VRM_322M_156M_OSC_EN"
					( Origin gPackager )
				)
				( objectStatus "FM_CPU1_VRM_322M_156M_OSC_EN" )
			)
			( signal "@baseboard_fab2_lib.baseboard_fab2(sch_1):fm_cpu1_vrm_osc_en"
				( attribute "CDS_PHYS_NET_NAME" "FM_CPU1_VRM_OSC_EN"
					( Origin gPackager )
				)
				( objectStatus "FM_CPU1_VRM_OSC_EN" )
			)
			( signal "@baseboard_fab2_lib.baseboard_fab2(sch_1):p3e_cpu0_pe1_pch_c_txn(8)"
				( attribute "CDS_PHYS_NET_NAME" "P3E_CPU0_PE1_PCH_C_TXN<8>"
					( Origin gPackager )
				)
				( attribute "PNN" "P3E_CPU0_PE1_PCH_C_TXN<8>"
					( Origin gPackager )
				)
				( objectStatus "P3E_CPU0_PE1_PCH_C_TXN<8>" )
			)
			( signal "@baseboard_fab2_lib.baseboard_fab2(sch_1):p3e_cpu0_pe1_pch_c_txn(9)"
				( attribute "CDS_PHYS_NET_NAME" "P3E_CPU0_PE1_PCH_C_TXN<9>"
					( Origin gPackager )
				)
				( attribute "PNN" "P3E_CPU0_PE1_PCH_C_TXN<9>"
					( Origin gPackager )
				)
				( objectStatus "P3E_CPU0_PE1_PCH_C_TXN<9>" )
			)
			( signal "@baseboard_fab2_lib.baseboard_fab2(sch_1):p3e_cpu0_pe1_pch_c_txn(10)"
				( attribute "CDS_PHYS_NET_NAME" "P3E_CPU0_PE1_PCH_C_TXN<10>"
					( Origin gPackager )
				)
				( attribute "PNN" "P3E_CPU0_PE1_PCH_C_TXN<10>"
					( Origin gPackager )
				)
				( objectStatus "P3E_CPU0_PE1_PCH_C_TXN<10>" )
			)
			( signal "@baseboard_fab2_lib.baseboard_fab2(sch_1):p3e_cpu0_pe1_pch_c_txn(11)"
				( attribute "CDS_PHYS_NET_NAME" "P3E_CPU0_PE1_PCH_C_TXN<11>"
					( Origin gPackager )
				)
				( attribute "PNN" "P3E_CPU0_PE1_PCH_C_TXN<11>"
					( Origin gPackager )
				)
				( objectStatus "P3E_CPU0_PE1_PCH_C_TXN<11>" )
			)
			( signal "@baseboard_fab2_lib.baseboard_fab2(sch_1):p3e_cpu0_pe1_pch_c_txn(12)"
				( attribute "CDS_PHYS_NET_NAME" "P3E_CPU0_PE1_PCH_C_TXN<12>"
					( Origin gPackager )
				)
				( attribute "PNN" "P3E_CPU0_PE1_PCH_C_TXN<12>"
					( Origin gPackager )
				)
				( objectStatus "P3E_CPU0_PE1_PCH_C_TXN<12>" )
			)
			( signal "@baseboard_fab2_lib.baseboard_fab2(sch_1):p3e_cpu0_pe1_pch_c_txn(13)"
				( attribute "CDS_PHYS_NET_NAME" "P3E_CPU0_PE1_PCH_C_TXN<13>"
					( Origin gPackager )
				)
				( attribute "PNN" "P3E_CPU0_PE1_PCH_C_TXN<13>"
					( Origin gPackager )
				)
				( objectStatus "P3E_CPU0_PE1_PCH_C_TXN<13>" )
			)
			( signal "@baseboard_fab2_lib.baseboard_fab2(sch_1):p3e_cpu0_pe1_pch_c_txn(14)"
				( attribute "CDS_PHYS_NET_NAME" "P3E_CPU0_PE1_PCH_C_TXN<14>"
					( Origin gPackager )
				)
				( attribute "PNN" "P3E_CPU0_PE1_PCH_C_TXN<14>"
					( Origin gPackager )
				)
				( objectStatus "P3E_CPU0_PE1_PCH_C_TXN<14>" )
			)
			( signal "@baseboard_fab2_lib.baseboard_fab2(sch_1):p3e_cpu0_pe1_pch_c_txn(15)"
				( attribute "CDS_PHYS_NET_NAME" "P3E_CPU0_PE1_PCH_C_TXN<15>"
					( Origin gPackager )
				)
				( attribute "PNN" "P3E_CPU0_PE1_PCH_C_TXN<15>"
					( Origin gPackager )
				)
				( objectStatus "P3E_CPU0_PE1_PCH_C_TXN<15>" )
			)
			( signal "@baseboard_fab2_lib.baseboard_fab2(sch_1):p3e_cpu0_pe1_pch_c_txp(8)"
				( attribute "CDS_PHYS_NET_NAME" "P3E_CPU0_PE1_PCH_C_TXP<8>"
					( Origin gPackager )
				)
				( attribute "PNN" "P3E_CPU0_PE1_PCH_C_TXP<8>"
					( Origin gPackager )
				)
				( objectStatus "P3E_CPU0_PE1_PCH_C_TXP<8>" )
			)
			( signal "@baseboard_fab2_lib.baseboard_fab2(sch_1):p3e_cpu0_pe1_pch_c_txp(9)"
				( attribute "CDS_PHYS_NET_NAME" "P3E_CPU0_PE1_PCH_C_TXP<9>"
					( Origin gPackager )
				)
				( attribute "PNN" "P3E_CPU0_PE1_PCH_C_TXP<9>"
					( Origin gPackager )
				)
				( objectStatus "P3E_CPU0_PE1_PCH_C_TXP<9>" )
			)
			( signal "@baseboard_fab2_lib.baseboard_fab2(sch_1):p3e_cpu0_pe1_pch_c_txp(10)"
				( attribute "CDS_PHYS_NET_NAME" "P3E_CPU0_PE1_PCH_C_TXP<10>"
					( Origin gPackager )
				)
				( attribute "PNN" "P3E_CPU0_PE1_PCH_C_TXP<10>"
					( Origin gPackager )
				)
				( objectStatus "P3E_CPU0_PE1_PCH_C_TXP<10>" )
			)
			( signal "@baseboard_fab2_lib.baseboard_fab2(sch_1):p3e_cpu0_pe1_pch_c_txp(11)"
				( attribute "CDS_PHYS_NET_NAME" "P3E_CPU0_PE1_PCH_C_TXP<11>"
					( Origin gPackager )
				)
				( attribute "PNN" "P3E_CPU0_PE1_PCH_C_TXP<11>"
					( Origin gPackager )
				)
				( objectStatus "P3E_CPU0_PE1_PCH_C_TXP<11>" )
			)
			( signal "@baseboard_fab2_lib.baseboard_fab2(sch_1):p3e_cpu0_pe1_pch_c_txp(12)"
				( attribute "CDS_PHYS_NET_NAME" "P3E_CPU0_PE1_PCH_C_TXP<12>"
					( Origin gPackager )
				)
				( attribute "PNN" "P3E_CPU0_PE1_PCH_C_TXP<12>"
					( Origin gPackager )
				)
				( objectStatus "P3E_CPU0_PE1_PCH_C_TXP<12>" )
			)
			( signal "@baseboard_fab2_lib.baseboard_fab2(sch_1):p3e_cpu0_pe1_pch_c_txp(13)"
				( attribute "CDS_PHYS_NET_NAME" "P3E_CPU0_PE1_PCH_C_TXP<13>"
					( Origin gPackager )
				)
				( attribute "PNN" "P3E_CPU0_PE1_PCH_C_TXP<13>"
					( Origin gPackager )
				)
				( objectStatus "P3E_CPU0_PE1_PCH_C_TXP<13>" )
			)
			( signal "@baseboard_fab2_lib.baseboard_fab2(sch_1):p3e_cpu0_pe1_pch_c_txp(14)"
				( attribute "CDS_PHYS_NET_NAME" "P3E_CPU0_PE1_PCH_C_TXP<14>"
					( Origin gPackager )
				)
				( attribute "PNN" "P3E_CPU0_PE1_PCH_C_TXP<14>"
					( Origin gPackager )
				)
				( objectStatus "P3E_CPU0_PE1_PCH_C_TXP<14>" )
			)
			( signal "@baseboard_fab2_lib.baseboard_fab2(sch_1):p3e_cpu0_pe1_pch_c_txp(15)"
				( attribute "CDS_PHYS_NET_NAME" "P3E_CPU0_PE1_PCH_C_TXP<15>"
					( Origin gPackager )
				)
				( attribute "PNN" "P3E_CPU0_PE1_PCH_C_TXP<15>"
					( Origin gPackager )
				)
				( objectStatus "P3E_CPU0_PE1_PCH_C_TXP<15>" )
			)
			( signal "@baseboard_fab2_lib.baseboard_fab2(sch_1):p3e_cpu0_pe1_pch_r_rxn(8)"
				( attribute "CDS_PHYS_NET_NAME" "P3E_CPU0_PE1_PCH_R_RXN<8>"
					( Origin gPackager )
				)
				( attribute "PNN" "P3E_CPU0_PE1_PCH_R_RXN<8>"
					( Origin gPackager )
				)
				( objectStatus "P3E_CPU0_PE1_PCH_R_RXN<8>" )
			)
			( signal "@baseboard_fab2_lib.baseboard_fab2(sch_1):p3e_cpu0_pe1_pch_r_rxn(9)"
				( attribute "CDS_PHYS_NET_NAME" "P3E_CPU0_PE1_PCH_R_RXN<9>"
					( Origin gPackager )
				)
				( attribute "PNN" "P3E_CPU0_PE1_PCH_R_RXN<9>"
					( Origin gPackager )
				)
				( objectStatus "P3E_CPU0_PE1_PCH_R_RXN<9>" )
			)
			( signal "@baseboard_fab2_lib.baseboard_fab2(sch_1):p3e_cpu0_pe1_pch_r_rxn(10)"
				( attribute "CDS_PHYS_NET_NAME" "P3E_CPU0_PE1_PCH_R_RXN<10>"
					( Origin gPackager )
				)
				( attribute "PNN" "P3E_CPU0_PE1_PCH_R_RXN<10>"
					( Origin gPackager )
				)
				( objectStatus "P3E_CPU0_PE1_PCH_R_RXN<10>" )
			)
			( signal "@baseboard_fab2_lib.baseboard_fab2(sch_1):p3e_cpu0_pe1_pch_r_rxn(11)"
				( attribute "CDS_PHYS_NET_NAME" "P3E_CPU0_PE1_PCH_R_RXN<11>"
					( Origin gPackager )
				)
				( attribute "PNN" "P3E_CPU0_PE1_PCH_R_RXN<11>"
					( Origin gPackager )
				)
				( objectStatus "P3E_CPU0_PE1_PCH_R_RXN<11>" )
			)
			( signal "@baseboard_fab2_lib.baseboard_fab2(sch_1):p3e_cpu0_pe1_pch_r_rxn(12)"
				( attribute "CDS_PHYS_NET_NAME" "P3E_CPU0_PE1_PCH_R_RXN<12>"
					( Origin gPackager )
				)
				( attribute "PNN" "P3E_CPU0_PE1_PCH_R_RXN<12>"
					( Origin gPackager )
				)
				( objectStatus "P3E_CPU0_PE1_PCH_R_RXN<12>" )
			)
			( signal "@baseboard_fab2_lib.baseboard_fab2(sch_1):p3e_cpu0_pe1_pch_r_rxn(13)"
				( attribute "CDS_PHYS_NET_NAME" "P3E_CPU0_PE1_PCH_R_RXN<13>"
					( Origin gPackager )
				)
				( attribute "PNN" "P3E_CPU0_PE1_PCH_R_RXN<13>"
					( Origin gPackager )
				)
				( objectStatus "P3E_CPU0_PE1_PCH_R_RXN<13>" )
			)
			( signal "@baseboard_fab2_lib.baseboard_fab2(sch_1):p3e_cpu0_pe1_pch_r_rxn(14)"
				( attribute "CDS_PHYS_NET_NAME" "P3E_CPU0_PE1_PCH_R_RXN<14>"
					( Origin gPackager )
				)
				( attribute "PNN" "P3E_CPU0_PE1_PCH_R_RXN<14>"
					( Origin gPackager )
				)
				( objectStatus "P3E_CPU0_PE1_PCH_R_RXN<14>" )
			)
			( signal "@baseboard_fab2_lib.baseboard_fab2(sch_1):p3e_cpu0_pe1_pch_r_rxn(15)"
				( attribute "CDS_PHYS_NET_NAME" "P3E_CPU0_PE1_PCH_R_RXN<15>"
					( Origin gPackager )
				)
				( attribute "PNN" "P3E_CPU0_PE1_PCH_R_RXN<15>"
					( Origin gPackager )
				)
				( objectStatus "P3E_CPU0_PE1_PCH_R_RXN<15>" )
			)
			( signal "@baseboard_fab2_lib.baseboard_fab2(sch_1):p3e_cpu0_pe1_pch_r_rxp(8)"
				( attribute "CDS_PHYS_NET_NAME" "P3E_CPU0_PE1_PCH_R_RXP<8>"
					( Origin gPackager )
				)
				( attribute "PNN" "P3E_CPU0_PE1_PCH_R_RXP<8>"
					( Origin gPackager )
				)
				( objectStatus "P3E_CPU0_PE1_PCH_R_RXP<8>" )
			)
			( signal "@baseboard_fab2_lib.baseboard_fab2(sch_1):p3e_cpu0_pe1_pch_r_rxp(9)"
				( attribute "CDS_PHYS_NET_NAME" "P3E_CPU0_PE1_PCH_R_RXP<9>"
					( Origin gPackager )
				)
				( attribute "PNN" "P3E_CPU0_PE1_PCH_R_RXP<9>"
					( Origin gPackager )
				)
				( objectStatus "P3E_CPU0_PE1_PCH_R_RXP<9>" )
			)
			( signal "@baseboard_fab2_lib.baseboard_fab2(sch_1):p3e_cpu0_pe1_pch_r_rxp(10)"
				( attribute "CDS_PHYS_NET_NAME" "P3E_CPU0_PE1_PCH_R_RXP<10>"
					( Origin gPackager )
				)
				( attribute "PNN" "P3E_CPU0_PE1_PCH_R_RXP<10>"
					( Origin gPackager )
				)
				( objectStatus "P3E_CPU0_PE1_PCH_R_RXP<10>" )
			)
			( signal "@baseboard_fab2_lib.baseboard_fab2(sch_1):p3e_cpu0_pe1_pch_r_rxp(11)"
				( attribute "CDS_PHYS_NET_NAME" "P3E_CPU0_PE1_PCH_R_RXP<11>"
					( Origin gPackager )
				)
				( attribute "PNN" "P3E_CPU0_PE1_PCH_R_RXP<11>"
					( Origin gPackager )
				)
				( objectStatus "P3E_CPU0_PE1_PCH_R_RXP<11>" )
			)
			( signal "@baseboard_fab2_lib.baseboard_fab2(sch_1):p3e_cpu0_pe1_pch_r_rxp(12)"
				( attribute "CDS_PHYS_NET_NAME" "P3E_CPU0_PE1_PCH_R_RXP<12>"
					( Origin gPackager )
				)
				( attribute "PNN" "P3E_CPU0_PE1_PCH_R_RXP<12>"
					( Origin gPackager )
				)
				( objectStatus "P3E_CPU0_PE1_PCH_R_RXP<12>" )
			)
			( signal "@baseboard_fab2_lib.baseboard_fab2(sch_1):p3e_cpu0_pe1_pch_r_rxp(13)"
				( attribute "CDS_PHYS_NET_NAME" "P3E_CPU0_PE1_PCH_R_RXP<13>"
					( Origin gPackager )
				)
				( attribute "PNN" "P3E_CPU0_PE1_PCH_R_RXP<13>"
					( Origin gPackager )
				)
				( objectStatus "P3E_CPU0_PE1_PCH_R_RXP<13>" )
			)
			( signal "@baseboard_fab2_lib.baseboard_fab2(sch_1):p3e_cpu0_pe1_pch_r_rxp(14)"
				( attribute "CDS_PHYS_NET_NAME" "P3E_CPU0_PE1_PCH_R_RXP<14>"
					( Origin gPackager )
				)
				( attribute "PNN" "P3E_CPU0_PE1_PCH_R_RXP<14>"
					( Origin gPackager )
				)
				( objectStatus "P3E_CPU0_PE1_PCH_R_RXP<14>" )
			)
			( signal "@baseboard_fab2_lib.baseboard_fab2(sch_1):p3e_cpu0_pe1_pch_r_rxp(15)"
				( attribute "CDS_PHYS_NET_NAME" "P3E_CPU0_PE1_PCH_R_RXP<15>"
					( Origin gPackager )
				)
				( attribute "PNN" "P3E_CPU0_PE1_PCH_R_RXP<15>"
					( Origin gPackager )
				)
				( objectStatus "P3E_CPU0_PE1_PCH_R_RXP<15>" )
			)
			( signal "@baseboard_fab2_lib.baseboard_fab2(sch_1):p3e_cpu0_pe2_ss_c_txn(0)"
				( attribute "CDS_PHYS_NET_NAME" "P3E_CPU0_PE2_SS_C_TXN<0>"
					( Origin gPackager )
				)
				( attribute "PNN" "P3E_CPU0_PE2_SS_C_TXN<0>"
					( Origin gPackager )
				)
				( objectStatus "P3E_CPU0_PE2_SS_C_TXN<0>" )
			)
			( signal "@baseboard_fab2_lib.baseboard_fab2(sch_1):p3e_cpu0_pe2_ss_c_txn(1)"
				( attribute "CDS_PHYS_NET_NAME" "P3E_CPU0_PE2_SS_C_TXN<1>"
					( Origin gPackager )
				)
				( attribute "PNN" "P3E_CPU0_PE2_SS_C_TXN<1>"
					( Origin gPackager )
				)
				( objectStatus "P3E_CPU0_PE2_SS_C_TXN<1>" )
			)
			( signal "@baseboard_fab2_lib.baseboard_fab2(sch_1):p3e_cpu0_pe2_ss_c_txn(2)"
				( attribute "CDS_PHYS_NET_NAME" "P3E_CPU0_PE2_SS_C_TXN<2>"
					( Origin gPackager )
				)
				( attribute "PNN" "P3E_CPU0_PE2_SS_C_TXN<2>"
					( Origin gPackager )
				)
				( objectStatus "P3E_CPU0_PE2_SS_C_TXN<2>" )
			)
			( signal "@baseboard_fab2_lib.baseboard_fab2(sch_1):p3e_cpu0_pe2_ss_c_txn(3)"
				( attribute "CDS_PHYS_NET_NAME" "P3E_CPU0_PE2_SS_C_TXN<3>"
					( Origin gPackager )
				)
				( attribute "PNN" "P3E_CPU0_PE2_SS_C_TXN<3>"
					( Origin gPackager )
				)
				( objectStatus "P3E_CPU0_PE2_SS_C_TXN<3>" )
			)
			( signal "@baseboard_fab2_lib.baseboard_fab2(sch_1):p3e_cpu0_pe2_ss_c_txn(4)"
				( attribute "CDS_PHYS_NET_NAME" "P3E_CPU0_PE2_SS_C_TXN<4>"
					( Origin gPackager )
				)
				( attribute "PNN" "P3E_CPU0_PE2_SS_C_TXN<4>"
					( Origin gPackager )
				)
				( objectStatus "P3E_CPU0_PE2_SS_C_TXN<4>" )
			)
			( signal "@baseboard_fab2_lib.baseboard_fab2(sch_1):p3e_cpu0_pe2_ss_c_txn(5)"
				( attribute "CDS_PHYS_NET_NAME" "P3E_CPU0_PE2_SS_C_TXN<5>"
					( Origin gPackager )
				)
				( attribute "PNN" "P3E_CPU0_PE2_SS_C_TXN<5>"
					( Origin gPackager )
				)
				( objectStatus "P3E_CPU0_PE2_SS_C_TXN<5>" )
			)
			( signal "@baseboard_fab2_lib.baseboard_fab2(sch_1):p3e_cpu0_pe2_ss_c_txn(6)"
				( attribute "CDS_PHYS_NET_NAME" "P3E_CPU0_PE2_SS_C_TXN<6>"
					( Origin gPackager )
				)
				( attribute "PNN" "P3E_CPU0_PE2_SS_C_TXN<6>"
					( Origin gPackager )
				)
				( objectStatus "P3E_CPU0_PE2_SS_C_TXN<6>" )
			)
			( signal "@baseboard_fab2_lib.baseboard_fab2(sch_1):p3e_cpu0_pe2_ss_c_txn(7)"
				( attribute "CDS_PHYS_NET_NAME" "P3E_CPU0_PE2_SS_C_TXN<7>"
					( Origin gPackager )
				)
				( attribute "PNN" "P3E_CPU0_PE2_SS_C_TXN<7>"
					( Origin gPackager )
				)
				( objectStatus "P3E_CPU0_PE2_SS_C_TXN<7>" )
			)
			( signal "@baseboard_fab2_lib.baseboard_fab2(sch_1):p3e_cpu0_pe2_ss_c_txn(8)"
				( attribute "CDS_PHYS_NET_NAME" "P3E_CPU0_PE2_SS_C_TXN<8>"
					( Origin gPackager )
				)
				( attribute "PNN" "P3E_CPU0_PE2_SS_C_TXN<8>"
					( Origin gPackager )
				)
				( objectStatus "P3E_CPU0_PE2_SS_C_TXN<8>" )
			)
			( signal "@baseboard_fab2_lib.baseboard_fab2(sch_1):p3e_cpu0_pe2_ss_c_txn(9)"
				( attribute "CDS_PHYS_NET_NAME" "P3E_CPU0_PE2_SS_C_TXN<9>"
					( Origin gPackager )
				)
				( attribute "PNN" "P3E_CPU0_PE2_SS_C_TXN<9>"
					( Origin gPackager )
				)
				( objectStatus "P3E_CPU0_PE2_SS_C_TXN<9>" )
			)
			( signal "@baseboard_fab2_lib.baseboard_fab2(sch_1):p3e_cpu0_pe2_ss_c_txn(10)"
				( attribute "CDS_PHYS_NET_NAME" "P3E_CPU0_PE2_SS_C_TXN<10>"
					( Origin gPackager )
				)
				( attribute "PNN" "P3E_CPU0_PE2_SS_C_TXN<10>"
					( Origin gPackager )
				)
				( objectStatus "P3E_CPU0_PE2_SS_C_TXN<10>" )
			)
			( signal "@baseboard_fab2_lib.baseboard_fab2(sch_1):p3e_cpu0_pe2_ss_c_txn(11)"
				( attribute "CDS_PHYS_NET_NAME" "P3E_CPU0_PE2_SS_C_TXN<11>"
					( Origin gPackager )
				)
				( attribute "PNN" "P3E_CPU0_PE2_SS_C_TXN<11>"
					( Origin gPackager )
				)
				( objectStatus "P3E_CPU0_PE2_SS_C_TXN<11>" )
			)
			( signal "@baseboard_fab2_lib.baseboard_fab2(sch_1):p3e_cpu0_pe2_ss_c_txn(12)"
				( attribute "CDS_PHYS_NET_NAME" "P3E_CPU0_PE2_SS_C_TXN<12>"
					( Origin gPackager )
				)
				( attribute "PNN" "P3E_CPU0_PE2_SS_C_TXN<12>"
					( Origin gPackager )
				)
				( objectStatus "P3E_CPU0_PE2_SS_C_TXN<12>" )
			)
			( signal "@baseboard_fab2_lib.baseboard_fab2(sch_1):p3e_cpu0_pe2_ss_c_txn(13)"
				( attribute "CDS_PHYS_NET_NAME" "P3E_CPU0_PE2_SS_C_TXN<13>"
					( Origin gPackager )
				)
				( attribute "PNN" "P3E_CPU0_PE2_SS_C_TXN<13>"
					( Origin gPackager )
				)
				( objectStatus "P3E_CPU0_PE2_SS_C_TXN<13>" )
			)
			( signal "@baseboard_fab2_lib.baseboard_fab2(sch_1):p3e_cpu0_pe2_ss_c_txn(14)"
				( attribute "CDS_PHYS_NET_NAME" "P3E_CPU0_PE2_SS_C_TXN<14>"
					( Origin gPackager )
				)
				( attribute "PNN" "P3E_CPU0_PE2_SS_C_TXN<14>"
					( Origin gPackager )
				)
				( objectStatus "P3E_CPU0_PE2_SS_C_TXN<14>" )
			)
			( signal "@baseboard_fab2_lib.baseboard_fab2(sch_1):p3e_cpu0_pe2_ss_c_txn(15)"
				( attribute "CDS_PHYS_NET_NAME" "P3E_CPU0_PE2_SS_C_TXN<15>"
					( Origin gPackager )
				)
				( attribute "PNN" "P3E_CPU0_PE2_SS_C_TXN<15>"
					( Origin gPackager )
				)
				( objectStatus "P3E_CPU0_PE2_SS_C_TXN<15>" )
			)
			( signal "@baseboard_fab2_lib.baseboard_fab2(sch_1):p3e_cpu0_pe2_ss_c_txp(0)"
				( attribute "CDS_PHYS_NET_NAME" "P3E_CPU0_PE2_SS_C_TXP<0>"
					( Origin gPackager )
				)
				( attribute "PNN" "P3E_CPU0_PE2_SS_C_TXP<0>"
					( Origin gPackager )
				)
				( objectStatus "P3E_CPU0_PE2_SS_C_TXP<0>" )
			)
			( signal "@baseboard_fab2_lib.baseboard_fab2(sch_1):p3e_cpu0_pe2_ss_c_txp(1)"
				( attribute "CDS_PHYS_NET_NAME" "P3E_CPU0_PE2_SS_C_TXP<1>"
					( Origin gPackager )
				)
				( attribute "PNN" "P3E_CPU0_PE2_SS_C_TXP<1>"
					( Origin gPackager )
				)
				( objectStatus "P3E_CPU0_PE2_SS_C_TXP<1>" )
			)
			( signal "@baseboard_fab2_lib.baseboard_fab2(sch_1):p3e_cpu0_pe2_ss_c_txp(2)"
				( attribute "CDS_PHYS_NET_NAME" "P3E_CPU0_PE2_SS_C_TXP<2>"
					( Origin gPackager )
				)
				( attribute "PNN" "P3E_CPU0_PE2_SS_C_TXP<2>"
					( Origin gPackager )
				)
				( objectStatus "P3E_CPU0_PE2_SS_C_TXP<2>" )
			)
			( signal "@baseboard_fab2_lib.baseboard_fab2(sch_1):p3e_cpu0_pe2_ss_c_txp(3)"
				( attribute "CDS_PHYS_NET_NAME" "P3E_CPU0_PE2_SS_C_TXP<3>"
					( Origin gPackager )
				)
				( attribute "PNN" "P3E_CPU0_PE2_SS_C_TXP<3>"
					( Origin gPackager )
				)
				( objectStatus "P3E_CPU0_PE2_SS_C_TXP<3>" )
			)
			( signal "@baseboard_fab2_lib.baseboard_fab2(sch_1):p3e_cpu0_pe2_ss_c_txp(4)"
				( attribute "CDS_PHYS_NET_NAME" "P3E_CPU0_PE2_SS_C_TXP<4>"
					( Origin gPackager )
				)
				( attribute "PNN" "P3E_CPU0_PE2_SS_C_TXP<4>"
					( Origin gPackager )
				)
				( objectStatus "P3E_CPU0_PE2_SS_C_TXP<4>" )
			)
			( signal "@baseboard_fab2_lib.baseboard_fab2(sch_1):p3e_cpu0_pe2_ss_c_txp(5)"
				( attribute "CDS_PHYS_NET_NAME" "P3E_CPU0_PE2_SS_C_TXP<5>"
					( Origin gPackager )
				)
				( attribute "PNN" "P3E_CPU0_PE2_SS_C_TXP<5>"
					( Origin gPackager )
				)
				( objectStatus "P3E_CPU0_PE2_SS_C_TXP<5>" )
			)
			( signal "@baseboard_fab2_lib.baseboard_fab2(sch_1):p3e_cpu0_pe2_ss_c_txp(6)"
				( attribute "CDS_PHYS_NET_NAME" "P3E_CPU0_PE2_SS_C_TXP<6>"
					( Origin gPackager )
				)
				( attribute "PNN" "P3E_CPU0_PE2_SS_C_TXP<6>"
					( Origin gPackager )
				)
				( objectStatus "P3E_CPU0_PE2_SS_C_TXP<6>" )
			)
			( signal "@baseboard_fab2_lib.baseboard_fab2(sch_1):p3e_cpu0_pe2_ss_c_txp(7)"
				( attribute "CDS_PHYS_NET_NAME" "P3E_CPU0_PE2_SS_C_TXP<7>"
					( Origin gPackager )
				)
				( attribute "PNN" "P3E_CPU0_PE2_SS_C_TXP<7>"
					( Origin gPackager )
				)
				( objectStatus "P3E_CPU0_PE2_SS_C_TXP<7>" )
			)
			( signal "@baseboard_fab2_lib.baseboard_fab2(sch_1):p3e_cpu0_pe2_ss_c_txp(8)"
				( attribute "CDS_PHYS_NET_NAME" "P3E_CPU0_PE2_SS_C_TXP<8>"
					( Origin gPackager )
				)
				( attribute "PNN" "P3E_CPU0_PE2_SS_C_TXP<8>"
					( Origin gPackager )
				)
				( objectStatus "P3E_CPU0_PE2_SS_C_TXP<8>" )
			)
			( signal "@baseboard_fab2_lib.baseboard_fab2(sch_1):p3e_cpu0_pe2_ss_c_txp(9)"
				( attribute "CDS_PHYS_NET_NAME" "P3E_CPU0_PE2_SS_C_TXP<9>"
					( Origin gPackager )
				)
				( attribute "PNN" "P3E_CPU0_PE2_SS_C_TXP<9>"
					( Origin gPackager )
				)
				( objectStatus "P3E_CPU0_PE2_SS_C_TXP<9>" )
			)
			( signal "@baseboard_fab2_lib.baseboard_fab2(sch_1):p3e_cpu0_pe2_ss_c_txp(10)"
				( attribute "CDS_PHYS_NET_NAME" "P3E_CPU0_PE2_SS_C_TXP<10>"
					( Origin gPackager )
				)
				( attribute "PNN" "P3E_CPU0_PE2_SS_C_TXP<10>"
					( Origin gPackager )
				)
				( objectStatus "P3E_CPU0_PE2_SS_C_TXP<10>" )
			)
			( signal "@baseboard_fab2_lib.baseboard_fab2(sch_1):p3e_cpu0_pe2_ss_c_txp(11)"
				( attribute "CDS_PHYS_NET_NAME" "P3E_CPU0_PE2_SS_C_TXP<11>"
					( Origin gPackager )
				)
				( attribute "PNN" "P3E_CPU0_PE2_SS_C_TXP<11>"
					( Origin gPackager )
				)
				( objectStatus "P3E_CPU0_PE2_SS_C_TXP<11>" )
			)
			( signal "@baseboard_fab2_lib.baseboard_fab2(sch_1):p3e_cpu0_pe2_ss_c_txp(12)"
				( attribute "CDS_PHYS_NET_NAME" "P3E_CPU0_PE2_SS_C_TXP<12>"
					( Origin gPackager )
				)
				( attribute "PNN" "P3E_CPU0_PE2_SS_C_TXP<12>"
					( Origin gPackager )
				)
				( objectStatus "P3E_CPU0_PE2_SS_C_TXP<12>" )
			)
			( signal "@baseboard_fab2_lib.baseboard_fab2(sch_1):p3e_cpu0_pe2_ss_c_txp(13)"
				( attribute "CDS_PHYS_NET_NAME" "P3E_CPU0_PE2_SS_C_TXP<13>"
					( Origin gPackager )
				)
				( attribute "PNN" "P3E_CPU0_PE2_SS_C_TXP<13>"
					( Origin gPackager )
				)
				( objectStatus "P3E_CPU0_PE2_SS_C_TXP<13>" )
			)
			( signal "@baseboard_fab2_lib.baseboard_fab2(sch_1):p3e_cpu0_pe2_ss_c_txp(14)"
				( attribute "CDS_PHYS_NET_NAME" "P3E_CPU0_PE2_SS_C_TXP<14>"
					( Origin gPackager )
				)
				( attribute "PNN" "P3E_CPU0_PE2_SS_C_TXP<14>"
					( Origin gPackager )
				)
				( objectStatus "P3E_CPU0_PE2_SS_C_TXP<14>" )
			)
			( signal "@baseboard_fab2_lib.baseboard_fab2(sch_1):p3e_cpu0_pe2_ss_c_txp(15)"
				( attribute "CDS_PHYS_NET_NAME" "P3E_CPU0_PE2_SS_C_TXP<15>"
					( Origin gPackager )
				)
				( attribute "PNN" "P3E_CPU0_PE2_SS_C_TXP<15>"
					( Origin gPackager )
				)
				( objectStatus "P3E_CPU0_PE2_SS_C_TXP<15>" )
			)
			( signal "@baseboard_fab2_lib.baseboard_fab2(sch_1):p3e_ocp_cpu0_pe3_c_txn(0)"
				( attribute "CDS_PHYS_NET_NAME" "P3E_OCP_CPU0_PE3_C_TXN<0>"
					( Origin gPackager )
				)
				( attribute "PNN" "P3E_OCP_CPU0_PE3_C_TXN<0>"
					( Origin gPackager )
				)
				( objectStatus "P3E_OCP_CPU0_PE3_C_TXN<0>" )
			)
			( signal "@baseboard_fab2_lib.baseboard_fab2(sch_1):p3e_ocp_cpu0_pe3_c_txn(1)"
				( attribute "CDS_PHYS_NET_NAME" "P3E_OCP_CPU0_PE3_C_TXN<1>"
					( Origin gPackager )
				)
				( attribute "PNN" "P3E_OCP_CPU0_PE3_C_TXN<1>"
					( Origin gPackager )
				)
				( objectStatus "P3E_OCP_CPU0_PE3_C_TXN<1>" )
			)
			( signal "@baseboard_fab2_lib.baseboard_fab2(sch_1):p3e_ocp_cpu0_pe3_c_txn(2)"
				( attribute "CDS_PHYS_NET_NAME" "P3E_OCP_CPU0_PE3_C_TXN<2>"
					( Origin gPackager )
				)
				( attribute "PNN" "P3E_OCP_CPU0_PE3_C_TXN<2>"
					( Origin gPackager )
				)
				( objectStatus "P3E_OCP_CPU0_PE3_C_TXN<2>" )
			)
			( signal "@baseboard_fab2_lib.baseboard_fab2(sch_1):p3e_ocp_cpu0_pe3_c_txn(3)"
				( attribute "CDS_PHYS_NET_NAME" "P3E_OCP_CPU0_PE3_C_TXN<3>"
					( Origin gPackager )
				)
				( attribute "PNN" "P3E_OCP_CPU0_PE3_C_TXN<3>"
					( Origin gPackager )
				)
				( objectStatus "P3E_OCP_CPU0_PE3_C_TXN<3>" )
			)
			( signal "@baseboard_fab2_lib.baseboard_fab2(sch_1):p3e_ocp_cpu0_pe3_c_txn(4)"
				( attribute "CDS_PHYS_NET_NAME" "P3E_OCP_CPU0_PE3_C_TXN<4>"
					( Origin gPackager )
				)
				( attribute "PNN" "P3E_OCP_CPU0_PE3_C_TXN<4>"
					( Origin gPackager )
				)
				( objectStatus "P3E_OCP_CPU0_PE3_C_TXN<4>" )
			)
			( signal "@baseboard_fab2_lib.baseboard_fab2(sch_1):p3e_ocp_cpu0_pe3_c_txn(5)"
				( attribute "CDS_PHYS_NET_NAME" "P3E_OCP_CPU0_PE3_C_TXN<5>"
					( Origin gPackager )
				)
				( attribute "PNN" "P3E_OCP_CPU0_PE3_C_TXN<5>"
					( Origin gPackager )
				)
				( objectStatus "P3E_OCP_CPU0_PE3_C_TXN<5>" )
			)
			( signal "@baseboard_fab2_lib.baseboard_fab2(sch_1):p3e_ocp_cpu0_pe3_c_txn(6)"
				( attribute "CDS_PHYS_NET_NAME" "P3E_OCP_CPU0_PE3_C_TXN<6>"
					( Origin gPackager )
				)
				( attribute "PNN" "P3E_OCP_CPU0_PE3_C_TXN<6>"
					( Origin gPackager )
				)
				( objectStatus "P3E_OCP_CPU0_PE3_C_TXN<6>" )
			)
			( signal "@baseboard_fab2_lib.baseboard_fab2(sch_1):p3e_ocp_cpu0_pe3_c_txn(7)"
				( attribute "CDS_PHYS_NET_NAME" "P3E_OCP_CPU0_PE3_C_TXN<7>"
					( Origin gPackager )
				)
				( attribute "PNN" "P3E_OCP_CPU0_PE3_C_TXN<7>"
					( Origin gPackager )
				)
				( objectStatus "P3E_OCP_CPU0_PE3_C_TXN<7>" )
			)
			( signal "@baseboard_fab2_lib.baseboard_fab2(sch_1):p3e_ocp_cpu0_pe3_c_txn(8)"
				( attribute "CDS_PHYS_NET_NAME" "P3E_OCP_CPU0_PE3_C_TXN<8>"
					( Origin gPackager )
				)
				( attribute "PNN" "P3E_OCP_CPU0_PE3_C_TXN<8>"
					( Origin gPackager )
				)
				( objectStatus "P3E_OCP_CPU0_PE3_C_TXN<8>" )
			)
			( signal "@baseboard_fab2_lib.baseboard_fab2(sch_1):p3e_ocp_cpu0_pe3_c_txn(9)"
				( attribute "CDS_PHYS_NET_NAME" "P3E_OCP_CPU0_PE3_C_TXN<9>"
					( Origin gPackager )
				)
				( attribute "PNN" "P3E_OCP_CPU0_PE3_C_TXN<9>"
					( Origin gPackager )
				)
				( objectStatus "P3E_OCP_CPU0_PE3_C_TXN<9>" )
			)
			( signal "@baseboard_fab2_lib.baseboard_fab2(sch_1):p3e_ocp_cpu0_pe3_c_txn(10)"
				( attribute "CDS_PHYS_NET_NAME" "P3E_OCP_CPU0_PE3_C_TXN<10>"
					( Origin gPackager )
				)
				( attribute "PNN" "P3E_OCP_CPU0_PE3_C_TXN<10>"
					( Origin gPackager )
				)
				( objectStatus "P3E_OCP_CPU0_PE3_C_TXN<10>" )
			)
			( signal "@baseboard_fab2_lib.baseboard_fab2(sch_1):p3e_ocp_cpu0_pe3_c_txn(11)"
				( attribute "CDS_PHYS_NET_NAME" "P3E_OCP_CPU0_PE3_C_TXN<11>"
					( Origin gPackager )
				)
				( attribute "PNN" "P3E_OCP_CPU0_PE3_C_TXN<11>"
					( Origin gPackager )
				)
				( objectStatus "P3E_OCP_CPU0_PE3_C_TXN<11>" )
			)
			( signal "@baseboard_fab2_lib.baseboard_fab2(sch_1):p3e_ocp_cpu0_pe3_c_txn(12)"
				( attribute "CDS_PHYS_NET_NAME" "P3E_OCP_CPU0_PE3_C_TXN<12>"
					( Origin gPackager )
				)
				( attribute "PNN" "P3E_OCP_CPU0_PE3_C_TXN<12>"
					( Origin gPackager )
				)
				( objectStatus "P3E_OCP_CPU0_PE3_C_TXN<12>" )
			)
			( signal "@baseboard_fab2_lib.baseboard_fab2(sch_1):p3e_ocp_cpu0_pe3_c_txn(13)"
				( attribute "CDS_PHYS_NET_NAME" "P3E_OCP_CPU0_PE3_C_TXN<13>"
					( Origin gPackager )
				)
				( attribute "PNN" "P3E_OCP_CPU0_PE3_C_TXN<13>"
					( Origin gPackager )
				)
				( objectStatus "P3E_OCP_CPU0_PE3_C_TXN<13>" )
			)
			( signal "@baseboard_fab2_lib.baseboard_fab2(sch_1):p3e_ocp_cpu0_pe3_c_txn(14)"
				( attribute "CDS_PHYS_NET_NAME" "P3E_OCP_CPU0_PE3_C_TXN<14>"
					( Origin gPackager )
				)
				( attribute "PNN" "P3E_OCP_CPU0_PE3_C_TXN<14>"
					( Origin gPackager )
				)
				( objectStatus "P3E_OCP_CPU0_PE3_C_TXN<14>" )
			)
			( signal "@baseboard_fab2_lib.baseboard_fab2(sch_1):p3e_ocp_cpu0_pe3_c_txn(15)"
				( attribute "CDS_PHYS_NET_NAME" "P3E_OCP_CPU0_PE3_C_TXN<15>"
					( Origin gPackager )
				)
				( attribute "PNN" "P3E_OCP_CPU0_PE3_C_TXN<15>"
					( Origin gPackager )
				)
				( objectStatus "P3E_OCP_CPU0_PE3_C_TXN<15>" )
			)
			( signal "@baseboard_fab2_lib.baseboard_fab2(sch_1):p3e_ocp_cpu0_pe3_c_txp(0)"
				( attribute "CDS_PHYS_NET_NAME" "P3E_OCP_CPU0_PE3_C_TXP<0>"
					( Origin gPackager )
				)
				( attribute "PNN" "P3E_OCP_CPU0_PE3_C_TXP<0>"
					( Origin gPackager )
				)
				( objectStatus "P3E_OCP_CPU0_PE3_C_TXP<0>" )
			)
			( signal "@baseboard_fab2_lib.baseboard_fab2(sch_1):p3e_ocp_cpu0_pe3_c_txp(1)"
				( attribute "CDS_PHYS_NET_NAME" "P3E_OCP_CPU0_PE3_C_TXP<1>"
					( Origin gPackager )
				)
				( attribute "PNN" "P3E_OCP_CPU0_PE3_C_TXP<1>"
					( Origin gPackager )
				)
				( objectStatus "P3E_OCP_CPU0_PE3_C_TXP<1>" )
			)
			( signal "@baseboard_fab2_lib.baseboard_fab2(sch_1):p3e_ocp_cpu0_pe3_c_txp(2)"
				( attribute "CDS_PHYS_NET_NAME" "P3E_OCP_CPU0_PE3_C_TXP<2>"
					( Origin gPackager )
				)
				( attribute "PNN" "P3E_OCP_CPU0_PE3_C_TXP<2>"
					( Origin gPackager )
				)
				( objectStatus "P3E_OCP_CPU0_PE3_C_TXP<2>" )
			)
			( signal "@baseboard_fab2_lib.baseboard_fab2(sch_1):p3e_ocp_cpu0_pe3_c_txp(3)"
				( attribute "CDS_PHYS_NET_NAME" "P3E_OCP_CPU0_PE3_C_TXP<3>"
					( Origin gPackager )
				)
				( attribute "PNN" "P3E_OCP_CPU0_PE3_C_TXP<3>"
					( Origin gPackager )
				)
				( objectStatus "P3E_OCP_CPU0_PE3_C_TXP<3>" )
			)
			( signal "@baseboard_fab2_lib.baseboard_fab2(sch_1):p3e_ocp_cpu0_pe3_c_txp(4)"
				( attribute "CDS_PHYS_NET_NAME" "P3E_OCP_CPU0_PE3_C_TXP<4>"
					( Origin gPackager )
				)
				( attribute "PNN" "P3E_OCP_CPU0_PE3_C_TXP<4>"
					( Origin gPackager )
				)
				( objectStatus "P3E_OCP_CPU0_PE3_C_TXP<4>" )
			)
			( signal "@baseboard_fab2_lib.baseboard_fab2(sch_1):p3e_ocp_cpu0_pe3_c_txp(5)"
				( attribute "CDS_PHYS_NET_NAME" "P3E_OCP_CPU0_PE3_C_TXP<5>"
					( Origin gPackager )
				)
				( attribute "PNN" "P3E_OCP_CPU0_PE3_C_TXP<5>"
					( Origin gPackager )
				)
				( objectStatus "P3E_OCP_CPU0_PE3_C_TXP<5>" )
			)
			( signal "@baseboard_fab2_lib.baseboard_fab2(sch_1):p3e_ocp_cpu0_pe3_c_txp(6)"
				( attribute "CDS_PHYS_NET_NAME" "P3E_OCP_CPU0_PE3_C_TXP<6>"
					( Origin gPackager )
				)
				( attribute "PNN" "P3E_OCP_CPU0_PE3_C_TXP<6>"
					( Origin gPackager )
				)
				( objectStatus "P3E_OCP_CPU0_PE3_C_TXP<6>" )
			)
			( signal "@baseboard_fab2_lib.baseboard_fab2(sch_1):p3e_ocp_cpu0_pe3_c_txp(7)"
				( attribute "CDS_PHYS_NET_NAME" "P3E_OCP_CPU0_PE3_C_TXP<7>"
					( Origin gPackager )
				)
				( attribute "PNN" "P3E_OCP_CPU0_PE3_C_TXP<7>"
					( Origin gPackager )
				)
				( objectStatus "P3E_OCP_CPU0_PE3_C_TXP<7>" )
			)
			( signal "@baseboard_fab2_lib.baseboard_fab2(sch_1):p3e_ocp_cpu0_pe3_c_txp(8)"
				( attribute "CDS_PHYS_NET_NAME" "P3E_OCP_CPU0_PE3_C_TXP<8>"
					( Origin gPackager )
				)
				( attribute "PNN" "P3E_OCP_CPU0_PE3_C_TXP<8>"
					( Origin gPackager )
				)
				( objectStatus "P3E_OCP_CPU0_PE3_C_TXP<8>" )
			)
			( signal "@baseboard_fab2_lib.baseboard_fab2(sch_1):p3e_ocp_cpu0_pe3_c_txp(9)"
				( attribute "CDS_PHYS_NET_NAME" "P3E_OCP_CPU0_PE3_C_TXP<9>"
					( Origin gPackager )
				)
				( attribute "PNN" "P3E_OCP_CPU0_PE3_C_TXP<9>"
					( Origin gPackager )
				)
				( objectStatus "P3E_OCP_CPU0_PE3_C_TXP<9>" )
			)
			( signal "@baseboard_fab2_lib.baseboard_fab2(sch_1):p3e_ocp_cpu0_pe3_c_txp(10)"
				( attribute "CDS_PHYS_NET_NAME" "P3E_OCP_CPU0_PE3_C_TXP<10>"
					( Origin gPackager )
				)
				( attribute "PNN" "P3E_OCP_CPU0_PE3_C_TXP<10>"
					( Origin gPackager )
				)
				( objectStatus "P3E_OCP_CPU0_PE3_C_TXP<10>" )
			)
			( signal "@baseboard_fab2_lib.baseboard_fab2(sch_1):p3e_ocp_cpu0_pe3_c_txp(11)"
				( attribute "CDS_PHYS_NET_NAME" "P3E_OCP_CPU0_PE3_C_TXP<11>"
					( Origin gPackager )
				)
				( attribute "PNN" "P3E_OCP_CPU0_PE3_C_TXP<11>"
					( Origin gPackager )
				)
				( objectStatus "P3E_OCP_CPU0_PE3_C_TXP<11>" )
			)
			( signal "@baseboard_fab2_lib.baseboard_fab2(sch_1):p3e_ocp_cpu0_pe3_c_txp(12)"
				( attribute "CDS_PHYS_NET_NAME" "P3E_OCP_CPU0_PE3_C_TXP<12>"
					( Origin gPackager )
				)
				( attribute "PNN" "P3E_OCP_CPU0_PE3_C_TXP<12>"
					( Origin gPackager )
				)
				( objectStatus "P3E_OCP_CPU0_PE3_C_TXP<12>" )
			)
			( signal "@baseboard_fab2_lib.baseboard_fab2(sch_1):p3e_ocp_cpu0_pe3_c_txp(13)"
				( attribute "CDS_PHYS_NET_NAME" "P3E_OCP_CPU0_PE3_C_TXP<13>"
					( Origin gPackager )
				)
				( attribute "PNN" "P3E_OCP_CPU0_PE3_C_TXP<13>"
					( Origin gPackager )
				)
				( objectStatus "P3E_OCP_CPU0_PE3_C_TXP<13>" )
			)
			( signal "@baseboard_fab2_lib.baseboard_fab2(sch_1):p3e_ocp_cpu0_pe3_c_txp(14)"
				( attribute "CDS_PHYS_NET_NAME" "P3E_OCP_CPU0_PE3_C_TXP<14>"
					( Origin gPackager )
				)
				( attribute "PNN" "P3E_OCP_CPU0_PE3_C_TXP<14>"
					( Origin gPackager )
				)
				( objectStatus "P3E_OCP_CPU0_PE3_C_TXP<14>" )
			)
			( signal "@baseboard_fab2_lib.baseboard_fab2(sch_1):p3e_ocp_cpu0_pe3_c_txp(15)"
				( attribute "CDS_PHYS_NET_NAME" "P3E_OCP_CPU0_PE3_C_TXP<15>"
					( Origin gPackager )
				)
				( attribute "PNN" "P3E_OCP_CPU0_PE3_C_TXP<15>"
					( Origin gPackager )
				)
				( objectStatus "P3E_OCP_CPU0_PE3_C_TXP<15>" )
			)
			( signal "@baseboard_fab2_lib.baseboard_fab2(sch_1):p3e_cpu0_pe1_pch_rxn(0)"
				( attribute "CDS_PHYS_NET_NAME" "P3E_CPU0_PE1_PCH_RXN<0>"
					( Origin gPackager )
				)
				( attribute "PNN" "P3E_CPU0_PE1_PCH_RXN<0>"
					( Origin gPackager )
				)
				( objectStatus "P3E_CPU0_PE1_PCH_RXN<0>" )
			)
			( signal "@baseboard_fab2_lib.baseboard_fab2(sch_1):p3e_cpu0_pe1_pch_rxn(1)"
				( attribute "CDS_PHYS_NET_NAME" "P3E_CPU0_PE1_PCH_RXN<1>"
					( Origin gPackager )
				)
				( attribute "PNN" "P3E_CPU0_PE1_PCH_RXN<1>"
					( Origin gPackager )
				)
				( objectStatus "P3E_CPU0_PE1_PCH_RXN<1>" )
			)
			( signal "@baseboard_fab2_lib.baseboard_fab2(sch_1):p3e_cpu0_pe1_pch_rxn(2)"
				( attribute "CDS_PHYS_NET_NAME" "P3E_CPU0_PE1_PCH_RXN<2>"
					( Origin gPackager )
				)
				( attribute "PNN" "P3E_CPU0_PE1_PCH_RXN<2>"
					( Origin gPackager )
				)
				( objectStatus "P3E_CPU0_PE1_PCH_RXN<2>" )
			)
			( signal "@baseboard_fab2_lib.baseboard_fab2(sch_1):p3e_cpu0_pe1_pch_rxn(3)"
				( attribute "CDS_PHYS_NET_NAME" "P3E_CPU0_PE1_PCH_RXN<3>"
					( Origin gPackager )
				)
				( attribute "PNN" "P3E_CPU0_PE1_PCH_RXN<3>"
					( Origin gPackager )
				)
				( objectStatus "P3E_CPU0_PE1_PCH_RXN<3>" )
			)
			( signal "@baseboard_fab2_lib.baseboard_fab2(sch_1):p3e_cpu0_pe1_pch_rxn(4)"
				( attribute "CDS_PHYS_NET_NAME" "P3E_CPU0_PE1_PCH_RXN<4>"
					( Origin gPackager )
				)
				( attribute "PNN" "P3E_CPU0_PE1_PCH_RXN<4>"
					( Origin gPackager )
				)
				( objectStatus "P3E_CPU0_PE1_PCH_RXN<4>" )
			)
			( signal "@baseboard_fab2_lib.baseboard_fab2(sch_1):p3e_cpu0_pe1_pch_rxn(5)"
				( attribute "CDS_PHYS_NET_NAME" "P3E_CPU0_PE1_PCH_RXN<5>"
					( Origin gPackager )
				)
				( attribute "PNN" "P3E_CPU0_PE1_PCH_RXN<5>"
					( Origin gPackager )
				)
				( objectStatus "P3E_CPU0_PE1_PCH_RXN<5>" )
			)
			( signal "@baseboard_fab2_lib.baseboard_fab2(sch_1):p3e_cpu0_pe1_pch_rxn(6)"
				( attribute "CDS_PHYS_NET_NAME" "P3E_CPU0_PE1_PCH_RXN<6>"
					( Origin gPackager )
				)
				( attribute "PNN" "P3E_CPU0_PE1_PCH_RXN<6>"
					( Origin gPackager )
				)
				( objectStatus "P3E_CPU0_PE1_PCH_RXN<6>" )
			)
			( signal "@baseboard_fab2_lib.baseboard_fab2(sch_1):p3e_cpu0_pe1_pch_rxn(7)"
				( attribute "CDS_PHYS_NET_NAME" "P3E_CPU0_PE1_PCH_RXN<7>"
					( Origin gPackager )
				)
				( attribute "PNN" "P3E_CPU0_PE1_PCH_RXN<7>"
					( Origin gPackager )
				)
				( objectStatus "P3E_CPU0_PE1_PCH_RXN<7>" )
			)
			( signal "@baseboard_fab2_lib.baseboard_fab2(sch_1):p3e_cpu0_pe1_pch_rxp(0)"
				( attribute "CDS_PHYS_NET_NAME" "P3E_CPU0_PE1_PCH_RXP<0>"
					( Origin gPackager )
				)
				( attribute "PNN" "P3E_CPU0_PE1_PCH_RXP<0>"
					( Origin gPackager )
				)
				( objectStatus "P3E_CPU0_PE1_PCH_RXP<0>" )
			)
			( signal "@baseboard_fab2_lib.baseboard_fab2(sch_1):p3e_cpu0_pe1_pch_rxp(1)"
				( attribute "CDS_PHYS_NET_NAME" "P3E_CPU0_PE1_PCH_RXP<1>"
					( Origin gPackager )
				)
				( attribute "PNN" "P3E_CPU0_PE1_PCH_RXP<1>"
					( Origin gPackager )
				)
				( objectStatus "P3E_CPU0_PE1_PCH_RXP<1>" )
			)
			( signal "@baseboard_fab2_lib.baseboard_fab2(sch_1):p3e_cpu0_pe1_pch_rxp(2)"
				( attribute "CDS_PHYS_NET_NAME" "P3E_CPU0_PE1_PCH_RXP<2>"
					( Origin gPackager )
				)
				( attribute "PNN" "P3E_CPU0_PE1_PCH_RXP<2>"
					( Origin gPackager )
				)
				( objectStatus "P3E_CPU0_PE1_PCH_RXP<2>" )
			)
			( signal "@baseboard_fab2_lib.baseboard_fab2(sch_1):p3e_cpu0_pe1_pch_rxp(3)"
				( attribute "CDS_PHYS_NET_NAME" "P3E_CPU0_PE1_PCH_RXP<3>"
					( Origin gPackager )
				)
				( attribute "PNN" "P3E_CPU0_PE1_PCH_RXP<3>"
					( Origin gPackager )
				)
				( objectStatus "P3E_CPU0_PE1_PCH_RXP<3>" )
			)
			( signal "@baseboard_fab2_lib.baseboard_fab2(sch_1):p3e_cpu0_pe1_pch_rxp(4)"
				( attribute "CDS_PHYS_NET_NAME" "P3E_CPU0_PE1_PCH_RXP<4>"
					( Origin gPackager )
				)
				( attribute "PNN" "P3E_CPU0_PE1_PCH_RXP<4>"
					( Origin gPackager )
				)
				( objectStatus "P3E_CPU0_PE1_PCH_RXP<4>" )
			)
			( signal "@baseboard_fab2_lib.baseboard_fab2(sch_1):p3e_cpu0_pe1_pch_rxp(5)"
				( attribute "CDS_PHYS_NET_NAME" "P3E_CPU0_PE1_PCH_RXP<5>"
					( Origin gPackager )
				)
				( attribute "PNN" "P3E_CPU0_PE1_PCH_RXP<5>"
					( Origin gPackager )
				)
				( objectStatus "P3E_CPU0_PE1_PCH_RXP<5>" )
			)
			( signal "@baseboard_fab2_lib.baseboard_fab2(sch_1):p3e_cpu0_pe1_pch_rxp(6)"
				( attribute "CDS_PHYS_NET_NAME" "P3E_CPU0_PE1_PCH_RXP<6>"
					( Origin gPackager )
				)
				( attribute "PNN" "P3E_CPU0_PE1_PCH_RXP<6>"
					( Origin gPackager )
				)
				( objectStatus "P3E_CPU0_PE1_PCH_RXP<6>" )
			)
			( signal "@baseboard_fab2_lib.baseboard_fab2(sch_1):p3e_cpu0_pe1_pch_rxp(7)"
				( attribute "CDS_PHYS_NET_NAME" "P3E_CPU0_PE1_PCH_RXP<7>"
					( Origin gPackager )
				)
				( attribute "PNN" "P3E_CPU0_PE1_PCH_RXP<7>"
					( Origin gPackager )
				)
				( objectStatus "P3E_CPU0_PE1_PCH_RXP<7>" )
			)
			( signal "@baseboard_fab2_lib.baseboard_fab2(sch_1):p3e_cpu0_pe1_pch_txn(0)"
				( attribute "CDS_PHYS_NET_NAME" "P3E_CPU0_PE1_PCH_TXN<0>"
					( Origin gPackager )
				)
				( attribute "PNN" "P3E_CPU0_PE1_PCH_TXN<0>"
					( Origin gPackager )
				)
				( objectStatus "P3E_CPU0_PE1_PCH_TXN<0>" )
			)
			( signal "@baseboard_fab2_lib.baseboard_fab2(sch_1):p3e_cpu0_pe1_pch_txn(1)"
				( attribute "CDS_PHYS_NET_NAME" "P3E_CPU0_PE1_PCH_TXN<1>"
					( Origin gPackager )
				)
				( attribute "PNN" "P3E_CPU0_PE1_PCH_TXN<1>"
					( Origin gPackager )
				)
				( objectStatus "P3E_CPU0_PE1_PCH_TXN<1>" )
			)
			( signal "@baseboard_fab2_lib.baseboard_fab2(sch_1):p3e_cpu0_pe1_pch_txn(2)"
				( attribute "CDS_PHYS_NET_NAME" "P3E_CPU0_PE1_PCH_TXN<2>"
					( Origin gPackager )
				)
				( attribute "PNN" "P3E_CPU0_PE1_PCH_TXN<2>"
					( Origin gPackager )
				)
				( objectStatus "P3E_CPU0_PE1_PCH_TXN<2>" )
			)
			( signal "@baseboard_fab2_lib.baseboard_fab2(sch_1):p3e_cpu0_pe1_pch_txn(3)"
				( attribute "CDS_PHYS_NET_NAME" "P3E_CPU0_PE1_PCH_TXN<3>"
					( Origin gPackager )
				)
				( attribute "PNN" "P3E_CPU0_PE1_PCH_TXN<3>"
					( Origin gPackager )
				)
				( objectStatus "P3E_CPU0_PE1_PCH_TXN<3>" )
			)
			( signal "@baseboard_fab2_lib.baseboard_fab2(sch_1):p3e_cpu0_pe1_pch_txn(4)"
				( attribute "CDS_PHYS_NET_NAME" "P3E_CPU0_PE1_PCH_TXN<4>"
					( Origin gPackager )
				)
				( attribute "PNN" "P3E_CPU0_PE1_PCH_TXN<4>"
					( Origin gPackager )
				)
				( objectStatus "P3E_CPU0_PE1_PCH_TXN<4>" )
			)
			( signal "@baseboard_fab2_lib.baseboard_fab2(sch_1):p3e_cpu0_pe1_pch_txn(5)"
				( attribute "CDS_PHYS_NET_NAME" "P3E_CPU0_PE1_PCH_TXN<5>"
					( Origin gPackager )
				)
				( attribute "PNN" "P3E_CPU0_PE1_PCH_TXN<5>"
					( Origin gPackager )
				)
				( objectStatus "P3E_CPU0_PE1_PCH_TXN<5>" )
			)
			( signal "@baseboard_fab2_lib.baseboard_fab2(sch_1):p3e_cpu0_pe1_pch_txn(6)"
				( attribute "CDS_PHYS_NET_NAME" "P3E_CPU0_PE1_PCH_TXN<6>"
					( Origin gPackager )
				)
				( attribute "PNN" "P3E_CPU0_PE1_PCH_TXN<6>"
					( Origin gPackager )
				)
				( objectStatus "P3E_CPU0_PE1_PCH_TXN<6>" )
			)
			( signal "@baseboard_fab2_lib.baseboard_fab2(sch_1):p3e_cpu0_pe1_pch_txn(7)"
				( attribute "CDS_PHYS_NET_NAME" "P3E_CPU0_PE1_PCH_TXN<7>"
					( Origin gPackager )
				)
				( attribute "PNN" "P3E_CPU0_PE1_PCH_TXN<7>"
					( Origin gPackager )
				)
				( objectStatus "P3E_CPU0_PE1_PCH_TXN<7>" )
			)
			( signal "@baseboard_fab2_lib.baseboard_fab2(sch_1):p3e_cpu0_pe1_pch_txp(0)"
				( attribute "CDS_PHYS_NET_NAME" "P3E_CPU0_PE1_PCH_TXP<0>"
					( Origin gPackager )
				)
				( attribute "PNN" "P3E_CPU0_PE1_PCH_TXP<0>"
					( Origin gPackager )
				)
				( objectStatus "P3E_CPU0_PE1_PCH_TXP<0>" )
			)
			( signal "@baseboard_fab2_lib.baseboard_fab2(sch_1):p3e_cpu0_pe1_pch_txp(1)"
				( attribute "CDS_PHYS_NET_NAME" "P3E_CPU0_PE1_PCH_TXP<1>"
					( Origin gPackager )
				)
				( attribute "PNN" "P3E_CPU0_PE1_PCH_TXP<1>"
					( Origin gPackager )
				)
				( objectStatus "P3E_CPU0_PE1_PCH_TXP<1>" )
			)
			( signal "@baseboard_fab2_lib.baseboard_fab2(sch_1):p3e_cpu0_pe1_pch_txp(2)"
				( attribute "CDS_PHYS_NET_NAME" "P3E_CPU0_PE1_PCH_TXP<2>"
					( Origin gPackager )
				)
				( attribute "PNN" "P3E_CPU0_PE1_PCH_TXP<2>"
					( Origin gPackager )
				)
				( objectStatus "P3E_CPU0_PE1_PCH_TXP<2>" )
			)
			( signal "@baseboard_fab2_lib.baseboard_fab2(sch_1):p3e_cpu0_pe1_pch_txp(3)"
				( attribute "CDS_PHYS_NET_NAME" "P3E_CPU0_PE1_PCH_TXP<3>"
					( Origin gPackager )
				)
				( attribute "PNN" "P3E_CPU0_PE1_PCH_TXP<3>"
					( Origin gPackager )
				)
				( objectStatus "P3E_CPU0_PE1_PCH_TXP<3>" )
			)
			( signal "@baseboard_fab2_lib.baseboard_fab2(sch_1):p3e_cpu0_pe1_pch_txp(4)"
				( attribute "CDS_PHYS_NET_NAME" "P3E_CPU0_PE1_PCH_TXP<4>"
					( Origin gPackager )
				)
				( attribute "PNN" "P3E_CPU0_PE1_PCH_TXP<4>"
					( Origin gPackager )
				)
				( objectStatus "P3E_CPU0_PE1_PCH_TXP<4>" )
			)
			( signal "@baseboard_fab2_lib.baseboard_fab2(sch_1):p3e_cpu0_pe1_pch_txp(5)"
				( attribute "CDS_PHYS_NET_NAME" "P3E_CPU0_PE1_PCH_TXP<5>"
					( Origin gPackager )
				)
				( attribute "PNN" "P3E_CPU0_PE1_PCH_TXP<5>"
					( Origin gPackager )
				)
				( objectStatus "P3E_CPU0_PE1_PCH_TXP<5>" )
			)
			( signal "@baseboard_fab2_lib.baseboard_fab2(sch_1):p3e_cpu0_pe1_pch_txp(6)"
				( attribute "CDS_PHYS_NET_NAME" "P3E_CPU0_PE1_PCH_TXP<6>"
					( Origin gPackager )
				)
				( attribute "PNN" "P3E_CPU0_PE1_PCH_TXP<6>"
					( Origin gPackager )
				)
				( objectStatus "P3E_CPU0_PE1_PCH_TXP<6>" )
			)
			( signal "@baseboard_fab2_lib.baseboard_fab2(sch_1):p3e_cpu0_pe1_pch_txp(7)"
				( attribute "CDS_PHYS_NET_NAME" "P3E_CPU0_PE1_PCH_TXP<7>"
					( Origin gPackager )
				)
				( attribute "PNN" "P3E_CPU0_PE1_PCH_TXP<7>"
					( Origin gPackager )
				)
				( objectStatus "P3E_CPU0_PE1_PCH_TXP<7>" )
			)
			( signal "@baseboard_fab2_lib.baseboard_fab2(sch_1):p3e_cpu0_pe1_ss_c_txn(0)"
				( attribute "CDS_PHYS_NET_NAME" "P3E_CPU0_PE1_SS_C_TXN<0>"
					( Origin gPackager )
				)
				( attribute "PNN" "P3E_CPU0_PE1_SS_C_TXN<0>"
					( Origin gPackager )
				)
				( objectStatus "P3E_CPU0_PE1_SS_C_TXN<0>" )
			)
			( signal "@baseboard_fab2_lib.baseboard_fab2(sch_1):p3e_cpu0_pe1_ss_c_txn(1)"
				( attribute "CDS_PHYS_NET_NAME" "P3E_CPU0_PE1_SS_C_TXN<1>"
					( Origin gPackager )
				)
				( attribute "PNN" "P3E_CPU0_PE1_SS_C_TXN<1>"
					( Origin gPackager )
				)
				( objectStatus "P3E_CPU0_PE1_SS_C_TXN<1>" )
			)
			( signal "@baseboard_fab2_lib.baseboard_fab2(sch_1):p3e_cpu0_pe1_ss_c_txn(2)"
				( attribute "CDS_PHYS_NET_NAME" "P3E_CPU0_PE1_SS_C_TXN<2>"
					( Origin gPackager )
				)
				( attribute "PNN" "P3E_CPU0_PE1_SS_C_TXN<2>"
					( Origin gPackager )
				)
				( objectStatus "P3E_CPU0_PE1_SS_C_TXN<2>" )
			)
			( signal "@baseboard_fab2_lib.baseboard_fab2(sch_1):p3e_cpu0_pe1_ss_c_txn(3)"
				( attribute "CDS_PHYS_NET_NAME" "P3E_CPU0_PE1_SS_C_TXN<3>"
					( Origin gPackager )
				)
				( attribute "PNN" "P3E_CPU0_PE1_SS_C_TXN<3>"
					( Origin gPackager )
				)
				( objectStatus "P3E_CPU0_PE1_SS_C_TXN<3>" )
			)
			( signal "@baseboard_fab2_lib.baseboard_fab2(sch_1):p3e_cpu0_pe1_ss_c_txn(4)"
				( attribute "CDS_PHYS_NET_NAME" "P3E_CPU0_PE1_SS_C_TXN<4>"
					( Origin gPackager )
				)
				( attribute "PNN" "P3E_CPU0_PE1_SS_C_TXN<4>"
					( Origin gPackager )
				)
				( objectStatus "P3E_CPU0_PE1_SS_C_TXN<4>" )
			)
			( signal "@baseboard_fab2_lib.baseboard_fab2(sch_1):p3e_cpu0_pe1_ss_c_txn(5)"
				( attribute "CDS_PHYS_NET_NAME" "P3E_CPU0_PE1_SS_C_TXN<5>"
					( Origin gPackager )
				)
				( attribute "PNN" "P3E_CPU0_PE1_SS_C_TXN<5>"
					( Origin gPackager )
				)
				( objectStatus "P3E_CPU0_PE1_SS_C_TXN<5>" )
			)
			( signal "@baseboard_fab2_lib.baseboard_fab2(sch_1):p3e_cpu0_pe1_ss_c_txn(6)"
				( attribute "CDS_PHYS_NET_NAME" "P3E_CPU0_PE1_SS_C_TXN<6>"
					( Origin gPackager )
				)
				( attribute "PNN" "P3E_CPU0_PE1_SS_C_TXN<6>"
					( Origin gPackager )
				)
				( objectStatus "P3E_CPU0_PE1_SS_C_TXN<6>" )
			)
			( signal "@baseboard_fab2_lib.baseboard_fab2(sch_1):p3e_cpu0_pe1_ss_c_txn(7)"
				( attribute "CDS_PHYS_NET_NAME" "P3E_CPU0_PE1_SS_C_TXN<7>"
					( Origin gPackager )
				)
				( attribute "PNN" "P3E_CPU0_PE1_SS_C_TXN<7>"
					( Origin gPackager )
				)
				( objectStatus "P3E_CPU0_PE1_SS_C_TXN<7>" )
			)
			( signal "@baseboard_fab2_lib.baseboard_fab2(sch_1):p3e_cpu0_pe1_ss_c_txp(0)"
				( attribute "CDS_PHYS_NET_NAME" "P3E_CPU0_PE1_SS_C_TXP<0>"
					( Origin gPackager )
				)
				( attribute "PNN" "P3E_CPU0_PE1_SS_C_TXP<0>"
					( Origin gPackager )
				)
				( objectStatus "P3E_CPU0_PE1_SS_C_TXP<0>" )
			)
			( signal "@baseboard_fab2_lib.baseboard_fab2(sch_1):p3e_cpu0_pe1_ss_c_txp(1)"
				( attribute "CDS_PHYS_NET_NAME" "P3E_CPU0_PE1_SS_C_TXP<1>"
					( Origin gPackager )
				)
				( attribute "PNN" "P3E_CPU0_PE1_SS_C_TXP<1>"
					( Origin gPackager )
				)
				( objectStatus "P3E_CPU0_PE1_SS_C_TXP<1>" )
			)
			( signal "@baseboard_fab2_lib.baseboard_fab2(sch_1):p3e_cpu0_pe1_ss_c_txp(2)"
				( attribute "CDS_PHYS_NET_NAME" "P3E_CPU0_PE1_SS_C_TXP<2>"
					( Origin gPackager )
				)
				( attribute "PNN" "P3E_CPU0_PE1_SS_C_TXP<2>"
					( Origin gPackager )
				)
				( objectStatus "P3E_CPU0_PE1_SS_C_TXP<2>" )
			)
			( signal "@baseboard_fab2_lib.baseboard_fab2(sch_1):p3e_cpu0_pe1_ss_c_txp(3)"
				( attribute "CDS_PHYS_NET_NAME" "P3E_CPU0_PE1_SS_C_TXP<3>"
					( Origin gPackager )
				)
				( attribute "PNN" "P3E_CPU0_PE1_SS_C_TXP<3>"
					( Origin gPackager )
				)
				( objectStatus "P3E_CPU0_PE1_SS_C_TXP<3>" )
			)
			( signal "@baseboard_fab2_lib.baseboard_fab2(sch_1):p3e_cpu0_pe1_ss_c_txp(4)"
				( attribute "CDS_PHYS_NET_NAME" "P3E_CPU0_PE1_SS_C_TXP<4>"
					( Origin gPackager )
				)
				( attribute "PNN" "P3E_CPU0_PE1_SS_C_TXP<4>"
					( Origin gPackager )
				)
				( objectStatus "P3E_CPU0_PE1_SS_C_TXP<4>" )
			)
			( signal "@baseboard_fab2_lib.baseboard_fab2(sch_1):p3e_cpu0_pe1_ss_c_txp(5)"
				( attribute "CDS_PHYS_NET_NAME" "P3E_CPU0_PE1_SS_C_TXP<5>"
					( Origin gPackager )
				)
				( attribute "PNN" "P3E_CPU0_PE1_SS_C_TXP<5>"
					( Origin gPackager )
				)
				( objectStatus "P3E_CPU0_PE1_SS_C_TXP<5>" )
			)
			( signal "@baseboard_fab2_lib.baseboard_fab2(sch_1):p3e_cpu0_pe1_ss_c_txp(6)"
				( attribute "CDS_PHYS_NET_NAME" "P3E_CPU0_PE1_SS_C_TXP<6>"
					( Origin gPackager )
				)
				( attribute "PNN" "P3E_CPU0_PE1_SS_C_TXP<6>"
					( Origin gPackager )
				)
				( objectStatus "P3E_CPU0_PE1_SS_C_TXP<6>" )
			)
			( signal "@baseboard_fab2_lib.baseboard_fab2(sch_1):p3e_cpu0_pe1_ss_c_txp(7)"
				( attribute "CDS_PHYS_NET_NAME" "P3E_CPU0_PE1_SS_C_TXP<7>"
					( Origin gPackager )
				)
				( attribute "PNN" "P3E_CPU0_PE1_SS_C_TXP<7>"
					( Origin gPackager )
				)
				( objectStatus "P3E_CPU0_PE1_SS_C_TXP<7>" )
			)
			( signal "@baseboard_fab2_lib.baseboard_fab2(sch_1):p3e_cpu0_pe1_ss_r_rxn(0)"
				( attribute "CDS_PHYS_NET_NAME" "P3E_CPU0_PE1_SS_R_RXN<0>"
					( Origin gPackager )
				)
				( attribute "PNN" "P3E_CPU0_PE1_SS_R_RXN<0>"
					( Origin gPackager )
				)
				( objectStatus "P3E_CPU0_PE1_SS_R_RXN<0>" )
			)
			( signal "@baseboard_fab2_lib.baseboard_fab2(sch_1):p3e_cpu0_pe1_ss_r_rxn(1)"
				( attribute "CDS_PHYS_NET_NAME" "P3E_CPU0_PE1_SS_R_RXN<1>"
					( Origin gPackager )
				)
				( attribute "PNN" "P3E_CPU0_PE1_SS_R_RXN<1>"
					( Origin gPackager )
				)
				( objectStatus "P3E_CPU0_PE1_SS_R_RXN<1>" )
			)
			( signal "@baseboard_fab2_lib.baseboard_fab2(sch_1):p3e_cpu0_pe1_ss_r_rxn(2)"
				( attribute "CDS_PHYS_NET_NAME" "P3E_CPU0_PE1_SS_R_RXN<2>"
					( Origin gPackager )
				)
				( attribute "PNN" "P3E_CPU0_PE1_SS_R_RXN<2>"
					( Origin gPackager )
				)
				( objectStatus "P3E_CPU0_PE1_SS_R_RXN<2>" )
			)
			( signal "@baseboard_fab2_lib.baseboard_fab2(sch_1):p3e_cpu0_pe1_ss_r_rxn(3)"
				( attribute "CDS_PHYS_NET_NAME" "P3E_CPU0_PE1_SS_R_RXN<3>"
					( Origin gPackager )
				)
				( attribute "PNN" "P3E_CPU0_PE1_SS_R_RXN<3>"
					( Origin gPackager )
				)
				( objectStatus "P3E_CPU0_PE1_SS_R_RXN<3>" )
			)
			( signal "@baseboard_fab2_lib.baseboard_fab2(sch_1):p3e_cpu0_pe1_ss_r_rxn(4)"
				( attribute "CDS_PHYS_NET_NAME" "P3E_CPU0_PE1_SS_R_RXN<4>"
					( Origin gPackager )
				)
				( attribute "PNN" "P3E_CPU0_PE1_SS_R_RXN<4>"
					( Origin gPackager )
				)
				( objectStatus "P3E_CPU0_PE1_SS_R_RXN<4>" )
			)
			( signal "@baseboard_fab2_lib.baseboard_fab2(sch_1):p3e_cpu0_pe1_ss_r_rxn(5)"
				( attribute "CDS_PHYS_NET_NAME" "P3E_CPU0_PE1_SS_R_RXN<5>"
					( Origin gPackager )
				)
				( attribute "PNN" "P3E_CPU0_PE1_SS_R_RXN<5>"
					( Origin gPackager )
				)
				( objectStatus "P3E_CPU0_PE1_SS_R_RXN<5>" )
			)
			( signal "@baseboard_fab2_lib.baseboard_fab2(sch_1):p3e_cpu0_pe1_ss_r_rxn(6)"
				( attribute "CDS_PHYS_NET_NAME" "P3E_CPU0_PE1_SS_R_RXN<6>"
					( Origin gPackager )
				)
				( attribute "PNN" "P3E_CPU0_PE1_SS_R_RXN<6>"
					( Origin gPackager )
				)
				( objectStatus "P3E_CPU0_PE1_SS_R_RXN<6>" )
			)
			( signal "@baseboard_fab2_lib.baseboard_fab2(sch_1):p3e_cpu0_pe1_ss_r_rxn(7)"
				( attribute "CDS_PHYS_NET_NAME" "P3E_CPU0_PE1_SS_R_RXN<7>"
					( Origin gPackager )
				)
				( attribute "PNN" "P3E_CPU0_PE1_SS_R_RXN<7>"
					( Origin gPackager )
				)
				( objectStatus "P3E_CPU0_PE1_SS_R_RXN<7>" )
			)
			( signal "@baseboard_fab2_lib.baseboard_fab2(sch_1):p3e_cpu0_pe1_ss_r_rxp(0)"
				( attribute "CDS_PHYS_NET_NAME" "P3E_CPU0_PE1_SS_R_RXP<0>"
					( Origin gPackager )
				)
				( attribute "PNN" "P3E_CPU0_PE1_SS_R_RXP<0>"
					( Origin gPackager )
				)
				( objectStatus "P3E_CPU0_PE1_SS_R_RXP<0>" )
			)
			( signal "@baseboard_fab2_lib.baseboard_fab2(sch_1):p3e_cpu0_pe1_ss_r_rxp(1)"
				( attribute "CDS_PHYS_NET_NAME" "P3E_CPU0_PE1_SS_R_RXP<1>"
					( Origin gPackager )
				)
				( attribute "PNN" "P3E_CPU0_PE1_SS_R_RXP<1>"
					( Origin gPackager )
				)
				( objectStatus "P3E_CPU0_PE1_SS_R_RXP<1>" )
			)
			( signal "@baseboard_fab2_lib.baseboard_fab2(sch_1):p3e_cpu0_pe1_ss_r_rxp(2)"
				( attribute "CDS_PHYS_NET_NAME" "P3E_CPU0_PE1_SS_R_RXP<2>"
					( Origin gPackager )
				)
				( attribute "PNN" "P3E_CPU0_PE1_SS_R_RXP<2>"
					( Origin gPackager )
				)
				( objectStatus "P3E_CPU0_PE1_SS_R_RXP<2>" )
			)
			( signal "@baseboard_fab2_lib.baseboard_fab2(sch_1):p3e_cpu0_pe1_ss_r_rxp(3)"
				( attribute "CDS_PHYS_NET_NAME" "P3E_CPU0_PE1_SS_R_RXP<3>"
					( Origin gPackager )
				)
				( attribute "PNN" "P3E_CPU0_PE1_SS_R_RXP<3>"
					( Origin gPackager )
				)
				( objectStatus "P3E_CPU0_PE1_SS_R_RXP<3>" )
			)
			( signal "@baseboard_fab2_lib.baseboard_fab2(sch_1):p3e_cpu0_pe1_ss_r_rxp(4)"
				( attribute "CDS_PHYS_NET_NAME" "P3E_CPU0_PE1_SS_R_RXP<4>"
					( Origin gPackager )
				)
				( attribute "PNN" "P3E_CPU0_PE1_SS_R_RXP<4>"
					( Origin gPackager )
				)
				( objectStatus "P3E_CPU0_PE1_SS_R_RXP<4>" )
			)
			( signal "@baseboard_fab2_lib.baseboard_fab2(sch_1):p3e_cpu0_pe1_ss_r_rxp(5)"
				( attribute "CDS_PHYS_NET_NAME" "P3E_CPU0_PE1_SS_R_RXP<5>"
					( Origin gPackager )
				)
				( attribute "PNN" "P3E_CPU0_PE1_SS_R_RXP<5>"
					( Origin gPackager )
				)
				( objectStatus "P3E_CPU0_PE1_SS_R_RXP<5>" )
			)
			( signal "@baseboard_fab2_lib.baseboard_fab2(sch_1):p3e_cpu0_pe1_ss_r_rxp(6)"
				( attribute "CDS_PHYS_NET_NAME" "P3E_CPU0_PE1_SS_R_RXP<6>"
					( Origin gPackager )
				)
				( attribute "PNN" "P3E_CPU0_PE1_SS_R_RXP<6>"
					( Origin gPackager )
				)
				( objectStatus "P3E_CPU0_PE1_SS_R_RXP<6>" )
			)
			( signal "@baseboard_fab2_lib.baseboard_fab2(sch_1):p3e_cpu0_pe1_ss_r_rxp(7)"
				( attribute "CDS_PHYS_NET_NAME" "P3E_CPU0_PE1_SS_R_RXP<7>"
					( Origin gPackager )
				)
				( attribute "PNN" "P3E_CPU0_PE1_SS_R_RXP<7>"
					( Origin gPackager )
				)
				( objectStatus "P3E_CPU0_PE1_SS_R_RXP<7>" )
			)
			( signal "@baseboard_fab2_lib.baseboard_fab2(sch_1):clk_100m_pch_slotx24_s0_dn"
				( attribute "CDS_PHYS_NET_NAME" "CLK_100M_PCH_SLOTX24_S0_DN"
					( Origin gPackager )
				)
				( objectStatus "CLK_100M_PCH_SLOTX24_S0_DN" )
			)
			( signal "@baseboard_fab2_lib.baseboard_fab2(sch_1):clk_100m_pch_slotx24_s0_dp"
				( attribute "CDS_PHYS_NET_NAME" "CLK_100M_PCH_SLOTX24_S0_DP"
					( Origin gPackager )
				)
				( objectStatus "CLK_100M_PCH_SLOTX24_S0_DP" )
			)
			( signal "@baseboard_fab2_lib.baseboard_fab2(sch_1):clk_100m_pch_slotx24_s1_dn"
				( attribute "CDS_PHYS_NET_NAME" "CLK_100M_PCH_SLOTX24_S1_DN"
					( Origin gPackager )
				)
				( objectStatus "CLK_100M_PCH_SLOTX24_S1_DN" )
			)
			( signal "@baseboard_fab2_lib.baseboard_fab2(sch_1):clk_100m_pch_slotx24_s1_dp"
				( attribute "CDS_PHYS_NET_NAME" "CLK_100M_PCH_SLOTX24_S1_DP"
					( Origin gPackager )
				)
				( objectStatus "CLK_100M_PCH_SLOTX24_S1_DP" )
			)
			( signal "@baseboard_fab2_lib.baseboard_fab2(sch_1):clk_100m_pch_slotx24_s2_dn"
				( attribute "CDS_PHYS_NET_NAME" "CLK_100M_PCH_SLOTX24_S2_DN"
					( Origin gPackager )
				)
				( objectStatus "CLK_100M_PCH_SLOTX24_S2_DN" )
			)
			( signal "@baseboard_fab2_lib.baseboard_fab2(sch_1):clk_100m_pch_slotx24_s2_dp"
				( attribute "CDS_PHYS_NET_NAME" "CLK_100M_PCH_SLOTX24_S2_DP"
					( Origin gPackager )
				)
				( objectStatus "CLK_100M_PCH_SLOTX24_S2_DP" )
			)
			( signal "@baseboard_fab2_lib.baseboard_fab2(sch_1):clk_100m_pch_slotx24_s3_dn"
				( attribute "CDS_PHYS_NET_NAME" "CLK_100M_PCH_SLOTX24_S3_DN"
					( Origin gPackager )
				)
				( objectStatus "CLK_100M_PCH_SLOTX24_S3_DN" )
			)
			( signal "@baseboard_fab2_lib.baseboard_fab2(sch_1):clk_100m_pch_slotx24_s3_dp"
				( attribute "CDS_PHYS_NET_NAME" "CLK_100M_PCH_SLOTX24_S3_DP"
					( Origin gPackager )
				)
				( objectStatus "CLK_100M_PCH_SLOTX24_S3_DP" )
			)
			( signal "@baseboard_fab2_lib.baseboard_fab2(sch_1):clk_100m_pch_slotx24_s4_dn"
				( attribute "CDS_PHYS_NET_NAME" "CLK_100M_PCH_SLOTX24_S4_DN"
					( Origin gPackager )
				)
				( objectStatus "CLK_100M_PCH_SLOTX24_S4_DN" )
			)
			( signal "@baseboard_fab2_lib.baseboard_fab2(sch_1):clk_100m_pch_slotx24_s4_dp"
				( attribute "CDS_PHYS_NET_NAME" "CLK_100M_PCH_SLOTX24_S4_DP"
					( Origin gPackager )
				)
				( objectStatus "CLK_100M_PCH_SLOTX24_S4_DP" )
			)
			( signal "@baseboard_fab2_lib.baseboard_fab2(sch_1):clk_100m_pch_slotx24_s5_dn"
				( attribute "CDS_PHYS_NET_NAME" "CLK_100M_PCH_SLOTX24_S5_DN"
					( Origin gPackager )
				)
				( objectStatus "CLK_100M_PCH_SLOTX24_S5_DN" )
			)
			( signal "@baseboard_fab2_lib.baseboard_fab2(sch_1):clk_100m_pch_slotx24_s5_dp"
				( attribute "CDS_PHYS_NET_NAME" "CLK_100M_PCH_SLOTX24_S5_DP"
					( Origin gPackager )
				)
				( objectStatus "CLK_100M_PCH_SLOTX24_S5_DP" )
			)
			( signal "@baseboard_fab2_lib.baseboard_fab2(sch_1):fm_pe_slotx24_wake_n"
				( attribute "CDS_PHYS_NET_NAME" "FM_PE_SLOTX24_WAKE_N"
					( Origin gPackager )
				)
				( objectStatus "FM_PE_SLOTX24_WAKE_N" )
			)
			( signal "@baseboard_fab2_lib.baseboard_fab2(sch_1):fm_prsnt_2_2_n"
				( attribute "CDS_PHYS_NET_NAME" "FM_PRSNT_2_2_N"
					( Origin gPackager )
				)
				( objectStatus "FM_PRSNT_2_2_N" )
			)
			( signal "@baseboard_fab2_lib.baseboard_fab2(sch_1):fm_prsnt_2_3_n"
				( attribute "CDS_PHYS_NET_NAME" "FM_PRSNT_2_3_N"
					( Origin gPackager )
				)
				( objectStatus "FM_PRSNT_2_3_N" )
			)
			( signal "@baseboard_fab2_lib.baseboard_fab2(sch_1):fm_prsnt_2_4_n"
				( attribute "CDS_PHYS_NET_NAME" "FM_PRSNT_2_4_N"
					( Origin gPackager )
				)
				( objectStatus "FM_PRSNT_2_4_N" )
			)
			( signal "@baseboard_fab2_lib.baseboard_fab2(sch_1):fm_prsnt_2_5_n"
				( attribute "CDS_PHYS_NET_NAME" "FM_PRSNT_2_5_N"
					( Origin gPackager )
				)
				( objectStatus "FM_PRSNT_2_5_N" )
			)
			( signal "@baseboard_fab2_lib.baseboard_fab2(sch_1):fm_pwrbrk_slot_n"
				( attribute "CDS_PHYS_NET_NAME" "FM_PWRBRK_SLOT_N"
					( Origin gPackager )
				)
				( objectStatus "FM_PWRBRK_SLOT_N" )
			)
			( signal "@baseboard_fab2_lib.baseboard_fab2(sch_1):fm_slt_cfg0"
				( attribute "CDS_PHYS_NET_NAME" "FM_SLT_CFG0"
					( Origin gPackager )
				)
				( objectStatus "FM_SLT_CFG0" )
			)
			( signal "@baseboard_fab2_lib.baseboard_fab2(sch_1):fm_slt_cfg1"
				( attribute "CDS_PHYS_NET_NAME" "FM_SLT_CFG1"
					( Origin gPackager )
				)
				( objectStatus "FM_SLT_CFG1" )
			)
			( signal "@baseboard_fab2_lib.baseboard_fab2(sch_1):irq_oob_mgmt_riser_alert_n"
				( alias ( signalRef "@baseboard_fab2_lib.baseboard_fab2(sch_1):page145_irq_oob_mgmt_riser_alert_n") )
				( attribute "CDS_PHYS_NET_NAME" "IRQ_OOB_MGMT_RISER_ALERT_N"
					( Origin gPackager )
				)
				( attribute "PHYS_NET_NAME" "IRQ_OOB_MGMT_RISER_ALERT_N"
					( Origin gPackager )
				)
				( objectStatus "IRQ_OOB_MGMT_RISER_ALERT_N" )
			)
			( signal "@baseboard_fab2_lib.baseboard_fab2(sch_1):page145_irq_oob_mgmt_riser_alert_n"
				( attribute "CDS_PHYS_NET_NAME" "IRQ_OOB_MGMT_RISER_ALERT_N"
					( Origin gPackager )
				)
				( objectFlag fObjectAlias )
				( objectStatus "page145_irq_oob_mgmt_riser_alert_n" )
			)
			( signal "@baseboard_fab2_lib.baseboard_fab2(sch_1):p12v"
				( alias ( signalRef "@baseboard_fab2_lib.baseboard_fab2(sch_1):page108_p12v") )
				( alias ( signalRef "@baseboard_fab2_lib.baseboard_fab2(sch_1):page172_p12v") )
				( alias ( signalRef "@baseboard_fab2_lib.baseboard_fab2(sch_1):page196_p12v") )
				( alias ( signalRef "@baseboard_fab2_lib.baseboard_fab2(sch_1):page198_p12v") )
				( attribute "CDS_PHYS_NET_NAME" "P12V"
					( Origin gPackager )
				)
				( attribute "VOLTAGE" "+12."
					( Units "uVoltage" "V" 1.000000)
					( Status sAliasFlattened )
					( Status sAliasConflict )
					( Origin gFrontEnd )
				)
				( objectStatus "P12V" )
			)
			( signal "@baseboard_fab2_lib.baseboard_fab2(sch_1):page108_p12v"
				( attribute "VOLTAGE" "+12."
					( Units "uVoltage" "V" 1.000000)
					( Origin gFrontEnd )
				)
				( objectFlag fObjectAlias )
				( objectStatus "page108_p12v" )
			)
			( signal "@baseboard_fab2_lib.baseboard_fab2(sch_1):page172_p12v"
				( attribute "VOLTAGE" "12.0V"
					( Units "uVoltage" "V" 1.000000)
					( Origin gFrontEnd )
				)
				( objectFlag fObjectAlias )
				( objectStatus "page172_p12v" )
			)
			( signal "@baseboard_fab2_lib.baseboard_fab2(sch_1):page196_p12v"
				( attribute "VOLTAGE" "12.0V"
					( Units "uVoltage" "V" 1.000000)
					( Origin gFrontEnd )
				)
				( objectFlag fObjectAlias )
				( objectStatus "page196_p12v" )
			)
			( signal "@baseboard_fab2_lib.baseboard_fab2(sch_1):page198_p12v"
				( attribute "VOLTAGE" "+12.0V"
					( Units "uVoltage" "V" 1.000000)
					( Origin gFrontEnd )
				)
				( objectFlag fObjectAlias )
				( objectStatus "page198_p12v" )
			)
			( signal "@baseboard_fab2_lib.baseboard_fab2(sch_1):rst_pcie_riser1_perst_n"
				( attribute "CDS_PHYS_NET_NAME" "RST_PCIE_RISER1_PERST_N"
					( Origin gPackager )
				)
				( objectStatus "RST_PCIE_RISER1_PERST_N" )
			)
			( signal "@baseboard_fab2_lib.baseboard_fab2(sch_1):rst_pcie_riser1_perst_r_n"
				( attribute "CDS_PHYS_NET_NAME" "RST_PCIE_RISER1_PERST_R_N"
					( Origin gPackager )
				)
				( objectStatus "RST_PCIE_RISER1_PERST_R_N" )
			)
			( signal "@baseboard_fab2_lib.baseboard_fab2(sch_1):smb_slotx24_bmc_stby_lvc3_scl"
				( attribute "CDS_PHYS_NET_NAME" "SMB_SLOTX24_BMC_STBY_LVC3_SCL"
					( Origin gPackager )
				)
				( objectStatus "SMB_SLOTX24_BMC_STBY_LVC3_SCL" )
			)
			( signal "@baseboard_fab2_lib.baseboard_fab2(sch_1):smb_slotx24_bmc_stby_lvc3_sda"
				( attribute "CDS_PHYS_NET_NAME" "SMB_SLOTX24_BMC_STBY_LVC3_SDA"
					( Origin gPackager )
				)
				( objectStatus "SMB_SLOTX24_BMC_STBY_LVC3_SDA" )
			)
			( signal "@baseboard_fab2_lib.baseboard_fab2(sch_1):smb_slotx24_stby_lvc3_scl_r2"
				( attribute "CDS_PHYS_NET_NAME" "SMB_SLOTX24_STBY_LVC3_SCL_R2"
					( Origin gPackager )
				)
				( objectStatus "SMB_SLOTX24_STBY_LVC3_SCL_R2" )
			)
			( signal "@baseboard_fab2_lib.baseboard_fab2(sch_1):smb_slotx24_stby_lvc3_sda_r2"
				( attribute "CDS_PHYS_NET_NAME" "SMB_SLOTX24_STBY_LVC3_SDA_R2"
					( Origin gPackager )
				)
				( objectStatus "SMB_SLOTX24_STBY_LVC3_SDA_R2" )
			)
			( signal "@baseboard_fab2_lib.baseboard_fab2(sch_1):fm_prsnt_2_6_n"
				( attribute "CDS_PHYS_NET_NAME" "FM_PRSNT_2_6_N"
					( Origin gPackager )
				)
				( objectStatus "FM_PRSNT_2_6_N" )
			)
			( signal "@baseboard_fab2_lib.baseboard_fab2(sch_1):clk_100m_pch_xdp_dn"
				( attribute "CDS_PHYS_NET_NAME" "CLK_100M_PCH_XDP_DN"
					( Origin gPackager )
				)
				( objectStatus "CLK_100M_PCH_XDP_DN" )
			)
			( signal "@baseboard_fab2_lib.baseboard_fab2(sch_1):clk_100m_pch_xdp_dp"
				( attribute "CDS_PHYS_NET_NAME" "CLK_100M_PCH_XDP_DP"
					( Origin gPackager )
				)
				( objectStatus "CLK_100M_PCH_XDP_DP" )
			)
			( signal "@baseboard_fab2_lib.baseboard_fab2(sch_1):fm_debug_rst_btn_n"
				( attribute "CDS_PHYS_NET_NAME" "FM_DEBUG_RST_BTN_N"
					( Origin gPackager )
				)
				( objectStatus "FM_DEBUG_RST_BTN_N" )
			)
			( signal "@baseboard_fab2_lib.baseboard_fab2(sch_1):fm_debug_rst_btn_r1_n"
				( attribute "CDS_PHYS_NET_NAME" "FM_DEBUG_RST_BTN_R1_N"
					( Origin gPackager )
				)
				( objectStatus "FM_DEBUG_RST_BTN_R1_N" )
			)
			( signal "@baseboard_fab2_lib.baseboard_fab2(sch_1):p1v05_pch_stby"
				( alias ( signalRef "@baseboard_fab2_lib.baseboard_fab2(sch_1):page111_p1v05_pch_stby") )
				( alias ( signalRef "@baseboard_fab2_lib.baseboard_fab2(sch_1):page112_p1v05_pch_stby") )
				( alias ( signalRef "@baseboard_fab2_lib.baseboard_fab2(sch_1):page122_p1v05_pch_stby") )
				( alias ( signalRef "@baseboard_fab2_lib.baseboard_fab2(sch_1):page123_p1v05_pch_stby") )
				( alias ( signalRef "@baseboard_fab2_lib.baseboard_fab2(sch_1):page127_p1v05_pch_stby") )
				( alias ( signalRef "@baseboard_fab2_lib.baseboard_fab2(sch_1):page131_p1v05_pch_stby") )
				( alias ( signalRef "@baseboard_fab2_lib.baseboard_fab2(sch_1):page133_p1v05_pch_stby") )
				( alias ( signalRef "@baseboard_fab2_lib.baseboard_fab2(sch_1):page134_p1v05_pch_stby") )
				( alias ( signalRef "@baseboard_fab2_lib.baseboard_fab2(sch_1):page169_p1v05_pch_stby") )
				( alias ( signalRef "@baseboard_fab2_lib.baseboard_fab2(sch_1):page236_p1v05_pch_stby") )
				( alias ( signalRef "@baseboard_fab2_lib.baseboard_fab2(sch_1):page269_p1v05_pch_stby") )
				( alias ( signalRef "@baseboard_fab2_lib.baseboard_fab2(sch_1):page268_p1v05_pch_stby") )
				( attribute "CDS_PHYS_NET_NAME" "P1V05_PCH_STBY"
					( Origin gPackager )
				)
				( attribute "VOLTAGE" "1.05V"
					( Units "uVoltage" "V" 1.000000)
					( Status sAliasFlattened )
					( Origin gFrontEnd )
				)
				( objectStatus "P1V05_PCH_STBY" )
			)
			( signal "@baseboard_fab2_lib.baseboard_fab2(sch_1):page111_p1v05_pch_stby"
				( attribute "VOLTAGE" "1.05V"
					( Units "uVoltage" "V" 1.000000)
					( Origin gFrontEnd )
				)
				( objectFlag fObjectAlias )
				( objectStatus "page111_p1v05_pch_stby" )
			)
			( signal "@baseboard_fab2_lib.baseboard_fab2(sch_1):page112_p1v05_pch_stby"
				( attribute "VOLTAGE" "1.05V"
					( Units "uVoltage" "V" 1.000000)
					( Origin gFrontEnd )
				)
				( objectFlag fObjectAlias )
				( objectStatus "page112_p1v05_pch_stby" )
			)
			( signal "@baseboard_fab2_lib.baseboard_fab2(sch_1):page122_p1v05_pch_stby"
				( attribute "VOLTAGE" "1.05V"
					( Units "uVoltage" "V" 1.000000)
					( Origin gFrontEnd )
				)
				( objectFlag fObjectAlias )
				( objectStatus "page122_p1v05_pch_stby" )
			)
			( signal "@baseboard_fab2_lib.baseboard_fab2(sch_1):page123_p1v05_pch_stby"
				( attribute "VOLTAGE" "1.05V"
					( Units "uVoltage" "V" 1.000000)
					( Origin gFrontEnd )
				)
				( objectFlag fObjectAlias )
				( objectStatus "page123_p1v05_pch_stby" )
			)
			( signal "@baseboard_fab2_lib.baseboard_fab2(sch_1):page127_p1v05_pch_stby"
				( attribute "VOLTAGE" "1.05V"
					( Units "uVoltage" "V" 1.000000)
					( Origin gFrontEnd )
				)
				( objectFlag fObjectAlias )
				( objectStatus "page127_p1v05_pch_stby" )
			)
			( signal "@baseboard_fab2_lib.baseboard_fab2(sch_1):page131_p1v05_pch_stby"
				( attribute "VOLTAGE" "1.05V"
					( Units "uVoltage" "V" 1.000000)
					( Origin gFrontEnd )
				)
				( objectFlag fObjectAlias )
				( objectStatus "page131_p1v05_pch_stby" )
			)
			( signal "@baseboard_fab2_lib.baseboard_fab2(sch_1):page133_p1v05_pch_stby"
				( attribute "VOLTAGE" "1.05V"
					( Units "uVoltage" "V" 1.000000)
					( Origin gFrontEnd )
				)
				( objectFlag fObjectAlias )
				( objectStatus "page133_p1v05_pch_stby" )
			)
			( signal "@baseboard_fab2_lib.baseboard_fab2(sch_1):page134_p1v05_pch_stby"
				( attribute "VOLTAGE" "1.05V"
					( Units "uVoltage" "V" 1.000000)
					( Origin gFrontEnd )
				)
				( objectFlag fObjectAlias )
				( objectStatus "page134_p1v05_pch_stby" )
			)
			( signal "@baseboard_fab2_lib.baseboard_fab2(sch_1):page169_p1v05_pch_stby"
				( attribute "VOLTAGE" "1.05V"
					( Units "uVoltage" "V" 1.000000)
					( Origin gFrontEnd )
				)
				( objectFlag fObjectAlias )
				( objectStatus "page169_p1v05_pch_stby" )
			)
			( signal "@baseboard_fab2_lib.baseboard_fab2(sch_1):page236_p1v05_pch_stby"
				( attribute "VOLTAGE" "1.05V"
					( Units "uVoltage" "V" 1.000000)
					( Origin gFrontEnd )
				)
				( objectFlag fObjectAlias )
				( objectStatus "page236_p1v05_pch_stby" )
			)
			( signal "@baseboard_fab2_lib.baseboard_fab2(sch_1):page269_p1v05_pch_stby"
				( attribute "VOLTAGE" "1.05V"
					( Units "uVoltage" "V" 1.000000)
					( Origin gFrontEnd )
				)
				( objectFlag fObjectAlias )
				( objectStatus "page269_p1v05_pch_stby" )
			)
			( signal "@baseboard_fab2_lib.baseboard_fab2(sch_1):page268_p1v05_pch_stby"
				( attribute "VOLTAGE" "1.05V"
					( Units "uVoltage" "V" 1.000000)
					( Origin gFrontEnd )
				)
				( objectFlag fObjectAlias )
				( objectStatus "page268_p1v05_pch_stby" )
			)
			( signal "@baseboard_fab2_lib.baseboard_fab2(sch_1):rst_rsmrst_n"
				( attribute "CDS_PHYS_NET_NAME" "RST_RSMRST_N"
					( Origin gPackager )
				)
				( objectStatus "RST_RSMRST_N" )
			)
			( signal "@baseboard_fab2_lib.baseboard_fab2(sch_1):spi_pch_io2"
				( attribute "CDS_PHYS_NET_NAME" "SPI_PCH_IO2"
					( Origin gPackager )
				)
				( objectStatus "SPI_PCH_IO2" )
			)
			( signal "@baseboard_fab2_lib.baseboard_fab2(sch_1):spi_pch_mosi"
				( attribute "CDS_PHYS_NET_NAME" "SPI_PCH_MOSI"
					( Origin gPackager )
				)
				( objectStatus "SPI_PCH_MOSI" )
			)
			( signal "@baseboard_fab2_lib.baseboard_fab2(sch_1):tp_xdp_cpu_obsdata_c0"
				( attribute "CDS_PHYS_NET_NAME" "TP_XDP_CPU_OBSDATA_C0"
					( Origin gPackager )
				)
				( objectStatus "TP_XDP_CPU_OBSDATA_C0" )
			)
			( signal "@baseboard_fab2_lib.baseboard_fab2(sch_1):tp_xdp_cpu_obsdata_c1"
				( attribute "CDS_PHYS_NET_NAME" "TP_XDP_CPU_OBSDATA_C1"
					( Origin gPackager )
				)
				( objectStatus "TP_XDP_CPU_OBSDATA_C1" )
			)
			( signal "@baseboard_fab2_lib.baseboard_fab2(sch_1):tp_xdp_cpu_obsdata_c2"
				( attribute "CDS_PHYS_NET_NAME" "TP_XDP_CPU_OBSDATA_C2"
					( Origin gPackager )
				)
				( objectStatus "TP_XDP_CPU_OBSDATA_C2" )
			)
			( signal "@baseboard_fab2_lib.baseboard_fab2(sch_1):tp_xdp_cpu_obsdata_c3"
				( attribute "CDS_PHYS_NET_NAME" "TP_XDP_CPU_OBSDATA_C3"
					( Origin gPackager )
				)
				( objectStatus "TP_XDP_CPU_OBSDATA_C3" )
			)
			( signal "@baseboard_fab2_lib.baseboard_fab2(sch_1):tp_xdp_cpu_obsdata_d0"
				( attribute "CDS_PHYS_NET_NAME" "TP_XDP_CPU_OBSDATA_D0"
					( Origin gPackager )
				)
				( objectStatus "TP_XDP_CPU_OBSDATA_D0" )
			)
			( signal "@baseboard_fab2_lib.baseboard_fab2(sch_1):tp_xdp_cpu_obsdata_d1"
				( attribute "CDS_PHYS_NET_NAME" "TP_XDP_CPU_OBSDATA_D1"
					( Origin gPackager )
				)
				( objectStatus "TP_XDP_CPU_OBSDATA_D1" )
			)
			( signal "@baseboard_fab2_lib.baseboard_fab2(sch_1):tp_xdp_cpu_obsdata_d2"
				( attribute "CDS_PHYS_NET_NAME" "TP_XDP_CPU_OBSDATA_D2"
					( Origin gPackager )
				)
				( objectStatus "TP_XDP_CPU_OBSDATA_D2" )
			)
			( signal "@baseboard_fab2_lib.baseboard_fab2(sch_1):tp_xdp_cpu_obsdata_d3"
				( attribute "CDS_PHYS_NET_NAME" "TP_XDP_CPU_OBSDATA_D3"
					( Origin gPackager )
				)
				( objectStatus "TP_XDP_CPU_OBSDATA_D3" )
			)
			( signal "@baseboard_fab2_lib.baseboard_fab2(sch_1):tp_xdp_cpu_obsfn_c0"
				( attribute "CDS_PHYS_NET_NAME" "TP_XDP_CPU_OBSFN_C0"
					( Origin gPackager )
				)
				( objectStatus "TP_XDP_CPU_OBSFN_C0" )
			)
			( signal "@baseboard_fab2_lib.baseboard_fab2(sch_1):tp_xdp_obsdata_a0"
				( attribute "CDS_PHYS_NET_NAME" "TP_XDP_OBSDATA_A0"
					( Origin gPackager )
				)
				( objectStatus "TP_XDP_OBSDATA_A0" )
			)
			( signal "@baseboard_fab2_lib.baseboard_fab2(sch_1):tp_xdp_obsdata_a1"
				( attribute "CDS_PHYS_NET_NAME" "TP_XDP_OBSDATA_A1"
					( Origin gPackager )
				)
				( objectStatus "TP_XDP_OBSDATA_A1" )
			)
			( signal "@baseboard_fab2_lib.baseboard_fab2(sch_1):tp_xdp_obsdata_a2"
				( attribute "CDS_PHYS_NET_NAME" "TP_XDP_OBSDATA_A2"
					( Origin gPackager )
				)
				( objectStatus "TP_XDP_OBSDATA_A2" )
			)
			( signal "@baseboard_fab2_lib.baseboard_fab2(sch_1):tp_xdp_obsdata_a3"
				( attribute "CDS_PHYS_NET_NAME" "TP_XDP_OBSDATA_A3"
					( Origin gPackager )
				)
				( objectStatus "TP_XDP_OBSDATA_A3" )
			)
			( signal "@baseboard_fab2_lib.baseboard_fab2(sch_1):tp_xdp_obsdata_b0"
				( attribute "CDS_PHYS_NET_NAME" "TP_XDP_OBSDATA_B0"
					( Origin gPackager )
				)
				( objectStatus "TP_XDP_OBSDATA_B0" )
			)
			( signal "@baseboard_fab2_lib.baseboard_fab2(sch_1):tp_xdp_obsdata_b1"
				( attribute "CDS_PHYS_NET_NAME" "TP_XDP_OBSDATA_B1"
					( Origin gPackager )
				)
				( objectStatus "TP_XDP_OBSDATA_B1" )
			)
			( signal "@baseboard_fab2_lib.baseboard_fab2(sch_1):tp_xdp_obsdata_b2"
				( attribute "CDS_PHYS_NET_NAME" "TP_XDP_OBSDATA_B2"
					( Origin gPackager )
				)
				( objectStatus "TP_XDP_OBSDATA_B2" )
			)
			( signal "@baseboard_fab2_lib.baseboard_fab2(sch_1):tp_xdp_obsdata_b3"
				( attribute "CDS_PHYS_NET_NAME" "TP_XDP_OBSDATA_B3"
					( Origin gPackager )
				)
				( objectStatus "TP_XDP_OBSDATA_B3" )
			)
			( signal "@baseboard_fab2_lib.baseboard_fab2(sch_1):tp_xdp_obsfn_b0"
				( attribute "CDS_PHYS_NET_NAME" "TP_XDP_OBSFN_B0"
					( Origin gPackager )
				)
				( objectStatus "TP_XDP_OBSFN_B0" )
			)
			( signal "@baseboard_fab2_lib.baseboard_fab2(sch_1):tp_xdp_obsfn_b1"
				( attribute "CDS_PHYS_NET_NAME" "TP_XDP_OBSFN_B1"
					( Origin gPackager )
				)
				( objectStatus "TP_XDP_OBSFN_B1" )
			)
			( signal "@baseboard_fab2_lib.baseboard_fab2(sch_1):xdp_cpu_gtl_tck_r2"
				( attribute "CDS_PHYS_NET_NAME" "XDP_CPU_GTL_TCK_R2"
					( Origin gPackager )
				)
				( objectStatus "XDP_CPU_GTL_TCK_R2" )
			)
			( signal "@baseboard_fab2_lib.baseboard_fab2(sch_1):xdp_cpu_tck_buf"
				( attribute "CDS_PHYS_NET_NAME" "XDP_CPU_TCK_BUF"
					( Origin gPackager )
				)
				( objectStatus "XDP_CPU_TCK_BUF" )
			)
			( signal "@baseboard_fab2_lib.baseboard_fab2(sch_1):xdp_debug_consent_n"
				( attribute "CDS_PHYS_NET_NAME" "XDP_DEBUG_CONSENT_N"
					( Origin gPackager )
				)
				( objectStatus "XDP_DEBUG_CONSENT_N" )
			)
			( signal "@baseboard_fab2_lib.baseboard_fab2(sch_1):xdp_itp_pmode"
				( attribute "CDS_PHYS_NET_NAME" "XDP_ITP_PMODE"
					( Origin gPackager )
				)
				( objectStatus "XDP_ITP_PMODE" )
			)
			( signal "@baseboard_fab2_lib.baseboard_fab2(sch_1):xdp_obsfn_b0_mbp6_n"
				( attribute "CDS_PHYS_NET_NAME" "XDP_OBSFN_B0_MBP6_N"
					( Origin gPackager )
				)
				( objectStatus "XDP_OBSFN_B0_MBP6_N" )
			)
			( signal "@baseboard_fab2_lib.baseboard_fab2(sch_1):xdp_obsfn_b1_mbp7_n"
				( attribute "CDS_PHYS_NET_NAME" "XDP_OBSFN_B1_MBP7_N"
					( Origin gPackager )
				)
				( objectStatus "XDP_OBSFN_B1_MBP7_N" )
			)
			( signal "@baseboard_fab2_lib.baseboard_fab2(sch_1):xdp_pch_cpu_tck0"
				( attribute "CDS_PHYS_NET_NAME" "XDP_PCH_CPU_TCK0"
					( Origin gPackager )
				)
				( objectStatus "XDP_PCH_CPU_TCK0" )
			)
			( signal "@baseboard_fab2_lib.baseboard_fab2(sch_1):xdp_pch_tck1"
				( attribute "CDS_PHYS_NET_NAME" "XDP_PCH_TCK1"
					( Origin gPackager )
				)
				( objectStatus "XDP_PCH_TCK1" )
			)
			( signal "@baseboard_fab2_lib.baseboard_fab2(sch_1):xdp_prdy_n"
				( attribute "CDS_PHYS_NET_NAME" "XDP_PRDY_N"
					( Origin gPackager )
				)
				( objectStatus "XDP_PRDY_N" )
			)
			( signal "@baseboard_fab2_lib.baseboard_fab2(sch_1):xdp_preq_n"
				( attribute "CDS_PHYS_NET_NAME" "XDP_PREQ_N"
					( Origin gPackager )
				)
				( objectStatus "XDP_PREQ_N" )
			)
			( signal "@baseboard_fab2_lib.baseboard_fab2(sch_1):xdp_pwrgd_rst_n"
				( attribute "CDS_PHYS_NET_NAME" "XDP_PWRGD_RST_N"
					( Origin gPackager )
				)
				( objectStatus "XDP_PWRGD_RST_N" )
			)
			( signal "@baseboard_fab2_lib.baseboard_fab2(sch_1):xdp_rsmrst_n"
				( attribute "CDS_PHYS_NET_NAME" "XDP_RSMRST_N"
					( Origin gPackager )
				)
				( objectStatus "XDP_RSMRST_N" )
			)
			( signal "@baseboard_fab2_lib.baseboard_fab2(sch_1):xdp_rst_co_n"
				( attribute "CDS_PHYS_NET_NAME" "XDP_RST_CO_N"
					( Origin gPackager )
				)
				( objectStatus "XDP_RST_CO_N" )
			)
			( signal "@baseboard_fab2_lib.baseboard_fab2(sch_1):xdp_spi_pch_mosi_boot_halt_n"
				( attribute "CDS_PHYS_NET_NAME" "XDP_SPI_PCH_MOSI_BOOT_HALT_N"
					( Origin gPackager )
				)
				( objectStatus "XDP_SPI_PCH_MOSI_BOOT_HALT_N" )
			)
			( signal "@baseboard_fab2_lib.baseboard_fab2(sch_1):xdp_syspwrok"
				( attribute "CDS_PHYS_NET_NAME" "XDP_SYSPWROK"
					( Origin gPackager )
				)
				( objectStatus "XDP_SYSPWROK" )
			)
			( signal "@baseboard_fab2_lib.baseboard_fab2(sch_1):xdp_tdi"
				( attribute "CDS_PHYS_NET_NAME" "XDP_TDI"
					( Origin gPackager )
				)
				( objectStatus "XDP_TDI" )
			)
			( signal "@baseboard_fab2_lib.baseboard_fab2(sch_1):xdp_tdo"
				( attribute "CDS_PHYS_NET_NAME" "XDP_TDO"
					( Origin gPackager )
				)
				( objectStatus "XDP_TDO" )
			)
			( signal "@baseboard_fab2_lib.baseboard_fab2(sch_1):xdp_tms"
				( attribute "CDS_PHYS_NET_NAME" "XDP_TMS"
					( Origin gPackager )
				)
				( objectStatus "XDP_TMS" )
			)
			( signal "@baseboard_fab2_lib.baseboard_fab2(sch_1):xdp_trst_n"
				( attribute "CDS_PHYS_NET_NAME" "XDP_TRST_N"
					( Origin gPackager )
				)
				( objectStatus "XDP_TRST_N" )
			)
			( signal "@baseboard_fab2_lib.baseboard_fab2(sch_1):pwrgd_pvccin_cpu0"
				( attribute "CDS_PHYS_NET_NAME" "PWRGD_PVCCIN_CPU0"
					( Origin gPackager )
				)
				( objectStatus "PWRGD_PVCCIN_CPU0" )
			)
			( signal "@baseboard_fab2_lib.baseboard_fab2(sch_1):xdp_cpu_tdo"
				( attribute "CDS_PHYS_NET_NAME" "XDP_CPU_TDO"
					( Origin gPackager )
				)
				( objectStatus "XDP_CPU_TDO" )
			)
			( signal "@baseboard_fab2_lib.baseboard_fab2(sch_1):fm_cpu0_and_cpu1_mcp_pres"
				( attribute "CDS_PHYS_NET_NAME" "FM_CPU0_AND_CPU1_MCP_PRES"
					( Origin gPackager )
				)
				( objectStatus "FM_CPU0_AND_CPU1_MCP_PRES" )
			)
			( signal "@baseboard_fab2_lib.baseboard_fab2(sch_1):fm_cpu0_cd_pres"
				( attribute "CDS_PHYS_NET_NAME" "FM_CPU0_CD_PRES"
					( Origin gPackager )
				)
				( objectStatus "FM_CPU0_CD_PRES" )
			)
			( signal "@baseboard_fab2_lib.baseboard_fab2(sch_1):fm_cpu0_or_cpu1_mcp_pres"
				( attribute "CDS_PHYS_NET_NAME" "FM_CPU0_OR_CPU1_MCP_PRES"
					( Origin gPackager )
				)
				( objectStatus "FM_CPU0_OR_CPU1_MCP_PRES" )
			)
			( signal "@baseboard_fab2_lib.baseboard_fab2(sch_1):jtag_mcp_cpu0_tdi_r"
				( attribute "CDS_PHYS_NET_NAME" "JTAG_MCP_CPU0_TDI_R"
					( Origin gPackager )
				)
				( objectStatus "JTAG_MCP_CPU0_TDI_R" )
			)
			( signal "@baseboard_fab2_lib.baseboard_fab2(sch_1):jtag_mcp_cpu1_tdi_r"
				( attribute "CDS_PHYS_NET_NAME" "JTAG_MCP_CPU1_TDI_R"
					( Origin gPackager )
				)
				( objectStatus "JTAG_MCP_CPU1_TDI_R" )
			)
			( signal "@baseboard_fab2_lib.baseboard_fab2(sch_1):jtag_mcp_mux_tdi"
				( attribute "CDS_PHYS_NET_NAME" "JTAG_MCP_MUX_TDI"
					( Origin gPackager )
				)
				( objectStatus "JTAG_MCP_MUX_TDI" )
			)
			( signal "@baseboard_fab2_lib.baseboard_fab2(sch_1):jtag_mcp_mux_tdo"
				( attribute "CDS_PHYS_NET_NAME" "JTAG_MCP_MUX_TDO"
					( Origin gPackager )
				)
				( objectStatus "JTAG_MCP_MUX_TDO" )
			)
			( signal "@baseboard_fab2_lib.baseboard_fab2(sch_1):jtag_mcp_tck_r"
				( attribute "CDS_PHYS_NET_NAME" "JTAG_MCP_TCK_R"
					( Origin gPackager )
				)
				( objectStatus "JTAG_MCP_TCK_R" )
			)
			( signal "@baseboard_fab2_lib.baseboard_fab2(sch_1):jtag_mcp_tms_r"
				( attribute "CDS_PHYS_NET_NAME" "JTAG_MCP_TMS_R"
					( Origin gPackager )
				)
				( objectStatus "JTAG_MCP_TMS_R" )
			)
			( signal "@baseboard_fab2_lib.baseboard_fab2(sch_1):jtag_mcp_tms_r1"
				( attribute "CDS_PHYS_NET_NAME" "JTAG_MCP_TMS_R1"
					( Origin gPackager )
				)
				( objectStatus "JTAG_MCP_TMS_R1" )
			)
			( signal "@baseboard_fab2_lib.baseboard_fab2(sch_1):pwrgd_cpu0_g_r"
				( attribute "CDS_PHYS_NET_NAME" "PWRGD_CPU0_G_R"
					( Origin gPackager )
				)
				( objectStatus "PWRGD_CPU0_G_R" )
			)
			( signal "@baseboard_fab2_lib.baseboard_fab2(sch_1):tp_jtag_mcp_io8_rsvd"
				( attribute "CDS_PHYS_NET_NAME" "TP_JTAG_MCP_IO8_RSVD"
					( Origin gPackager )
				)
				( objectStatus "TP_JTAG_MCP_IO8_RSVD" )
			)
			( signal "@baseboard_fab2_lib.baseboard_fab2(sch_1):a_pch_xclk_biasref"
				( attribute "CDS_PHYS_NET_NAME" "A_PCH_XCLK_BIASREF"
					( Origin gPackager )
				)
				( objectStatus "A_PCH_XCLK_BIASREF" )
			)
			( signal "@baseboard_fab2_lib.baseboard_fab2(sch_1):clk_100m_airmax8_pe1_dn"
				( attribute "CDS_PHYS_NET_NAME" "CLK_100M_AIRMAX8_PE1_DN"
					( Origin gPackager )
				)
				( objectStatus "CLK_100M_AIRMAX8_PE1_DN" )
			)
			( signal "@baseboard_fab2_lib.baseboard_fab2(sch_1):clk_100m_airmax8_pe1_dp"
				( attribute "CDS_PHYS_NET_NAME" "CLK_100M_AIRMAX8_PE1_DP"
					( Origin gPackager )
				)
				( objectStatus "CLK_100M_AIRMAX8_PE1_DP" )
			)
			( signal "@baseboard_fab2_lib.baseboard_fab2(sch_1):clk_100m_bmc_pe_dn"
				( attribute "CDS_PHYS_NET_NAME" "CLK_100M_BMC_PE_DN"
					( Origin gPackager )
				)
				( objectStatus "CLK_100M_BMC_PE_DN" )
			)
			( signal "@baseboard_fab2_lib.baseboard_fab2(sch_1):clk_100m_bmc_pe_dp"
				( attribute "CDS_PHYS_NET_NAME" "CLK_100M_BMC_PE_DP"
					( Origin gPackager )
				)
				( objectStatus "CLK_100M_BMC_PE_DP" )
			)
			( signal "@baseboard_fab2_lib.baseboard_fab2(sch_1):clk_100m_bmc_pe_r_dn"
				( attribute "CDS_PHYS_NET_NAME" "CLK_100M_BMC_PE_R_DN"
					( Origin gPackager )
				)
				( objectStatus "CLK_100M_BMC_PE_R_DN" )
			)
			( signal "@baseboard_fab2_lib.baseboard_fab2(sch_1):clk_100m_bmc_pe_r_dp"
				( attribute "CDS_PHYS_NET_NAME" "CLK_100M_BMC_PE_R_DP"
					( Origin gPackager )
				)
				( objectStatus "CLK_100M_BMC_PE_R_DP" )
			)
			( signal "@baseboard_fab2_lib.baseboard_fab2(sch_1):clk_100m_m2_dn"
				( attribute "CDS_PHYS_NET_NAME" "CLK_100M_M2_DN"
					( Origin gPackager )
				)
				( objectStatus "CLK_100M_M2_DN" )
			)
			( signal "@baseboard_fab2_lib.baseboard_fab2(sch_1):clk_100m_m2_dp"
				( attribute "CDS_PHYS_NET_NAME" "CLK_100M_M2_DP"
					( Origin gPackager )
				)
				( objectStatus "CLK_100M_M2_DP" )
			)
			( signal "@baseboard_fab2_lib.baseboard_fab2(sch_1):clk_100m_mezz1_dn"
				( attribute "CDS_PHYS_NET_NAME" "CLK_100M_MEZZ1_DN"
					( Origin gPackager )
				)
				( objectStatus "CLK_100M_MEZZ1_DN" )
			)
			( signal "@baseboard_fab2_lib.baseboard_fab2(sch_1):clk_100m_mezz1_dp"
				( attribute "CDS_PHYS_NET_NAME" "CLK_100M_MEZZ1_DP"
					( Origin gPackager )
				)
				( objectStatus "CLK_100M_MEZZ1_DP" )
			)
			( signal "@baseboard_fab2_lib.baseboard_fab2(sch_1):clk_100m_mezz2_dn"
				( attribute "CDS_PHYS_NET_NAME" "CLK_100M_MEZZ2_DN"
					( Origin gPackager )
				)
				( objectStatus "CLK_100M_MEZZ2_DN" )
			)
			( signal "@baseboard_fab2_lib.baseboard_fab2(sch_1):clk_100m_mezz2_dp"
				( attribute "CDS_PHYS_NET_NAME" "CLK_100M_MEZZ2_DP"
					( Origin gPackager )
				)
				( objectStatus "CLK_100M_MEZZ2_DP" )
			)
			( signal "@baseboard_fab2_lib.baseboard_fab2(sch_1):clk_100m_mezz3_dn"
				( attribute "CDS_PHYS_NET_NAME" "CLK_100M_MEZZ3_DN"
					( Origin gPackager )
				)
				( objectStatus "CLK_100M_MEZZ3_DN" )
			)
			( signal "@baseboard_fab2_lib.baseboard_fab2(sch_1):vcc_a_1v1"
				( alias ( signalRef "@baseboard_fab2_lib.baseboard_fab2(sch_1):page148_vcc_a_1v1") )
				( alias ( signalRef "@baseboard_fab2_lib.baseboard_fab2(sch_1):page149_vcc_a_1v1") )
				( attribute "CDS_PHYS_NET_NAME" "VCC_A_1V1"
					( Origin gPackager )
				)
				( objectStatus "VCC_A_1V1" )
			)
			( signal "@baseboard_fab2_lib.baseboard_fab2(sch_1):page148_vcc_a_1v1"
				( objectFlag fObjectAlias )
				( objectStatus "page148_vcc_a_1v1" )
			)
			( signal "@baseboard_fab2_lib.baseboard_fab2(sch_1):page149_vcc_a_1v1"
				( objectFlag fObjectAlias )
				( objectStatus "page149_vcc_a_1v1" )
			)
			( signal "@baseboard_fab2_lib.baseboard_fab2(sch_1):spi_bmc_bt_clk_r"
				( attribute "CDS_PHYS_NET_NAME" "SPI_BMC_BT_CLK_R"
					( Origin gPackager )
				)
				( objectStatus "SPI_BMC_BT_CLK_R" )
			)
			( signal "@baseboard_fab2_lib.baseboard_fab2(sch_1):spi_bmc_bt_do"
				( attribute "CDS_PHYS_NET_NAME" "SPI_BMC_BT_DO"
					( Origin gPackager )
				)
				( objectStatus "SPI_BMC_BT_DO" )
			)
			( signal "@baseboard_fab2_lib.baseboard_fab2(sch_1):tp_pch_rsvd53"
				( attribute "CDS_PHYS_NET_NAME" "TP_PCH_RSVD53"
					( Origin gPackager )
				)
				( objectStatus "TP_PCH_RSVD53" )
			)
			( signal "@baseboard_fab2_lib.baseboard_fab2(sch_1):fm_bmc_ready_n"
				( attribute "CDS_PHYS_NET_NAME" "FM_BMC_READY_N"
					( Origin gPackager )
				)
				( attribute "PHYS_NET_NAME" "FM_BMC_READY_N"
					( Origin gPackager )
				)
				( objectStatus "FM_BMC_READY_N" )
			)
			( signal "@baseboard_fab2_lib.baseboard_fab2(sch_1):tp_pch_rsvd37"
				( attribute "CDS_PHYS_NET_NAME" "TP_PCH_RSVD37"
					( Origin gPackager )
				)
				( objectStatus "TP_PCH_RSVD37" )
			)
			( signal "@baseboard_fab2_lib.baseboard_fab2(sch_1):fm_adr_mode_sel"
				( attribute "CDS_PHYS_NET_NAME" "FM_ADR_MODE_SEL"
					( Origin gPackager )
				)
				( objectStatus "FM_ADR_MODE_SEL" )
			)
			( signal "@baseboard_fab2_lib.baseboard_fab2(sch_1):fm_adr_mode_sel_r"
				( attribute "CDS_PHYS_NET_NAME" "FM_ADR_MODE_SEL_R"
					( Origin gPackager )
				)
				( objectStatus "FM_ADR_MODE_SEL_R" )
			)
			( signal "@baseboard_fab2_lib.baseboard_fab2(sch_1):clk_24m_bmc_lpc_r"
				( attribute "CDS_PHYS_NET_NAME" "CLK_24M_BMC_LPC_R"
					( Origin gPackager )
				)
				( objectStatus "CLK_24M_BMC_LPC_R" )
			)
			( signal "@baseboard_fab2_lib.baseboard_fab2(sch_1):page147_fm_fast_prochot_en_n"
				( attribute "CDS_PHYS_NET_NAME" "FM_FAST_PROCHOT_EN_N"
					( Origin gPackager )
				)
				( objectFlag fObjectAlias )
				( objectStatus "page147_fm_fast_prochot_en_n" )
			)
			( signal "@baseboard_fab2_lib.baseboard_fab2(sch_1):page147_p3v3_stby_bmc_adcvrefp"
				( attribute "VOLTAGE" "+3.3V"
					( Units "uVoltage" "V" 1.000000)
					( Origin gFrontEnd )
				)
				( objectFlag fObjectAlias )
				( objectStatus "page147_p3v3_stby_bmc_adcvrefp" )
			)
			( signal "@baseboard_fab2_lib.baseboard_fab2(sch_1):clk_100m_mezz3_dp"
				( attribute "CDS_PHYS_NET_NAME" "CLK_100M_MEZZ3_DP"
					( Origin gPackager )
				)
				( objectStatus "CLK_100M_MEZZ3_DP" )
			)
			( signal "@baseboard_fab2_lib.baseboard_fab2(sch_1):clk_100m_mezz4_dn"
				( attribute "CDS_PHYS_NET_NAME" "CLK_100M_MEZZ4_DN"
					( Origin gPackager )
				)
				( objectStatus "CLK_100M_MEZZ4_DN" )
			)
			( signal "@baseboard_fab2_lib.baseboard_fab2(sch_1):page146_fm_bmc_cpld_gpo"
				( attribute "CDS_PHYS_NET_NAME" "FM_BMC_CPLD_GPO"
					( Origin gPackager )
				)
				( attribute "PHYS_NET_NAME" "FM_BMC_CPLD_GPO"
					( Origin gFrontEnd )
				)
				( objectFlag fObjectAlias )
				( objectStatus "page146_fm_bmc_cpld_gpo" )
			)
			( signal "@baseboard_fab2_lib.baseboard_fab2(sch_1):clk_100m_mezz4_dp"
				( attribute "CDS_PHYS_NET_NAME" "CLK_100M_MEZZ4_DP"
					( Origin gPackager )
				)
				( objectStatus "CLK_100M_MEZZ4_DP" )
			)
			( signal "@baseboard_fab2_lib.baseboard_fab2(sch_1):fm_bmc_fault_led_n"
				( alias ( signalRef "@baseboard_fab2_lib.baseboard_fab2(sch_1):page147_fm_bmc_fault_led_n") )
				( attribute "PHYS_NET_NAME" "FM_BMC_FAULT_LED_N"
					( Origin gPackager )
				)
				( attribute "CDS_PHYS_NET_NAME" "FM_BMC_FAULT_LED_N"
					( Origin gPackager )
				)
				( objectStatus "FM_BMC_FAULT_LED_N" )
			)
			( signal "@baseboard_fab2_lib.baseboard_fab2(sch_1):page147_fm_bmc_fault_led_n"
				( attribute "CDS_PHYS_NET_NAME" "FM_BMC_FAULT_LED_N"
					( Origin gPackager )
				)
				( objectFlag fObjectAlias )
				( objectStatus "page147_fm_bmc_fault_led_n" )
			)
			( signal "@baseboard_fab2_lib.baseboard_fab2(sch_1):tp_pltrst_cpu_n"
				( attribute "CDS_PHYS_NET_NAME" "TP_PLTRST_CPU_N"
					( Origin gPackager )
				)
				( objectStatus "TP_PLTRST_CPU_N" )
			)
			( signal "@baseboard_fab2_lib.baseboard_fab2(sch_1):tp_pm_sync_gtl"
				( attribute "CDS_PHYS_NET_NAME" "TP_PM_SYNC_GTL"
					( Origin gPackager )
				)
				( objectStatus "TP_PM_SYNC_GTL" )
			)
			( signal "@baseboard_fab2_lib.baseboard_fab2(sch_1):a_p5v_scaled"
				( alias ( signalRef "@baseboard_fab2_lib.baseboard_fab2(sch_1):page169_a_p5v_scaled") )
				( attribute "CDS_PHYS_NET_NAME" "A_P5V_SCALED"
					( Origin gPackager )
				)
				( attribute "PHYS_NET_NAME" "A_P5V_SCALED"
					( Origin gPackager )
				)
				( attribute "VOLTAGE" "+2V"
					( Units "uVoltage" "V" 1.000000)
					( Status sAliasFlattened )
					( Origin gFrontEnd )
				)
				( objectStatus "A_P5V_SCALED" )
			)
			( signal "@baseboard_fab2_lib.baseboard_fab2(sch_1):page169_a_p5v_scaled"
				( attribute "VOLTAGE" "+2V"
					( Units "uVoltage" "V" 1.000000)
					( Origin gFrontEnd )
				)
				( objectFlag fObjectAlias )
				( objectStatus "page169_a_p5v_scaled" )
			)
			( signal "@baseboard_fab2_lib.baseboard_fab2(sch_1):tp_pch_rsvd45"
				( attribute "CDS_PHYS_NET_NAME" "TP_PCH_RSVD45"
					( Origin gPackager )
				)
				( objectStatus "TP_PCH_RSVD45" )
			)
			( signal "@baseboard_fab2_lib.baseboard_fab2(sch_1):xdp_pch_pwr_debug_n"
				( attribute "CDS_PHYS_NET_NAME" "XDP_PCH_PWR_DEBUG_N"
					( Origin gPackager )
				)
				( objectStatus "XDP_PCH_PWR_DEBUG_N" )
			)
			( signal "@baseboard_fab2_lib.baseboard_fab2(sch_1):clk_100m_sprv_dn"
				( attribute "CDS_PHYS_NET_NAME" "CLK_100M_SPRV_DN"
					( Origin gPackager )
				)
				( objectStatus "CLK_100M_SPRV_DN" )
			)
			( signal "@baseboard_fab2_lib.baseboard_fab2(sch_1):clk_100m_sprv_dp"
				( attribute "CDS_PHYS_NET_NAME" "CLK_100M_SPRV_DP"
					( Origin gPackager )
				)
				( objectStatus "CLK_100M_SPRV_DP" )
			)
			( signal "@baseboard_fab2_lib.baseboard_fab2(sch_1):clk_48m_usb_bmc"
				( attribute "CDS_PHYS_NET_NAME" "CLK_48M_USB_BMC"
					( Origin gPackager )
				)
				( attribute "PHYS_NET_NAME" "CLK_48M_USB_BMC"
					( Origin gPackager )
				)
				( objectStatus "CLK_48M_USB_BMC" )
			)
			( signal "@baseboard_fab2_lib.baseboard_fab2(sch_1):page145_fm_cpld_bmc_pwrdn_n"
				( attribute "CDS_PHYS_NET_NAME" "FM_CPLD_BMC_PWRDN_N"
					( Origin gPackager )
				)
				( attribute "PHYS_NET_NAME" "FM_CPLD_BMC_PWRDN_N"
					( Origin gFrontEnd )
				)
				( objectFlag fObjectAlias )
				( objectStatus "page145_fm_cpld_bmc_pwrdn_n" )
			)
			( signal "@baseboard_fab2_lib.baseboard_fab2(sch_1):h_pmsync_clk_24m_r"
				( attribute "CDS_PHYS_NET_NAME" "H_PMSYNC_CLK_24M_R"
					( Origin gPackager )
				)
				( objectStatus "H_PMSYNC_CLK_24M_R" )
			)
			( signal "@baseboard_fab2_lib.baseboard_fab2(sch_1):tp_clk_100m_nsscc0_dn"
				( attribute "CDS_PHYS_NET_NAME" "TP_CLK_100M_NSSCC0_DN"
					( Origin gPackager )
				)
				( objectStatus "TP_CLK_100M_NSSCC0_DN" )
			)
			( signal "@baseboard_fab2_lib.baseboard_fab2(sch_1):tp_clk_100m_nsscc0_dp"
				( attribute "CDS_PHYS_NET_NAME" "TP_CLK_100M_NSSCC0_DP"
					( Origin gPackager )
				)
				( objectStatus "TP_CLK_100M_NSSCC0_DP" )
			)
			( signal "@baseboard_fab2_lib.baseboard_fab2(sch_1):tp_clk_100m_nsscc1_dn"
				( attribute "CDS_PHYS_NET_NAME" "TP_CLK_100M_NSSCC1_DN"
					( Origin gPackager )
				)
				( objectStatus "TP_CLK_100M_NSSCC1_DN" )
			)
			( signal "@baseboard_fab2_lib.baseboard_fab2(sch_1):tp_clk_100m_nsscc1_dp"
				( attribute "CDS_PHYS_NET_NAME" "TP_CLK_100M_NSSCC1_DP"
					( Origin gPackager )
				)
				( objectStatus "TP_CLK_100M_NSSCC1_DP" )
			)
			( signal "@baseboard_fab2_lib.baseboard_fab2(sch_1):tp_clk_100m_plat1_dn"
				( attribute "CDS_PHYS_NET_NAME" "TP_CLK_100M_PLAT1_DN"
					( Origin gPackager )
				)
				( objectStatus "TP_CLK_100M_PLAT1_DN" )
			)
			( signal "@baseboard_fab2_lib.baseboard_fab2(sch_1):tp_clk_100m_plat1_dp"
				( attribute "CDS_PHYS_NET_NAME" "TP_CLK_100M_PLAT1_DP"
					( Origin gPackager )
				)
				( objectStatus "TP_CLK_100M_PLAT1_DP" )
			)
			( signal "@baseboard_fab2_lib.baseboard_fab2(sch_1):tp_clk_24m_pmsync2"
				( attribute "CDS_PHYS_NET_NAME" "TP_CLK_24M_PMSYNC2"
					( Origin gPackager )
				)
				( objectStatus "TP_CLK_24M_PMSYNC2" )
			)
			( signal "@baseboard_fab2_lib.baseboard_fab2(sch_1):tp_pch_rsvd64"
				( attribute "CDS_PHYS_NET_NAME" "TP_PCH_RSVD64"
					( Origin gPackager )
				)
				( objectStatus "TP_PCH_RSVD64" )
			)
			( signal "@baseboard_fab2_lib.baseboard_fab2(sch_1):tp_pch_rsvd65"
				( attribute "CDS_PHYS_NET_NAME" "TP_PCH_RSVD65"
					( Origin gPackager )
				)
				( objectStatus "TP_PCH_RSVD65" )
			)
			( signal "@baseboard_fab2_lib.baseboard_fab2(sch_1):xtal_33k_rtc1"
				( attribute "CDS_PHYS_NET_NAME" "XTAL_33K_RTC1"
					( Origin gPackager )
				)
				( objectStatus "XTAL_33K_RTC1" )
			)
			( signal "@baseboard_fab2_lib.baseboard_fab2(sch_1):xtal_33k_rtc2"
				( attribute "CDS_PHYS_NET_NAME" "XTAL_33K_RTC2"
					( Origin gPackager )
				)
				( objectStatus "XTAL_33K_RTC2" )
			)
			( signal "@baseboard_fab2_lib.baseboard_fab2(sch_1):xtal_pch_48m_in"
				( attribute "CDS_PHYS_NET_NAME" "XTAL_PCH_48M_IN"
					( Origin gPackager )
				)
				( objectStatus "XTAL_PCH_48M_IN" )
			)
			( signal "@baseboard_fab2_lib.baseboard_fab2(sch_1):xtal_pch_48m_out"
				( attribute "CDS_PHYS_NET_NAME" "XTAL_PCH_48M_OUT"
					( Origin gPackager )
				)
				( objectStatus "XTAL_PCH_48M_OUT" )
			)
			( signal "@baseboard_fab2_lib.baseboard_fab2(sch_1):a_usb2_comp"
				( attribute "CDS_PHYS_NET_NAME" "A_USB2_COMP"
					( Origin gPackager )
				)
				( objectStatus "A_USB2_COMP" )
			)
			( signal "@baseboard_fab2_lib.baseboard_fab2(sch_1):a_usb2_vbus"
				( attribute "CDS_PHYS_NET_NAME" "A_USB2_VBUS"
					( Origin gPackager )
				)
				( objectStatus "A_USB2_VBUS" )
			)
			( signal "@baseboard_fab2_lib.baseboard_fab2(sch_1):tp_pch_rsvd55"
				( attribute "CDS_PHYS_NET_NAME" "TP_PCH_RSVD55"
					( Origin gPackager )
				)
				( objectStatus "TP_PCH_RSVD55" )
			)
			( signal "@baseboard_fab2_lib.baseboard_fab2(sch_1):jtag_riser_tdi"
				( attribute "CDS_PHYS_NET_NAME" "JTAG_RISER_TDI"
					( Origin gPackager )
				)
				( objectStatus "JTAG_RISER_TDI" )
			)
			( signal "@baseboard_fab2_lib.baseboard_fab2(sch_1):jtag_riser_tdo"
				( attribute "CDS_PHYS_NET_NAME" "JTAG_RISER_TDO"
					( Origin gPackager )
				)
				( objectStatus "JTAG_RISER_TDO" )
			)
			( signal "@baseboard_fab2_lib.baseboard_fab2(sch_1):tp_usb2_p03_dn"
				( attribute "CDS_PHYS_NET_NAME" "TP_USB2_P03_DN"
					( Origin gPackager )
				)
				( objectStatus "TP_USB2_P03_DN" )
			)
			( signal "@baseboard_fab2_lib.baseboard_fab2(sch_1):tp_usb2_p03_dp"
				( attribute "CDS_PHYS_NET_NAME" "TP_USB2_P03_DP"
					( Origin gPackager )
				)
				( objectStatus "TP_USB2_P03_DP" )
			)
			( signal "@baseboard_fab2_lib.baseboard_fab2(sch_1):tp_usb2_p06_dn"
				( attribute "CDS_PHYS_NET_NAME" "TP_USB2_P06_DN"
					( Origin gPackager )
				)
				( objectStatus "TP_USB2_P06_DN" )
			)
			( signal "@baseboard_fab2_lib.baseboard_fab2(sch_1):tp_usb2_p06_dp"
				( attribute "CDS_PHYS_NET_NAME" "TP_USB2_P06_DP"
					( Origin gPackager )
				)
				( objectStatus "TP_USB2_P06_DP" )
			)
			( signal "@baseboard_fab2_lib.baseboard_fab2(sch_1):tp_usb2_p07_dn"
				( attribute "CDS_PHYS_NET_NAME" "TP_USB2_P07_DN"
					( Origin gPackager )
				)
				( objectStatus "TP_USB2_P07_DN" )
			)
			( signal "@baseboard_fab2_lib.baseboard_fab2(sch_1):tp_usb2_p07_dp"
				( attribute "CDS_PHYS_NET_NAME" "TP_USB2_P07_DP"
					( Origin gPackager )
				)
				( objectStatus "TP_USB2_P07_DP" )
			)
			( signal "@baseboard_fab2_lib.baseboard_fab2(sch_1):tp_usb2_p10_dn"
				( attribute "CDS_PHYS_NET_NAME" "TP_USB2_P10_DN"
					( Origin gPackager )
				)
				( objectStatus "TP_USB2_P10_DN" )
			)
			( signal "@baseboard_fab2_lib.baseboard_fab2(sch_1):tp_usb2_p10_dp"
				( attribute "CDS_PHYS_NET_NAME" "TP_USB2_P10_DP"
					( Origin gPackager )
				)
				( objectStatus "TP_USB2_P10_DP" )
			)
			( signal "@baseboard_fab2_lib.baseboard_fab2(sch_1):tp_usb2_p11_dn"
				( attribute "CDS_PHYS_NET_NAME" "TP_USB2_P11_DN"
					( Origin gPackager )
				)
				( objectStatus "TP_USB2_P11_DN" )
			)
			( signal "@baseboard_fab2_lib.baseboard_fab2(sch_1):tp_usb2_p11_dp"
				( attribute "CDS_PHYS_NET_NAME" "TP_USB2_P11_DP"
					( Origin gPackager )
				)
				( objectStatus "TP_USB2_P11_DP" )
			)
			( signal "@baseboard_fab2_lib.baseboard_fab2(sch_1):tp_usb2_p12_dn"
				( attribute "CDS_PHYS_NET_NAME" "TP_USB2_P12_DN"
					( Origin gPackager )
				)
				( objectStatus "TP_USB2_P12_DN" )
			)
			( signal "@baseboard_fab2_lib.baseboard_fab2(sch_1):tp_usb2_p12_dp"
				( attribute "CDS_PHYS_NET_NAME" "TP_USB2_P12_DP"
					( Origin gPackager )
				)
				( objectStatus "TP_USB2_P12_DP" )
			)
			( signal "@baseboard_fab2_lib.baseboard_fab2(sch_1):tp_usb2_p13_dn"
				( attribute "CDS_PHYS_NET_NAME" "TP_USB2_P13_DN"
					( Origin gPackager )
				)
				( objectStatus "TP_USB2_P13_DN" )
			)
			( signal "@baseboard_fab2_lib.baseboard_fab2(sch_1):tp_usb2_p13_dp"
				( attribute "CDS_PHYS_NET_NAME" "TP_USB2_P13_DP"
					( Origin gPackager )
				)
				( objectStatus "TP_USB2_P13_DP" )
			)
			( signal "@baseboard_fab2_lib.baseboard_fab2(sch_1):tp_usb2_p14_dn"
				( attribute "CDS_PHYS_NET_NAME" "TP_USB2_P14_DN"
					( Origin gPackager )
				)
				( objectStatus "TP_USB2_P14_DN" )
			)
			( signal "@baseboard_fab2_lib.baseboard_fab2(sch_1):tp_usb2_p14_dp"
				( attribute "CDS_PHYS_NET_NAME" "TP_USB2_P14_DP"
					( Origin gPackager )
				)
				( objectStatus "TP_USB2_P14_DP" )
			)
			( signal "@baseboard_fab2_lib.baseboard_fab2(sch_1):tp_usb2_p8_dn"
				( attribute "CDS_PHYS_NET_NAME" "TP_USB2_P8_DN"
					( Origin gPackager )
				)
				( objectStatus "TP_USB2_P8_DN" )
			)
			( signal "@baseboard_fab2_lib.baseboard_fab2(sch_1):tp_usb2_p8_dp"
				( attribute "CDS_PHYS_NET_NAME" "TP_USB2_P8_DP"
					( Origin gPackager )
				)
				( objectStatus "TP_USB2_P8_DP" )
			)
			( signal "@baseboard_fab2_lib.baseboard_fab2(sch_1):tp_usb2_p9_dn"
				( attribute "CDS_PHYS_NET_NAME" "TP_USB2_P9_DN"
					( Origin gPackager )
				)
				( objectStatus "TP_USB2_P9_DN" )
			)
			( signal "@baseboard_fab2_lib.baseboard_fab2(sch_1):tp_usb2_p9_dp"
				( attribute "CDS_PHYS_NET_NAME" "TP_USB2_P9_DP"
					( Origin gPackager )
				)
				( objectStatus "TP_USB2_P9_DP" )
			)
			( signal "@baseboard_fab2_lib.baseboard_fab2(sch_1):tp_usb3_p02_rxn"
				( attribute "CDS_PHYS_NET_NAME" "TP_USB3_P02_RXN"
					( Origin gPackager )
				)
				( objectStatus "TP_USB3_P02_RXN" )
			)
			( signal "@baseboard_fab2_lib.baseboard_fab2(sch_1):tp_usb3_p02_rxp"
				( attribute "CDS_PHYS_NET_NAME" "TP_USB3_P02_RXP"
					( Origin gPackager )
				)
				( objectStatus "TP_USB3_P02_RXP" )
			)
			( signal "@baseboard_fab2_lib.baseboard_fab2(sch_1):tp_usb3_p02_txn"
				( attribute "CDS_PHYS_NET_NAME" "TP_USB3_P02_TXN"
					( Origin gPackager )
				)
				( objectStatus "TP_USB3_P02_TXN" )
			)
			( signal "@baseboard_fab2_lib.baseboard_fab2(sch_1):tp_usb3_p02_txp"
				( attribute "CDS_PHYS_NET_NAME" "TP_USB3_P02_TXP"
					( Origin gPackager )
				)
				( objectStatus "TP_USB3_P02_TXP" )
			)
			( signal "@baseboard_fab2_lib.baseboard_fab2(sch_1):tp_usb3_p03_rxn"
				( attribute "CDS_PHYS_NET_NAME" "TP_USB3_P03_RXN"
					( Origin gPackager )
				)
				( objectStatus "TP_USB3_P03_RXN" )
			)
			( signal "@baseboard_fab2_lib.baseboard_fab2(sch_1):tp_usb3_p03_rxp"
				( attribute "CDS_PHYS_NET_NAME" "TP_USB3_P03_RXP"
					( Origin gPackager )
				)
				( objectStatus "TP_USB3_P03_RXP" )
			)
			( signal "@baseboard_fab2_lib.baseboard_fab2(sch_1):tp_usb3_p03_txn"
				( attribute "CDS_PHYS_NET_NAME" "TP_USB3_P03_TXN"
					( Origin gPackager )
				)
				( objectStatus "TP_USB3_P03_TXN" )
			)
			( signal "@baseboard_fab2_lib.baseboard_fab2(sch_1):tp_usb3_p03_txp"
				( attribute "CDS_PHYS_NET_NAME" "TP_USB3_P03_TXP"
					( Origin gPackager )
				)
				( objectStatus "TP_USB3_P03_TXP" )
			)
			( signal "@baseboard_fab2_lib.baseboard_fab2(sch_1):tp_usb3_p04_rxn"
				( attribute "CDS_PHYS_NET_NAME" "TP_USB3_P04_RXN"
					( Origin gPackager )
				)
				( objectStatus "TP_USB3_P04_RXN" )
			)
			( signal "@baseboard_fab2_lib.baseboard_fab2(sch_1):tp_usb3_p04_rxp"
				( attribute "CDS_PHYS_NET_NAME" "TP_USB3_P04_RXP"
					( Origin gPackager )
				)
				( objectStatus "TP_USB3_P04_RXP" )
			)
			( signal "@baseboard_fab2_lib.baseboard_fab2(sch_1):tp_usb3_p04_txn"
				( attribute "CDS_PHYS_NET_NAME" "TP_USB3_P04_TXN"
					( Origin gPackager )
				)
				( objectStatus "TP_USB3_P04_TXN" )
			)
			( signal "@baseboard_fab2_lib.baseboard_fab2(sch_1):tp_usb3_p04_txp"
				( attribute "CDS_PHYS_NET_NAME" "TP_USB3_P04_TXP"
					( Origin gPackager )
				)
				( objectStatus "TP_USB3_P04_TXP" )
			)
			( signal "@baseboard_fab2_lib.baseboard_fab2(sch_1):tp_usb3_p05_rxn"
				( attribute "CDS_PHYS_NET_NAME" "TP_USB3_P05_RXN"
					( Origin gPackager )
				)
				( objectStatus "TP_USB3_P05_RXN" )
			)
			( signal "@baseboard_fab2_lib.baseboard_fab2(sch_1):tp_usb3_p05_rxp"
				( attribute "CDS_PHYS_NET_NAME" "TP_USB3_P05_RXP"
					( Origin gPackager )
				)
				( objectStatus "TP_USB3_P05_RXP" )
			)
			( signal "@baseboard_fab2_lib.baseboard_fab2(sch_1):tp_usb3_p05_txn"
				( attribute "CDS_PHYS_NET_NAME" "TP_USB3_P05_TXN"
					( Origin gPackager )
				)
				( objectStatus "TP_USB3_P05_TXN" )
			)
			( signal "@baseboard_fab2_lib.baseboard_fab2(sch_1):tp_usb3_p05_txp"
				( attribute "CDS_PHYS_NET_NAME" "TP_USB3_P05_TXP"
					( Origin gPackager )
				)
				( objectStatus "TP_USB3_P05_TXP" )
			)
			( signal "@baseboard_fab2_lib.baseboard_fab2(sch_1):tp_usb3_p06_rxn"
				( attribute "CDS_PHYS_NET_NAME" "TP_USB3_P06_RXN"
					( Origin gPackager )
				)
				( objectStatus "TP_USB3_P06_RXN" )
			)
			( signal "@baseboard_fab2_lib.baseboard_fab2(sch_1):tp_usb3_p06_rxp"
				( attribute "CDS_PHYS_NET_NAME" "TP_USB3_P06_RXP"
					( Origin gPackager )
				)
				( objectStatus "TP_USB3_P06_RXP" )
			)
			( signal "@baseboard_fab2_lib.baseboard_fab2(sch_1):tp_usb3_p06_txn"
				( attribute "CDS_PHYS_NET_NAME" "TP_USB3_P06_TXN"
					( Origin gPackager )
				)
				( objectStatus "TP_USB3_P06_TXN" )
			)
			( signal "@baseboard_fab2_lib.baseboard_fab2(sch_1):tp_usb3_p06_txp"
				( attribute "CDS_PHYS_NET_NAME" "TP_USB3_P06_TXP"
					( Origin gPackager )
				)
				( objectStatus "TP_USB3_P06_TXP" )
			)
			( signal "@baseboard_fab2_lib.baseboard_fab2(sch_1):usb2_p01_dn"
				( attribute "CDS_PHYS_NET_NAME" "USB2_P01_DN"
					( Origin gPackager )
				)
				( objectStatus "USB2_P01_DN" )
			)
			( signal "@baseboard_fab2_lib.baseboard_fab2(sch_1):usb2_p01_dp"
				( attribute "CDS_PHYS_NET_NAME" "USB2_P01_DP"
					( Origin gPackager )
				)
				( objectStatus "USB2_P01_DP" )
			)
			( signal "@baseboard_fab2_lib.baseboard_fab2(sch_1):usb2_pch_bmc_p5_dn"
				( attribute "CDS_PHYS_NET_NAME" "USB2_PCH_BMC_P5_DN"
					( Origin gPackager )
				)
				( objectStatus "USB2_PCH_BMC_P5_DN" )
			)
			( signal "@baseboard_fab2_lib.baseboard_fab2(sch_1):usb2_pch_bmc_p5_dp"
				( attribute "CDS_PHYS_NET_NAME" "USB2_PCH_BMC_P5_DP"
					( Origin gPackager )
				)
				( objectStatus "USB2_PCH_BMC_P5_DP" )
			)
			( signal "@baseboard_fab2_lib.baseboard_fab2(sch_1):vcc_va_3v3"
				( alias ( signalRef "@baseboard_fab2_lib.baseboard_fab2(sch_1):page148_vcc_va_3v3") )
				( alias ( signalRef "@baseboard_fab2_lib.baseboard_fab2(sch_1):page149_vcc_va_3v3") )
				( attribute "CDS_PHYS_NET_NAME" "VCC_VA_3V3"
					( Origin gPackager )
				)
				( objectStatus "VCC_VA_3V3" )
			)
			( signal "@baseboard_fab2_lib.baseboard_fab2(sch_1):page148_vcc_va_3v3"
				( objectFlag fObjectAlias )
				( objectStatus "page148_vcc_va_3v3" )
			)
			( signal "@baseboard_fab2_lib.baseboard_fab2(sch_1):page149_vcc_va_3v3"
				( objectFlag fObjectAlias )
				( objectStatus "page149_vcc_va_3v3" )
			)
			( signal "@baseboard_fab2_lib.baseboard_fab2(sch_1):tp_tpm_spi_2"
				( attribute "CDS_PHYS_NET_NAME" "TP_TPM_SPI_2"
					( Origin gPackager )
				)
				( objectStatus "TP_TPM_SPI_2" )
			)
			( signal "@baseboard_fab2_lib.baseboard_fab2(sch_1):bmc_m_rst_n"
				( attribute "CDS_PHYS_NET_NAME" "BMC_M_RST_N"
					( Origin gPackager )
				)
				( objectStatus "BMC_M_RST_N" )
			)
			( signal "@baseboard_fab2_lib.baseboard_fab2(sch_1):usb_pch_bmc_p4_dn"
				( attribute "CDS_PHYS_NET_NAME" "USB_PCH_BMC_P4_DN"
					( Origin gPackager )
				)
				( objectStatus "USB_PCH_BMC_P4_DN" )
			)
			( signal "@baseboard_fab2_lib.baseboard_fab2(sch_1):bmc_m_vrefca"
				( attribute "CDS_PHYS_NET_NAME" "BMC_M_VREFCA"
					( Origin gPackager )
				)
				( objectStatus "BMC_M_VREFCA" )
			)
			( signal "@baseboard_fab2_lib.baseboard_fab2(sch_1):jtag_bmc_tdi"
				( attribute "CDS_PHYS_NET_NAME" "JTAG_BMC_TDI"
					( Origin gPackager )
				)
				( objectStatus "JTAG_BMC_TDI" )
			)
			( signal "@baseboard_fab2_lib.baseboard_fab2(sch_1):fm_uart_alert_n"
				( attribute "CDS_PHYS_NET_NAME" "FM_UART_ALERT_N"
					( Origin gPackager )
				)
				( objectStatus "FM_UART_ALERT_N" )
			)
			( signal "@baseboard_fab2_lib.baseboard_fab2(sch_1):jtag_bmc_tck"
				( attribute "CDS_PHYS_NET_NAME" "JTAG_BMC_TCK"
					( Origin gPackager )
				)
				( objectStatus "JTAG_BMC_TCK" )
			)
			( signal "@baseboard_fab2_lib.baseboard_fab2(sch_1):page149_p3v3_usb2a_alg"
				( objectFlag fObjectAlias )
				( objectStatus "page149_p3v3_usb2a_alg" )
			)
			( signal "@baseboard_fab2_lib.baseboard_fab2(sch_1):sgpio_bmc_din"
				( attribute "CDS_PHYS_NET_NAME" "SGPIO_BMC_DIN"
					( Origin gPackager )
				)
				( objectStatus "SGPIO_BMC_DIN" )
			)
			( signal "@baseboard_fab2_lib.baseboard_fab2(sch_1):usb_pch_bmc_p4_dp"
				( attribute "CDS_PHYS_NET_NAME" "USB_PCH_BMC_P4_DP"
					( Origin gPackager )
				)
				( objectStatus "USB_PCH_BMC_P4_DP" )
			)
			( signal "@baseboard_fab2_lib.baseboard_fab2(sch_1):vcc_pa_3v3"
				( alias ( signalRef "@baseboard_fab2_lib.baseboard_fab2(sch_1):page148_vcc_pa_3v3") )
				( alias ( signalRef "@baseboard_fab2_lib.baseboard_fab2(sch_1):page149_vcc_pa_3v3") )
				( attribute "CDS_PHYS_NET_NAME" "VCC_PA_3V3"
					( Origin gPackager )
				)
				( objectStatus "VCC_PA_3V3" )
			)
			( signal "@baseboard_fab2_lib.baseboard_fab2(sch_1):page148_vcc_pa_3v3"
				( objectFlag fObjectAlias )
				( objectStatus "page148_vcc_pa_3v3" )
			)
			( signal "@baseboard_fab2_lib.baseboard_fab2(sch_1):page149_vcc_pa_3v3"
				( objectFlag fObjectAlias )
				( objectStatus "page149_vcc_pa_3v3" )
			)
			( signal "@baseboard_fab2_lib.baseboard_fab2(sch_1):page149_p1v2_aux_bmc"
				( objectFlag fObjectAlias )
				( objectStatus "page149_p1v2_aux_bmc" )
			)
			( signal "@baseboard_fab2_lib.baseboard_fab2(sch_1):peci_bmc_r"
				( attribute "CDS_PHYS_NET_NAME" "PECI_BMC_R"
					( Origin gPackager )
				)
				( objectStatus "PECI_BMC_R" )
			)
			( signal "@baseboard_fab2_lib.baseboard_fab2(sch_1):a_extclkn"
				( attribute "CDS_PHYS_NET_NAME" "A_EXTCLKN"
					( Origin gPackager )
				)
				( objectStatus "A_EXTCLKN" )
			)
			( signal "@baseboard_fab2_lib.baseboard_fab2(sch_1):a_extclkp"
				( attribute "CDS_PHYS_NET_NAME" "A_EXTCLKP"
					( Origin gPackager )
				)
				( objectStatus "A_EXTCLKP" )
			)
			( signal "@baseboard_fab2_lib.baseboard_fab2(sch_1):a_pcie_rcomp_n"
				( attribute "CDS_PHYS_NET_NAME" "A_PCIE_RCOMP_N"
					( Origin gPackager )
				)
				( objectStatus "A_PCIE_RCOMP_N" )
			)
			( signal "@baseboard_fab2_lib.baseboard_fab2(sch_1):a_pcie_rcomp_p"
				( attribute "CDS_PHYS_NET_NAME" "A_PCIE_RCOMP_P"
					( Origin gPackager )
				)
				( objectStatus "A_PCIE_RCOMP_P" )
			)
			( signal "@baseboard_fab2_lib.baseboard_fab2(sch_1):a_pcieup_rcomp_n"
				( attribute "CDS_PHYS_NET_NAME" "A_PCIEUP_RCOMP_N"
					( Origin gPackager )
				)
				( objectStatus "A_PCIEUP_RCOMP_N" )
			)
			( signal "@baseboard_fab2_lib.baseboard_fab2(sch_1):a_pcieup_rcomp_p"
				( attribute "CDS_PHYS_NET_NAME" "A_PCIEUP_RCOMP_P"
					( Origin gPackager )
				)
				( objectStatus "A_PCIEUP_RCOMP_P" )
			)
			( signal "@baseboard_fab2_lib.baseboard_fab2(sch_1):p2e_ssb_bmc_rx_c_dn"
				( attribute "CDS_PHYS_NET_NAME" "P2E_SSB_BMC_RX_C_DN"
					( Origin gPackager )
				)
				( objectStatus "P2E_SSB_BMC_RX_C_DN" )
			)
			( signal "@baseboard_fab2_lib.baseboard_fab2(sch_1):p2e_ssb_bmc_rx_c_dp"
				( attribute "CDS_PHYS_NET_NAME" "P2E_SSB_BMC_RX_C_DP"
					( Origin gPackager )
				)
				( objectStatus "P2E_SSB_BMC_RX_C_DP" )
			)
			( signal "@baseboard_fab2_lib.baseboard_fab2(sch_1):p2e_ssb_bmc_tx_c_dn"
				( attribute "CDS_PHYS_NET_NAME" "P2E_SSB_BMC_TX_C_DN"
					( Origin gPackager )
				)
				( objectStatus "P2E_SSB_BMC_TX_C_DN" )
			)
			( signal "@baseboard_fab2_lib.baseboard_fab2(sch_1):p2e_ssb_bmc_tx_c_dp"
				( attribute "CDS_PHYS_NET_NAME" "P2E_SSB_BMC_TX_C_DP"
					( Origin gPackager )
				)
				( objectStatus "P2E_SSB_BMC_TX_C_DP" )
			)
			( signal "@baseboard_fab2_lib.baseboard_fab2(sch_1):p2e_ssb_bmc_tx_dn"
				( attribute "CDS_PHYS_NET_NAME" "P2E_SSB_BMC_TX_DN"
					( Origin gPackager )
				)
				( objectStatus "P2E_SSB_BMC_TX_DN" )
			)
			( signal "@baseboard_fab2_lib.baseboard_fab2(sch_1):p2e_ssb_bmc_tx_dp"
				( attribute "CDS_PHYS_NET_NAME" "P2E_SSB_BMC_TX_DP"
					( Origin gPackager )
				)
				( objectStatus "P2E_SSB_BMC_TX_DP" )
			)
			( signal "@baseboard_fab2_lib.baseboard_fab2(sch_1):p3e_pch_m2_rx_dn(1)"
				( attribute "CDS_PHYS_NET_NAME" "P3E_PCH_M2_RX_DN<1>"
					( Origin gPackager )
				)
				( attribute "PNN" "P3E_PCH_M2_RX_DN<1>"
					( Origin gPackager )
				)
				( objectStatus "P3E_PCH_M2_RX_DN<1>" )
			)
			( signal "@baseboard_fab2_lib.baseboard_fab2(sch_1):p3e_pch_m2_rx_dn(2)"
				( attribute "CDS_PHYS_NET_NAME" "P3E_PCH_M2_RX_DN<2>"
					( Origin gPackager )
				)
				( attribute "PNN" "P3E_PCH_M2_RX_DN<2>"
					( Origin gPackager )
				)
				( objectStatus "P3E_PCH_M2_RX_DN<2>" )
			)
			( signal "@baseboard_fab2_lib.baseboard_fab2(sch_1):p3e_pch_m2_rx_dn(3)"
				( attribute "CDS_PHYS_NET_NAME" "P3E_PCH_M2_RX_DN<3>"
					( Origin gPackager )
				)
				( attribute "PNN" "P3E_PCH_M2_RX_DN<3>"
					( Origin gPackager )
				)
				( objectStatus "P3E_PCH_M2_RX_DN<3>" )
			)
			( signal "@baseboard_fab2_lib.baseboard_fab2(sch_1):p3e_pch_m2_rx_dp(1)"
				( attribute "CDS_PHYS_NET_NAME" "P3E_PCH_M2_RX_DP<1>"
					( Origin gPackager )
				)
				( attribute "PNN" "P3E_PCH_M2_RX_DP<1>"
					( Origin gPackager )
				)
				( objectStatus "P3E_PCH_M2_RX_DP<1>" )
			)
			( signal "@baseboard_fab2_lib.baseboard_fab2(sch_1):p3e_pch_m2_rx_dp(2)"
				( attribute "CDS_PHYS_NET_NAME" "P3E_PCH_M2_RX_DP<2>"
					( Origin gPackager )
				)
				( attribute "PNN" "P3E_PCH_M2_RX_DP<2>"
					( Origin gPackager )
				)
				( objectStatus "P3E_PCH_M2_RX_DP<2>" )
			)
			( signal "@baseboard_fab2_lib.baseboard_fab2(sch_1):p3e_pch_m2_rx_dp(3)"
				( attribute "CDS_PHYS_NET_NAME" "P3E_PCH_M2_RX_DP<3>"
					( Origin gPackager )
				)
				( attribute "PNN" "P3E_PCH_M2_RX_DP<3>"
					( Origin gPackager )
				)
				( objectStatus "P3E_PCH_M2_RX_DP<3>" )
			)
			( signal "@baseboard_fab2_lib.baseboard_fab2(sch_1):p3e_pch_m2_tx_dn(1)"
				( attribute "CDS_PHYS_NET_NAME" "P3E_PCH_M2_TX_DN<1>"
					( Origin gPackager )
				)
				( attribute "PNN" "P3E_PCH_M2_TX_DN<1>"
					( Origin gPackager )
				)
				( objectStatus "P3E_PCH_M2_TX_DN<1>" )
			)
			( signal "@baseboard_fab2_lib.baseboard_fab2(sch_1):p3e_pch_m2_tx_dn(2)"
				( attribute "CDS_PHYS_NET_NAME" "P3E_PCH_M2_TX_DN<2>"
					( Origin gPackager )
				)
				( attribute "PNN" "P3E_PCH_M2_TX_DN<2>"
					( Origin gPackager )
				)
				( objectStatus "P3E_PCH_M2_TX_DN<2>" )
			)
			( signal "@baseboard_fab2_lib.baseboard_fab2(sch_1):p3e_pch_m2_tx_dn(3)"
				( attribute "CDS_PHYS_NET_NAME" "P3E_PCH_M2_TX_DN<3>"
					( Origin gPackager )
				)
				( attribute "PNN" "P3E_PCH_M2_TX_DN<3>"
					( Origin gPackager )
				)
				( objectStatus "P3E_PCH_M2_TX_DN<3>" )
			)
			( signal "@baseboard_fab2_lib.baseboard_fab2(sch_1):p3e_pch_m2_tx_dp(1)"
				( attribute "CDS_PHYS_NET_NAME" "P3E_PCH_M2_TX_DP<1>"
					( Origin gPackager )
				)
				( attribute "PNN" "P3E_PCH_M2_TX_DP<1>"
					( Origin gPackager )
				)
				( objectStatus "P3E_PCH_M2_TX_DP<1>" )
			)
			( signal "@baseboard_fab2_lib.baseboard_fab2(sch_1):p3e_pch_m2_tx_dp(2)"
				( attribute "CDS_PHYS_NET_NAME" "P3E_PCH_M2_TX_DP<2>"
					( Origin gPackager )
				)
				( attribute "PNN" "P3E_PCH_M2_TX_DP<2>"
					( Origin gPackager )
				)
				( objectStatus "P3E_PCH_M2_TX_DP<2>" )
			)
			( signal "@baseboard_fab2_lib.baseboard_fab2(sch_1):p3e_pch_m2_tx_dp(3)"
				( attribute "CDS_PHYS_NET_NAME" "P3E_PCH_M2_TX_DP<3>"
					( Origin gPackager )
				)
				( attribute "PNN" "P3E_PCH_M2_TX_DP<3>"
					( Origin gPackager )
				)
				( objectStatus "P3E_PCH_M2_TX_DP<3>" )
			)
			( signal "@baseboard_fab2_lib.baseboard_fab2(sch_1):p3e_pch_rx_0_dn"
				( attribute "CDS_PHYS_NET_NAME" "P3E_PCH_RX_0_DN"
					( Origin gPackager )
				)
				( objectStatus "P3E_PCH_RX_0_DN" )
			)
			( signal "@baseboard_fab2_lib.baseboard_fab2(sch_1):p3e_pch_rx_0_dp"
				( attribute "CDS_PHYS_NET_NAME" "P3E_PCH_RX_0_DP"
					( Origin gPackager )
				)
				( objectStatus "P3E_PCH_RX_0_DP" )
			)
			( signal "@baseboard_fab2_lib.baseboard_fab2(sch_1):p3e_pch_tx_0_dn"
				( attribute "CDS_PHYS_NET_NAME" "P3E_PCH_TX_0_DN"
					( Origin gPackager )
				)
				( objectStatus "P3E_PCH_TX_0_DN" )
			)
			( signal "@baseboard_fab2_lib.baseboard_fab2(sch_1):p3e_pch_tx_0_dp"
				( attribute "CDS_PHYS_NET_NAME" "P3E_PCH_TX_0_DP"
					( Origin gPackager )
				)
				( objectStatus "P3E_PCH_TX_0_DP" )
			)
			( signal "@baseboard_fab2_lib.baseboard_fab2(sch_1):pe_pch_sprv_rx_c_dn"
				( attribute "CDS_PHYS_NET_NAME" "PE_PCH_SPRV_RX_C_DN"
					( Origin gPackager )
				)
				( objectStatus "PE_PCH_SPRV_RX_C_DN" )
			)
			( signal "@baseboard_fab2_lib.baseboard_fab2(sch_1):pe_pch_sprv_rx_c_dp"
				( attribute "CDS_PHYS_NET_NAME" "PE_PCH_SPRV_RX_C_DP"
					( Origin gPackager )
				)
				( objectStatus "PE_PCH_SPRV_RX_C_DP" )
			)
			( signal "@baseboard_fab2_lib.baseboard_fab2(sch_1):pe_pch_sprv_tx_dn"
				( attribute "CDS_PHYS_NET_NAME" "PE_PCH_SPRV_TX_DN"
					( Origin gPackager )
				)
				( objectStatus "PE_PCH_SPRV_TX_DN" )
			)
			( signal "@baseboard_fab2_lib.baseboard_fab2(sch_1):pe_pch_sprv_tx_dp"
				( attribute "CDS_PHYS_NET_NAME" "PE_PCH_SPRV_TX_DP"
					( Origin gPackager )
				)
				( objectStatus "PE_PCH_SPRV_TX_DP" )
			)
			( signal "@baseboard_fab2_lib.baseboard_fab2(sch_1):sata6g_pch_pcie_up_sata_rxn(0)"
				( attribute "CDS_PHYS_NET_NAME" "SATA6G_PCH_PCIE_UP_SATA_RXN<0>"
					( Origin gPackager )
				)
				( attribute "PNN" "SATA6G_PCH_PCIE_UP_SATA_RXN<0>"
					( Origin gPackager )
				)
				( objectStatus "SATA6G_PCH_PCIE_UP_SATA_RXN<0>" )
			)
			( signal "@baseboard_fab2_lib.baseboard_fab2(sch_1):sata6g_pch_pcie_up_sata_rxn(1)"
				( attribute "CDS_PHYS_NET_NAME" "SATA6G_PCH_PCIE_UP_SATA_RXN<1>"
					( Origin gPackager )
				)
				( attribute "PNN" "SATA6G_PCH_PCIE_UP_SATA_RXN<1>"
					( Origin gPackager )
				)
				( objectStatus "SATA6G_PCH_PCIE_UP_SATA_RXN<1>" )
			)
			( signal "@baseboard_fab2_lib.baseboard_fab2(sch_1):sata6g_pch_pcie_up_sata_rxn(2)"
				( attribute "CDS_PHYS_NET_NAME" "SATA6G_PCH_PCIE_UP_SATA_RXN<2>"
					( Origin gPackager )
				)
				( attribute "PNN" "SATA6G_PCH_PCIE_UP_SATA_RXN<2>"
					( Origin gPackager )
				)
				( objectStatus "SATA6G_PCH_PCIE_UP_SATA_RXN<2>" )
			)
			( signal "@baseboard_fab2_lib.baseboard_fab2(sch_1):sata6g_pch_pcie_up_sata_rxn(3)"
				( attribute "CDS_PHYS_NET_NAME" "SATA6G_PCH_PCIE_UP_SATA_RXN<3>"
					( Origin gPackager )
				)
				( attribute "PNN" "SATA6G_PCH_PCIE_UP_SATA_RXN<3>"
					( Origin gPackager )
				)
				( objectStatus "SATA6G_PCH_PCIE_UP_SATA_RXN<3>" )
			)
			( signal "@baseboard_fab2_lib.baseboard_fab2(sch_1):sata6g_pch_pcie_up_sata_rxn(4)"
				( attribute "CDS_PHYS_NET_NAME" "SATA6G_PCH_PCIE_UP_SATA_RXN<4>"
					( Origin gPackager )
				)
				( attribute "PNN" "SATA6G_PCH_PCIE_UP_SATA_RXN<4>"
					( Origin gPackager )
				)
				( objectStatus "SATA6G_PCH_PCIE_UP_SATA_RXN<4>" )
			)
			( signal "@baseboard_fab2_lib.baseboard_fab2(sch_1):sata6g_pch_pcie_up_sata_rxn(5)"
				( attribute "CDS_PHYS_NET_NAME" "SATA6G_PCH_PCIE_UP_SATA_RXN<5>"
					( Origin gPackager )
				)
				( attribute "PNN" "SATA6G_PCH_PCIE_UP_SATA_RXN<5>"
					( Origin gPackager )
				)
				( objectStatus "SATA6G_PCH_PCIE_UP_SATA_RXN<5>" )
			)
			( signal "@baseboard_fab2_lib.baseboard_fab2(sch_1):sata6g_pch_pcie_up_sata_rxn(6)"
				( attribute "CDS_PHYS_NET_NAME" "SATA6G_PCH_PCIE_UP_SATA_RXN<6>"
					( Origin gPackager )
				)
				( attribute "PNN" "SATA6G_PCH_PCIE_UP_SATA_RXN<6>"
					( Origin gPackager )
				)
				( objectStatus "SATA6G_PCH_PCIE_UP_SATA_RXN<6>" )
			)
			( signal "@baseboard_fab2_lib.baseboard_fab2(sch_1):sata6g_pch_pcie_up_sata_rxn(7)"
				( attribute "CDS_PHYS_NET_NAME" "SATA6G_PCH_PCIE_UP_SATA_RXN<7>"
					( Origin gPackager )
				)
				( attribute "PNN" "SATA6G_PCH_PCIE_UP_SATA_RXN<7>"
					( Origin gPackager )
				)
				( objectStatus "SATA6G_PCH_PCIE_UP_SATA_RXN<7>" )
			)
			( signal "@baseboard_fab2_lib.baseboard_fab2(sch_1):sata6g_pch_pcie_up_sata_rxp(0)"
				( attribute "CDS_PHYS_NET_NAME" "SATA6G_PCH_PCIE_UP_SATA_RXP<0>"
					( Origin gPackager )
				)
				( attribute "PNN" "SATA6G_PCH_PCIE_UP_SATA_RXP<0>"
					( Origin gPackager )
				)
				( objectStatus "SATA6G_PCH_PCIE_UP_SATA_RXP<0>" )
			)
			( signal "@baseboard_fab2_lib.baseboard_fab2(sch_1):sata6g_pch_pcie_up_sata_rxp(1)"
				( attribute "CDS_PHYS_NET_NAME" "SATA6G_PCH_PCIE_UP_SATA_RXP<1>"
					( Origin gPackager )
				)
				( attribute "PNN" "SATA6G_PCH_PCIE_UP_SATA_RXP<1>"
					( Origin gPackager )
				)
				( objectStatus "SATA6G_PCH_PCIE_UP_SATA_RXP<1>" )
			)
			( signal "@baseboard_fab2_lib.baseboard_fab2(sch_1):sata6g_pch_pcie_up_sata_rxp(2)"
				( attribute "CDS_PHYS_NET_NAME" "SATA6G_PCH_PCIE_UP_SATA_RXP<2>"
					( Origin gPackager )
				)
				( attribute "PNN" "SATA6G_PCH_PCIE_UP_SATA_RXP<2>"
					( Origin gPackager )
				)
				( objectStatus "SATA6G_PCH_PCIE_UP_SATA_RXP<2>" )
			)
			( signal "@baseboard_fab2_lib.baseboard_fab2(sch_1):sata6g_pch_pcie_up_sata_rxp(3)"
				( attribute "CDS_PHYS_NET_NAME" "SATA6G_PCH_PCIE_UP_SATA_RXP<3>"
					( Origin gPackager )
				)
				( attribute "PNN" "SATA6G_PCH_PCIE_UP_SATA_RXP<3>"
					( Origin gPackager )
				)
				( objectStatus "SATA6G_PCH_PCIE_UP_SATA_RXP<3>" )
			)
			( signal "@baseboard_fab2_lib.baseboard_fab2(sch_1):sata6g_pch_pcie_up_sata_rxp(4)"
				( attribute "CDS_PHYS_NET_NAME" "SATA6G_PCH_PCIE_UP_SATA_RXP<4>"
					( Origin gPackager )
				)
				( attribute "PNN" "SATA6G_PCH_PCIE_UP_SATA_RXP<4>"
					( Origin gPackager )
				)
				( objectStatus "SATA6G_PCH_PCIE_UP_SATA_RXP<4>" )
			)
			( signal "@baseboard_fab2_lib.baseboard_fab2(sch_1):sata6g_pch_pcie_up_sata_rxp(5)"
				( attribute "CDS_PHYS_NET_NAME" "SATA6G_PCH_PCIE_UP_SATA_RXP<5>"
					( Origin gPackager )
				)
				( attribute "PNN" "SATA6G_PCH_PCIE_UP_SATA_RXP<5>"
					( Origin gPackager )
				)
				( objectStatus "SATA6G_PCH_PCIE_UP_SATA_RXP<5>" )
			)
			( signal "@baseboard_fab2_lib.baseboard_fab2(sch_1):sata6g_pch_pcie_up_sata_rxp(6)"
				( attribute "CDS_PHYS_NET_NAME" "SATA6G_PCH_PCIE_UP_SATA_RXP<6>"
					( Origin gPackager )
				)
				( attribute "PNN" "SATA6G_PCH_PCIE_UP_SATA_RXP<6>"
					( Origin gPackager )
				)
				( objectStatus "SATA6G_PCH_PCIE_UP_SATA_RXP<6>" )
			)
			( signal "@baseboard_fab2_lib.baseboard_fab2(sch_1):sata6g_pch_pcie_up_sata_rxp(7)"
				( attribute "CDS_PHYS_NET_NAME" "SATA6G_PCH_PCIE_UP_SATA_RXP<7>"
					( Origin gPackager )
				)
				( attribute "PNN" "SATA6G_PCH_PCIE_UP_SATA_RXP<7>"
					( Origin gPackager )
				)
				( objectStatus "SATA6G_PCH_PCIE_UP_SATA_RXP<7>" )
			)
			( signal "@baseboard_fab2_lib.baseboard_fab2(sch_1):sata6g_pch_pcie_up_sata_txn(0)"
				( attribute "CDS_PHYS_NET_NAME" "SATA6G_PCH_PCIE_UP_SATA_TXN<0>"
					( Origin gPackager )
				)
				( attribute "PNN" "SATA6G_PCH_PCIE_UP_SATA_TXN<0>"
					( Origin gPackager )
				)
				( objectStatus "SATA6G_PCH_PCIE_UP_SATA_TXN<0>" )
			)
			( signal "@baseboard_fab2_lib.baseboard_fab2(sch_1):sata6g_pch_pcie_up_sata_txn(1)"
				( attribute "CDS_PHYS_NET_NAME" "SATA6G_PCH_PCIE_UP_SATA_TXN<1>"
					( Origin gPackager )
				)
				( attribute "PNN" "SATA6G_PCH_PCIE_UP_SATA_TXN<1>"
					( Origin gPackager )
				)
				( objectStatus "SATA6G_PCH_PCIE_UP_SATA_TXN<1>" )
			)
			( signal "@baseboard_fab2_lib.baseboard_fab2(sch_1):sata6g_pch_pcie_up_sata_txn(2)"
				( attribute "CDS_PHYS_NET_NAME" "SATA6G_PCH_PCIE_UP_SATA_TXN<2>"
					( Origin gPackager )
				)
				( attribute "PNN" "SATA6G_PCH_PCIE_UP_SATA_TXN<2>"
					( Origin gPackager )
				)
				( objectStatus "SATA6G_PCH_PCIE_UP_SATA_TXN<2>" )
			)
			( signal "@baseboard_fab2_lib.baseboard_fab2(sch_1):sata6g_pch_pcie_up_sata_txn(3)"
				( attribute "CDS_PHYS_NET_NAME" "SATA6G_PCH_PCIE_UP_SATA_TXN<3>"
					( Origin gPackager )
				)
				( attribute "PNN" "SATA6G_PCH_PCIE_UP_SATA_TXN<3>"
					( Origin gPackager )
				)
				( objectStatus "SATA6G_PCH_PCIE_UP_SATA_TXN<3>" )
			)
			( signal "@baseboard_fab2_lib.baseboard_fab2(sch_1):sata6g_pch_pcie_up_sata_txn(4)"
				( attribute "CDS_PHYS_NET_NAME" "SATA6G_PCH_PCIE_UP_SATA_TXN<4>"
					( Origin gPackager )
				)
				( attribute "PNN" "SATA6G_PCH_PCIE_UP_SATA_TXN<4>"
					( Origin gPackager )
				)
				( objectStatus "SATA6G_PCH_PCIE_UP_SATA_TXN<4>" )
			)
			( signal "@baseboard_fab2_lib.baseboard_fab2(sch_1):sata6g_pch_pcie_up_sata_txn(5)"
				( attribute "CDS_PHYS_NET_NAME" "SATA6G_PCH_PCIE_UP_SATA_TXN<5>"
					( Origin gPackager )
				)
				( attribute "PNN" "SATA6G_PCH_PCIE_UP_SATA_TXN<5>"
					( Origin gPackager )
				)
				( objectStatus "SATA6G_PCH_PCIE_UP_SATA_TXN<5>" )
			)
			( signal "@baseboard_fab2_lib.baseboard_fab2(sch_1):sata6g_pch_pcie_up_sata_txn(6)"
				( attribute "CDS_PHYS_NET_NAME" "SATA6G_PCH_PCIE_UP_SATA_TXN<6>"
					( Origin gPackager )
				)
				( attribute "PNN" "SATA6G_PCH_PCIE_UP_SATA_TXN<6>"
					( Origin gPackager )
				)
				( objectStatus "SATA6G_PCH_PCIE_UP_SATA_TXN<6>" )
			)
			( signal "@baseboard_fab2_lib.baseboard_fab2(sch_1):sata6g_pch_pcie_up_sata_txn(7)"
				( attribute "CDS_PHYS_NET_NAME" "SATA6G_PCH_PCIE_UP_SATA_TXN<7>"
					( Origin gPackager )
				)
				( attribute "PNN" "SATA6G_PCH_PCIE_UP_SATA_TXN<7>"
					( Origin gPackager )
				)
				( objectStatus "SATA6G_PCH_PCIE_UP_SATA_TXN<7>" )
			)
			( signal "@baseboard_fab2_lib.baseboard_fab2(sch_1):sata6g_pch_pcie_up_sata_txp(0)"
				( attribute "CDS_PHYS_NET_NAME" "SATA6G_PCH_PCIE_UP_SATA_TXP<0>"
					( Origin gPackager )
				)
				( attribute "PNN" "SATA6G_PCH_PCIE_UP_SATA_TXP<0>"
					( Origin gPackager )
				)
				( objectStatus "SATA6G_PCH_PCIE_UP_SATA_TXP<0>" )
			)
			( signal "@baseboard_fab2_lib.baseboard_fab2(sch_1):sata6g_pch_pcie_up_sata_txp(1)"
				( attribute "CDS_PHYS_NET_NAME" "SATA6G_PCH_PCIE_UP_SATA_TXP<1>"
					( Origin gPackager )
				)
				( attribute "PNN" "SATA6G_PCH_PCIE_UP_SATA_TXP<1>"
					( Origin gPackager )
				)
				( objectStatus "SATA6G_PCH_PCIE_UP_SATA_TXP<1>" )
			)
			( signal "@baseboard_fab2_lib.baseboard_fab2(sch_1):sata6g_pch_pcie_up_sata_txp(2)"
				( attribute "CDS_PHYS_NET_NAME" "SATA6G_PCH_PCIE_UP_SATA_TXP<2>"
					( Origin gPackager )
				)
				( attribute "PNN" "SATA6G_PCH_PCIE_UP_SATA_TXP<2>"
					( Origin gPackager )
				)
				( objectStatus "SATA6G_PCH_PCIE_UP_SATA_TXP<2>" )
			)
			( signal "@baseboard_fab2_lib.baseboard_fab2(sch_1):sata6g_pch_pcie_up_sata_txp(3)"
				( attribute "CDS_PHYS_NET_NAME" "SATA6G_PCH_PCIE_UP_SATA_TXP<3>"
					( Origin gPackager )
				)
				( attribute "PNN" "SATA6G_PCH_PCIE_UP_SATA_TXP<3>"
					( Origin gPackager )
				)
				( objectStatus "SATA6G_PCH_PCIE_UP_SATA_TXP<3>" )
			)
			( signal "@baseboard_fab2_lib.baseboard_fab2(sch_1):sata6g_pch_pcie_up_sata_txp(4)"
				( attribute "CDS_PHYS_NET_NAME" "SATA6G_PCH_PCIE_UP_SATA_TXP<4>"
					( Origin gPackager )
				)
				( attribute "PNN" "SATA6G_PCH_PCIE_UP_SATA_TXP<4>"
					( Origin gPackager )
				)
				( objectStatus "SATA6G_PCH_PCIE_UP_SATA_TXP<4>" )
			)
			( signal "@baseboard_fab2_lib.baseboard_fab2(sch_1):sata6g_pch_pcie_up_sata_txp(5)"
				( attribute "CDS_PHYS_NET_NAME" "SATA6G_PCH_PCIE_UP_SATA_TXP<5>"
					( Origin gPackager )
				)
				( attribute "PNN" "SATA6G_PCH_PCIE_UP_SATA_TXP<5>"
					( Origin gPackager )
				)
				( objectStatus "SATA6G_PCH_PCIE_UP_SATA_TXP<5>" )
			)
			( signal "@baseboard_fab2_lib.baseboard_fab2(sch_1):sata6g_pch_pcie_up_sata_txp(6)"
				( attribute "CDS_PHYS_NET_NAME" "SATA6G_PCH_PCIE_UP_SATA_TXP<6>"
					( Origin gPackager )
				)
				( attribute "PNN" "SATA6G_PCH_PCIE_UP_SATA_TXP<6>"
					( Origin gPackager )
				)
				( objectStatus "SATA6G_PCH_PCIE_UP_SATA_TXP<6>" )
			)
			( signal "@baseboard_fab2_lib.baseboard_fab2(sch_1):sata6g_pch_pcie_up_sata_txp(7)"
				( attribute "CDS_PHYS_NET_NAME" "SATA6G_PCH_PCIE_UP_SATA_TXP<7>"
					( Origin gPackager )
				)
				( attribute "PNN" "SATA6G_PCH_PCIE_UP_SATA_TXP<7>"
					( Origin gPackager )
				)
				( objectStatus "SATA6G_PCH_PCIE_UP_SATA_TXP<7>" )
			)
			( signal "@baseboard_fab2_lib.baseboard_fab2(sch_1):bmc_pwr_debug_n"
				( attribute "CDS_PHYS_NET_NAME" "BMC_PWR_DEBUG_N"
					( Origin gPackager )
				)
				( objectStatus "BMC_PWR_DEBUG_N" )
			)
			( signal "@baseboard_fab2_lib.baseboard_fab2(sch_1):page147_bmc_preq_n"
				( attribute "CDS_PHYS_NET_NAME" "BMC_PREQ_N"
					( Origin gPackager )
				)
				( objectFlag fObjectAlias )
				( objectStatus "page147_bmc_preq_n" )
			)
			( signal "@baseboard_fab2_lib.baseboard_fab2(sch_1):bmc_preq_n"
				( alias ( signalRef "@baseboard_fab2_lib.baseboard_fab2(sch_1):page147_bmc_preq_n") )
				( attribute "CDS_PHYS_NET_NAME" "BMC_PREQ_N"
					( Origin gPackager )
				)
				( objectStatus "BMC_PREQ_N" )
			)
			( signal "@baseboard_fab2_lib.baseboard_fab2(sch_1):sata6g_s0_rx_dn"
				( attribute "CDS_PHYS_NET_NAME" "SATA6G_S0_RX_DN"
					( Origin gPackager )
				)
				( objectStatus "SATA6G_S0_RX_DN" )
			)
			( signal "@baseboard_fab2_lib.baseboard_fab2(sch_1):sata6g_s0_rx_dp"
				( attribute "CDS_PHYS_NET_NAME" "SATA6G_S0_RX_DP"
					( Origin gPackager )
				)
				( objectStatus "SATA6G_S0_RX_DP" )
			)
			( signal "@baseboard_fab2_lib.baseboard_fab2(sch_1):sata6g_s0_tx_dn"
				( attribute "CDS_PHYS_NET_NAME" "SATA6G_S0_TX_DN"
					( Origin gPackager )
				)
				( objectStatus "SATA6G_S0_TX_DN" )
			)
			( signal "@baseboard_fab2_lib.baseboard_fab2(sch_1):sata6g_s0_tx_dp"
				( attribute "CDS_PHYS_NET_NAME" "SATA6G_S0_TX_DP"
					( Origin gPackager )
				)
				( objectStatus "SATA6G_S0_TX_DP" )
			)
			( signal "@baseboard_fab2_lib.baseboard_fab2(sch_1):sata6g_s1_rx_dn"
				( attribute "CDS_PHYS_NET_NAME" "SATA6G_S1_RX_DN"
					( Origin gPackager )
				)
				( objectStatus "SATA6G_S1_RX_DN" )
			)
			( signal "@baseboard_fab2_lib.baseboard_fab2(sch_1):sata6g_s1_rx_dp"
				( attribute "CDS_PHYS_NET_NAME" "SATA6G_S1_RX_DP"
					( Origin gPackager )
				)
				( objectStatus "SATA6G_S1_RX_DP" )
			)
			( signal "@baseboard_fab2_lib.baseboard_fab2(sch_1):sata6g_s1_tx_dn"
				( attribute "CDS_PHYS_NET_NAME" "SATA6G_S1_TX_DN"
					( Origin gPackager )
				)
				( objectStatus "SATA6G_S1_TX_DN" )
			)
			( signal "@baseboard_fab2_lib.baseboard_fab2(sch_1):sata6g_s1_tx_dp"
				( attribute "CDS_PHYS_NET_NAME" "SATA6G_S1_TX_DP"
					( Origin gPackager )
				)
				( objectStatus "SATA6G_S1_TX_DP" )
			)
			( signal "@baseboard_fab2_lib.baseboard_fab2(sch_1):bmc_prdy_n"
				( alias ( signalRef "@baseboard_fab2_lib.baseboard_fab2(sch_1):page146_bmc_prdy_n") )
				( attribute "CDS_PHYS_NET_NAME" "BMC_PRDY_N"
					( Origin gPackager )
				)
				( objectStatus "BMC_PRDY_N" )
			)
			( signal "@baseboard_fab2_lib.baseboard_fab2(sch_1):page146_bmc_prdy_n"
				( attribute "CDS_PHYS_NET_NAME" "BMC_PRDY_N"
					( Origin gPackager )
				)
				( objectFlag fObjectAlias )
				( objectStatus "page146_bmc_prdy_n" )
			)
			( signal "@baseboard_fab2_lib.baseboard_fab2(sch_1):bmc_rsmrst_b_n"
				( attribute "CDS_PHYS_NET_NAME" "BMC_RSMRST_B_N"
					( Origin gPackager )
				)
				( objectStatus "BMC_RSMRST_B_N" )
			)
			( signal "@baseboard_fab2_lib.baseboard_fab2(sch_1):bmc_tck_mux_sel"
				( alias ( signalRef "@baseboard_fab2_lib.baseboard_fab2(sch_1):page146_bmc_tck_mux_sel") )
				( attribute "CDS_PHYS_NET_NAME" "BMC_TCK_MUX_SEL"
					( Origin gPackager )
				)
				( objectStatus "BMC_TCK_MUX_SEL" )
			)
			( signal "@baseboard_fab2_lib.baseboard_fab2(sch_1):page146_bmc_tck_mux_sel"
				( attribute "CDS_PHYS_NET_NAME" "BMC_TCK_MUX_SEL"
					( Origin gPackager )
				)
				( objectFlag fObjectAlias )
				( objectStatus "page146_bmc_tck_mux_sel" )
			)
			( signal "@baseboard_fab2_lib.baseboard_fab2(sch_1):tp_pch_rsvd47"
				( attribute "CDS_PHYS_NET_NAME" "TP_PCH_RSVD47"
					( Origin gPackager )
				)
				( objectStatus "TP_PCH_RSVD47" )
			)
			( signal "@baseboard_fab2_lib.baseboard_fab2(sch_1):tp_pch_rsvd48"
				( attribute "CDS_PHYS_NET_NAME" "TP_PCH_RSVD48"
					( Origin gPackager )
				)
				( objectStatus "TP_PCH_RSVD48" )
			)
			( signal "@baseboard_fab2_lib.baseboard_fab2(sch_1):tp_pch_rsvd49"
				( attribute "CDS_PHYS_NET_NAME" "TP_PCH_RSVD49"
					( Origin gPackager )
				)
				( objectStatus "TP_PCH_RSVD49" )
			)
			( signal "@baseboard_fab2_lib.baseboard_fab2(sch_1):tp_pch_rsvd50"
				( attribute "CDS_PHYS_NET_NAME" "TP_PCH_RSVD50"
					( Origin gPackager )
				)
				( objectStatus "TP_PCH_RSVD50" )
			)
			( signal "@baseboard_fab2_lib.baseboard_fab2(sch_1):tp_pch_rsvd51"
				( attribute "CDS_PHYS_NET_NAME" "TP_PCH_RSVD51"
					( Origin gPackager )
				)
				( objectStatus "TP_PCH_RSVD51" )
			)
			( signal "@baseboard_fab2_lib.baseboard_fab2(sch_1):tp_pch_rsvd52"
				( attribute "CDS_PHYS_NET_NAME" "TP_PCH_RSVD52"
					( Origin gPackager )
				)
				( objectStatus "TP_PCH_RSVD52" )
			)
			( signal "@baseboard_fab2_lib.baseboard_fab2(sch_1):dmi_cpu0_pch_rx_dn(0)"
				( attribute "CDS_PHYS_NET_NAME" "DMI_CPU0_PCH_RX_DN<0>"
					( Origin gPackager )
				)
				( attribute "PNN" "DMI_CPU0_PCH_RX_DN<0>"
					( Origin gPackager )
				)
				( objectStatus "DMI_CPU0_PCH_RX_DN<0>" )
			)
			( signal "@baseboard_fab2_lib.baseboard_fab2(sch_1):dmi_cpu0_pch_rx_dn(1)"
				( attribute "CDS_PHYS_NET_NAME" "DMI_CPU0_PCH_RX_DN<1>"
					( Origin gPackager )
				)
				( attribute "PNN" "DMI_CPU0_PCH_RX_DN<1>"
					( Origin gPackager )
				)
				( objectStatus "DMI_CPU0_PCH_RX_DN<1>" )
			)
			( signal "@baseboard_fab2_lib.baseboard_fab2(sch_1):dmi_cpu0_pch_rx_dn(2)"
				( attribute "CDS_PHYS_NET_NAME" "DMI_CPU0_PCH_RX_DN<2>"
					( Origin gPackager )
				)
				( attribute "PNN" "DMI_CPU0_PCH_RX_DN<2>"
					( Origin gPackager )
				)
				( objectStatus "DMI_CPU0_PCH_RX_DN<2>" )
			)
			( signal "@baseboard_fab2_lib.baseboard_fab2(sch_1):dmi_cpu0_pch_rx_dn(3)"
				( attribute "CDS_PHYS_NET_NAME" "DMI_CPU0_PCH_RX_DN<3>"
					( Origin gPackager )
				)
				( attribute "PNN" "DMI_CPU0_PCH_RX_DN<3>"
					( Origin gPackager )
				)
				( objectStatus "DMI_CPU0_PCH_RX_DN<3>" )
			)
			( signal "@baseboard_fab2_lib.baseboard_fab2(sch_1):dmi_cpu0_pch_rx_dp(0)"
				( attribute "CDS_PHYS_NET_NAME" "DMI_CPU0_PCH_RX_DP<0>"
					( Origin gPackager )
				)
				( attribute "PNN" "DMI_CPU0_PCH_RX_DP<0>"
					( Origin gPackager )
				)
				( objectStatus "DMI_CPU0_PCH_RX_DP<0>" )
			)
			( signal "@baseboard_fab2_lib.baseboard_fab2(sch_1):dmi_cpu0_pch_rx_dp(1)"
				( attribute "CDS_PHYS_NET_NAME" "DMI_CPU0_PCH_RX_DP<1>"
					( Origin gPackager )
				)
				( attribute "PNN" "DMI_CPU0_PCH_RX_DP<1>"
					( Origin gPackager )
				)
				( objectStatus "DMI_CPU0_PCH_RX_DP<1>" )
			)
			( signal "@baseboard_fab2_lib.baseboard_fab2(sch_1):dmi_cpu0_pch_rx_dp(2)"
				( attribute "CDS_PHYS_NET_NAME" "DMI_CPU0_PCH_RX_DP<2>"
					( Origin gPackager )
				)
				( attribute "PNN" "DMI_CPU0_PCH_RX_DP<2>"
					( Origin gPackager )
				)
				( objectStatus "DMI_CPU0_PCH_RX_DP<2>" )
			)
			( signal "@baseboard_fab2_lib.baseboard_fab2(sch_1):dmi_cpu0_pch_rx_dp(3)"
				( attribute "CDS_PHYS_NET_NAME" "DMI_CPU0_PCH_RX_DP<3>"
					( Origin gPackager )
				)
				( attribute "PNN" "DMI_CPU0_PCH_RX_DP<3>"
					( Origin gPackager )
				)
				( objectStatus "DMI_CPU0_PCH_RX_DP<3>" )
			)
			( signal "@baseboard_fab2_lib.baseboard_fab2(sch_1):dmi_cpu0_pch_tx_c_dn(0)"
				( attribute "CDS_PHYS_NET_NAME" "DMI_CPU0_PCH_TX_C_DN<0>"
					( Origin gPackager )
				)
				( attribute "PNN" "DMI_CPU0_PCH_TX_C_DN<0>"
					( Origin gPackager )
				)
				( objectStatus "DMI_CPU0_PCH_TX_C_DN<0>" )
			)
			( signal "@baseboard_fab2_lib.baseboard_fab2(sch_1):dmi_cpu0_pch_tx_c_dn(1)"
				( attribute "CDS_PHYS_NET_NAME" "DMI_CPU0_PCH_TX_C_DN<1>"
					( Origin gPackager )
				)
				( attribute "PNN" "DMI_CPU0_PCH_TX_C_DN<1>"
					( Origin gPackager )
				)
				( objectStatus "DMI_CPU0_PCH_TX_C_DN<1>" )
			)
			( signal "@baseboard_fab2_lib.baseboard_fab2(sch_1):dmi_cpu0_pch_tx_c_dn(2)"
				( attribute "CDS_PHYS_NET_NAME" "DMI_CPU0_PCH_TX_C_DN<2>"
					( Origin gPackager )
				)
				( attribute "PNN" "DMI_CPU0_PCH_TX_C_DN<2>"
					( Origin gPackager )
				)
				( objectStatus "DMI_CPU0_PCH_TX_C_DN<2>" )
			)
			( signal "@baseboard_fab2_lib.baseboard_fab2(sch_1):dmi_cpu0_pch_tx_c_dn(3)"
				( attribute "CDS_PHYS_NET_NAME" "DMI_CPU0_PCH_TX_C_DN<3>"
					( Origin gPackager )
				)
				( attribute "PNN" "DMI_CPU0_PCH_TX_C_DN<3>"
					( Origin gPackager )
				)
				( objectStatus "DMI_CPU0_PCH_TX_C_DN<3>" )
			)
			( signal "@baseboard_fab2_lib.baseboard_fab2(sch_1):dmi_cpu0_pch_tx_c_dp(0)"
				( attribute "CDS_PHYS_NET_NAME" "DMI_CPU0_PCH_TX_C_DP<0>"
					( Origin gPackager )
				)
				( attribute "PNN" "DMI_CPU0_PCH_TX_C_DP<0>"
					( Origin gPackager )
				)
				( objectStatus "DMI_CPU0_PCH_TX_C_DP<0>" )
			)
			( signal "@baseboard_fab2_lib.baseboard_fab2(sch_1):dmi_cpu0_pch_tx_c_dp(1)"
				( attribute "CDS_PHYS_NET_NAME" "DMI_CPU0_PCH_TX_C_DP<1>"
					( Origin gPackager )
				)
				( attribute "PNN" "DMI_CPU0_PCH_TX_C_DP<1>"
					( Origin gPackager )
				)
				( objectStatus "DMI_CPU0_PCH_TX_C_DP<1>" )
			)
			( signal "@baseboard_fab2_lib.baseboard_fab2(sch_1):dmi_cpu0_pch_tx_c_dp(2)"
				( attribute "CDS_PHYS_NET_NAME" "DMI_CPU0_PCH_TX_C_DP<2>"
					( Origin gPackager )
				)
				( attribute "PNN" "DMI_CPU0_PCH_TX_C_DP<2>"
					( Origin gPackager )
				)
				( objectStatus "DMI_CPU0_PCH_TX_C_DP<2>" )
			)
			( signal "@baseboard_fab2_lib.baseboard_fab2(sch_1):dmi_cpu0_pch_tx_c_dp(3)"
				( attribute "CDS_PHYS_NET_NAME" "DMI_CPU0_PCH_TX_C_DP<3>"
					( Origin gPackager )
				)
				( attribute "PNN" "DMI_CPU0_PCH_TX_C_DP<3>"
					( Origin gPackager )
				)
				( objectStatus "DMI_CPU0_PCH_TX_C_DP<3>" )
			)
			( signal "@baseboard_fab2_lib.baseboard_fab2(sch_1):bmc_m_ras_n"
				( attribute "CDS_PHYS_NET_NAME" "BMC_M_RAS_N"
					( Origin gPackager )
				)
				( objectStatus "BMC_M_RAS_N" )
			)
			( signal "@baseboard_fab2_lib.baseboard_fab2(sch_1):a_kr0_rbias"
				( attribute "CDS_PHYS_NET_NAME" "A_KR0_RBIAS"
					( Origin gPackager )
				)
				( objectStatus "A_KR0_RBIAS" )
			)
			( signal "@baseboard_fab2_lib.baseboard_fab2(sch_1):a_kr1_rbias"
				( attribute "CDS_PHYS_NET_NAME" "A_KR1_RBIAS"
					( Origin gPackager )
				)
				( objectStatus "A_KR1_RBIAS" )
			)
			( signal "@baseboard_fab2_lib.baseboard_fab2(sch_1):bmc_m_malert_n"
				( attribute "CDS_PHYS_NET_NAME" "BMC_M_MALERT_N"
					( Origin gPackager )
				)
				( objectStatus "BMC_M_MALERT_N" )
			)
			( signal "@baseboard_fab2_lib.baseboard_fab2(sch_1):irq_lvc3_wake_r_n"
				( attribute "CDS_PHYS_NET_NAME" "IRQ_LVC3_WAKE_R_N"
					( Origin gPackager )
				)
				( objectStatus "IRQ_LVC3_WAKE_R_N" )
			)
			( signal "@baseboard_fab2_lib.baseboard_fab2(sch_1):smb_bmc_pmbus_stby_lvc3_scl_r"
				( attribute "CDS_PHYS_NET_NAME" "SMB_BMC_PMBUS_STBY_LVC3_SCL_R"
					( Origin gPackager )
				)
				( objectStatus "SMB_BMC_PMBUS_STBY_LVC3_SCL_R" )
			)
			( signal "@baseboard_fab2_lib.baseboard_fab2(sch_1):pu_tri_state_en"
				( attribute "CDS_PHYS_NET_NAME" "PU_TRI_STATE_EN"
					( Origin gPackager )
				)
				( objectStatus "PU_TRI_STATE_EN" )
			)
			( signal "@baseboard_fab2_lib.baseboard_fab2(sch_1):fm_pe_ocp_wake_n"
				( attribute "CDS_PHYS_NET_NAME" "FM_PE_OCP_WAKE_N"
					( Origin gPackager )
				)
				( objectStatus "FM_PE_OCP_WAKE_N" )
			)
			( signal "@baseboard_fab2_lib.baseboard_fab2(sch_1):sgpio_bmc_clk"
				( attribute "CDS_PHYS_NET_NAME" "SGPIO_BMC_CLK"
					( Origin gPackager )
				)
				( objectStatus "SGPIO_BMC_CLK" )
			)
			( signal "@baseboard_fab2_lib.baseboard_fab2(sch_1):fm_10gbe_lom_disable_n"
				( attribute "CDS_PHYS_NET_NAME" "FM_10GBE_LOM_DISABLE_N"
					( Origin gPackager )
				)
				( objectStatus "FM_10GBE_LOM_DISABLE_N" )
			)
			( signal "@baseboard_fab2_lib.baseboard_fab2(sch_1):fm_1gb_lom_disable_n"
				( attribute "CDS_PHYS_NET_NAME" "FM_1GB_LOM_DISABLE_N"
					( Origin gPackager )
				)
				( objectStatus "FM_1GB_LOM_DISABLE_N" )
			)
			( signal "@baseboard_fab2_lib.baseboard_fab2(sch_1):fm_battery_sense_en_n"
				( attribute "CDS_PHYS_NET_NAME" "FM_BATTERY_SENSE_EN_N"
					( Origin gPackager )
				)
				( attribute "PHYS_NET_NAME" "FM_BATTERY_SENSE_EN_N"
					( Origin gPackager )
				)
				( objectStatus "FM_BATTERY_SENSE_EN_N" )
			)
			( signal "@baseboard_fab2_lib.baseboard_fab2(sch_1):fm_bmc_cpld_mp_rst_n"
				( alias ( signalRef "@baseboard_fab2_lib.baseboard_fab2(sch_1):page147_fm_bmc_cpld_mp_rst_n") )
				( attribute "CDS_PHYS_NET_NAME" "FM_BMC_CPLD_MP_RST_N"
					( Origin gPackager )
				)
				( attribute "PHYS_NET_NAME" "FM_BMC_CPLD_MP_RST_N"
					( Origin gPackager )
				)
				( objectStatus "FM_BMC_CPLD_MP_RST_N" )
			)
			( signal "@baseboard_fab2_lib.baseboard_fab2(sch_1):page147_fm_bmc_cpld_mp_rst_n"
				( attribute "CDS_PHYS_NET_NAME" "FM_BMC_CPLD_MP_RST_N"
					( Origin gPackager )
				)
				( objectFlag fObjectAlias )
				( objectStatus "page147_fm_bmc_cpld_mp_rst_n" )
			)
			( signal "@baseboard_fab2_lib.baseboard_fab2(sch_1):page148_p1v2_aux_bmc"
				( objectFlag fObjectAlias )
				( objectStatus "page148_p1v2_aux_bmc" )
			)
			( signal "@baseboard_fab2_lib.baseboard_fab2(sch_1):fm_gbe_lom_disable_n"
				( attribute "CDS_PHYS_NET_NAME" "FM_GBE_LOM_DISABLE_N"
					( Origin gPackager )
				)
				( objectStatus "FM_GBE_LOM_DISABLE_N" )
			)
			( signal "@baseboard_fab2_lib.baseboard_fab2(sch_1):fm_pch_lvc1_thermtrip_n"
				( attribute "CDS_PHYS_NET_NAME" "FM_PCH_LVC1_THERMTRIP_N"
					( Origin gPackager )
				)
				( objectStatus "FM_PCH_LVC1_THERMTRIP_N" )
			)
			( signal "@baseboard_fab2_lib.baseboard_fab2(sch_1):fm_pch_pwrbtn_n"
				( attribute "CDS_PHYS_NET_NAME" "FM_PCH_PWRBTN_N"
					( Origin gPackager )
				)
				( objectStatus "FM_PCH_PWRBTN_N" )
			)
			( signal "@baseboard_fab2_lib.baseboard_fab2(sch_1):fm_slp_sus_n"
				( attribute "CDS_PHYS_NET_NAME" "FM_SLP_SUS_N"
					( Origin gPackager )
				)
				( objectStatus "FM_SLP_SUS_N" )
			)
			( signal "@baseboard_fab2_lib.baseboard_fab2(sch_1):fm_slps3_n"
				( attribute "CDS_PHYS_NET_NAME" "FM_SLPS3_N"
					( Origin gPackager )
				)
				( objectStatus "FM_SLPS3_N" )
			)
			( signal "@baseboard_fab2_lib.baseboard_fab2(sch_1):fm_slps4_n"
				( attribute "CDS_PHYS_NET_NAME" "FM_SLPS4_N"
					( Origin gPackager )
				)
				( objectStatus "FM_SLPS4_N" )
			)
			( signal "@baseboard_fab2_lib.baseboard_fab2(sch_1):h_pm_sync1_gtl_r"
				( attribute "CDS_PHYS_NET_NAME" "H_PM_SYNC1_GTL_R"
					( Origin gPackager )
				)
				( objectStatus "H_PM_SYNC1_GTL_R" )
			)
			( signal "@baseboard_fab2_lib.baseboard_fab2(sch_1):irq_lvc3_wake_n"
				( attribute "CDS_PHYS_NET_NAME" "IRQ_LVC3_WAKE_N"
					( Origin gPackager )
				)
				( objectStatus "IRQ_LVC3_WAKE_N" )
			)
			( signal "@baseboard_fab2_lib.baseboard_fab2(sch_1):irq_sml1_pmbus_alert_n"
				( attribute "CDS_PHYS_NET_NAME" "IRQ_SML1_PMBUS_ALERT_N"
					( Origin gPackager )
				)
				( attribute "PHYS_NET_NAME" "IRQ_SML1_PMBUS_ALERT_N"
					( Origin gPackager )
				)
				( objectStatus "IRQ_SML1_PMBUS_ALERT_N" )
			)
			( signal "@baseboard_fab2_lib.baseboard_fab2(sch_1):kr_p0_ocp_rx_c_dn"
				( attribute "CDS_PHYS_NET_NAME" "KR_P0_OCP_RX_C_DN"
					( Origin gPackager )
				)
				( objectStatus "KR_P0_OCP_RX_C_DN" )
			)
			( signal "@baseboard_fab2_lib.baseboard_fab2(sch_1):kr_p0_ocp_rx_c_dp"
				( attribute "CDS_PHYS_NET_NAME" "KR_P0_OCP_RX_C_DP"
					( Origin gPackager )
				)
				( objectStatus "KR_P0_OCP_RX_C_DP" )
			)
			( signal "@baseboard_fab2_lib.baseboard_fab2(sch_1):kr_p0_ocp_tx_dn"
				( attribute "CDS_PHYS_NET_NAME" "KR_P0_OCP_TX_DN"
					( Origin gPackager )
				)
				( objectStatus "KR_P0_OCP_TX_DN" )
			)
			( signal "@baseboard_fab2_lib.baseboard_fab2(sch_1):kr_p0_ocp_tx_dp"
				( attribute "CDS_PHYS_NET_NAME" "KR_P0_OCP_TX_DP"
					( Origin gPackager )
				)
				( objectStatus "KR_P0_OCP_TX_DP" )
			)
			( signal "@baseboard_fab2_lib.baseboard_fab2(sch_1):p1v05_pch_stby_kr_pll"
				( alias ( signalRef "@baseboard_fab2_lib.baseboard_fab2(sch_1):page118_p1v05_pch_stby_kr_pll") )
				( alias ( signalRef "@baseboard_fab2_lib.baseboard_fab2(sch_1):page122_p1v05_pch_stby_kr_pll") )
				( alias ( signalRef "@baseboard_fab2_lib.baseboard_fab2(sch_1):page127_p1v05_pch_stby_kr_pll") )
				( attribute "VOLTAGE" "1.05V"
					( Units "uVoltage" "V" 1.000000)
					( Status sAliasFlattened )
					( Origin gFrontEnd )
				)
				( attribute "CDS_PHYS_NET_NAME" "P1V05_PCH_STBY_KR_PLL"
					( Origin gPackager )
				)
				( objectStatus "P1V05_PCH_STBY_KR_PLL" )
			)
			( signal "@baseboard_fab2_lib.baseboard_fab2(sch_1):page118_p1v05_pch_stby_kr_pll"
				( attribute "VOLTAGE" "1.05V"
					( Units "uVoltage" "V" 1.000000)
					( Origin gFrontEnd )
				)
				( objectFlag fObjectAlias )
				( objectStatus "page118_p1v05_pch_stby_kr_pll" )
			)
			( signal "@baseboard_fab2_lib.baseboard_fab2(sch_1):page122_p1v05_pch_stby_kr_pll"
				( attribute "VOLTAGE" "1.05V"
					( Units "uVoltage" "V" 1.000000)
					( Origin gFrontEnd )
				)
				( objectFlag fObjectAlias )
				( objectStatus "page122_p1v05_pch_stby_kr_pll" )
			)
			( signal "@baseboard_fab2_lib.baseboard_fab2(sch_1):page127_p1v05_pch_stby_kr_pll"
				( attribute "VOLTAGE" "1.05V"
					( Units "uVoltage" "V" 1.000000)
					( Origin gFrontEnd )
				)
				( objectFlag fObjectAlias )
				( objectStatus "page127_p1v05_pch_stby_kr_pll" )
			)
			( signal "@baseboard_fab2_lib.baseboard_fab2(sch_1):peci_pch"
				( attribute "CDS_PHYS_NET_NAME" "PECI_PCH"
					( Origin gPackager )
				)
				( objectStatus "PECI_PCH" )
			)
			( signal "@baseboard_fab2_lib.baseboard_fab2(sch_1):pwrgd_dsw_pwrok"
				( attribute "CDS_PHYS_NET_NAME" "PWRGD_DSW_PWROK"
					( Origin gPackager )
				)
				( objectStatus "PWRGD_DSW_PWROK" )
			)
			( signal "@baseboard_fab2_lib.baseboard_fab2(sch_1):pwrgd_pch_pwrok"
				( alias ( signalRef "@baseboard_fab2_lib.baseboard_fab2(sch_1):page144_pwrgd_pch_pwrok") )
				( attribute "CDS_PHYS_NET_NAME" "PWRGD_PCH_PWROK"
					( Origin gPackager )
				)
				( attribute "PHYS_NET_NAME" "PWRGD_PCH_PWROK"
					( Origin gPackager )
				)
				( objectStatus "PWRGD_PCH_PWROK" )
			)
			( signal "@baseboard_fab2_lib.baseboard_fab2(sch_1):page144_pwrgd_pch_pwrok"
				( attribute "PHYS_NET_NAME" "H_CPU0_FAST_WAKE_LVT3_N"
					( Origin gFrontEnd )
				)
				( objectFlag fObjectAlias )
				( objectStatus "page144_pwrgd_pch_pwrok" )
			)
			( signal "@baseboard_fab2_lib.baseboard_fab2(sch_1):pwrgd_pvccio_cpu0"
				( attribute "CDS_PHYS_NET_NAME" "PWRGD_PVCCIO_CPU0"
					( Origin gPackager )
				)
				( objectStatus "PWRGD_PVCCIO_CPU0" )
			)
			( signal "@baseboard_fab2_lib.baseboard_fab2(sch_1):pwrgd_sys_pwrok"
				( attribute "CDS_PHYS_NET_NAME" "PWRGD_SYS_PWROK"
					( Origin gPackager )
				)
				( attribute "PHYS_NET_NAME" "PWRGD_SYS_PWROK"
					( Origin gPackager )
				)
				( objectStatus "PWRGD_SYS_PWROK" )
			)
			( signal "@baseboard_fab2_lib.baseboard_fab2(sch_1):rst_bmc_srst_n"
				( attribute "CDS_PHYS_NET_NAME" "RST_BMC_SRST_N"
					( Origin gPackager )
				)
				( attribute "PHYS_NET_NAME" "RST_BMC_SRST_N"
					( Origin gPackager )
				)
				( objectStatus "RST_BMC_SRST_N" )
			)
			( signal "@baseboard_fab2_lib.baseboard_fab2(sch_1):rst_bmc_srst_r_n"
				( attribute "CDS_PHYS_NET_NAME" "RST_BMC_SRST_R_N"
					( Origin gPackager )
				)
				( objectStatus "RST_BMC_SRST_R_N" )
			)
			( signal "@baseboard_fab2_lib.baseboard_fab2(sch_1):rst_bmc_sysrst_btn_out_b_n"
				( attribute "CDS_PHYS_NET_NAME" "RST_BMC_SYSRST_BTN_OUT_B_N"
					( Origin gPackager )
				)
				( objectStatus "RST_BMC_SYSRST_BTN_OUT_B_N" )
			)
			( signal "@baseboard_fab2_lib.baseboard_fab2(sch_1):tp_10gbe_kr0_mon_dn"
				( attribute "CDS_PHYS_NET_NAME" "TP_10GBE_KR0_MON_DN"
					( Origin gPackager )
				)
				( objectStatus "TP_10GBE_KR0_MON_DN" )
			)
			( signal "@baseboard_fab2_lib.baseboard_fab2(sch_1):tp_10gbe_kr0_mon_dp"
				( attribute "CDS_PHYS_NET_NAME" "TP_10GBE_KR0_MON_DP"
					( Origin gPackager )
				)
				( objectStatus "TP_10GBE_KR0_MON_DP" )
			)
			( signal "@baseboard_fab2_lib.baseboard_fab2(sch_1):tp_10gbe_kr1_mon_dn"
				( attribute "CDS_PHYS_NET_NAME" "TP_10GBE_KR1_MON_DN"
					( Origin gPackager )
				)
				( objectStatus "TP_10GBE_KR1_MON_DN" )
			)
			( signal "@baseboard_fab2_lib.baseboard_fab2(sch_1):tp_10gbe_kr1_mon_dp"
				( attribute "CDS_PHYS_NET_NAME" "TP_10GBE_KR1_MON_DP"
					( Origin gPackager )
				)
				( objectStatus "TP_10GBE_KR1_MON_DP" )
			)
			( signal "@baseboard_fab2_lib.baseboard_fab2(sch_1):tp_cpu_pch_trigger_in"
				( attribute "CDS_PHYS_NET_NAME" "TP_CPU_PCH_TRIGGER_IN"
					( Origin gPackager )
				)
				( objectStatus "TP_CPU_PCH_TRIGGER_IN" )
			)
			( signal "@baseboard_fab2_lib.baseboard_fab2(sch_1):tp_cpu_pch_trigger_out"
				( attribute "CDS_PHYS_NET_NAME" "TP_CPU_PCH_TRIGGER_OUT"
					( Origin gPackager )
				)
				( objectStatus "TP_CPU_PCH_TRIGGER_OUT" )
			)
			( signal "@baseboard_fab2_lib.baseboard_fab2(sch_1):tp_pch_rsvd32"
				( attribute "CDS_PHYS_NET_NAME" "TP_PCH_RSVD32"
					( Origin gPackager )
				)
				( objectStatus "TP_PCH_RSVD32" )
			)
			( signal "@baseboard_fab2_lib.baseboard_fab2(sch_1):tp_pch_rsvd33"
				( attribute "CDS_PHYS_NET_NAME" "TP_PCH_RSVD33"
					( Origin gPackager )
				)
				( objectStatus "TP_PCH_RSVD33" )
			)
			( signal "@baseboard_fab2_lib.baseboard_fab2(sch_1):tp_pch_rsvd34"
				( attribute "CDS_PHYS_NET_NAME" "TP_PCH_RSVD34"
					( Origin gPackager )
				)
				( objectStatus "TP_PCH_RSVD34" )
			)
			( signal "@baseboard_fab2_lib.baseboard_fab2(sch_1):tp_pch_rsvd35"
				( attribute "CDS_PHYS_NET_NAME" "TP_PCH_RSVD35"
					( Origin gPackager )
				)
				( objectStatus "TP_PCH_RSVD35" )
			)
			( signal "@baseboard_fab2_lib.baseboard_fab2(sch_1):tp_pch_rsvd36"
				( attribute "CDS_PHYS_NET_NAME" "TP_PCH_RSVD36"
					( Origin gPackager )
				)
				( objectStatus "TP_PCH_RSVD36" )
			)
			( signal "@baseboard_fab2_lib.baseboard_fab2(sch_1):tp_pch_rsvd38"
				( attribute "CDS_PHYS_NET_NAME" "TP_PCH_RSVD38"
					( Origin gPackager )
				)
				( objectStatus "TP_PCH_RSVD38" )
			)
			( signal "@baseboard_fab2_lib.baseboard_fab2(sch_1):tp_pch_rsvd41"
				( attribute "CDS_PHYS_NET_NAME" "TP_PCH_RSVD41"
					( Origin gPackager )
				)
				( objectStatus "TP_PCH_RSVD41" )
			)
			( signal "@baseboard_fab2_lib.baseboard_fab2(sch_1):tp_pch_rsvd42"
				( attribute "CDS_PHYS_NET_NAME" "TP_PCH_RSVD42"
					( Origin gPackager )
				)
				( objectStatus "TP_PCH_RSVD42" )
			)
			( signal "@baseboard_fab2_lib.baseboard_fab2(sch_1):tp_pch_rsvd54"
				( attribute "CDS_PHYS_NET_NAME" "TP_PCH_RSVD54"
					( Origin gPackager )
				)
				( objectStatus "TP_PCH_RSVD54" )
			)
			( signal "@baseboard_fab2_lib.baseboard_fab2(sch_1):tp_slp_lan_n"
				( attribute "CDS_PHYS_NET_NAME" "TP_SLP_LAN_N"
					( Origin gPackager )
				)
				( objectStatus "TP_SLP_LAN_N" )
			)
			( signal "@baseboard_fab2_lib.baseboard_fab2(sch_1):fm_board_rev_id2"
				( attribute "CDS_PHYS_NET_NAME" "FM_BOARD_REV_ID2"
					( Origin gPackager )
				)
				( attribute "PHYS_NET_NAME" "FM_BOARD_REV_ID2"
					( Origin gPackager )
				)
				( objectStatus "FM_BOARD_REV_ID2" )
			)
			( signal "@baseboard_fab2_lib.baseboard_fab2(sch_1):p3v3_stby_bmc_adcvrefp"
				( alias ( signalRef "@baseboard_fab2_lib.baseboard_fab2(sch_1):page147_p3v3_stby_bmc_adcvrefp") )
				( attribute "CDS_PHYS_NET_NAME" "P3V3_STBY_BMC_ADCVREFP"
					( Origin gPackager )
				)
				( attribute "VOLTAGE" "+3.3V"
					( Units "uVoltage" "V" 1.000000)
					( Status sAliasFlattened )
					( Origin gFrontEnd )
				)
				( objectStatus "P3V3_STBY_BMC_ADCVREFP" )
			)
			( signal "@baseboard_fab2_lib.baseboard_fab2(sch_1):rmii_bmc_ocp_rxd1"
				( attribute "CDS_PHYS_NET_NAME" "RMII_BMC_OCP_RXD1"
					( Origin gPackager )
				)
				( attribute "PHYS_NET_NAME" "RMII_BMC_OCP_RXD1"
					( Origin gPackager )
				)
				( objectStatus "RMII_BMC_OCP_RXD1" )
			)
			( signal "@baseboard_fab2_lib.baseboard_fab2(sch_1):xtal_kr_25m_in"
				( attribute "CDS_PHYS_NET_NAME" "XTAL_KR_25M_IN"
					( Origin gPackager )
				)
				( objectStatus "XTAL_KR_25M_IN" )
			)
			( signal "@baseboard_fab2_lib.baseboard_fab2(sch_1):fm_cpld_bmc_pwrdn_n"
				( alias ( signalRef "@baseboard_fab2_lib.baseboard_fab2(sch_1):page145_fm_cpld_bmc_pwrdn_n") )
				( attribute "CDS_PHYS_NET_NAME" "FM_CPLD_BMC_PWRDN_N"
					( Origin gPackager )
				)
				( objectStatus "FM_CPLD_BMC_PWRDN_N" )
			)
			( signal "@baseboard_fab2_lib.baseboard_fab2(sch_1):nic_mdi_sprv_rj45_1_r_dn"
				( attribute "CDS_PHYS_NET_NAME" "NIC_MDI_SPRV_RJ45_1_R_DN"
					( Origin gPackager )
				)
				( objectStatus "NIC_MDI_SPRV_RJ45_1_R_DN" )
			)
			( signal "@baseboard_fab2_lib.baseboard_fab2(sch_1):fm_heartbeat_led"
				( attribute "CDS_PHYS_NET_NAME" "FM_HEARTBEAT_LED"
					( Origin gPackager )
				)
				( objectStatus "FM_HEARTBEAT_LED" )
			)
			( signal "@baseboard_fab2_lib.baseboard_fab2(sch_1):a_p3v3_stby_scaled"
				( alias ( signalRef "@baseboard_fab2_lib.baseboard_fab2(sch_1):page169_a_p3v3_stby_scaled") )
				( attribute "CDS_PHYS_NET_NAME" "A_P3V3_STBY_SCALED"
					( Origin gPackager )
				)
				( attribute "PHYS_NET_NAME" "A_P3V3_STBY_SCALED"
					( Origin gPackager )
				)
				( attribute "VOLTAGE" "+1.8V"
					( Units "uVoltage" "V" 1.000000)
					( Status sAliasFlattened )
					( Origin gFrontEnd )
				)
				( objectStatus "A_P3V3_STBY_SCALED" )
			)
			( signal "@baseboard_fab2_lib.baseboard_fab2(sch_1):page169_a_p3v3_stby_scaled"
				( attribute "VOLTAGE" "+1.8V"
					( Units "uVoltage" "V" 1.000000)
					( Origin gFrontEnd )
				)
				( objectFlag fObjectAlias )
				( objectStatus "page169_a_p3v3_stby_scaled" )
			)
			( signal "@baseboard_fab2_lib.baseboard_fab2(sch_1):xtal_kr_25m_out"
				( attribute "CDS_PHYS_NET_NAME" "XTAL_KR_25M_OUT"
					( Origin gPackager )
				)
				( objectStatus "XTAL_KR_25M_OUT" )
			)
			( signal "@baseboard_fab2_lib.baseboard_fab2(sch_1):fm_board_rev_id1"
				( attribute "CDS_PHYS_NET_NAME" "FM_BOARD_REV_ID1"
					( Origin gPackager )
				)
				( attribute "PHYS_NET_NAME" "FM_BOARD_REV_ID1"
					( Origin gPackager )
				)
				( objectStatus "FM_BOARD_REV_ID1" )
			)
			( signal "@baseboard_fab2_lib.baseboard_fab2(sch_1):fm_board_rev_id0"
				( attribute "CDS_PHYS_NET_NAME" "FM_BOARD_REV_ID0"
					( Origin gPackager )
				)
				( attribute "PHYS_NET_NAME" "FM_BOARD_REV_ID0"
					( Origin gPackager )
				)
				( objectStatus "FM_BOARD_REV_ID0" )
			)
			( signal "@baseboard_fab2_lib.baseboard_fab2(sch_1):fm_cpu1_rc_en"
				( attribute "CDS_PHYS_NET_NAME" "FM_CPU1_RC_EN"
					( Origin gPackager )
				)
				( objectStatus "FM_CPU1_RC_EN" )
			)
			( signal "@baseboard_fab2_lib.baseboard_fab2(sch_1):page149_vcc_dacav3v3"
				( objectFlag fObjectAlias )
				( objectStatus "page149_vcc_dacav3v3" )
			)
			( signal "@baseboard_fab2_lib.baseboard_fab2(sch_1):a_pvnn_stby_pch_sensor"
				( alias ( signalRef "@baseboard_fab2_lib.baseboard_fab2(sch_1):page169_a_pvnn_stby_pch_sensor") )
				( attribute "CDS_PHYS_NET_NAME" "A_PVNN_STBY_PCH_SENSOR"
					( Origin gPackager )
				)
				( attribute "PHYS_NET_NAME" "A_PVNN_STBY_PCH_SENSOR"
					( Origin gPackager )
				)
				( attribute "VOLTAGE" "+1.2V"
					( Units "uVoltage" "V" 1.000000)
					( Status sAliasFlattened )
					( Origin gFrontEnd )
				)
				( objectStatus "A_PVNN_STBY_PCH_SENSOR" )
			)
			( signal "@baseboard_fab2_lib.baseboard_fab2(sch_1):page169_a_pvnn_stby_pch_sensor"
				( attribute "VOLTAGE" "+1.2V"
					( Units "uVoltage" "V" 1.000000)
					( Origin gFrontEnd )
				)
				( objectFlag fObjectAlias )
				( objectStatus "page169_a_pvnn_stby_pch_sensor" )
			)
			( signal "@baseboard_fab2_lib.baseboard_fab2(sch_1):clk_24m_bmc_lpc"
				( attribute "CDS_PHYS_NET_NAME" "CLK_24M_BMC_LPC"
					( Origin gPackager )
				)
				( objectStatus "CLK_24M_BMC_LPC" )
			)
			( signal "@baseboard_fab2_lib.baseboard_fab2(sch_1):fm_bb_bmc_mp_gpio"
				( attribute "CDS_PHYS_NET_NAME" "FM_BB_BMC_MP_GPIO"
					( Origin gPackager )
				)
				( attribute "PHYS_NET_NAME" "FM_BB_BMC_MP_GPIO"
					( Origin gPackager )
				)
				( objectStatus "FM_BB_BMC_MP_GPIO" )
			)
			( signal "@baseboard_fab2_lib.baseboard_fab2(sch_1):fm_bios_post_cmplt_n"
				( attribute "CDS_PHYS_NET_NAME" "FM_BIOS_POST_CMPLT_N"
					( Origin gPackager )
				)
				( attribute "PHYS_NET_NAME" "FM_BIOS_POST_CMPLT_N"
					( Origin gPackager )
				)
				( objectStatus "FM_BIOS_POST_CMPLT_N" )
			)
			( signal "@baseboard_fab2_lib.baseboard_fab2(sch_1):fm_bios_prefrb2_good"
				( attribute "CDS_PHYS_NET_NAME" "FM_BIOS_PREFRB2_GOOD"
					( Origin gPackager )
				)
				( attribute "PHYS_NET_NAME" "FM_BIOS_PREFRB2_GOOD"
					( Origin gPackager )
				)
				( objectStatus "FM_BIOS_PREFRB2_GOOD" )
			)
			( signal "@baseboard_fab2_lib.baseboard_fab2(sch_1):sgpio_bmc_dout_r"
				( attribute "CDS_PHYS_NET_NAME" "SGPIO_BMC_DOUT_R"
					( Origin gPackager )
				)
				( objectStatus "SGPIO_BMC_DOUT_R" )
			)
			( signal "@baseboard_fab2_lib.baseboard_fab2(sch_1):fm_bios_top_swap_spkr"
				( attribute "CDS_PHYS_NET_NAME" "FM_BIOS_TOP_SWAP_SPKR"
					( Origin gPackager )
				)
				( objectStatus "FM_BIOS_TOP_SWAP_SPKR" )
			)
			( signal "@baseboard_fab2_lib.baseboard_fab2(sch_1):lpc_lad2_io2_r"
				( attribute "CDS_PHYS_NET_NAME" "LPC_LAD2_IO2_R"
					( Origin gPackager )
				)
				( objectStatus "LPC_LAD2_IO2_R" )
			)
			( signal "@baseboard_fab2_lib.baseboard_fab2(sch_1):fm_bmc_cpld_gpo"
				( alias ( signalRef "@baseboard_fab2_lib.baseboard_fab2(sch_1):page146_fm_bmc_cpld_gpo") )
				( attribute "CDS_PHYS_NET_NAME" "FM_BMC_CPLD_GPO"
					( Origin gPackager )
				)
				( objectStatus "FM_BMC_CPLD_GPO" )
			)
			( signal "@baseboard_fab2_lib.baseboard_fab2(sch_1):vcc_d_3v3"
				( alias ( signalRef "@baseboard_fab2_lib.baseboard_fab2(sch_1):page148_vcc_d_3v3") )
				( alias ( signalRef "@baseboard_fab2_lib.baseboard_fab2(sch_1):page149_vcc_d_3v3") )
				( attribute "CDS_PHYS_NET_NAME" "VCC_D_3V3"
					( Origin gPackager )
				)
				( objectStatus "VCC_D_3V3" )
			)
			( signal "@baseboard_fab2_lib.baseboard_fab2(sch_1):page148_vcc_d_3v3"
				( objectFlag fObjectAlias )
				( objectStatus "page148_vcc_d_3v3" )
			)
			( signal "@baseboard_fab2_lib.baseboard_fab2(sch_1):page149_vcc_d_3v3"
				( objectFlag fObjectAlias )
				( objectStatus "page149_vcc_d_3v3" )
			)
			( signal "@baseboard_fab2_lib.baseboard_fab2(sch_1):lpc_lframe_n_cs0_r_n"
				( attribute "CDS_PHYS_NET_NAME" "LPC_LFRAME_N_CS0_R_N"
					( Origin gPackager )
				)
				( objectStatus "LPC_LFRAME_N_CS0_R_N" )
			)
			( signal "@baseboard_fab2_lib.baseboard_fab2(sch_1):rmii_bmc_ocp_txd1"
				( attribute "CDS_PHYS_NET_NAME" "RMII_BMC_OCP_TXD1"
					( Origin gPackager )
				)
				( objectStatus "RMII_BMC_OCP_TXD1" )
			)
			( signal "@baseboard_fab2_lib.baseboard_fab2(sch_1):fm_bmc_enable_n"
				( attribute "CDS_PHYS_NET_NAME" "FM_BMC_ENABLE_N"
					( Origin gPackager )
				)
				( objectStatus "FM_BMC_ENABLE_N" )
			)
			( signal "@baseboard_fab2_lib.baseboard_fab2(sch_1):bmc_m_odt"
				( attribute "CDS_PHYS_NET_NAME" "BMC_M_ODT"
					( Origin gPackager )
				)
				( objectStatus "BMC_M_ODT" )
			)
			( signal "@baseboard_fab2_lib.baseboard_fab2(sch_1):fm_bmc_heartbeat_n"
				( attribute "CDS_PHYS_NET_NAME" "FM_BMC_HEARTBEAT_N"
					( Origin gPackager )
				)
				( objectStatus "FM_BMC_HEARTBEAT_N" )
			)
			( signal "@baseboard_fab2_lib.baseboard_fab2(sch_1):fm_cpu0_thermtrip_latch_lvt3_n"
				( attribute "CDS_PHYS_NET_NAME" "FM_CPU0_THERMTRIP_LATCH_LVT3_N"
					( Origin gPackager )
				)
				( objectStatus "FM_CPU0_THERMTRIP_LATCH_LVT3_N" )
			)
			( signal "@baseboard_fab2_lib.baseboard_fab2(sch_1):fm_cpu_bmc_init"
				( attribute "CDS_PHYS_NET_NAME" "FM_CPU_BMC_INIT"
					( Origin gPackager )
				)
				( objectStatus "FM_CPU_BMC_INIT" )
			)
			( signal "@baseboard_fab2_lib.baseboard_fab2(sch_1):fm_cpu_caterr_dly_lvt3_n"
				( attribute "CDS_PHYS_NET_NAME" "FM_CPU_CATERR_DLY_LVT3_N"
					( Origin gPackager )
				)
				( objectStatus "FM_CPU_CATERR_DLY_LVT3_N" )
			)
			( signal "@baseboard_fab2_lib.baseboard_fab2(sch_1):fm_cpu_caterr_dly_lvt3_r_n"
				( attribute "CDS_PHYS_NET_NAME" "FM_CPU_CATERR_DLY_LVT3_R_N"
					( Origin gPackager )
				)
				( objectStatus "FM_CPU_CATERR_DLY_LVT3_R_N" )
			)
			( signal "@baseboard_fab2_lib.baseboard_fab2(sch_1):fm_fast_prochot_en_n"
				( alias ( signalRef "@baseboard_fab2_lib.baseboard_fab2(sch_1):page147_fm_fast_prochot_en_n") )
				( attribute "CDS_PHYS_NET_NAME" "FM_FAST_PROCHOT_EN_N"
					( Origin gPackager )
				)
				( objectStatus "FM_FAST_PROCHOT_EN_N" )
			)
			( signal "@baseboard_fab2_lib.baseboard_fab2(sch_1):fm_global_rst_warn_n"
				( attribute "CDS_PHYS_NET_NAME" "FM_GLOBAL_RST_WARN_N"
					( Origin gPackager )
				)
				( objectStatus "FM_GLOBAL_RST_WARN_N" )
			)
			( signal "@baseboard_fab2_lib.baseboard_fab2(sch_1):fm_mb_slot_id0"
				( attribute "PHYS_NET_NAME" "FM_MB_SLOT_ID0"
					( Origin gPackager )
				)
				( attribute "CDS_PHYS_NET_NAME" "FM_MB_SLOT_ID0"
					( Origin gPackager )
				)
				( objectStatus "FM_MB_SLOT_ID0" )
			)
			( signal "@baseboard_fab2_lib.baseboard_fab2(sch_1):smb_pch_mezz_lom3_sda"
				( attribute "CDS_PHYS_NET_NAME" "SMB_PCH_MEZZ_LOM3_SDA"
					( Origin gPackager )
				)
				( objectStatus "SMB_PCH_MEZZ_LOM3_SDA" )
			)
			( signal "@baseboard_fab2_lib.baseboard_fab2(sch_1):fm_mb_slot_id1"
				( attribute "PHYS_NET_NAME" "FM_MB_SLOT_ID1"
					( Origin gPackager )
				)
				( attribute "CDS_PHYS_NET_NAME" "FM_MB_SLOT_ID1"
					( Origin gPackager )
				)
				( objectStatus "FM_MB_SLOT_ID1" )
			)
			( signal "@baseboard_fab2_lib.baseboard_fab2(sch_1):smb_pch_mezz_lom1_scl"
				( attribute "CDS_PHYS_NET_NAME" "SMB_PCH_MEZZ_LOM1_SCL"
					( Origin gPackager )
				)
				( objectStatus "SMB_PCH_MEZZ_LOM1_SCL" )
			)
			( signal "@baseboard_fab2_lib.baseboard_fab2(sch_1):smb_pch_mezz_lom3_scl"
				( attribute "CDS_PHYS_NET_NAME" "SMB_PCH_MEZZ_LOM3_SCL"
					( Origin gPackager )
				)
				( objectStatus "SMB_PCH_MEZZ_LOM3_SCL" )
			)
			( signal "@baseboard_fab2_lib.baseboard_fab2(sch_1):pd_smb_m2_en"
				( attribute "CDS_PHYS_NET_NAME" "PD_SMB_M2_EN"
					( Origin gPackager )
				)
				( objectStatus "PD_SMB_M2_EN" )
			)
			( signal "@baseboard_fab2_lib.baseboard_fab2(sch_1):smb_vr_stby_lvc3_sda_r1"
				( attribute "CDS_PHYS_NET_NAME" "SMB_VR_STBY_LVC3_SDA_R1"
					( Origin gPackager )
				)
				( objectStatus "SMB_VR_STBY_LVC3_SDA_R1" )
			)
			( signal "@baseboard_fab2_lib.baseboard_fab2(sch_1):smb_vr_stby_lvc3_scl_r1"
				( attribute "CDS_PHYS_NET_NAME" "SMB_VR_STBY_LVC3_SCL_R1"
					( Origin gPackager )
				)
				( objectStatus "SMB_VR_STBY_LVC3_SCL_R1" )
			)
			( signal "@baseboard_fab2_lib.baseboard_fab2(sch_1):fm_mb_slot_id2"
				( attribute "PHYS_NET_NAME" "FM_MB_SLOT_ID2"
					( Origin gPackager )
				)
				( attribute "CDS_PHYS_NET_NAME" "FM_MB_SLOT_ID2"
					( Origin gPackager )
				)
				( objectStatus "FM_MB_SLOT_ID2" )
			)
			( signal "@baseboard_fab2_lib.baseboard_fab2(sch_1):bmc_debug_en_n"
				( attribute "CDS_PHYS_NET_NAME" "BMC_DEBUG_EN_N"
					( Origin gPackager )
				)
				( objectStatus "BMC_DEBUG_EN_N" )
			)
			( signal "@baseboard_fab2_lib.baseboard_fab2(sch_1):fm_me_recover_n"
				( attribute "CDS_PHYS_NET_NAME" "FM_ME_RECOVER_N"
					( Origin gPackager )
				)
				( objectStatus "FM_ME_RECOVER_N" )
			)
			( signal "@baseboard_fab2_lib.baseboard_fab2(sch_1):fm_ocp_mezza_pres_n"
				( alias ( signalRef "@baseboard_fab2_lib.baseboard_fab2(sch_1):page250_fm_ocp_mezza_pres_n") )
				( attribute "PHYS_NET_NAME" "FM_OCP_MEZZA_PRES_N"
					( Origin gPackager )
				)
				( attribute "CDS_PHYS_NET_NAME" "FM_OCP_MEZZA_PRES_N"
					( Origin gPackager )
				)
				( objectStatus "FM_OCP_MEZZA_PRES_N" )
			)
			( signal "@baseboard_fab2_lib.baseboard_fab2(sch_1):page250_fm_ocp_mezza_pres_n"
				( attribute "CDS_PHYS_NET_NAME" "FM_OCP_MEZZA_PRES_N"
					( Origin gPackager )
				)
				( objectFlag fObjectAlias )
				( objectStatus "page250_fm_ocp_mezza_pres_n" )
			)
			( signal "@baseboard_fab2_lib.baseboard_fab2(sch_1):page250_fm_ocp_mezzb_pres_n"
				( attribute "CDS_PHYS_NET_NAME" "FM_OCP_MEZZB_PRES_N"
					( Origin gPackager )
				)
				( objectFlag fObjectAlias )
				( objectStatus "page250_fm_ocp_mezzb_pres_n" )
			)
			( signal "@baseboard_fab2_lib.baseboard_fab2(sch_1):fm_ocp_mezza_pres"
				( attribute "CDS_PHYS_NET_NAME" "FM_OCP_MEZZA_PRES"
					( Origin gPackager )
				)
				( objectStatus "FM_OCP_MEZZA_PRES" )
			)
			( signal "@baseboard_fab2_lib.baseboard_fab2(sch_1):fm_password_clear_n"
				( attribute "CDS_PHYS_NET_NAME" "FM_PASSWORD_CLEAR_N"
					( Origin gPackager )
				)
				( objectStatus "FM_PASSWORD_CLEAR_N" )
			)
			( signal "@baseboard_fab2_lib.baseboard_fab2(sch_1):fm_pch_bmc_thermtrip_exi_strap_n"
				( attribute "CDS_PHYS_NET_NAME" "FM_PCH_BMC_THERMTRIP_EXI_STRAP_"
					( Origin gPackager )
				)
				( attribute "PNN" "FM_PCH_BMC_THERMTRIP_EXI_STRAP_"
					( Origin gPackager )
				)
				( objectStatus "FM_PCH_BMC_THERMTRIP_EXI_STRAP_" )
			)
			( signal "@baseboard_fab2_lib.baseboard_fab2(sch_1):fm_pch_pld_data"
				( attribute "CDS_PHYS_NET_NAME" "FM_PCH_PLD_DATA"
					( Origin gPackager )
				)
				( objectStatus "FM_PCH_PLD_DATA" )
			)
			( signal "@baseboard_fab2_lib.baseboard_fab2(sch_1):fm_pch_pld_data_r"
				( attribute "CDS_PHYS_NET_NAME" "FM_PCH_PLD_DATA_R"
					( Origin gPackager )
				)
				( objectStatus "FM_PCH_PLD_DATA_R" )
			)
			( signal "@baseboard_fab2_lib.baseboard_fab2(sch_1):fm_pch_pwrbtn_out_n"
				( attribute "CDS_PHYS_NET_NAME" "FM_PCH_PWRBTN_OUT_N"
					( Origin gPackager )
				)
				( objectStatus "FM_PCH_PWRBTN_OUT_N" )
			)
			( signal "@baseboard_fab2_lib.baseboard_fab2(sch_1):fm_pch_sata_raid_key"
				( attribute "CDS_PHYS_NET_NAME" "FM_PCH_SATA_RAID_KEY"
					( Origin gPackager )
				)
				( objectStatus "FM_PCH_SATA_RAID_KEY" )
			)
			( signal "@baseboard_fab2_lib.baseboard_fab2(sch_1):fm_pmbus_alert_buf_en_n"
				( attribute "CDS_PHYS_NET_NAME" "FM_PMBUS_ALERT_BUF_EN_N"
					( Origin gPackager )
				)
				( attribute "PHYS_NET_NAME" "FM_PMBUS_ALERT_BUF_EN_N"
					( Origin gPackager )
				)
				( objectStatus "FM_PMBUS_ALERT_BUF_EN_N" )
			)
			( signal "@baseboard_fab2_lib.baseboard_fab2(sch_1):fm_post_card_pres_bmc_n"
				( alias ( signalRef "@baseboard_fab2_lib.baseboard_fab2(sch_1):page146_fm_post_card_pres_bmc_n") )
				( attribute "CDS_PHYS_NET_NAME" "FM_POST_CARD_PRES_BMC_N"
					( Origin gPackager )
				)
				( objectStatus "FM_POST_CARD_PRES_BMC_N" )
			)
			( signal "@baseboard_fab2_lib.baseboard_fab2(sch_1):page146_fm_post_card_pres_bmc_n"
				( attribute "CDS_PHYS_NET_NAME" "FM_POST_CARD_PRES_BMC_N"
					( Origin gPackager )
				)
				( objectFlag fObjectAlias )
				( objectStatus "page146_fm_post_card_pres_bmc_n" )
			)
			( signal "@baseboard_fab2_lib.baseboard_fab2(sch_1):fm_pwr_btn_n"
				( attribute "CDS_PHYS_NET_NAME" "FM_PWR_BTN_N"
					( Origin gPackager )
				)
				( attribute "PHYS_NET_NAME" "FM_PWR_BTN_N"
					( Origin gPackager )
				)
				( objectStatus "FM_PWR_BTN_N" )
			)
			( signal "@baseboard_fab2_lib.baseboard_fab2(sch_1):fm_pwr_led"
				( attribute "CDS_PHYS_NET_NAME" "FM_PWR_LED"
					( Origin gPackager )
				)
				( objectStatus "FM_PWR_LED" )
			)
			( signal "@baseboard_fab2_lib.baseboard_fab2(sch_1):fm_pwr_led_a"
				( attribute "CDS_PHYS_NET_NAME" "FM_PWR_LED_A"
					( Origin gPackager )
				)
				( objectStatus "FM_PWR_LED_A" )
			)
			( signal "@baseboard_fab2_lib.baseboard_fab2(sch_1):fm_pwr_led_k"
				( attribute "CDS_PHYS_NET_NAME" "FM_PWR_LED_K"
					( Origin gPackager )
				)
				( objectStatus "FM_PWR_LED_K" )
			)
			( signal "@baseboard_fab2_lib.baseboard_fab2(sch_1):fm_pwr_led_n"
				( attribute "CDS_PHYS_NET_NAME" "FM_PWR_LED_N"
					( Origin gPackager )
				)
				( objectStatus "FM_PWR_LED_N" )
			)
			( signal "@baseboard_fab2_lib.baseboard_fab2(sch_1):fm_qat_en_n"
				( attribute "CDS_PHYS_NET_NAME" "FM_QAT_EN_N"
					( Origin gPackager )
				)
				( objectStatus "FM_QAT_EN_N" )
			)
			( signal "@baseboard_fab2_lib.baseboard_fab2(sch_1):fm_slt_cfg2_r"
				( attribute "CDS_PHYS_NET_NAME" "FM_SLT_CFG2_R"
					( Origin gPackager )
				)
				( objectStatus "FM_SLT_CFG2_R" )
			)
			( signal "@baseboard_fab2_lib.baseboard_fab2(sch_1):fm_pe_bmc_wake_n"
				( attribute "CDS_PHYS_NET_NAME" "FM_PE_BMC_WAKE_N"
					( Origin gPackager )
				)
				( objectStatus "FM_PE_BMC_WAKE_N" )
			)
			( signal "@baseboard_fab2_lib.baseboard_fab2(sch_1):nic_mdi_sprv_rj45_3_r_dp"
				( attribute "CDS_PHYS_NET_NAME" "NIC_MDI_SPRV_RJ45_3_R_DP"
					( Origin gPackager )
				)
				( objectStatus "NIC_MDI_SPRV_RJ45_3_R_DP" )
			)
			( signal "@baseboard_fab2_lib.baseboard_fab2(sch_1):fm_xrc_ready_n"
				( attribute "CDS_PHYS_NET_NAME" "FM_XRC_READY_N"
					( Origin gPackager )
				)
				( attribute "PHYS_NET_NAME" "FM_XRC_READY_N"
					( Origin gPackager )
				)
				( objectStatus "FM_XRC_READY_N" )
			)
			( signal "@baseboard_fab2_lib.baseboard_fab2(sch_1):sgpio_bmc_ld_n"
				( attribute "CDS_PHYS_NET_NAME" "SGPIO_BMC_LD_N"
					( Origin gPackager )
				)
				( objectStatus "SGPIO_BMC_LD_N" )
			)
			( signal "@baseboard_fab2_lib.baseboard_fab2(sch_1):smb_lan_stby_lvc3_sda_r"
				( alias ( signalRef "@baseboard_fab2_lib.baseboard_fab2(sch_1):page144_smb_lan_stby_lvc3_sda_r") )
				( attribute "CDS_PHYS_NET_NAME" "SMB_LAN_STBY_LVC3_SDA_R"
					( Origin gPackager )
				)
				( objectStatus "SMB_LAN_STBY_LVC3_SDA_R" )
			)
			( signal "@baseboard_fab2_lib.baseboard_fab2(sch_1):page144_smb_lan_stby_lvc3_sda_r"
				( attribute "PHYS_NET_NAME" "H_CPU0_FAST_WAKE_LVT3_N"
					( Origin gFrontEnd )
				)
				( objectFlag fObjectAlias )
				( objectStatus "page144_smb_lan_stby_lvc3_sda_r" )
			)
			( signal "@baseboard_fab2_lib.baseboard_fab2(sch_1):page144_smb_lan_stby_lvc3_scl_r"
				( attribute "PHYS_NET_NAME" "H_CPU0_FAST_WAKE_LVT3_N"
					( Origin gFrontEnd )
				)
				( objectFlag fObjectAlias )
				( objectStatus "page144_smb_lan_stby_lvc3_scl_r" )
			)
			( signal "@baseboard_fab2_lib.baseboard_fab2(sch_1):fm_uart_pres_n"
				( attribute "CDS_PHYS_NET_NAME" "FM_UART_PRES_N"
					( Origin gPackager )
				)
				( objectStatus "FM_UART_PRES_N" )
			)
			( signal "@baseboard_fab2_lib.baseboard_fab2(sch_1):p1v2_aux_bmc"
				( alias ( signalRef "@baseboard_fab2_lib.baseboard_fab2(sch_1):page239_p1v2_aux_bmc") )
				( alias ( signalRef "@baseboard_fab2_lib.baseboard_fab2(sch_1):page148_p1v2_aux_bmc") )
				( alias ( signalRef "@baseboard_fab2_lib.baseboard_fab2(sch_1):page149_p1v2_aux_bmc") )
				( alias ( signalRef "@baseboard_fab2_lib.baseboard_fab2(sch_1):page151_p1v2_aux_bmc") )
				( attribute "PHYS_NET_NAME" "P1V2_AUX_BMC"
					( Origin gPackager )
				)
				( attribute "CDS_PHYS_NET_NAME" "P1V2_AUX_BMC"
					( Origin gPackager )
				)
				( attribute "VOLTAGE" "1.5"
					( Units "uVoltage" "V" 1.000000)
					( Status sAliasFlattened )
					( Origin gFrontEnd )
				)
				( objectStatus "P1V2_AUX_BMC" )
			)
			( signal "@baseboard_fab2_lib.baseboard_fab2(sch_1):page239_p1v2_aux_bmc"
				( attribute "VOLTAGE" "1.5"
					( Units "uVoltage" "V" 1.000000)
					( Origin gFrontEnd )
				)
				( objectFlag fObjectAlias )
				( objectStatus "page239_p1v2_aux_bmc" )
			)
			( signal "@baseboard_fab2_lib.baseboard_fab2(sch_1):page151_p1v2_aux_bmc"
				( objectFlag fObjectAlias )
				( objectStatus "page151_p1v2_aux_bmc" )
			)
			( signal "@baseboard_fab2_lib.baseboard_fab2(sch_1):fm_usb_p0_en_boot_bios_strap_n"
				( attribute "CDS_PHYS_NET_NAME" "FM_USB_P0_EN_BOOT_BIOS_STRAP_N"
					( Origin gPackager )
				)
				( objectStatus "FM_USB_P0_EN_BOOT_BIOS_STRAP_N" )
			)
			( signal "@baseboard_fab2_lib.baseboard_fab2(sch_1):bmc_mioz"
				( attribute "CDS_PHYS_NET_NAME" "BMC_MIOZ"
					( Origin gPackager )
				)
				( objectStatus "BMC_MIOZ" )
			)
			( signal "@baseboard_fab2_lib.baseboard_fab2(sch_1):fm_uv_adr_trigger_en"
				( alias ( signalRef "@baseboard_fab2_lib.baseboard_fab2(sch_1):page144_fm_uv_adr_trigger_en") )
				( attribute "CDS_PHYS_NET_NAME" "FM_UV_ADR_TRIGGER_EN"
					( Origin gPackager )
				)
				( attribute "PHYS_NET_NAME" "FM_UV_ADR_TRIGGER_EN"
					( Origin gPackager )
				)
				( objectStatus "FM_UV_ADR_TRIGGER_EN" )
			)
			( signal "@baseboard_fab2_lib.baseboard_fab2(sch_1):page144_fm_uv_adr_trigger_en"
				( attribute "CDS_PHYS_NET_NAME" "FM_UV_ADR_TRIGGER_EN"
					( Origin gPackager )
				)
				( objectFlag fObjectAlias )
				( objectStatus "page144_fm_uv_adr_trigger_en" )
			)
			( signal "@baseboard_fab2_lib.baseboard_fab2(sch_1):fm_xrc_present_n"
				( attribute "CDS_PHYS_NET_NAME" "FM_XRC_PRESENT_N"
					( Origin gPackager )
				)
				( attribute "PHYS_NET_NAME" "FM_XRC_PRESENT_N"
					( Origin gPackager )
				)
				( objectStatus "FM_XRC_PRESENT_N" )
			)
			( signal "@baseboard_fab2_lib.baseboard_fab2(sch_1):fp_nmi_btn_n"
				( attribute "CDS_PHYS_NET_NAME" "FP_NMI_BTN_N"
					( Origin gPackager )
				)
				( attribute "PHYS_NET_NAME" "FP_NMI_BTN_N"
					( Origin gPackager )
				)
				( objectStatus "FP_NMI_BTN_N" )
			)
			( signal "@baseboard_fab2_lib.baseboard_fab2(sch_1):h_cpu0_fast_wake_lvt3_n"
				( alias ( signalRef "@baseboard_fab2_lib.baseboard_fab2(sch_1):page144_h_cpu0_fast_wake_lvt3_n") )
				( attribute "CDS_PHYS_NET_NAME" "H_CPU0_FAST_WAKE_LVT3_N"
					( Origin gPackager )
				)
				( objectStatus "H_CPU0_FAST_WAKE_LVT3_N" )
			)
			( signal "@baseboard_fab2_lib.baseboard_fab2(sch_1):page144_h_cpu0_fast_wake_lvt3_n"
				( attribute "CDS_PHYS_NET_NAME" "H_CPU0_FAST_WAKE_LVT3_N"
					( Origin gPackager )
				)
				( attribute "PHYS_NET_NAME" "H_CPU0_FAST_WAKE_LVT3_N"
					( Origin gFrontEnd )
				)
				( objectFlag fObjectAlias )
				( objectStatus "page144_h_cpu0_fast_wake_lvt3_n" )
			)
			( signal "@baseboard_fab2_lib.baseboard_fab2(sch_1):page144_smb_slotx24_stby_lvc3_scl_r"
				( attribute "CDS_PHYS_NET_NAME" "SMB_SLOTX24_STBY_LVC3_SCL_R"
					( Origin gPackager )
				)
				( objectFlag fObjectAlias )
				( objectStatus "page144_smb_slotx24_stby_lvc3_scl_r" )
			)
			( signal "@baseboard_fab2_lib.baseboard_fab2(sch_1):irq_bmc_pch_nmi_stby_r_n"
				( attribute "CDS_PHYS_NET_NAME" "IRQ_BMC_PCH_NMI_STBY_R_N"
					( Origin gPackager )
				)
				( objectStatus "IRQ_BMC_PCH_NMI_STBY_R_N" )
			)
			( signal "@baseboard_fab2_lib.baseboard_fab2(sch_1):irq_bmc_pch_sci_lpc_n"
				( attribute "CDS_PHYS_NET_NAME" "IRQ_BMC_PCH_SCI_LPC_N"
					( Origin gPackager )
				)
				( attribute "PHYS_NET_NAME" "IRQ_BMC_PCH_SCI_LPC_N"
					( Origin gPackager )
				)
				( objectStatus "IRQ_BMC_PCH_SCI_LPC_N" )
			)
			( signal "@baseboard_fab2_lib.baseboard_fab2(sch_1):irq_bmc_pch_smi_lpc_n"
				( attribute "CDS_PHYS_NET_NAME" "IRQ_BMC_PCH_SMI_LPC_N"
					( Origin gPackager )
				)
				( attribute "PHYS_NET_NAME" "IRQ_BMC_PCH_SMI_LPC_N"
					( Origin gPackager )
				)
				( objectStatus "IRQ_BMC_PCH_SMI_LPC_N" )
			)
			( signal "@baseboard_fab2_lib.baseboard_fab2(sch_1):irq_force_nm_throttle_n"
				( alias ( signalRef "@baseboard_fab2_lib.baseboard_fab2(sch_1):page145_irq_force_nm_throttle_n") )
				( attribute "CDS_PHYS_NET_NAME" "IRQ_FORCE_NM_THROTTLE_N"
					( Origin gPackager )
				)
				( objectStatus "IRQ_FORCE_NM_THROTTLE_N" )
			)
			( signal "@baseboard_fab2_lib.baseboard_fab2(sch_1):page145_irq_force_nm_throttle_n"
				( attribute "CDS_PHYS_NET_NAME" "IRQ_FORCE_NM_THROTTLE_N"
					( Origin gPackager )
				)
				( objectFlag fObjectAlias )
				( objectStatus "page145_irq_force_nm_throttle_n" )
			)
			( signal "@baseboard_fab2_lib.baseboard_fab2(sch_1):irq_hsc_fault_n"
				( alias ( signalRef "@baseboard_fab2_lib.baseboard_fab2(sch_1):page146_irq_hsc_fault_n") )
				( attribute "CDS_PHYS_NET_NAME" "IRQ_HSC_FAULT_N"
					( Origin gPackager )
				)
				( objectStatus "IRQ_HSC_FAULT_N" )
			)
			( signal "@baseboard_fab2_lib.baseboard_fab2(sch_1):page146_irq_hsc_fault_n"
				( attribute "CDS_PHYS_NET_NAME" "IRQ_HSC_FAULT_N"
					( Origin gPackager )
				)
				( attribute "PHYS_NET_NAME" "IRQ_HSC_FAULT_N"
					( Origin gFrontEnd )
				)
				( objectFlag fObjectAlias )
				( objectStatus "page146_irq_hsc_fault_n" )
			)
			( signal "@baseboard_fab2_lib.baseboard_fab2(sch_1):irq_lom_alert_n"
				( attribute "CDS_PHYS_NET_NAME" "IRQ_LOM_ALERT_N"
					( Origin gPackager )
				)
				( attribute "PHYS_NET_NAME" "IRQ_LOM_ALERT_N"
					( Origin gPackager )
				)
				( objectStatus "IRQ_LOM_ALERT_N" )
			)
			( signal "@baseboard_fab2_lib.baseboard_fab2(sch_1):fm_bmc_onctl_r_n"
				( attribute "CDS_PHYS_NET_NAME" "FM_BMC_ONCTL_R_N"
					( Origin gPackager )
				)
				( objectStatus "FM_BMC_ONCTL_R_N" )
			)
			( signal "@baseboard_fab2_lib.baseboard_fab2(sch_1):irq_lpc_serirq_n"
				( attribute "CDS_PHYS_NET_NAME" "IRQ_LPC_SERIRQ_N"
					( Origin gPackager )
				)
				( objectStatus "IRQ_LPC_SERIRQ_N" )
			)
			( signal "@baseboard_fab2_lib.baseboard_fab2(sch_1):irq_mezz_lan_alert_n"
				( alias ( signalRef "@baseboard_fab2_lib.baseboard_fab2(sch_1):page145_irq_mezz_lan_alert_n") )
				( attribute "CDS_PHYS_NET_NAME" "IRQ_MEZZ_LAN_ALERT_N"
					( Origin gPackager )
				)
				( objectStatus "IRQ_MEZZ_LAN_ALERT_N" )
			)
			( signal "@baseboard_fab2_lib.baseboard_fab2(sch_1):page145_irq_mezz_lan_alert_n"
				( attribute "CDS_PHYS_NET_NAME" "IRQ_MEZZ_LAN_ALERT_N"
					( Origin gPackager )
				)
				( attribute "PHYS_NET_NAME" "IRQ_MEZZ_LAN_ALERT_N"
					( Origin gFrontEnd )
				)
				( objectFlag fObjectAlias )
				( objectStatus "page145_irq_mezz_lan_alert_n" )
			)
			( signal "@baseboard_fab2_lib.baseboard_fab2(sch_1):irq_pch_nic_alert_n"
				( attribute "CDS_PHYS_NET_NAME" "IRQ_PCH_NIC_ALERT_N"
					( Origin gPackager )
				)
				( objectStatus "IRQ_PCH_NIC_ALERT_N" )
			)
			( signal "@baseboard_fab2_lib.baseboard_fab2(sch_1):vr_pvddq_klm_ph1_rc"
				( attribute "CDS_PHYS_NET_NAME" "VR_PVDDQ_KLM_PH1_RC"
					( Origin gPackager )
				)
				( objectStatus "VR_PVDDQ_KLM_PH1_RC" )
			)
			( signal "@baseboard_fab2_lib.baseboard_fab2(sch_1):irq_pirqa_spi_tpm_n"
				( attribute "CDS_PHYS_NET_NAME" "IRQ_PIRQA_SPI_TPM_N"
					( Origin gPackager )
				)
				( objectStatus "IRQ_PIRQA_SPI_TPM_N" )
			)
			( signal "@baseboard_fab2_lib.baseboard_fab2(sch_1):irq_sml0_alert_n"
				( attribute "CDS_PHYS_NET_NAME" "IRQ_SML0_ALERT_N"
					( Origin gPackager )
				)
				( attribute "PHYS_NET_NAME" "IRQ_SML0_ALERT_N"
					( Origin gPackager )
				)
				( objectStatus "IRQ_SML0_ALERT_N" )
			)
			( signal "@baseboard_fab2_lib.baseboard_fab2(sch_1):lpc_lad0_io0"
				( alias ( signalRef "@baseboard_fab2_lib.baseboard_fab2(sch_1):page119_lpc_lad0_io0") )
				( alias ( signalRef "@baseboard_fab2_lib.baseboard_fab2(sch_1):page119_lpc_lad_io(0)") )
				( alias ( signalRef "@baseboard_fab2_lib.baseboard_fab2(sch_1):lpc_lad_io(0)") )
				( attribute "CDS_PHYS_NET_NAME" "LPC_LAD0_IO0"
					( Origin gPackager )
				)
				( objectStatus "LPC_LAD0_IO0" )
			)
			( signal "@baseboard_fab2_lib.baseboard_fab2(sch_1):page119_lpc_lad0_io0"
				( objectFlag fObjectAlias )
				( objectStatus "page119_lpc_lad0_io0" )
			)
			( signal "@baseboard_fab2_lib.baseboard_fab2(sch_1):page119_lpc_lad_io(0)"
				( objectFlag fObjectAlias )
				( objectStatus "page119_lpc_lad_io<0>" )
			)
			( signal "@baseboard_fab2_lib.baseboard_fab2(sch_1):lpc_lad_io(0)"
				( objectFlag fObjectAlias )
				( objectStatus "lpc_lad_io<0>" )
			)
			( signal "@baseboard_fab2_lib.baseboard_fab2(sch_1):lpc_lad1_io1"
				( alias ( signalRef "@baseboard_fab2_lib.baseboard_fab2(sch_1):page119_lpc_lad1_io1") )
				( alias ( signalRef "@baseboard_fab2_lib.baseboard_fab2(sch_1):page119_lpc_lad_io(1)") )
				( alias ( signalRef "@baseboard_fab2_lib.baseboard_fab2(sch_1):lpc_lad_io(1)") )
				( attribute "CDS_PHYS_NET_NAME" "LPC_LAD1_IO1"
					( Origin gPackager )
				)
				( objectStatus "LPC_LAD1_IO1" )
			)
			( signal "@baseboard_fab2_lib.baseboard_fab2(sch_1):page119_lpc_lad1_io1"
				( objectFlag fObjectAlias )
				( objectStatus "page119_lpc_lad1_io1" )
			)
			( signal "@baseboard_fab2_lib.baseboard_fab2(sch_1):page119_lpc_lad_io(1)"
				( objectFlag fObjectAlias )
				( objectStatus "page119_lpc_lad_io<1>" )
			)
			( signal "@baseboard_fab2_lib.baseboard_fab2(sch_1):lpc_lad_io(1)"
				( objectFlag fObjectAlias )
				( objectStatus "lpc_lad_io<1>" )
			)
			( signal "@baseboard_fab2_lib.baseboard_fab2(sch_1):lpc_lad2_io2"
				( alias ( signalRef "@baseboard_fab2_lib.baseboard_fab2(sch_1):page119_lpc_lad2_io2") )
				( alias ( signalRef "@baseboard_fab2_lib.baseboard_fab2(sch_1):page119_lpc_lad_io(2)") )
				( alias ( signalRef "@baseboard_fab2_lib.baseboard_fab2(sch_1):lpc_lad_io(2)") )
				( attribute "CDS_PHYS_NET_NAME" "LPC_LAD2_IO2"
					( Origin gPackager )
				)
				( objectStatus "LPC_LAD2_IO2" )
			)
			( signal "@baseboard_fab2_lib.baseboard_fab2(sch_1):page119_lpc_lad2_io2"
				( objectFlag fObjectAlias )
				( objectStatus "page119_lpc_lad2_io2" )
			)
			( signal "@baseboard_fab2_lib.baseboard_fab2(sch_1):page119_lpc_lad_io(2)"
				( objectFlag fObjectAlias )
				( objectStatus "page119_lpc_lad_io<2>" )
			)
			( signal "@baseboard_fab2_lib.baseboard_fab2(sch_1):lpc_lad_io(2)"
				( objectFlag fObjectAlias )
				( objectStatus "lpc_lad_io<2>" )
			)
			( signal "@baseboard_fab2_lib.baseboard_fab2(sch_1):lpc_lad3_io3"
				( alias ( signalRef "@baseboard_fab2_lib.baseboard_fab2(sch_1):page119_lpc_lad3_io3") )
				( alias ( signalRef "@baseboard_fab2_lib.baseboard_fab2(sch_1):page119_lpc_lad_io(3)") )
				( alias ( signalRef "@baseboard_fab2_lib.baseboard_fab2(sch_1):lpc_lad_io(3)") )
				( attribute "CDS_PHYS_NET_NAME" "LPC_LAD3_IO3"
					( Origin gPackager )
				)
				( objectStatus "LPC_LAD3_IO3" )
			)
			( signal "@baseboard_fab2_lib.baseboard_fab2(sch_1):page119_lpc_lad3_io3"
				( objectFlag fObjectAlias )
				( objectStatus "page119_lpc_lad3_io3" )
			)
			( signal "@baseboard_fab2_lib.baseboard_fab2(sch_1):page119_lpc_lad_io(3)"
				( objectFlag fObjectAlias )
				( objectStatus "page119_lpc_lad_io<3>" )
			)
			( signal "@baseboard_fab2_lib.baseboard_fab2(sch_1):lpc_lad_io(3)"
				( objectFlag fObjectAlias )
				( objectStatus "lpc_lad_io<3>" )
			)
			( signal "@baseboard_fab2_lib.baseboard_fab2(sch_1):lpc_lframe_n_cs0_n"
				( attribute "CDS_PHYS_NET_NAME" "LPC_LFRAME_N_CS0_N"
					( Origin gPackager )
				)
				( objectStatus "LPC_LFRAME_N_CS0_N" )
			)
			( signal "@baseboard_fab2_lib.baseboard_fab2(sch_1):pu_fm_rcin_n"
				( attribute "CDS_PHYS_NET_NAME" "PU_FM_RCIN_N"
					( Origin gPackager )
				)
				( objectStatus "PU_FM_RCIN_N" )
			)
			( signal "@baseboard_fab2_lib.baseboard_fab2(sch_1):pu_irq_pch_sci_whea_n"
				( attribute "CDS_PHYS_NET_NAME" "PU_IRQ_PCH_SCI_WHEA_N"
					( Origin gPackager )
				)
				( objectStatus "PU_IRQ_PCH_SCI_WHEA_N" )
			)
			( signal "@baseboard_fab2_lib.baseboard_fab2(sch_1):pu_irq_vralert_n"
				( attribute "CDS_PHYS_NET_NAME" "PU_IRQ_VRALERT_N"
					( Origin gPackager )
				)
				( objectStatus "PU_IRQ_VRALERT_N" )
			)
			( signal "@baseboard_fab2_lib.baseboard_fab2(sch_1):pu_lpc_clkrun_n"
				( attribute "CDS_PHYS_NET_NAME" "PU_LPC_CLKRUN_N"
					( Origin gPackager )
				)
				( objectStatus "PU_LPC_CLKRUN_N" )
			)
			( signal "@baseboard_fab2_lib.baseboard_fab2(sch_1):pu_lpc_pme_n"
				( attribute "CDS_PHYS_NET_NAME" "PU_LPC_PME_N"
					( Origin gPackager )
				)
				( objectStatus "PU_LPC_PME_N" )
			)
			( signal "@baseboard_fab2_lib.baseboard_fab2(sch_1):pu_pch_tls_enable_strap"
				( attribute "CDS_PHYS_NET_NAME" "PU_PCH_TLS_ENABLE_STRAP"
					( Origin gPackager )
				)
				( objectStatus "PU_PCH_TLS_ENABLE_STRAP" )
			)
			( signal "@baseboard_fab2_lib.baseboard_fab2(sch_1):rst_pch_sysrst_btn_out_n"
				( attribute "CDS_PHYS_NET_NAME" "RST_PCH_SYSRST_BTN_OUT_N"
					( Origin gPackager )
				)
				( objectStatus "RST_PCH_SYSRST_BTN_OUT_N" )
			)
			( signal "@baseboard_fab2_lib.baseboard_fab2(sch_1):rst_pltrst_n"
				( attribute "CDS_PHYS_NET_NAME" "RST_PLTRST_N"
					( Origin gPackager )
				)
				( objectStatus "RST_PLTRST_N" )
			)
			( signal "@baseboard_fab2_lib.baseboard_fab2(sch_1):rst_system_btn_n"
				( attribute "CDS_PHYS_NET_NAME" "RST_SYSTEM_BTN_N"
					( Origin gPackager )
				)
				( attribute "PHYS_NET_NAME" "RST_SYSTEM_BTN_N"
					( Origin gPackager )
				)
				( objectStatus "RST_SYSTEM_BTN_N" )
			)
			( signal "@baseboard_fab2_lib.baseboard_fab2(sch_1):sgpio_pch_ssata_dout0"
				( attribute "CDS_PHYS_NET_NAME" "SGPIO_PCH_SSATA_DOUT0"
					( Origin gPackager )
				)
				( objectStatus "SGPIO_PCH_SSATA_DOUT0" )
			)
			( signal "@baseboard_fab2_lib.baseboard_fab2(sch_1):smb_host_stby_lvc3_scl_r1"
				( attribute "CDS_PHYS_NET_NAME" "SMB_HOST_STBY_LVC3_SCL_R1"
					( Origin gPackager )
				)
				( objectStatus "SMB_HOST_STBY_LVC3_SCL_R1" )
			)
			( signal "@baseboard_fab2_lib.baseboard_fab2(sch_1):smb_host_stby_lvc3_sda_r1"
				( attribute "CDS_PHYS_NET_NAME" "SMB_HOST_STBY_LVC3_SDA_R1"
					( Origin gPackager )
				)
				( objectStatus "SMB_HOST_STBY_LVC3_SDA_R1" )
			)
			( signal "@baseboard_fab2_lib.baseboard_fab2(sch_1):smb_pmbus_bmc_stby_lvc3_scl_r1"
				( alias ( signalRef "@baseboard_fab2_lib.baseboard_fab2(sch_1):page247_smb_pmbus_bmc_stby_lvc3_scl_r1") )
				( attribute "CDS_PHYS_NET_NAME" "SMB_PMBUS_BMC_STBY_LVC3_SCL_R1"
					( Origin gPackager )
				)
				( objectStatus "SMB_PMBUS_BMC_STBY_LVC3_SCL_R1" )
			)
			( signal "@baseboard_fab2_lib.baseboard_fab2(sch_1):page247_smb_pmbus_bmc_stby_lvc3_scl_r1"
				( attribute "CDS_PHYS_NET_NAME" "SMB_PMBUS_BMC_STBY_LVC3_SCL_R1"
					( Origin gPackager )
				)
				( objectFlag fObjectAlias )
				( objectStatus "page247_smb_pmbus_bmc_stby_lvc3_scl_r1" )
			)
			( signal "@baseboard_fab2_lib.baseboard_fab2(sch_1):smb_pmbus_bmc_stby_lvc3_sda_r1"
				( alias ( signalRef "@baseboard_fab2_lib.baseboard_fab2(sch_1):page247_smb_pmbus_bmc_stby_lvc3_sda_r1") )
				( attribute "CDS_PHYS_NET_NAME" "SMB_PMBUS_BMC_STBY_LVC3_SDA_R1"
					( Origin gPackager )
				)
				( objectStatus "SMB_PMBUS_BMC_STBY_LVC3_SDA_R1" )
			)
			( signal "@baseboard_fab2_lib.baseboard_fab2(sch_1):page247_smb_pmbus_bmc_stby_lvc3_sda_r1"
				( attribute "CDS_PHYS_NET_NAME" "SMB_PMBUS_BMC_STBY_LVC3_SDA_R1"
					( Origin gPackager )
				)
				( objectFlag fObjectAlias )
				( objectStatus "page247_smb_pmbus_bmc_stby_lvc3_sda_r1" )
			)
			( signal "@baseboard_fab2_lib.baseboard_fab2(sch_1):smb_smlink0_stby_lvc3_scl_r1"
				( attribute "CDS_PHYS_NET_NAME" "SMB_SMLINK0_STBY_LVC3_SCL_R1"
					( Origin gPackager )
				)
				( objectStatus "SMB_SMLINK0_STBY_LVC3_SCL_R1" )
			)
			( signal "@baseboard_fab2_lib.baseboard_fab2(sch_1):smb_smlink0_stby_lvc3_sda_r1"
				( attribute "CDS_PHYS_NET_NAME" "SMB_SMLINK0_STBY_LVC3_SDA_R1"
					( Origin gPackager )
				)
				( objectStatus "SMB_SMLINK0_STBY_LVC3_SDA_R1" )
			)
			( signal "@baseboard_fab2_lib.baseboard_fab2(sch_1):sp2_bmc_cm_uart_rx"
				( attribute "CDS_PHYS_NET_NAME" "SP2_BMC_CM_UART_RX"
					( Origin gPackager )
				)
				( attribute "PHYS_NET_NAME" "SP2_BMC_CM_UART_RX"
					( Origin gPackager )
				)
				( objectStatus "SP2_BMC_CM_UART_RX" )
			)
			( signal "@baseboard_fab2_lib.baseboard_fab2(sch_1):sp2_bmc_cm_uart_tx"
				( attribute "CDS_PHYS_NET_NAME" "SP2_BMC_CM_UART_TX"
					( Origin gPackager )
				)
				( attribute "PHYS_NET_NAME" "SP2_BMC_CM_UART_TX"
					( Origin gPackager )
				)
				( objectStatus "SP2_BMC_CM_UART_TX" )
			)
			( signal "@baseboard_fab2_lib.baseboard_fab2(sch_1):vid_pch_core_pvnn_aux_vid_0"
				( attribute "CDS_PHYS_NET_NAME" "VID_PCH_CORE_PVNN_AUX_VID_0"
					( Origin gPackager )
				)
				( objectStatus "VID_PCH_CORE_PVNN_AUX_VID_0" )
			)
			( signal "@baseboard_fab2_lib.baseboard_fab2(sch_1):vid_pch_core_pvnn_aux_vid_1"
				( attribute "CDS_PHYS_NET_NAME" "VID_PCH_CORE_PVNN_AUX_VID_1"
					( Origin gPackager )
				)
				( objectStatus "VID_PCH_CORE_PVNN_AUX_VID_1" )
			)
			( signal "@baseboard_fab2_lib.baseboard_fab2(sch_1):a_p3v_bat_scaled"
				( alias ( signalRef "@baseboard_fab2_lib.baseboard_fab2(sch_1):page169_a_p3v_bat_scaled") )
				( attribute "CDS_PHYS_NET_NAME" "A_P3V_BAT_SCALED"
					( Origin gPackager )
				)
				( attribute "PHYS_NET_NAME" "A_P3V_BAT_SCALED"
					( Origin gPackager )
				)
				( attribute "VOLTAGE" "+1V"
					( Units "uVoltage" "V" 1.000000)
					( Status sAliasFlattened )
					( Origin gFrontEnd )
				)
				( objectStatus "A_P3V_BAT_SCALED" )
			)
			( signal "@baseboard_fab2_lib.baseboard_fab2(sch_1):page169_a_p3v_bat_scaled"
				( attribute "VOLTAGE" "+1V"
					( Units "uVoltage" "V" 1.000000)
					( Origin gFrontEnd )
				)
				( objectFlag fObjectAlias )
				( objectStatus "page169_a_p3v_bat_scaled" )
			)
			( signal "@baseboard_fab2_lib.baseboard_fab2(sch_1):a_rcomp_3p3"
				( attribute "CDS_PHYS_NET_NAME" "A_RCOMP_3P3"
					( Origin gPackager )
				)
				( objectStatus "A_RCOMP_3P3" )
			)
			( signal "@baseboard_fab2_lib.baseboard_fab2(sch_1):a_p5v_stby_scaled"
				( alias ( signalRef "@baseboard_fab2_lib.baseboard_fab2(sch_1):page169_a_p5v_stby_scaled") )
				( attribute "CDS_PHYS_NET_NAME" "A_P5V_STBY_SCALED"
					( Origin gPackager )
				)
				( attribute "PHYS_NET_NAME" "A_P5V_STBY_SCALED"
					( Origin gPackager )
				)
				( attribute "VOLTAGE" "+2V"
					( Units "uVoltage" "V" 1.000000)
					( Status sAliasFlattened )
					( Origin gFrontEnd )
				)
				( objectStatus "A_P5V_STBY_SCALED" )
			)
			( signal "@baseboard_fab2_lib.baseboard_fab2(sch_1):page169_a_p5v_stby_scaled"
				( attribute "VOLTAGE" "+2V"
					( Units "uVoltage" "V" 1.000000)
					( Origin gFrontEnd )
				)
				( objectFlag fObjectAlias )
				( objectStatus "page169_a_p5v_stby_scaled" )
			)
			( signal "@baseboard_fab2_lib.baseboard_fab2(sch_1):a_p3v3_scaled"
				( alias ( signalRef "@baseboard_fab2_lib.baseboard_fab2(sch_1):page169_a_p3v3_scaled") )
				( attribute "CDS_PHYS_NET_NAME" "A_P3V3_SCALED"
					( Origin gPackager )
				)
				( attribute "PHYS_NET_NAME" "A_P3V3_SCALED"
					( Origin gPackager )
				)
				( attribute "VOLTAGE" "+2V"
					( Units "uVoltage" "V" 1.000000)
					( Status sAliasFlattened )
					( Origin gFrontEnd )
				)
				( objectStatus "A_P3V3_SCALED" )
			)
			( signal "@baseboard_fab2_lib.baseboard_fab2(sch_1):page169_a_p3v3_scaled"
				( attribute "VOLTAGE" "+2V"
					( Units "uVoltage" "V" 1.000000)
					( Origin gFrontEnd )
				)
				( objectFlag fObjectAlias )
				( objectStatus "page169_a_p3v3_scaled" )
			)
			( signal "@baseboard_fab2_lib.baseboard_fab2(sch_1):rmii_bmc_pch_sprngvlle_txd1_r"
				( attribute "CDS_PHYS_NET_NAME" "RMII_BMC_PCH_SPRNGVLLE_TXD1_R"
					( Origin gPackager )
				)
				( objectStatus "RMII_BMC_PCH_SPRNGVLLE_TXD1_R" )
			)
			( signal "@baseboard_fab2_lib.baseboard_fab2(sch_1):fan_tach0"
				( attribute "CDS_PHYS_NET_NAME" "FAN_TACH0"
					( Origin gPackager )
				)
				( objectStatus "FAN_TACH0" )
			)
			( signal "@baseboard_fab2_lib.baseboard_fab2(sch_1):a_p1v05_stby_pch_sensor"
				( alias ( signalRef "@baseboard_fab2_lib.baseboard_fab2(sch_1):page169_a_p1v05_stby_pch_sensor") )
				( attribute "CDS_PHYS_NET_NAME" "A_P1V05_STBY_PCH_SENSOR"
					( Origin gPackager )
				)
				( attribute "PHYS_NET_NAME" "A_P1V05_STBY_PCH_SENSOR"
					( Origin gPackager )
				)
				( attribute "VOLTAGE" "+1.2V"
					( Units "uVoltage" "V" 1.000000)
					( Status sAliasFlattened )
					( Origin gFrontEnd )
				)
				( objectStatus "A_P1V05_STBY_PCH_SENSOR" )
			)
			( signal "@baseboard_fab2_lib.baseboard_fab2(sch_1):page169_a_p1v05_stby_pch_sensor"
				( attribute "VOLTAGE" "+1.2V"
					( Units "uVoltage" "V" 1.000000)
					( Origin gFrontEnd )
				)
				( objectFlag fObjectAlias )
				( objectStatus "page169_a_p1v05_stby_pch_sensor" )
			)
			( signal "@baseboard_fab2_lib.baseboard_fab2(sch_1):spi_bmc_bt_cs_r_n"
				( attribute "CDS_PHYS_NET_NAME" "SPI_BMC_BT_CS_R_N"
					( Origin gPackager )
				)
				( objectStatus "SPI_BMC_BT_CS_R_N" )
			)
			( signal "@baseboard_fab2_lib.baseboard_fab2(sch_1):a_p12v_stby_scaled"
				( alias ( signalRef "@baseboard_fab2_lib.baseboard_fab2(sch_1):page169_a_p12v_stby_scaled") )
				( attribute "CDS_PHYS_NET_NAME" "A_P12V_STBY_SCALED"
					( Origin gPackager )
				)
				( attribute "PHYS_NET_NAME" "A_P12V_STBY_SCALED"
					( Origin gPackager )
				)
				( attribute "VOLTAGE" "+2V"
					( Units "uVoltage" "V" 1.000000)
					( Status sAliasFlattened )
					( Origin gFrontEnd )
				)
				( objectStatus "A_P12V_STBY_SCALED" )
			)
			( signal "@baseboard_fab2_lib.baseboard_fab2(sch_1):page169_a_p12v_stby_scaled"
				( attribute "VOLTAGE" "+2V"
					( Units "uVoltage" "V" 1.000000)
					( Origin gFrontEnd )
				)
				( objectFlag fObjectAlias )
				( objectStatus "page169_a_p12v_stby_scaled" )
			)
			( signal "@baseboard_fab2_lib.baseboard_fab2(sch_1):fm_bios_spi_bmc_ctrl"
				( alias ( signalRef "@baseboard_fab2_lib.baseboard_fab2(sch_1):page147_fm_bios_spi_bmc_ctrl") )
				( attribute "CDS_PHYS_NET_NAME" "FM_BIOS_SPI_BMC_CTRL"
					( Origin gPackager )
				)
				( attribute "PHYS_NET_NAME" "FM_BIOS_SPI_BMC_CTRL"
					( Origin gPackager )
				)
				( objectStatus "FM_BIOS_SPI_BMC_CTRL" )
			)
			( signal "@baseboard_fab2_lib.baseboard_fab2(sch_1):page147_fm_bios_spi_bmc_ctrl"
				( attribute "CDS_PHYS_NET_NAME" "FM_BIOS_SPI_BMC_CTRL"
					( Origin gPackager )
				)
				( objectFlag fObjectAlias )
				( objectStatus "page147_fm_bios_spi_bmc_ctrl" )
			)
			( signal "@baseboard_fab2_lib.baseboard_fab2(sch_1):rmii_bmc_ocp_txen_r"
				( attribute "CDS_PHYS_NET_NAME" "RMII_BMC_OCP_TXEN_R"
					( Origin gPackager )
				)
				( objectStatus "RMII_BMC_OCP_TXEN_R" )
			)
			( signal "@baseboard_fab2_lib.baseboard_fab2(sch_1):fan_tach1"
				( attribute "CDS_PHYS_NET_NAME" "FAN_TACH1"
					( Origin gPackager )
				)
				( objectStatus "FAN_TACH1" )
			)
			( signal "@baseboard_fab2_lib.baseboard_fab2(sch_1):pu_tpm_spi_bmc_hold_n"
				( attribute "CDS_PHYS_NET_NAME" "PU_TPM_SPI_BMC_HOLD_N"
					( Origin gPackager )
				)
				( objectStatus "PU_TPM_SPI_BMC_HOLD_N" )
			)
			( signal "@baseboard_fab2_lib.baseboard_fab2(sch_1):fan_tach2"
				( attribute "CDS_PHYS_NET_NAME" "FAN_TACH2"
					( Origin gPackager )
				)
				( objectStatus "FAN_TACH2" )
			)
			( signal "@baseboard_fab2_lib.baseboard_fab2(sch_1):spi_bmc_bt_di"
				( attribute "CDS_PHYS_NET_NAME" "SPI_BMC_BT_DI"
					( Origin gPackager )
				)
				( attribute "PHYS_NET_NAME" "SPI_BMC_BT_DI"
					( Origin gPackager )
				)
				( objectStatus "SPI_BMC_BT_DI" )
			)
			( signal "@baseboard_fab2_lib.baseboard_fab2(sch_1):rmii_bmc_ocp_rxd0"
				( attribute "CDS_PHYS_NET_NAME" "RMII_BMC_OCP_RXD0"
					( Origin gPackager )
				)
				( attribute "PHYS_NET_NAME" "RMII_BMC_OCP_RXD0"
					( Origin gPackager )
				)
				( objectStatus "RMII_BMC_OCP_RXD0" )
			)
			( signal "@baseboard_fab2_lib.baseboard_fab2(sch_1):fan_tach3"
				( attribute "CDS_PHYS_NET_NAME" "FAN_TACH3"
					( Origin gPackager )
				)
				( objectStatus "FAN_TACH3" )
			)
			( signal "@baseboard_fab2_lib.baseboard_fab2(sch_1):rmii_bmc_ocp_rxer"
				( attribute "CDS_PHYS_NET_NAME" "RMII_BMC_OCP_RXER"
					( Origin gPackager )
				)
				( attribute "PHYS_NET_NAME" "RMII_BMC_OCP_RXER"
					( Origin gPackager )
				)
				( objectStatus "RMII_BMC_OCP_RXER" )
			)
			( signal "@baseboard_fab2_lib.baseboard_fab2(sch_1):spi_bmc_bt_clk"
				( attribute "CDS_PHYS_NET_NAME" "SPI_BMC_BT_CLK"
					( Origin gPackager )
				)
				( objectStatus "SPI_BMC_BT_CLK" )
			)
			( signal "@baseboard_fab2_lib.baseboard_fab2(sch_1):rmii_bmc_ocp_txen"
				( attribute "CDS_PHYS_NET_NAME" "RMII_BMC_OCP_TXEN"
					( Origin gPackager )
				)
				( objectStatus "RMII_BMC_OCP_TXEN" )
			)
			( signal "@baseboard_fab2_lib.baseboard_fab2(sch_1):rmii_bmc_ocp_txd0"
				( attribute "CDS_PHYS_NET_NAME" "RMII_BMC_OCP_TXD0"
					( Origin gPackager )
				)
				( objectStatus "RMII_BMC_OCP_TXD0" )
			)
			( signal "@baseboard_fab2_lib.baseboard_fab2(sch_1):spi_bmc_bt_cs_n"
				( attribute "CDS_PHYS_NET_NAME" "SPI_BMC_BT_CS_N"
					( Origin gPackager )
				)
				( objectStatus "SPI_BMC_BT_CS_N" )
			)
			( signal "@baseboard_fab2_lib.baseboard_fab2(sch_1):fm_adr_complete_r1"
				( attribute "CDS_PHYS_NET_NAME" "FM_ADR_COMPLETE_R1"
					( Origin gPackager )
				)
				( objectStatus "FM_ADR_COMPLETE_R1" )
			)
			( signal "@baseboard_fab2_lib.baseboard_fab2(sch_1):p3v3_stby_bmc_adcvrefn"
				( alias ( signalRef "@baseboard_fab2_lib.baseboard_fab2(sch_1):page147_p3v3_stby_bmc_adcvrefn") )
				( attribute "CDS_PHYS_NET_NAME" "P3V3_STBY_BMC_ADCVREFN"
					( Origin gPackager )
				)
				( attribute "VOLTAGE" "+3.3V"
					( Units "uVoltage" "V" 1.000000)
					( Status sAliasFlattened )
					( Origin gFrontEnd )
				)
				( objectStatus "P3V3_STBY_BMC_ADCVREFN" )
			)
			( signal "@baseboard_fab2_lib.baseboard_fab2(sch_1):page147_p3v3_stby_bmc_adcvrefn"
				( attribute "VOLTAGE" "+3.3V"
					( Units "uVoltage" "V" 1.000000)
					( Origin gFrontEnd )
				)
				( objectFlag fObjectAlias )
				( objectStatus "page147_p3v3_stby_bmc_adcvrefn" )
			)
			( signal "@baseboard_fab2_lib.baseboard_fab2(sch_1):pd_adcrext"
				( alias ( signalRef "@baseboard_fab2_lib.baseboard_fab2(sch_1):page147_pd_adcrext") )
				( attribute "CDS_PHYS_NET_NAME" "PD_ADCREXT"
					( Origin gPackager )
				)
				( objectStatus "PD_ADCREXT" )
			)
			( signal "@baseboard_fab2_lib.baseboard_fab2(sch_1):page147_pd_adcrext"
				( attribute "CDS_PHYS_NET_NAME" "PD_ADCREXT"
					( Origin gPackager )
				)
				( objectFlag fObjectAlias )
				( objectStatus "page147_pd_adcrext" )
			)
			( signal "@baseboard_fab2_lib.baseboard_fab2(sch_1):fm_backup_bios_sel_n"
				( attribute "CDS_PHYS_NET_NAME" "FM_BACKUP_BIOS_SEL_N"
					( Origin gPackager )
				)
				( attribute "PHYS_NET_NAME" "FM_BACKUP_BIOS_SEL_N"
					( Origin gPackager )
				)
				( objectStatus "FM_BACKUP_BIOS_SEL_N" )
			)
			( signal "@baseboard_fab2_lib.baseboard_fab2(sch_1):fm_heartbeat_led_a"
				( attribute "CDS_PHYS_NET_NAME" "FM_HEARTBEAT_LED_A"
					( Origin gPackager )
				)
				( objectStatus "FM_HEARTBEAT_LED_A" )
			)
			( signal "@baseboard_fab2_lib.baseboard_fab2(sch_1):fm_bios_mrc_debug_msg_dis_n"
				( alias ( signalRef "@baseboard_fab2_lib.baseboard_fab2(sch_1):page145_fm_bios_mrc_debug_msg_dis_n") )
				( attribute "CDS_PHYS_NET_NAME" "FM_BIOS_MRC_DEBUG_MSG_DIS_N"
					( Origin gPackager )
				)
				( objectStatus "FM_BIOS_MRC_DEBUG_MSG_DIS_N" )
			)
			( signal "@baseboard_fab2_lib.baseboard_fab2(sch_1):pd_perext"
				( attribute "CDS_PHYS_NET_NAME" "PD_PEREXT"
					( Origin gPackager )
				)
				( objectStatus "PD_PEREXT" )
			)
			( signal "@baseboard_fab2_lib.baseboard_fab2(sch_1):fm_bios_smi_active_n"
				( attribute "CDS_PHYS_NET_NAME" "FM_BIOS_SMI_ACTIVE_N"
					( Origin gPackager )
				)
				( objectStatus "FM_BIOS_SMI_ACTIVE_N" )
			)
			( signal "@baseboard_fab2_lib.baseboard_fab2(sch_1):fm_bios_top_swap"
				( attribute "CDS_PHYS_NET_NAME" "FM_BIOS_TOP_SWAP"
					( Origin gPackager )
				)
				( attribute "PHYS_NET_NAME" "FM_BIOS_TOP_SWAP"
					( Origin gPackager )
				)
				( objectStatus "FM_BIOS_TOP_SWAP" )
			)
			( signal "@baseboard_fab2_lib.baseboard_fab2(sch_1):page147_vcc_adcav3v3"
				( attribute "VOLTAGE" "+3.3V"
					( Units "uVoltage" "V" 1.000000)
					( Origin gFrontEnd )
				)
				( objectFlag fObjectAlias )
				( objectStatus "page147_vcc_adcav3v3" )
			)
			( signal "@baseboard_fab2_lib.baseboard_fab2(sch_1):fm_bios_usb_recovery"
				( attribute "CDS_PHYS_NET_NAME" "FM_BIOS_USB_RECOVERY"
					( Origin gPackager )
				)
				( objectStatus "FM_BIOS_USB_RECOVERY" )
			)
			( signal "@baseboard_fab2_lib.baseboard_fab2(sch_1):fm_bmc_nmi_n"
				( attribute "CDS_PHYS_NET_NAME" "FM_BMC_NMI_N"
					( Origin gPackager )
				)
				( attribute "PHYS_NET_NAME" "FM_BMC_NMI_N"
					( Origin gPackager )
				)
				( objectStatus "FM_BMC_NMI_N" )
			)
			( signal "@baseboard_fab2_lib.baseboard_fab2(sch_1):fm_board_sku_id0"
				( attribute "CDS_PHYS_NET_NAME" "FM_BOARD_SKU_ID0"
					( Origin gPackager )
				)
				( attribute "PHYS_NET_NAME" "FM_BOARD_SKU_ID0"
					( Origin gPackager )
				)
				( objectStatus "FM_BOARD_SKU_ID0" )
			)
			( signal "@baseboard_fab2_lib.baseboard_fab2(sch_1):pca9554_a1"
				( attribute "CDS_PHYS_NET_NAME" "PCA9554_A1"
					( Origin gPackager )
				)
				( objectStatus "PCA9554_A1" )
			)
			( signal "@baseboard_fab2_lib.baseboard_fab2(sch_1):page148_vcc_dacav3v3"
				( objectFlag fObjectAlias )
				( objectStatus "page148_vcc_dacav3v3" )
			)
			( signal "@baseboard_fab2_lib.baseboard_fab2(sch_1):pca9555_a1"
				( attribute "CDS_PHYS_NET_NAME" "PCA9555_A1"
					( Origin gPackager )
				)
				( objectStatus "PCA9555_A1" )
			)
			( signal "@baseboard_fab2_lib.baseboard_fab2(sch_1):fm_board_sku_id1"
				( attribute "CDS_PHYS_NET_NAME" "FM_BOARD_SKU_ID1"
					( Origin gPackager )
				)
				( attribute "PHYS_NET_NAME" "FM_BOARD_SKU_ID1"
					( Origin gPackager )
				)
				( objectStatus "FM_BOARD_SKU_ID1" )
			)
			( signal "@baseboard_fab2_lib.baseboard_fab2(sch_1):spa_mid_dbg2_rx"
				( attribute "CDS_PHYS_NET_NAME" "SPA_MID_DBG2_RX"
					( Origin gPackager )
				)
				( objectStatus "SPA_MID_DBG2_RX" )
			)
			( signal "@baseboard_fab2_lib.baseboard_fab2(sch_1):pca9555_a2"
				( attribute "CDS_PHYS_NET_NAME" "PCA9555_A2"
					( Origin gPackager )
				)
				( objectStatus "PCA9555_A2" )
			)
			( signal "@baseboard_fab2_lib.baseboard_fab2(sch_1):fm_board_sku_id2"
				( attribute "CDS_PHYS_NET_NAME" "FM_BOARD_SKU_ID2"
					( Origin gPackager )
				)
				( attribute "PHYS_NET_NAME" "FM_BOARD_SKU_ID2"
					( Origin gPackager )
				)
				( objectStatus "FM_BOARD_SKU_ID2" )
			)
			( signal "@baseboard_fab2_lib.baseboard_fab2(sch_1):fm_board_sku_id3"
				( attribute "CDS_PHYS_NET_NAME" "FM_BOARD_SKU_ID3"
					( Origin gPackager )
				)
				( attribute "PHYS_NET_NAME" "FM_BOARD_SKU_ID3"
					( Origin gPackager )
				)
				( objectStatus "FM_BOARD_SKU_ID3" )
			)
			( signal "@baseboard_fab2_lib.baseboard_fab2(sch_1):bmc_tpm_hw_c_rst"
				( attribute "CDS_PHYS_NET_NAME" "BMC_TPM_HW_C_RST"
					( Origin gPackager )
				)
				( objectStatus "BMC_TPM_HW_C_RST" )
			)
			( signal "@baseboard_fab2_lib.baseboard_fab2(sch_1):fm_board_sku_id4"
				( attribute "CDS_PHYS_NET_NAME" "FM_BOARD_SKU_ID4"
					( Origin gPackager )
				)
				( attribute "PHYS_NET_NAME" "FM_BOARD_SKU_ID4"
					( Origin gPackager )
				)
				( objectStatus "FM_BOARD_SKU_ID4" )
			)
			( signal "@baseboard_fab2_lib.baseboard_fab2(sch_1):uv_high_set"
				( alias ( signalRef "@baseboard_fab2_lib.baseboard_fab2(sch_1):page146_uv_high_set") )
				( attribute "CDS_PHYS_NET_NAME" "UV_HIGH_SET"
					( Origin gPackager )
				)
				( objectStatus "UV_HIGH_SET" )
			)
			( signal "@baseboard_fab2_lib.baseboard_fab2(sch_1):page146_uv_high_set"
				( objectFlag fObjectAlias )
				( objectStatus "page146_uv_high_set" )
			)
			( signal "@baseboard_fab2_lib.baseboard_fab2(sch_1):fm_cpld_adr_trigger_n"
				( attribute "CDS_PHYS_NET_NAME" "FM_CPLD_ADR_TRIGGER_N"
					( Origin gPackager )
				)
				( objectStatus "FM_CPLD_ADR_TRIGGER_N" )
			)
			( signal "@baseboard_fab2_lib.baseboard_fab2(sch_1):fm_cpld_adr_trigger_r_n"
				( attribute "CDS_PHYS_NET_NAME" "FM_CPLD_ADR_TRIGGER_R_N"
					( Origin gPackager )
				)
				( objectStatus "FM_CPLD_ADR_TRIGGER_R_N" )
			)
			( signal "@baseboard_fab2_lib.baseboard_fab2(sch_1):fm_cpu0_fivr_fault_lvt3_n"
				( attribute "CDS_PHYS_NET_NAME" "FM_CPU0_FIVR_FAULT_LVT3_N"
					( Origin gPackager )
				)
				( objectStatus "FM_CPU0_FIVR_FAULT_LVT3_N" )
			)
			( signal "@baseboard_fab2_lib.baseboard_fab2(sch_1):fm_cpu0_rc_en"
				( attribute "CDS_PHYS_NET_NAME" "FM_CPU0_RC_EN"
					( Origin gPackager )
				)
				( objectStatus "FM_CPU0_RC_EN" )
			)
			( signal "@baseboard_fab2_lib.baseboard_fab2(sch_1):fm_cpu1_fivr_fault_lvt3_n"
				( attribute "CDS_PHYS_NET_NAME" "FM_CPU1_FIVR_FAULT_LVT3_N"
					( Origin gPackager )
				)
				( objectStatus "FM_CPU1_FIVR_FAULT_LVT3_N" )
			)
			( signal "@baseboard_fab2_lib.baseboard_fab2(sch_1):fm_cpu1_thermtrip_latch_lvt3_n"
				( attribute "CDS_PHYS_NET_NAME" "FM_CPU1_THERMTRIP_LATCH_LVT3_N"
					( Origin gPackager )
				)
				( objectStatus "FM_CPU1_THERMTRIP_LATCH_LVT3_N" )
			)
			( signal "@baseboard_fab2_lib.baseboard_fab2(sch_1):fm_flash_attach_cfg_strap"
				( attribute "CDS_PHYS_NET_NAME" "FM_FLASH_ATTACH_CFG_STRAP"
					( Origin gPackager )
				)
				( objectStatus "FM_FLASH_ATTACH_CFG_STRAP" )
			)
			( signal "@baseboard_fab2_lib.baseboard_fab2(sch_1):fm_force_adr_n"
				( alias ( signalRef "@baseboard_fab2_lib.baseboard_fab2(sch_1):page144_fm_force_adr_n") )
				( attribute "CDS_PHYS_NET_NAME" "FM_FORCE_ADR_N"
					( Origin gPackager )
				)
				( attribute "PHYS_NET_NAME" "FM_FORCE_ADR_N"
					( Origin gPackager )
				)
				( objectStatus "FM_FORCE_ADR_N" )
			)
			( signal "@baseboard_fab2_lib.baseboard_fab2(sch_1):page144_fm_force_adr_n"
				( attribute "CDS_PHYS_NET_NAME" "FM_FORCE_ADR_N"
					( Origin gPackager )
				)
				( attribute "PHYS_NET_NAME" "FM_FORCE_ADR_N"
					( Origin gPackager )
				)
				( objectFlag fObjectAlias )
				( objectStatus "page144_fm_force_adr_n" )
			)
			( signal "@baseboard_fab2_lib.baseboard_fab2(sch_1):fm_gbe0_lvc3_mod_abs"
				( attribute "CDS_PHYS_NET_NAME" "FM_GBE0_LVC3_MOD_ABS"
					( Origin gPackager )
				)
				( objectStatus "FM_GBE0_LVC3_MOD_ABS" )
			)
			( signal "@baseboard_fab2_lib.baseboard_fab2(sch_1):fm_gbe1_lvc3_mod_abs"
				( attribute "CDS_PHYS_NET_NAME" "FM_GBE1_LVC3_MOD_ABS"
					( Origin gPackager )
				)
				( objectStatus "FM_GBE1_LVC3_MOD_ABS" )
			)
			( signal "@baseboard_fab2_lib.baseboard_fab2(sch_1):fm_gbe2_lvc3_mod_abs"
				( attribute "CDS_PHYS_NET_NAME" "FM_GBE2_LVC3_MOD_ABS"
					( Origin gPackager )
				)
				( objectStatus "FM_GBE2_LVC3_MOD_ABS" )
			)
			( signal "@baseboard_fab2_lib.baseboard_fab2(sch_1):fm_gbe3_lvc3_mod_abs"
				( attribute "CDS_PHYS_NET_NAME" "FM_GBE3_LVC3_MOD_ABS"
					( Origin gPackager )
				)
				( objectStatus "FM_GBE3_LVC3_MOD_ABS" )
			)
			( signal "@baseboard_fab2_lib.baseboard_fab2(sch_1):smb_host_stby_lvc3_sda_r"
				( attribute "CDS_PHYS_NET_NAME" "SMB_HOST_STBY_LVC3_SDA_R"
					( Origin gPackager )
				)
				( attribute "PHYS_NET_NAME" "SMB_HOST_STBY_LVC3_SDA_R"
					( Origin gPackager )
				)
				( objectStatus "SMB_HOST_STBY_LVC3_SDA_R" )
			)
			( signal "@baseboard_fab2_lib.baseboard_fab2(sch_1):fm_hsc_timer_exp_n"
				( attribute "CDS_PHYS_NET_NAME" "FM_HSC_TIMER_EXP_N"
					( Origin gPackager )
				)
				( attribute "PHYS_NET_NAME" "FM_HSC_TIMER_EXP_N"
					( Origin gPackager )
				)
				( objectStatus "FM_HSC_TIMER_EXP_N" )
			)
			( signal "@baseboard_fab2_lib.baseboard_fab2(sch_1):smb_host_stby_lvc3_scl_r"
				( attribute "CDS_PHYS_NET_NAME" "SMB_HOST_STBY_LVC3_SCL_R"
					( Origin gPackager )
				)
				( attribute "PHYS_NET_NAME" "SMB_HOST_STBY_LVC3_SCL_R"
					( Origin gPackager )
				)
				( objectStatus "SMB_HOST_STBY_LVC3_SCL_R" )
			)
			( signal "@baseboard_fab2_lib.baseboard_fab2(sch_1):fm_ie_disable_n"
				( attribute "CDS_PHYS_NET_NAME" "FM_IE_DISABLE_N"
					( Origin gPackager )
				)
				( objectStatus "FM_IE_DISABLE_N" )
			)
			( signal "@baseboard_fab2_lib.baseboard_fab2(sch_1):smb_ocp_fru_stby_lvc3_scl_r"
				( attribute "CDS_PHYS_NET_NAME" "SMB_OCP_FRU_STBY_LVC3_SCL_R"
					( Origin gPackager )
				)
				( objectStatus "SMB_OCP_FRU_STBY_LVC3_SCL_R" )
			)
			( signal "@baseboard_fab2_lib.baseboard_fab2(sch_1):smb_ocp_lan_stby_lvc3_scl_r"
				( attribute "CDS_PHYS_NET_NAME" "SMB_OCP_LAN_STBY_LVC3_SCL_R"
					( Origin gPackager )
				)
				( objectStatus "SMB_OCP_LAN_STBY_LVC3_SCL_R" )
			)
			( signal "@baseboard_fab2_lib.baseboard_fab2(sch_1):fm_mem_therm_event_pch_n"
				( attribute "CDS_PHYS_NET_NAME" "FM_MEM_THERM_EVENT_PCH_N"
					( Origin gPackager )
				)
				( attribute "PHYS_NET_NAME" "FM_MEM_THERM_EVENT_PCH_N"
					( Origin gPackager )
				)
				( objectStatus "FM_MEM_THERM_EVENT_PCH_N" )
			)
			( signal "@baseboard_fab2_lib.baseboard_fab2(sch_1):fm_mp_ps_fail_n"
				( alias ( signalRef "@baseboard_fab2_lib.baseboard_fab2(sch_1):page144_fm_mp_ps_fail_n") )
				( attribute "CDS_PHYS_NET_NAME" "FM_MP_PS_FAIL_N"
					( Origin gPackager )
				)
				( attribute "PHYS_NET_NAME" "FM_MP_PS_FAIL_N"
					( Origin gPackager )
				)
				( objectStatus "FM_MP_PS_FAIL_N" )
			)
			( signal "@baseboard_fab2_lib.baseboard_fab2(sch_1):page144_fm_mp_ps_fail_n"
				( attribute "PHYS_NET_NAME" "H_CPU0_FAST_WAKE_LVT3_N"
					( Origin gFrontEnd )
				)
				( objectFlag fObjectAlias )
				( objectStatus "page144_fm_mp_ps_fail_n" )
			)
			( signal "@baseboard_fab2_lib.baseboard_fab2(sch_1):bmc_m_we_n"
				( attribute "CDS_PHYS_NET_NAME" "BMC_M_WE_N"
					( Origin gPackager )
				)
				( objectStatus "BMC_M_WE_N" )
			)
			( signal "@baseboard_fab2_lib.baseboard_fab2(sch_1):fm_mp_ps_redundant_lost_n"
				( attribute "CDS_PHYS_NET_NAME" "FM_MP_PS_REDUNDANT_LOST_N"
					( Origin gPackager )
				)
				( attribute "PHYS_NET_NAME" "FM_MP_PS_REDUNDANT_LOST_N"
					( Origin gPackager )
				)
				( objectStatus "FM_MP_PS_REDUNDANT_LOST_N" )
			)
			( signal "@baseboard_fab2_lib.baseboard_fab2(sch_1):fm_nmi_event_n"
				( attribute "CDS_PHYS_NET_NAME" "FM_NMI_EVENT_N"
					( Origin gPackager )
				)
				( objectStatus "FM_NMI_EVENT_N" )
			)
			( signal "@baseboard_fab2_lib.baseboard_fab2(sch_1):fm_oc0_usb_n"
				( attribute "CDS_PHYS_NET_NAME" "FM_OC0_USB_N"
					( Origin gPackager )
				)
				( objectStatus "FM_OC0_USB_N" )
			)
			( signal "@baseboard_fab2_lib.baseboard_fab2(sch_1):fm_oc_detect_en_n"
				( alias ( signalRef "@baseboard_fab2_lib.baseboard_fab2(sch_1):page145_fm_oc_detect_en_n") )
				( attribute "CDS_PHYS_NET_NAME" "FM_OC_DETECT_EN_N"
					( Origin gPackager )
				)
				( attribute "PHYS_NET_NAME" "FM_OC_DETECT_EN_N"
					( Origin gPackager )
				)
				( objectStatus "FM_OC_DETECT_EN_N" )
			)
			( signal "@baseboard_fab2_lib.baseboard_fab2(sch_1):page145_fm_oc_detect_en_n"
				( attribute "CDS_PHYS_NET_NAME" "FM_OC_DETECT_EN_N"
					( Origin gPackager )
				)
				( attribute "PHYS_NET_NAME" "FM_OC_DETECT_EN_N"
					( Origin gFrontEnd )
				)
				( objectFlag fObjectAlias )
				( objectStatus "page145_fm_oc_detect_en_n" )
			)
			( signal "@baseboard_fab2_lib.baseboard_fab2(sch_1):fm_pch_bmc_thermtrip_n"
				( attribute "CDS_PHYS_NET_NAME" "FM_PCH_BMC_THERMTRIP_N"
					( Origin gPackager )
				)
				( attribute "PHYS_NET_NAME" "FM_PCH_BMC_THERMTRIP_N"
					( Origin gPackager )
				)
				( objectStatus "FM_PCH_BMC_THERMTRIP_N" )
			)
			( signal "@baseboard_fab2_lib.baseboard_fab2(sch_1):fm_sol_uart_ch_sel"
				( alias ( signalRef "@baseboard_fab2_lib.baseboard_fab2(sch_1):page145_fm_sol_uart_ch_sel") )
				( attribute "CDS_PHYS_NET_NAME" "FM_SOL_UART_CH_SEL"
					( Origin gPackager )
				)
				( attribute "PHYS_NET_NAME" "FM_SOL_UART_CH_SEL"
					( Origin gPackager )
				)
				( objectStatus "FM_SOL_UART_CH_SEL" )
			)
			( signal "@baseboard_fab2_lib.baseboard_fab2(sch_1):page145_fm_sol_uart_ch_sel"
				( attribute "CDS_PHYS_NET_NAME" "FM_SOL_UART_CH_SEL"
					( Origin gPackager )
				)
				( objectFlag fObjectAlias )
				( objectStatus "page145_fm_sol_uart_ch_sel" )
			)
			( signal "@baseboard_fab2_lib.baseboard_fab2(sch_1):fm_ssata_pcie_m2_sel"
				( attribute "CDS_PHYS_NET_NAME" "FM_SSATA_PCIE_M2_SEL"
					( Origin gPackager )
				)
				( objectStatus "FM_SSATA_PCIE_M2_SEL" )
			)
			( signal "@baseboard_fab2_lib.baseboard_fab2(sch_1):fm_uartsw_lsb_n"
				( attribute "CDS_PHYS_NET_NAME" "FM_UARTSW_LSB_N"
					( Origin gPackager )
				)
				( attribute "PHYS_NET_NAME" "FM_UARTSW_LSB_N"
					( Origin gPackager )
				)
				( objectStatus "FM_UARTSW_LSB_N" )
			)
			( signal "@baseboard_fab2_lib.baseboard_fab2(sch_1):page144_smb_slotx24_stby_lvc3_sda_r"
				( attribute "CDS_PHYS_NET_NAME" "SMB_SLOTX24_STBY_LVC3_SDA_R"
					( Origin gPackager )
				)
				( objectFlag fObjectAlias )
				( objectStatus "page144_smb_slotx24_stby_lvc3_sda_r" )
			)
			( signal "@baseboard_fab2_lib.baseboard_fab2(sch_1):fm_uartsw_msb_n"
				( attribute "CDS_PHYS_NET_NAME" "FM_UARTSW_MSB_N"
					( Origin gPackager )
				)
				( attribute "PHYS_NET_NAME" "FM_UARTSW_MSB_N"
					( Origin gPackager )
				)
				( objectStatus "FM_UARTSW_MSB_N" )
			)
			( signal "@baseboard_fab2_lib.baseboard_fab2(sch_1):fp_pwr_id_led_n"
				( attribute "CDS_PHYS_NET_NAME" "FP_PWR_ID_LED_N"
					( Origin gPackager )
				)
				( attribute "PHYS_NET_NAME" "FP_PWR_ID_LED_N"
					( Origin gPackager )
				)
				( objectStatus "FP_PWR_ID_LED_N" )
			)
			( signal "@baseboard_fab2_lib.baseboard_fab2(sch_1):irq_bmc_pch_nmi_stby_n"
				( attribute "CDS_PHYS_NET_NAME" "IRQ_BMC_PCH_NMI_STBY_N"
					( Origin gPackager )
				)
				( attribute "PHYS_NET_NAME" "IRQ_BMC_PCH_NMI_STBY_N"
					( Origin gPackager )
				)
				( objectStatus "IRQ_BMC_PCH_NMI_STBY_N" )
			)
			( signal "@baseboard_fab2_lib.baseboard_fab2(sch_1):irq_board_bmc_alert_n"
				( alias ( signalRef "@baseboard_fab2_lib.baseboard_fab2(sch_1):page145_irq_board_bmc_alert_n") )
				( attribute "CDS_PHYS_NET_NAME" "IRQ_BOARD_BMC_ALERT_N"
					( Origin gPackager )
				)
				( attribute "PHYS_NET_NAME" "IRQ_BOARD_BMC_ALERT_N"
					( Origin gPackager )
				)
				( objectStatus "IRQ_BOARD_BMC_ALERT_N" )
			)
			( signal "@baseboard_fab2_lib.baseboard_fab2(sch_1):page145_irq_board_bmc_alert_n"
				( attribute "CDS_PHYS_NET_NAME" "IRQ_BOARD_BMC_ALERT_N"
					( Origin gPackager )
				)
				( attribute "PHYS_NET_NAME" "IRQ_BOARD_BMC_ALERT_N"
					( Origin gFrontEnd )
				)
				( objectFlag fObjectAlias )
				( objectStatus "page145_irq_board_bmc_alert_n" )
			)
			( signal "@baseboard_fab2_lib.baseboard_fab2(sch_1):irq_oc_detect_n"
				( attribute "CDS_PHYS_NET_NAME" "IRQ_OC_DETECT_N"
					( Origin gPackager )
				)
				( attribute "PHYS_NET_NAME" "IRQ_OC_DETECT_N"
					( Origin gPackager )
				)
				( objectStatus "IRQ_OC_DETECT_N" )
			)
			( signal "@baseboard_fab2_lib.baseboard_fab2(sch_1):irq_uv_detect_n"
				( attribute "CDS_PHYS_NET_NAME" "IRQ_UV_DETECT_N"
					( Origin gPackager )
				)
				( attribute "PHYS_NET_NAME" "IRQ_UV_DETECT_N"
					( Origin gPackager )
				)
				( objectStatus "IRQ_UV_DETECT_N" )
			)
			( signal "@baseboard_fab2_lib.baseboard_fab2(sch_1):jtag_pch_gbe_clk"
				( attribute "CDS_PHYS_NET_NAME" "JTAG_PCH_GBE_CLK"
					( Origin gPackager )
				)
				( objectStatus "JTAG_PCH_GBE_CLK" )
			)
			( signal "@baseboard_fab2_lib.baseboard_fab2(sch_1):jtag_pch_gbe_tdi"
				( attribute "CDS_PHYS_NET_NAME" "JTAG_PCH_GBE_TDI"
					( Origin gPackager )
				)
				( objectStatus "JTAG_PCH_GBE_TDI" )
			)
			( signal "@baseboard_fab2_lib.baseboard_fab2(sch_1):jtag_pch_gbe_tdo"
				( attribute "CDS_PHYS_NET_NAME" "JTAG_PCH_GBE_TDO"
					( Origin gPackager )
				)
				( objectStatus "JTAG_PCH_GBE_TDO" )
			)
			( signal "@baseboard_fab2_lib.baseboard_fab2(sch_1):jtag_pch_gbe_tms"
				( attribute "CDS_PHYS_NET_NAME" "JTAG_PCH_GBE_TMS"
					( Origin gPackager )
				)
				( objectStatus "JTAG_PCH_GBE_TMS" )
			)
			( signal "@baseboard_fab2_lib.baseboard_fab2(sch_1):jtag_pch_gbe_trst_n"
				( attribute "CDS_PHYS_NET_NAME" "JTAG_PCH_GBE_TRST_N"
					( Origin gPackager )
				)
				( objectStatus "JTAG_PCH_GBE_TRST_N" )
			)
			( signal "@baseboard_fab2_lib.baseboard_fab2(sch_1):jtag_pch_pld_tck"
				( attribute "CDS_PHYS_NET_NAME" "JTAG_PCH_PLD_TCK"
					( Origin gPackager )
				)
				( objectStatus "JTAG_PCH_PLD_TCK" )
			)
			( signal "@baseboard_fab2_lib.baseboard_fab2(sch_1):jtag_pch_pld_tdi"
				( attribute "CDS_PHYS_NET_NAME" "JTAG_PCH_PLD_TDI"
					( Origin gPackager )
				)
				( objectStatus "JTAG_PCH_PLD_TDI" )
			)
			( signal "@baseboard_fab2_lib.baseboard_fab2(sch_1):jtag_pch_pld_tdo"
				( attribute "CDS_PHYS_NET_NAME" "JTAG_PCH_PLD_TDO"
					( Origin gPackager )
				)
				( objectStatus "JTAG_PCH_PLD_TDO" )
			)
			( signal "@baseboard_fab2_lib.baseboard_fab2(sch_1):jtag_pch_pld_tms"
				( attribute "CDS_PHYS_NET_NAME" "JTAG_PCH_PLD_TMS"
					( Origin gPackager )
				)
				( objectStatus "JTAG_PCH_PLD_TMS" )
			)
			( signal "@baseboard_fab2_lib.baseboard_fab2(sch_1):led_gbe_p0_0"
				( attribute "CDS_PHYS_NET_NAME" "LED_GBE_P0_0"
					( Origin gPackager )
				)
				( objectStatus "LED_GBE_P0_0" )
			)
			( signal "@baseboard_fab2_lib.baseboard_fab2(sch_1):led_gbe_p0_1"
				( attribute "CDS_PHYS_NET_NAME" "LED_GBE_P0_1"
					( Origin gPackager )
				)
				( objectStatus "LED_GBE_P0_1" )
			)
			( signal "@baseboard_fab2_lib.baseboard_fab2(sch_1):led_gbe_p1_0"
				( attribute "CDS_PHYS_NET_NAME" "LED_GBE_P1_0"
					( Origin gPackager )
				)
				( objectStatus "LED_GBE_P1_0" )
			)
			( signal "@baseboard_fab2_lib.baseboard_fab2(sch_1):led_gbe_p1_1"
				( attribute "CDS_PHYS_NET_NAME" "LED_GBE_P1_1"
					( Origin gPackager )
				)
				( objectStatus "LED_GBE_P1_1" )
			)
			( signal "@baseboard_fab2_lib.baseboard_fab2(sch_1):led_gbe_p2_0"
				( attribute "CDS_PHYS_NET_NAME" "LED_GBE_P2_0"
					( Origin gPackager )
				)
				( objectStatus "LED_GBE_P2_0" )
			)
			( signal "@baseboard_fab2_lib.baseboard_fab2(sch_1):led_gbe_p2_1"
				( attribute "CDS_PHYS_NET_NAME" "LED_GBE_P2_1"
					( Origin gPackager )
				)
				( objectStatus "LED_GBE_P2_1" )
			)
			( signal "@baseboard_fab2_lib.baseboard_fab2(sch_1):led_gbe_p3_0"
				( attribute "CDS_PHYS_NET_NAME" "LED_GBE_P3_0"
					( Origin gPackager )
				)
				( objectStatus "LED_GBE_P3_0" )
			)
			( signal "@baseboard_fab2_lib.baseboard_fab2(sch_1):led_gbe_p3_1"
				( attribute "CDS_PHYS_NET_NAME" "LED_GBE_P3_1"
					( Origin gPackager )
				)
				( objectStatus "LED_GBE_P3_1" )
			)
			( signal "@baseboard_fab2_lib.baseboard_fab2(sch_1):led_pch_sata_hdd_n"
				( attribute "CDS_PHYS_NET_NAME" "LED_PCH_SATA_HDD_N"
					( Origin gPackager )
				)
				( objectStatus "LED_PCH_SATA_HDD_N" )
			)
			( signal "@baseboard_fab2_lib.baseboard_fab2(sch_1):led_pch_ssata_hdd_n"
				( attribute "CDS_PHYS_NET_NAME" "LED_PCH_SSATA_HDD_N"
					( Origin gPackager )
				)
				( objectStatus "LED_PCH_SSATA_HDD_N" )
			)
			( signal "@baseboard_fab2_lib.baseboard_fab2(sch_1):led_postcode_0"
				( attribute "CDS_PHYS_NET_NAME" "LED_POSTCODE_0"
					( Origin gPackager )
				)
				( attribute "PHYS_NET_NAME" "LED_POSTCODE_0"
					( Origin gPackager )
				)
				( objectStatus "LED_POSTCODE_0" )
			)
			( signal "@baseboard_fab2_lib.baseboard_fab2(sch_1):led_postcode_1"
				( attribute "CDS_PHYS_NET_NAME" "LED_POSTCODE_1"
					( Origin gPackager )
				)
				( attribute "PHYS_NET_NAME" "LED_POSTCODE_1"
					( Origin gPackager )
				)
				( objectStatus "LED_POSTCODE_1" )
			)
			( signal "@baseboard_fab2_lib.baseboard_fab2(sch_1):led_postcode_2"
				( attribute "CDS_PHYS_NET_NAME" "LED_POSTCODE_2"
					( Origin gPackager )
				)
				( attribute "PHYS_NET_NAME" "LED_POSTCODE_2"
					( Origin gPackager )
				)
				( objectStatus "LED_POSTCODE_2" )
			)
			( signal "@baseboard_fab2_lib.baseboard_fab2(sch_1):led_postcode_3"
				( attribute "CDS_PHYS_NET_NAME" "LED_POSTCODE_3"
					( Origin gPackager )
				)
				( attribute "PHYS_NET_NAME" "LED_POSTCODE_3"
					( Origin gPackager )
				)
				( objectStatus "LED_POSTCODE_3" )
			)
			( signal "@baseboard_fab2_lib.baseboard_fab2(sch_1):led_postcode_4"
				( attribute "CDS_PHYS_NET_NAME" "LED_POSTCODE_4"
					( Origin gPackager )
				)
				( attribute "PHYS_NET_NAME" "LED_POSTCODE_4"
					( Origin gPackager )
				)
				( objectStatus "LED_POSTCODE_4" )
			)
			( signal "@baseboard_fab2_lib.baseboard_fab2(sch_1):led_postcode_5"
				( attribute "CDS_PHYS_NET_NAME" "LED_POSTCODE_5"
					( Origin gPackager )
				)
				( attribute "PHYS_NET_NAME" "LED_POSTCODE_5"
					( Origin gPackager )
				)
				( objectStatus "LED_POSTCODE_5" )
			)
			( signal "@baseboard_fab2_lib.baseboard_fab2(sch_1):led_postcode_6"
				( attribute "CDS_PHYS_NET_NAME" "LED_POSTCODE_6"
					( Origin gPackager )
				)
				( attribute "PHYS_NET_NAME" "LED_POSTCODE_6"
					( Origin gPackager )
				)
				( objectStatus "LED_POSTCODE_6" )
			)
			( signal "@baseboard_fab2_lib.baseboard_fab2(sch_1):led_postcode_7"
				( attribute "CDS_PHYS_NET_NAME" "LED_POSTCODE_7"
					( Origin gPackager )
				)
				( attribute "PHYS_NET_NAME" "LED_POSTCODE_7"
					( Origin gPackager )
				)
				( objectStatus "LED_POSTCODE_7" )
			)
			( signal "@baseboard_fab2_lib.baseboard_fab2(sch_1):pu_10gbe_lom_pci_disable_n"
				( attribute "CDS_PHYS_NET_NAME" "PU_10GBE_LOM_PCI_DISABLE_N"
					( Origin gPackager )
				)
				( objectStatus "PU_10GBE_LOM_PCI_DISABLE_N" )
			)
			( signal "@baseboard_fab2_lib.baseboard_fab2(sch_1):pu_adr_timer_hold_off_n"
				( attribute "CDS_PHYS_NET_NAME" "PU_ADR_TIMER_HOLD_OFF_N"
					( Origin gPackager )
				)
				( objectStatus "PU_ADR_TIMER_HOLD_OFF_N" )
			)
			( signal "@baseboard_fab2_lib.baseboard_fab2(sch_1):sgpio_pch_sata_clock"
				( attribute "CDS_PHYS_NET_NAME" "SGPIO_PCH_SATA_CLOCK"
					( Origin gPackager )
				)
				( objectStatus "SGPIO_PCH_SATA_CLOCK" )
			)
			( signal "@baseboard_fab2_lib.baseboard_fab2(sch_1):sgpio_pch_sata_dout0"
				( attribute "CDS_PHYS_NET_NAME" "SGPIO_PCH_SATA_DOUT0"
					( Origin gPackager )
				)
				( objectStatus "SGPIO_PCH_SATA_DOUT0" )
			)
			( signal "@baseboard_fab2_lib.baseboard_fab2(sch_1):sgpio_pch_sata_load"
				( attribute "CDS_PHYS_NET_NAME" "SGPIO_PCH_SATA_LOAD"
					( Origin gPackager )
				)
				( objectStatus "SGPIO_PCH_SATA_LOAD" )
			)
			( signal "@baseboard_fab2_lib.baseboard_fab2(sch_1):sgpio_pch_ssata_clock"
				( attribute "CDS_PHYS_NET_NAME" "SGPIO_PCH_SSATA_CLOCK"
					( Origin gPackager )
				)
				( objectStatus "SGPIO_PCH_SSATA_CLOCK" )
			)
			( signal "@baseboard_fab2_lib.baseboard_fab2(sch_1):sgpio_pch_ssata_load"
				( attribute "CDS_PHYS_NET_NAME" "SGPIO_PCH_SSATA_LOAD"
					( Origin gPackager )
				)
				( objectStatus "SGPIO_PCH_SSATA_LOAD" )
			)
			( signal "@baseboard_fab2_lib.baseboard_fab2(sch_1):smb_lan_stby_lvc3_scl_r1"
				( attribute "CDS_PHYS_NET_NAME" "SMB_LAN_STBY_LVC3_SCL_R1"
					( Origin gPackager )
				)
				( objectStatus "SMB_LAN_STBY_LVC3_SCL_R1" )
			)
			( signal "@baseboard_fab2_lib.baseboard_fab2(sch_1):smb_lan_stby_lvc3_scl_r2"
				( attribute "CDS_PHYS_NET_NAME" "SMB_LAN_STBY_LVC3_SCL_R2"
					( Origin gPackager )
				)
				( objectStatus "SMB_LAN_STBY_LVC3_SCL_R2" )
			)
			( signal "@baseboard_fab2_lib.baseboard_fab2(sch_1):smb_lan_stby_lvc3_sda_r1"
				( attribute "CDS_PHYS_NET_NAME" "SMB_LAN_STBY_LVC3_SDA_R1"
					( Origin gPackager )
				)
				( objectStatus "SMB_LAN_STBY_LVC3_SDA_R1" )
			)
			( signal "@baseboard_fab2_lib.baseboard_fab2(sch_1):smb_lan_stby_lvc3_sda_r2"
				( attribute "CDS_PHYS_NET_NAME" "SMB_LAN_STBY_LVC3_SDA_R2"
					( Origin gPackager )
				)
				( objectStatus "SMB_LAN_STBY_LVC3_SDA_R2" )
			)
			( signal "@baseboard_fab2_lib.baseboard_fab2(sch_1):smb_pch_mezz_lom0_scl"
				( attribute "CDS_PHYS_NET_NAME" "SMB_PCH_MEZZ_LOM0_SCL"
					( Origin gPackager )
				)
				( objectStatus "SMB_PCH_MEZZ_LOM0_SCL" )
			)
			( signal "@baseboard_fab2_lib.baseboard_fab2(sch_1):smb_pch_mezz_lom0_sda"
				( attribute "CDS_PHYS_NET_NAME" "SMB_PCH_MEZZ_LOM0_SDA"
					( Origin gPackager )
				)
				( objectStatus "SMB_PCH_MEZZ_LOM0_SDA" )
			)
			( signal "@baseboard_fab2_lib.baseboard_fab2(sch_1):smb_pch_mezz_lom1_sda"
				( attribute "CDS_PHYS_NET_NAME" "SMB_PCH_MEZZ_LOM1_SDA"
					( Origin gPackager )
				)
				( objectStatus "SMB_PCH_MEZZ_LOM1_SDA" )
			)
			( signal "@baseboard_fab2_lib.baseboard_fab2(sch_1):smb_pch_mezz_lom2_scl"
				( attribute "CDS_PHYS_NET_NAME" "SMB_PCH_MEZZ_LOM2_SCL"
					( Origin gPackager )
				)
				( objectStatus "SMB_PCH_MEZZ_LOM2_SCL" )
			)
			( signal "@baseboard_fab2_lib.baseboard_fab2(sch_1):smb_pch_mezz_lom2_sda"
				( attribute "CDS_PHYS_NET_NAME" "SMB_PCH_MEZZ_LOM2_SDA"
					( Origin gPackager )
				)
				( objectStatus "SMB_PCH_MEZZ_LOM2_SDA" )
			)
			( signal "@baseboard_fab2_lib.baseboard_fab2(sch_1):tp_pch_gpp_j17"
				( attribute "CDS_PHYS_NET_NAME" "TP_PCH_GPP_J17"
					( Origin gPackager )
				)
				( objectStatus "TP_PCH_GPP_J17" )
			)
			( signal "@baseboard_fab2_lib.baseboard_fab2(sch_1):tp_pch_gpp_j19"
				( attribute "CDS_PHYS_NET_NAME" "TP_PCH_GPP_J19"
					( Origin gPackager )
				)
				( objectStatus "TP_PCH_GPP_J19" )
			)
			( signal "@baseboard_fab2_lib.baseboard_fab2(sch_1):tp_pch_gpp_j21"
				( attribute "CDS_PHYS_NET_NAME" "TP_PCH_GPP_J21"
					( Origin gPackager )
				)
				( objectStatus "TP_PCH_GPP_J21" )
			)
			( signal "@baseboard_fab2_lib.baseboard_fab2(sch_1):tp_pch_gpp_j23"
				( attribute "CDS_PHYS_NET_NAME" "TP_PCH_GPP_J23"
					( Origin gPackager )
				)
				( objectStatus "TP_PCH_GPP_J23" )
			)
			( signal "@baseboard_fab2_lib.baseboard_fab2(sch_1):a_1p8_3p3_rcomp"
				( attribute "CDS_PHYS_NET_NAME" "A_1P8_3P3_RCOMP"
					( Origin gPackager )
				)
				( objectStatus "A_1P8_3P3_RCOMP" )
			)
			( signal "@baseboard_fab2_lib.baseboard_fab2(sch_1):fm_flash_desc_override"
				( alias ( signalRef "@baseboard_fab2_lib.baseboard_fab2(sch_1):page147_fm_flash_desc_override") )
				( attribute "CDS_PHYS_NET_NAME" "FM_FLASH_DESC_OVERRIDE"
					( Origin gPackager )
				)
				( objectStatus "FM_FLASH_DESC_OVERRIDE" )
			)
			( signal "@baseboard_fab2_lib.baseboard_fab2(sch_1):page147_fm_flash_desc_override"
				( attribute "CDS_PHYS_NET_NAME" "FM_FLASH_DESC_OVERRIDE"
					( Origin gPackager )
				)
				( objectFlag fObjectAlias )
				( objectStatus "page147_fm_flash_desc_override" )
			)
			( signal "@baseboard_fab2_lib.baseboard_fab2(sch_1):fm_intruder_hdr_pch_n"
				( attribute "CDS_PHYS_NET_NAME" "FM_INTRUDER_HDR_PCH_N"
					( Origin gPackager )
				)
				( objectStatus "FM_INTRUDER_HDR_PCH_N" )
			)
			( signal "@baseboard_fab2_lib.baseboard_fab2(sch_1):fm_ocp_mezzb_pres_n"
				( alias ( signalRef "@baseboard_fab2_lib.baseboard_fab2(sch_1):page250_fm_ocp_mezzb_pres_n") )
				( attribute "CDS_PHYS_NET_NAME" "FM_OCP_MEZZB_PRES_N"
					( Origin gPackager )
				)
				( attribute "PHYS_NET_NAME" "FM_OCP_MEZZB_PRES_N"
					( Origin gPackager )
				)
				( objectStatus "FM_OCP_MEZZB_PRES_N" )
			)
			( signal "@baseboard_fab2_lib.baseboard_fab2(sch_1):fm_ocp_mezzc_pres_n"
				( alias ( signalRef "@baseboard_fab2_lib.baseboard_fab2(sch_1):page250_fm_ocp_mezzc_pres_n") )
				( attribute "CDS_PHYS_NET_NAME" "FM_OCP_MEZZC_PRES_N"
					( Origin gPackager )
				)
				( objectStatus "FM_OCP_MEZZC_PRES_N" )
			)
			( signal "@baseboard_fab2_lib.baseboard_fab2(sch_1):page250_fm_ocp_mezzc_pres_n"
				( objectFlag fObjectAlias )
				( objectStatus "page250_fm_ocp_mezzc_pres_n" )
			)
			( signal "@baseboard_fab2_lib.baseboard_fab2(sch_1):fm_pch_prsnt_n"
				( attribute "CDS_PHYS_NET_NAME" "FM_PCH_PRSNT_N"
					( Origin gPackager )
				)
				( objectStatus "FM_PCH_PRSNT_N" )
			)
			( signal "@baseboard_fab2_lib.baseboard_fab2(sch_1):fm_sint_prsnt_n"
				( attribute "CDS_PHYS_NET_NAME" "FM_SINT_PRSNT_N"
					( Origin gPackager )
				)
				( objectStatus "FM_SINT_PRSNT_N" )
			)
			( signal "@baseboard_fab2_lib.baseboard_fab2(sch_1):fm_wbg_prsnt_n"
				( attribute "CDS_PHYS_NET_NAME" "FM_WBG_PRSNT_N"
					( Origin gPackager )
				)
				( objectStatus "FM_WBG_PRSNT_N" )
			)
			( signal "@baseboard_fab2_lib.baseboard_fab2(sch_1):h_cpu0_memabc_memhot_pch_n"
				( attribute "CDS_PHYS_NET_NAME" "H_CPU0_MEMABC_MEMHOT_PCH_N"
					( Origin gPackager )
				)
				( objectStatus "H_CPU0_MEMABC_MEMHOT_PCH_N" )
			)
			( signal "@baseboard_fab2_lib.baseboard_fab2(sch_1):h_cpu0_memdef_memhot_pch_n"
				( attribute "CDS_PHYS_NET_NAME" "H_CPU0_MEMDEF_MEMHOT_PCH_N"
					( Origin gPackager )
				)
				( objectStatus "H_CPU0_MEMDEF_MEMHOT_PCH_N" )
			)
			( signal "@baseboard_fab2_lib.baseboard_fab2(sch_1):h_cpu1_memghj_memhot_pch_n"
				( attribute "CDS_PHYS_NET_NAME" "H_CPU1_MEMGHJ_MEMHOT_PCH_N"
					( Origin gPackager )
				)
				( objectStatus "H_CPU1_MEMGHJ_MEMHOT_PCH_N" )
			)
			( signal "@baseboard_fab2_lib.baseboard_fab2(sch_1):h_cpu1_memklm_memhot_pch_n"
				( attribute "CDS_PHYS_NET_NAME" "H_CPU1_MEMKLM_MEMHOT_PCH_N"
					( Origin gPackager )
				)
				( objectStatus "H_CPU1_MEMKLM_MEMHOT_PCH_N" )
			)
			( signal "@baseboard_fab2_lib.baseboard_fab2(sch_1):rmii_bmc_pch_sprngvlle_crsdv"
				( attribute "CDS_PHYS_NET_NAME" "RMII_BMC_PCH_SPRNGVLLE_CRSDV"
					( Origin gPackager )
				)
				( attribute "PHYS_NET_NAME" "RMII_BMC_PCH_SPRNGVLLE_CRSDV"
					( Origin gPackager )
				)
				( objectStatus "RMII_BMC_PCH_SPRNGVLLE_CRSDV" )
			)
			( signal "@baseboard_fab2_lib.baseboard_fab2(sch_1):rmii_bmc_pch_sprngvlle_crsdv_r1"
				( attribute "CDS_PHYS_NET_NAME" "RMII_BMC_PCH_SPRNGVLLE_CRSDV_R1"
					( Origin gPackager )
				)
				( objectStatus "RMII_BMC_PCH_SPRNGVLLE_CRSDV_R1" )
			)
			( signal "@baseboard_fab2_lib.baseboard_fab2(sch_1):rmii_bmc_pch_sprngvlle_rxer"
				( attribute "CDS_PHYS_NET_NAME" "RMII_BMC_PCH_SPRNGVLLE_RXER"
					( Origin gPackager )
				)
				( attribute "PHYS_NET_NAME" "RMII_BMC_PCH_SPRNGVLLE_RXER"
					( Origin gPackager )
				)
				( objectStatus "RMII_BMC_PCH_SPRNGVLLE_RXER" )
			)
			( signal "@baseboard_fab2_lib.baseboard_fab2(sch_1):rmii_bmc_pch_sprngvlle_rxer_r"
				( attribute "CDS_PHYS_NET_NAME" "RMII_BMC_PCH_SPRNGVLLE_RXER_R"
					( Origin gPackager )
				)
				( objectStatus "RMII_BMC_PCH_SPRNGVLLE_RXER_R" )
			)
			( signal "@baseboard_fab2_lib.baseboard_fab2(sch_1):rmii_bmc_pch_sprngvlle_txd0"
				( attribute "CDS_PHYS_NET_NAME" "RMII_BMC_PCH_SPRNGVLLE_TXD0"
					( Origin gPackager )
				)
				( objectStatus "RMII_BMC_PCH_SPRNGVLLE_TXD0" )
			)
			( signal "@baseboard_fab2_lib.baseboard_fab2(sch_1):rmii_bmc_pch_sprngvlle_txd1"
				( attribute "CDS_PHYS_NET_NAME" "RMII_BMC_PCH_SPRNGVLLE_TXD1"
					( Origin gPackager )
				)
				( objectStatus "RMII_BMC_PCH_SPRNGVLLE_TXD1" )
			)
			( signal "@baseboard_fab2_lib.baseboard_fab2(sch_1):rmii_bmc_pch_sprngvlle_txen"
				( attribute "CDS_PHYS_NET_NAME" "RMII_BMC_PCH_SPRNGVLLE_TXEN"
					( Origin gPackager )
				)
				( objectStatus "RMII_BMC_PCH_SPRNGVLLE_TXEN" )
			)
			( signal "@baseboard_fab2_lib.baseboard_fab2(sch_1):rmii_pch_sprngvlle_arb_in"
				( attribute "CDS_PHYS_NET_NAME" "RMII_PCH_SPRNGVLLE_ARB_IN"
					( Origin gPackager )
				)
				( objectStatus "RMII_PCH_SPRNGVLLE_ARB_IN" )
			)
			( signal "@baseboard_fab2_lib.baseboard_fab2(sch_1):rmii_pch_sprngvlle_arb_out"
				( attribute "CDS_PHYS_NET_NAME" "RMII_PCH_SPRNGVLLE_ARB_OUT"
					( Origin gPackager )
				)
				( objectStatus "RMII_PCH_SPRNGVLLE_ARB_OUT" )
			)
			( signal "@baseboard_fab2_lib.baseboard_fab2(sch_1):rmii_pch_sprngvlle_arb_out_r"
				( attribute "CDS_PHYS_NET_NAME" "RMII_PCH_SPRNGVLLE_ARB_OUT_R"
					( Origin gPackager )
				)
				( objectStatus "RMII_PCH_SPRNGVLLE_ARB_OUT_R" )
			)
			( signal "@baseboard_fab2_lib.baseboard_fab2(sch_1):rmii_sprngvlle_bmc_pch_rxd0"
				( attribute "CDS_PHYS_NET_NAME" "RMII_SPRNGVLLE_BMC_PCH_RXD0"
					( Origin gPackager )
				)
				( objectStatus "RMII_SPRNGVLLE_BMC_PCH_RXD0" )
			)
			( signal "@baseboard_fab2_lib.baseboard_fab2(sch_1):rmii_sprngvlle_bmc_pch_rxd0_r1"
				( attribute "CDS_PHYS_NET_NAME" "RMII_SPRNGVLLE_BMC_PCH_RXD0_R1"
					( Origin gPackager )
				)
				( objectStatus "RMII_SPRNGVLLE_BMC_PCH_RXD0_R1" )
			)
			( signal "@baseboard_fab2_lib.baseboard_fab2(sch_1):rmii_sprngvlle_bmc_pch_rxd1"
				( attribute "CDS_PHYS_NET_NAME" "RMII_SPRNGVLLE_BMC_PCH_RXD1"
					( Origin gPackager )
				)
				( objectStatus "RMII_SPRNGVLLE_BMC_PCH_RXD1" )
			)
			( signal "@baseboard_fab2_lib.baseboard_fab2(sch_1):rmii_sprngvlle_bmc_pch_rxd1_r1"
				( attribute "CDS_PHYS_NET_NAME" "RMII_SPRNGVLLE_BMC_PCH_RXD1_R1"
					( Origin gPackager )
				)
				( objectStatus "RMII_SPRNGVLLE_BMC_PCH_RXD1_R1" )
			)
			( signal "@baseboard_fab2_lib.baseboard_fab2(sch_1):rst_pcie_pch_perst_n"
				( attribute "CDS_PHYS_NET_NAME" "RST_PCIE_PCH_PERST_N"
					( Origin gPackager )
				)
				( objectStatus "RST_PCIE_PCH_PERST_N" )
			)
			( signal "@baseboard_fab2_lib.baseboard_fab2(sch_1):rst_rtcrst_n"
				( attribute "CDS_PHYS_NET_NAME" "RST_RTCRST_N"
					( Origin gPackager )
				)
				( objectStatus "RST_RTCRST_N" )
			)
			( signal "@baseboard_fab2_lib.baseboard_fab2(sch_1):rst_srtcrst_n"
				( attribute "CDS_PHYS_NET_NAME" "RST_SRTCRST_N"
					( Origin gPackager )
				)
				( objectStatus "RST_SRTCRST_N" )
			)
			( signal "@baseboard_fab2_lib.baseboard_fab2(sch_1):spi_pch_clk"
				( attribute "CDS_PHYS_NET_NAME" "SPI_PCH_CLK"
					( Origin gPackager )
				)
				( objectStatus "SPI_PCH_CLK" )
			)
			( signal "@baseboard_fab2_lib.baseboard_fab2(sch_1):spi_pch_cs0_n"
				( attribute "CDS_PHYS_NET_NAME" "SPI_PCH_CS0_N"
					( Origin gPackager )
				)
				( objectStatus "SPI_PCH_CS0_N" )
			)
			( signal "@baseboard_fab2_lib.baseboard_fab2(sch_1):spi_pch_cs0_r_n"
				( attribute "CDS_PHYS_NET_NAME" "SPI_PCH_CS0_R_N"
					( Origin gPackager )
				)
				( objectStatus "SPI_PCH_CS0_R_N" )
			)
			( signal "@baseboard_fab2_lib.baseboard_fab2(sch_1):spi_pch_io3"
				( attribute "CDS_PHYS_NET_NAME" "SPI_PCH_IO3"
					( Origin gPackager )
				)
				( objectStatus "SPI_PCH_IO3" )
			)
			( signal "@baseboard_fab2_lib.baseboard_fab2(sch_1):spi_pch_miso"
				( attribute "CDS_PHYS_NET_NAME" "SPI_PCH_MISO"
					( Origin gPackager )
				)
				( objectStatus "SPI_PCH_MISO" )
			)
			( signal "@baseboard_fab2_lib.baseboard_fab2(sch_1):spi_pch_mosi_r"
				( attribute "CDS_PHYS_NET_NAME" "SPI_PCH_MOSI_R"
					( Origin gPackager )
				)
				( objectStatus "SPI_PCH_MOSI_R" )
			)
			( signal "@baseboard_fab2_lib.baseboard_fab2(sch_1):spi_pch_tpm_cs_n"
				( attribute "CDS_PHYS_NET_NAME" "SPI_PCH_TPM_CS_N"
					( Origin gPackager )
				)
				( objectStatus "SPI_PCH_TPM_CS_N" )
			)
			( signal "@baseboard_fab2_lib.baseboard_fab2(sch_1):tp_pch_dispa_bclk"
				( attribute "CDS_PHYS_NET_NAME" "TP_PCH_DISPA_BCLK"
					( Origin gPackager )
				)
				( objectStatus "TP_PCH_DISPA_BCLK" )
			)
			( signal "@baseboard_fab2_lib.baseboard_fab2(sch_1):tp_pch_dispa_sdi"
				( attribute "CDS_PHYS_NET_NAME" "TP_PCH_DISPA_SDI"
					( Origin gPackager )
				)
				( objectStatus "TP_PCH_DISPA_SDI" )
			)
			( signal "@baseboard_fab2_lib.baseboard_fab2(sch_1):tp_pch_dispa_sdo"
				( attribute "CDS_PHYS_NET_NAME" "TP_PCH_DISPA_SDO"
					( Origin gPackager )
				)
				( objectStatus "TP_PCH_DISPA_SDO" )
			)
			( signal "@baseboard_fab2_lib.baseboard_fab2(sch_1):tp_pch_gpp_l10"
				( attribute "CDS_PHYS_NET_NAME" "TP_PCH_GPP_L10"
					( Origin gPackager )
				)
				( objectStatus "TP_PCH_GPP_L10" )
			)
			( signal "@baseboard_fab2_lib.baseboard_fab2(sch_1):tp_pch_gpp_l11"
				( attribute "CDS_PHYS_NET_NAME" "TP_PCH_GPP_L11"
					( Origin gPackager )
				)
				( objectStatus "TP_PCH_GPP_L11" )
			)
			( signal "@baseboard_fab2_lib.baseboard_fab2(sch_1):tp_pch_hda_bclk"
				( attribute "CDS_PHYS_NET_NAME" "TP_PCH_HDA_BCLK"
					( Origin gPackager )
				)
				( objectStatus "TP_PCH_HDA_BCLK" )
			)
			( signal "@baseboard_fab2_lib.baseboard_fab2(sch_1):tp_pch_hda_sdi_0"
				( attribute "CDS_PHYS_NET_NAME" "TP_PCH_HDA_SDI_0"
					( Origin gPackager )
				)
				( objectStatus "TP_PCH_HDA_SDI_0" )
			)
			( signal "@baseboard_fab2_lib.baseboard_fab2(sch_1):tp_pch_hda_sdi_1"
				( attribute "CDS_PHYS_NET_NAME" "TP_PCH_HDA_SDI_1"
					( Origin gPackager )
				)
				( objectStatus "TP_PCH_HDA_SDI_1" )
			)
			( signal "@baseboard_fab2_lib.baseboard_fab2(sch_1):tp_pch_hda_sync"
				( attribute "CDS_PHYS_NET_NAME" "TP_PCH_HDA_SYNC"
					( Origin gPackager )
				)
				( objectStatus "TP_PCH_HDA_SYNC" )
			)
			( signal "@baseboard_fab2_lib.baseboard_fab2(sch_1):tp_pch_hsa_rst_n"
				( attribute "CDS_PHYS_NET_NAME" "TP_PCH_HSA_RST_N"
					( Origin gPackager )
				)
				( objectStatus "TP_PCH_HSA_RST_N" )
			)
			( signal "@baseboard_fab2_lib.baseboard_fab2(sch_1):tp_pch_rsvd0"
				( attribute "CDS_PHYS_NET_NAME" "TP_PCH_RSVD0"
					( Origin gPackager )
				)
				( objectStatus "TP_PCH_RSVD0" )
			)
			( signal "@baseboard_fab2_lib.baseboard_fab2(sch_1):tp_pch_rsvd1"
				( attribute "CDS_PHYS_NET_NAME" "TP_PCH_RSVD1"
					( Origin gPackager )
				)
				( objectStatus "TP_PCH_RSVD1" )
			)
			( signal "@baseboard_fab2_lib.baseboard_fab2(sch_1):tp_pch_rsvd12"
				( attribute "CDS_PHYS_NET_NAME" "TP_PCH_RSVD12"
					( Origin gPackager )
				)
				( objectStatus "TP_PCH_RSVD12" )
			)
			( signal "@baseboard_fab2_lib.baseboard_fab2(sch_1):tp_pch_rsvd13"
				( attribute "CDS_PHYS_NET_NAME" "TP_PCH_RSVD13"
					( Origin gPackager )
				)
				( objectStatus "TP_PCH_RSVD13" )
			)
			( signal "@baseboard_fab2_lib.baseboard_fab2(sch_1):tp_pch_rsvd14"
				( attribute "CDS_PHYS_NET_NAME" "TP_PCH_RSVD14"
					( Origin gPackager )
				)
				( objectStatus "TP_PCH_RSVD14" )
			)
			( signal "@baseboard_fab2_lib.baseboard_fab2(sch_1):tp_pch_rsvd15"
				( attribute "CDS_PHYS_NET_NAME" "TP_PCH_RSVD15"
					( Origin gPackager )
				)
				( objectStatus "TP_PCH_RSVD15" )
			)
			( signal "@baseboard_fab2_lib.baseboard_fab2(sch_1):tp_pch_rsvd16"
				( attribute "CDS_PHYS_NET_NAME" "TP_PCH_RSVD16"
					( Origin gPackager )
				)
				( objectStatus "TP_PCH_RSVD16" )
			)
			( signal "@baseboard_fab2_lib.baseboard_fab2(sch_1):tp_pch_rsvd17"
				( attribute "CDS_PHYS_NET_NAME" "TP_PCH_RSVD17"
					( Origin gPackager )
				)
				( objectStatus "TP_PCH_RSVD17" )
			)
			( signal "@baseboard_fab2_lib.baseboard_fab2(sch_1):tp_pch_rsvd18"
				( attribute "CDS_PHYS_NET_NAME" "TP_PCH_RSVD18"
					( Origin gPackager )
				)
				( objectStatus "TP_PCH_RSVD18" )
			)
			( signal "@baseboard_fab2_lib.baseboard_fab2(sch_1):tp_pch_rsvd19"
				( attribute "CDS_PHYS_NET_NAME" "TP_PCH_RSVD19"
					( Origin gPackager )
				)
				( objectStatus "TP_PCH_RSVD19" )
			)
			( signal "@baseboard_fab2_lib.baseboard_fab2(sch_1):tp_pch_rsvd2"
				( attribute "CDS_PHYS_NET_NAME" "TP_PCH_RSVD2"
					( Origin gPackager )
				)
				( objectStatus "TP_PCH_RSVD2" )
			)
			( signal "@baseboard_fab2_lib.baseboard_fab2(sch_1):tp_pch_rsvd20"
				( attribute "CDS_PHYS_NET_NAME" "TP_PCH_RSVD20"
					( Origin gPackager )
				)
				( objectStatus "TP_PCH_RSVD20" )
			)
			( signal "@baseboard_fab2_lib.baseboard_fab2(sch_1):tp_pch_rsvd21"
				( attribute "CDS_PHYS_NET_NAME" "TP_PCH_RSVD21"
					( Origin gPackager )
				)
				( objectStatus "TP_PCH_RSVD21" )
			)
			( signal "@baseboard_fab2_lib.baseboard_fab2(sch_1):tp_pch_rsvd22"
				( attribute "CDS_PHYS_NET_NAME" "TP_PCH_RSVD22"
					( Origin gPackager )
				)
				( objectStatus "TP_PCH_RSVD22" )
			)
			( signal "@baseboard_fab2_lib.baseboard_fab2(sch_1):tp_pch_rsvd23"
				( attribute "CDS_PHYS_NET_NAME" "TP_PCH_RSVD23"
					( Origin gPackager )
				)
				( objectStatus "TP_PCH_RSVD23" )
			)
			( signal "@baseboard_fab2_lib.baseboard_fab2(sch_1):tp_pch_rsvd24"
				( attribute "CDS_PHYS_NET_NAME" "TP_PCH_RSVD24"
					( Origin gPackager )
				)
				( objectStatus "TP_PCH_RSVD24" )
			)
			( signal "@baseboard_fab2_lib.baseboard_fab2(sch_1):tp_pch_rsvd25"
				( attribute "CDS_PHYS_NET_NAME" "TP_PCH_RSVD25"
					( Origin gPackager )
				)
				( objectStatus "TP_PCH_RSVD25" )
			)
			( signal "@baseboard_fab2_lib.baseboard_fab2(sch_1):tp_pch_rsvd26"
				( attribute "CDS_PHYS_NET_NAME" "TP_PCH_RSVD26"
					( Origin gPackager )
				)
				( objectStatus "TP_PCH_RSVD26" )
			)
			( signal "@baseboard_fab2_lib.baseboard_fab2(sch_1):tp_pch_rsvd27"
				( attribute "CDS_PHYS_NET_NAME" "TP_PCH_RSVD27"
					( Origin gPackager )
				)
				( objectStatus "TP_PCH_RSVD27" )
			)
			( signal "@baseboard_fab2_lib.baseboard_fab2(sch_1):tp_pch_rsvd3"
				( attribute "CDS_PHYS_NET_NAME" "TP_PCH_RSVD3"
					( Origin gPackager )
				)
				( objectStatus "TP_PCH_RSVD3" )
			)
			( signal "@baseboard_fab2_lib.baseboard_fab2(sch_1):tp_pch_rsvd4"
				( attribute "CDS_PHYS_NET_NAME" "TP_PCH_RSVD4"
					( Origin gPackager )
				)
				( objectStatus "TP_PCH_RSVD4" )
			)
			( signal "@baseboard_fab2_lib.baseboard_fab2(sch_1):tp_pch_rsvd46"
				( attribute "CDS_PHYS_NET_NAME" "TP_PCH_RSVD46"
					( Origin gPackager )
				)
				( objectStatus "TP_PCH_RSVD46" )
			)
			( signal "@baseboard_fab2_lib.baseboard_fab2(sch_1):tp_pch_rsvd5"
				( attribute "CDS_PHYS_NET_NAME" "TP_PCH_RSVD5"
					( Origin gPackager )
				)
				( objectStatus "TP_PCH_RSVD5" )
			)
			( signal "@baseboard_fab2_lib.baseboard_fab2(sch_1):tp_pch_rsvd6"
				( attribute "CDS_PHYS_NET_NAME" "TP_PCH_RSVD6"
					( Origin gPackager )
				)
				( objectStatus "TP_PCH_RSVD6" )
			)
			( signal "@baseboard_fab2_lib.baseboard_fab2(sch_1):tp_pch_rsvd7"
				( attribute "CDS_PHYS_NET_NAME" "TP_PCH_RSVD7"
					( Origin gPackager )
				)
				( objectStatus "TP_PCH_RSVD7" )
			)
			( signal "@baseboard_fab2_lib.baseboard_fab2(sch_1):tp_pch_rsvd8"
				( attribute "CDS_PHYS_NET_NAME" "TP_PCH_RSVD8"
					( Origin gPackager )
				)
				( objectStatus "TP_PCH_RSVD8" )
			)
			( signal "@baseboard_fab2_lib.baseboard_fab2(sch_1):tp_pch_rsvd9"
				( attribute "CDS_PHYS_NET_NAME" "TP_PCH_RSVD9"
					( Origin gPackager )
				)
				( objectStatus "TP_PCH_RSVD9" )
			)
			( signal "@baseboard_fab2_lib.baseboard_fab2(sch_1):tp_spi_pch_cs1_r1_n"
				( attribute "CDS_PHYS_NET_NAME" "TP_SPI_PCH_CS1_R1_N"
					( Origin gPackager )
				)
				( objectStatus "TP_SPI_PCH_CS1_R1_N" )
			)
			( signal "@baseboard_fab2_lib.baseboard_fab2(sch_1):a_pvccrtc_ext_cap"
				( attribute "CDS_PHYS_NET_NAME" "A_PVCCRTC_EXT_CAP"
					( Origin gPackager )
				)
				( objectStatus "A_PVCCRTC_EXT_CAP" )
			)
			( signal "@baseboard_fab2_lib.baseboard_fab2(sch_1):p1v05_pch_stby_isclk_pll"
				( alias ( signalRef "@baseboard_fab2_lib.baseboard_fab2(sch_1):page122_p1v05_pch_stby_isclk_pll") )
				( alias ( signalRef "@baseboard_fab2_lib.baseboard_fab2(sch_1):page127_p1v05_pch_stby_isclk_pll") )
				( attribute "VOLTAGE" "1.05V"
					( Units "uVoltage" "V" 1.000000)
					( Status sAliasFlattened )
					( Origin gFrontEnd )
				)
				( attribute "CDS_PHYS_NET_NAME" "P1V05_PCH_STBY_ISCLK_PLL"
					( Origin gPackager )
				)
				( objectStatus "P1V05_PCH_STBY_ISCLK_PLL" )
			)
			( signal "@baseboard_fab2_lib.baseboard_fab2(sch_1):page122_p1v05_pch_stby_isclk_pll"
				( attribute "VOLTAGE" "1.05V"
					( Units "uVoltage" "V" 1.000000)
					( Origin gFrontEnd )
				)
				( objectFlag fObjectAlias )
				( objectStatus "page122_p1v05_pch_stby_isclk_pll" )
			)
			( signal "@baseboard_fab2_lib.baseboard_fab2(sch_1):page127_p1v05_pch_stby_isclk_pll"
				( attribute "VOLTAGE" "1.05V"
					( Units "uVoltage" "V" 1.000000)
					( Origin gFrontEnd )
				)
				( objectFlag fObjectAlias )
				( objectStatus "page127_p1v05_pch_stby_isclk_pll" )
			)
			( signal "@baseboard_fab2_lib.baseboard_fab2(sch_1):p1v05_pch_stby_vcca_pll0"
				( alias ( signalRef "@baseboard_fab2_lib.baseboard_fab2(sch_1):page122_p1v05_pch_stby_vcca_pll0") )
				( alias ( signalRef "@baseboard_fab2_lib.baseboard_fab2(sch_1):page127_p1v05_pch_stby_vcca_pll0") )
				( attribute "VOLTAGE" "1.05V"
					( Units "uVoltage" "V" 1.000000)
					( Status sAliasFlattened )
					( Origin gFrontEnd )
				)
				( attribute "CDS_PHYS_NET_NAME" "P1V05_PCH_STBY_VCCA_PLL0"
					( Origin gPackager )
				)
				( objectStatus "P1V05_PCH_STBY_VCCA_PLL0" )
			)
			( signal "@baseboard_fab2_lib.baseboard_fab2(sch_1):page122_p1v05_pch_stby_vcca_pll0"
				( attribute "VOLTAGE" "1.05V"
					( Units "uVoltage" "V" 1.000000)
					( Origin gFrontEnd )
				)
				( objectFlag fObjectAlias )
				( objectStatus "page122_p1v05_pch_stby_vcca_pll0" )
			)
			( signal "@baseboard_fab2_lib.baseboard_fab2(sch_1):page127_p1v05_pch_stby_vcca_pll0"
				( attribute "VOLTAGE" "1.05V"
					( Units "uVoltage" "V" 1.000000)
					( Origin gFrontEnd )
				)
				( objectFlag fObjectAlias )
				( objectStatus "page127_p1v05_pch_stby_vcca_pll0" )
			)
			( signal "@baseboard_fab2_lib.baseboard_fab2(sch_1):p1v05_pch_stby_vcca_pll1"
				( alias ( signalRef "@baseboard_fab2_lib.baseboard_fab2(sch_1):page122_p1v05_pch_stby_vcca_pll1") )
				( alias ( signalRef "@baseboard_fab2_lib.baseboard_fab2(sch_1):page127_p1v05_pch_stby_vcca_pll1") )
				( attribute "VOLTAGE" "1.05V"
					( Units "uVoltage" "V" 1.000000)
					( Status sAliasFlattened )
					( Origin gFrontEnd )
				)
				( attribute "CDS_PHYS_NET_NAME" "P1V05_PCH_STBY_VCCA_PLL1"
					( Origin gPackager )
				)
				( objectStatus "P1V05_PCH_STBY_VCCA_PLL1" )
			)
			( signal "@baseboard_fab2_lib.baseboard_fab2(sch_1):page122_p1v05_pch_stby_vcca_pll1"
				( attribute "VOLTAGE" "1.05V"
					( Units "uVoltage" "V" 1.000000)
					( Origin gFrontEnd )
				)
				( objectFlag fObjectAlias )
				( objectStatus "page122_p1v05_pch_stby_vcca_pll1" )
			)
			( signal "@baseboard_fab2_lib.baseboard_fab2(sch_1):page127_p1v05_pch_stby_vcca_pll1"
				( attribute "VOLTAGE" "1.05V"
					( Units "uVoltage" "V" 1.000000)
					( Origin gFrontEnd )
				)
				( objectFlag fObjectAlias )
				( objectStatus "page127_p1v05_pch_stby_vcca_pll1" )
			)
			( signal "@baseboard_fab2_lib.baseboard_fab2(sch_1):p1v05_pch_stby_vcca_xtal"
				( alias ( signalRef "@baseboard_fab2_lib.baseboard_fab2(sch_1):page122_p1v05_pch_stby_vcca_xtal") )
				( alias ( signalRef "@baseboard_fab2_lib.baseboard_fab2(sch_1):page127_p1v05_pch_stby_vcca_xtal") )
				( attribute "VOLTAGE" "1.05V"
					( Units "uVoltage" "V" 1.000000)
					( Status sAliasFlattened )
					( Origin gFrontEnd )
				)
				( attribute "CDS_PHYS_NET_NAME" "P1V05_PCH_STBY_VCCA_XTAL"
					( Origin gPackager )
				)
				( objectStatus "P1V05_PCH_STBY_VCCA_XTAL" )
			)
			( signal "@baseboard_fab2_lib.baseboard_fab2(sch_1):page122_p1v05_pch_stby_vcca_xtal"
				( attribute "VOLTAGE" "1.05V"
					( Units "uVoltage" "V" 1.000000)
					( Origin gFrontEnd )
				)
				( objectFlag fObjectAlias )
				( objectStatus "page122_p1v05_pch_stby_vcca_xtal" )
			)
			( signal "@baseboard_fab2_lib.baseboard_fab2(sch_1):page127_p1v05_pch_stby_vcca_xtal"
				( attribute "VOLTAGE" "1.05V"
					( Units "uVoltage" "V" 1.000000)
					( Origin gFrontEnd )
				)
				( objectFlag fObjectAlias )
				( objectStatus "page127_p1v05_pch_stby_vcca_xtal" )
			)
			( signal "@baseboard_fab2_lib.baseboard_fab2(sch_1):p1v05_pch_stby_wm20_pll"
				( alias ( signalRef "@baseboard_fab2_lib.baseboard_fab2(sch_1):page122_p1v05_pch_stby_wm20_pll") )
				( alias ( signalRef "@baseboard_fab2_lib.baseboard_fab2(sch_1):page127_p1v05_pch_stby_wm20_pll") )
				( attribute "VOLTAGE" "1.05V"
					( Units "uVoltage" "V" 1.000000)
					( Status sAliasFlattened )
					( Origin gFrontEnd )
				)
				( attribute "CDS_PHYS_NET_NAME" "P1V05_PCH_STBY_WM20_PLL"
					( Origin gPackager )
				)
				( objectStatus "P1V05_PCH_STBY_WM20_PLL" )
			)
			( signal "@baseboard_fab2_lib.baseboard_fab2(sch_1):page122_p1v05_pch_stby_wm20_pll"
				( attribute "VOLTAGE" "1.05V"
					( Units "uVoltage" "V" 1.000000)
					( Origin gFrontEnd )
				)
				( objectFlag fObjectAlias )
				( objectStatus "page122_p1v05_pch_stby_wm20_pll" )
			)
			( signal "@baseboard_fab2_lib.baseboard_fab2(sch_1):page127_p1v05_pch_stby_wm20_pll"
				( attribute "VOLTAGE" "1.05V"
					( Units "uVoltage" "V" 1.000000)
					( Origin gFrontEnd )
				)
				( objectFlag fObjectAlias )
				( objectStatus "page127_p1v05_pch_stby_wm20_pll" )
			)
			( signal "@baseboard_fab2_lib.baseboard_fab2(sch_1):p1v05_pch_stby_wm26_pll"
				( alias ( signalRef "@baseboard_fab2_lib.baseboard_fab2(sch_1):page122_p1v05_pch_stby_wm26_pll") )
				( alias ( signalRef "@baseboard_fab2_lib.baseboard_fab2(sch_1):page127_p1v05_pch_stby_wm26_pll") )
				( attribute "VOLTAGE" "1.05V"
					( Units "uVoltage" "V" 1.000000)
					( Status sAliasFlattened )
					( Origin gFrontEnd )
				)
				( attribute "CDS_PHYS_NET_NAME" "P1V05_PCH_STBY_WM26_PLL"
					( Origin gPackager )
				)
				( objectStatus "P1V05_PCH_STBY_WM26_PLL" )
			)
			( signal "@baseboard_fab2_lib.baseboard_fab2(sch_1):page122_p1v05_pch_stby_wm26_pll"
				( attribute "VOLTAGE" "1.05V"
					( Units "uVoltage" "V" 1.000000)
					( Origin gFrontEnd )
				)
				( objectFlag fObjectAlias )
				( objectStatus "page122_p1v05_pch_stby_wm26_pll" )
			)
			( signal "@baseboard_fab2_lib.baseboard_fab2(sch_1):page127_p1v05_pch_stby_wm26_pll"
				( attribute "VOLTAGE" "1.05V"
					( Units "uVoltage" "V" 1.000000)
					( Origin gFrontEnd )
				)
				( objectFlag fObjectAlias )
				( objectStatus "page127_p1v05_pch_stby_wm26_pll" )
			)
			( signal "@baseboard_fab2_lib.baseboard_fab2(sch_1):p1v8_pch_stby"
				( alias ( signalRef "@baseboard_fab2_lib.baseboard_fab2(sch_1):page122_p1v8_pch_stby") )
				( alias ( signalRef "@baseboard_fab2_lib.baseboard_fab2(sch_1):page130_p1v8_pch_stby") )
				( alias ( signalRef "@baseboard_fab2_lib.baseboard_fab2(sch_1):page237_p1v8_pch_stby") )
				( attribute "CDS_PHYS_NET_NAME" "P1V8_PCH_STBY"
					( Origin gPackager )
				)
				( attribute "VOLTAGE" "1.8V"
					( Units "uVoltage" "V" 1.000000)
					( Status sAliasFlattened )
					( Origin gFrontEnd )
				)
				( objectStatus "P1V8_PCH_STBY" )
			)
			( signal "@baseboard_fab2_lib.baseboard_fab2(sch_1):page122_p1v8_pch_stby"
				( attribute "VOLTAGE" "1.8V"
					( Units "uVoltage" "V" 1.000000)
					( Origin gFrontEnd )
				)
				( objectFlag fObjectAlias )
				( objectStatus "page122_p1v8_pch_stby" )
			)
			( signal "@baseboard_fab2_lib.baseboard_fab2(sch_1):page130_p1v8_pch_stby"
				( attribute "VOLTAGE" "1.8V"
					( Units "uVoltage" "V" 1.000000)
					( Origin gFrontEnd )
				)
				( objectFlag fObjectAlias )
				( objectStatus "page130_p1v8_pch_stby" )
			)
			( signal "@baseboard_fab2_lib.baseboard_fab2(sch_1):page237_p1v8_pch_stby"
				( attribute "VOLTAGE" "1.8V"
					( Units "uVoltage" "V" 1.000000)
					( Origin gFrontEnd )
				)
				( objectFlag fObjectAlias )
				( objectStatus "page237_p1v8_pch_stby" )
			)
			( signal "@baseboard_fab2_lib.baseboard_fab2(sch_1):p3v3_rtc_stby"
				( alias ( signalRef "@baseboard_fab2_lib.baseboard_fab2(sch_1):page122_p3v3_rtc_stby") )
				( alias ( signalRef "@baseboard_fab2_lib.baseboard_fab2(sch_1):page137_p3v3_rtc_stby") )
				( alias ( signalRef "@baseboard_fab2_lib.baseboard_fab2(sch_1):page196_p3v3_rtc_stby") )
				( attribute "VOLTAGE" "3.3V"
					( Units "uVoltage" "V" 1.000000)
					( Status sAliasFlattened )
					( Origin gFrontEnd )
				)
				( attribute "CDS_PHYS_NET_NAME" "P3V3_RTC_STBY"
					( Origin gPackager )
				)
				( objectStatus "P3V3_RTC_STBY" )
			)
			( signal "@baseboard_fab2_lib.baseboard_fab2(sch_1):page122_p3v3_rtc_stby"
				( attribute "VOLTAGE" "3.3V"
					( Units "uVoltage" "V" 1.000000)
					( Origin gFrontEnd )
				)
				( objectFlag fObjectAlias )
				( objectStatus "page122_p3v3_rtc_stby" )
			)
			( signal "@baseboard_fab2_lib.baseboard_fab2(sch_1):page137_p3v3_rtc_stby"
				( attribute "VOLTAGE" "3.3V"
					( Units "uVoltage" "V" 1.000000)
					( Origin gFrontEnd )
				)
				( objectFlag fObjectAlias )
				( objectStatus "page137_p3v3_rtc_stby" )
			)
			( signal "@baseboard_fab2_lib.baseboard_fab2(sch_1):page196_p3v3_rtc_stby"
				( attribute "VOLTAGE" "3.3V"
					( Units "uVoltage" "V" 1.000000)
					( Origin gFrontEnd )
				)
				( objectFlag fObjectAlias )
				( objectStatus "page196_p3v3_rtc_stby" )
			)
			( signal "@baseboard_fab2_lib.baseboard_fab2(sch_1):tp_pch_rsvd28"
				( attribute "CDS_PHYS_NET_NAME" "TP_PCH_RSVD28"
					( Origin gPackager )
				)
				( objectStatus "TP_PCH_RSVD28" )
			)
			( signal "@baseboard_fab2_lib.baseboard_fab2(sch_1):tp_pch_rsvd29"
				( attribute "CDS_PHYS_NET_NAME" "TP_PCH_RSVD29"
					( Origin gPackager )
				)
				( objectStatus "TP_PCH_RSVD29" )
			)
			( signal "@baseboard_fab2_lib.baseboard_fab2(sch_1):tp_pch_rsvd30"
				( attribute "CDS_PHYS_NET_NAME" "TP_PCH_RSVD30"
					( Origin gPackager )
				)
				( objectStatus "TP_PCH_RSVD30" )
			)
			( signal "@baseboard_fab2_lib.baseboard_fab2(sch_1):tp_pch_rsvd31"
				( attribute "CDS_PHYS_NET_NAME" "TP_PCH_RSVD31"
					( Origin gPackager )
				)
				( objectStatus "TP_PCH_RSVD31" )
			)
			( signal "@baseboard_fab2_lib.baseboard_fab2(sch_1):tp_pch_rsvd58"
				( attribute "CDS_PHYS_NET_NAME" "TP_PCH_RSVD58"
					( Origin gPackager )
				)
				( objectStatus "TP_PCH_RSVD58" )
			)
			( signal "@baseboard_fab2_lib.baseboard_fab2(sch_1):tp_pch_rsvd59"
				( attribute "CDS_PHYS_NET_NAME" "TP_PCH_RSVD59"
					( Origin gPackager )
				)
				( objectStatus "TP_PCH_RSVD59" )
			)
			( signal "@baseboard_fab2_lib.baseboard_fab2(sch_1):pvnn_pch_stby"
				( alias ( signalRef "@baseboard_fab2_lib.baseboard_fab2(sch_1):page123_pvnn_pch_stby") )
				( alias ( signalRef "@baseboard_fab2_lib.baseboard_fab2(sch_1):page132_pvnn_pch_stby") )
				( alias ( signalRef "@baseboard_fab2_lib.baseboard_fab2(sch_1):page169_pvnn_pch_stby") )
				( alias ( signalRef "@baseboard_fab2_lib.baseboard_fab2(sch_1):page236_pvnn_pch_stby") )
				( attribute "VOLTAGE" "1.0V"
					( Units "uVoltage" "V" 1.000000)
					( Status sAliasFlattened )
					( Origin gFrontEnd )
				)
				( attribute "CDS_PHYS_NET_NAME" "PVNN_PCH_STBY"
					( Origin gPackager )
				)
				( objectStatus "PVNN_PCH_STBY" )
			)
			( signal "@baseboard_fab2_lib.baseboard_fab2(sch_1):page123_pvnn_pch_stby"
				( attribute "VOLTAGE" "1.0V"
					( Units "uVoltage" "V" 1.000000)
					( Origin gFrontEnd )
				)
				( objectFlag fObjectAlias )
				( objectStatus "page123_pvnn_pch_stby" )
			)
			( signal "@baseboard_fab2_lib.baseboard_fab2(sch_1):page132_pvnn_pch_stby"
				( attribute "VOLTAGE" "1.0V"
					( Units "uVoltage" "V" 1.000000)
					( Origin gFrontEnd )
				)
				( objectFlag fObjectAlias )
				( objectStatus "page132_pvnn_pch_stby" )
			)
			( signal "@baseboard_fab2_lib.baseboard_fab2(sch_1):page169_pvnn_pch_stby"
				( attribute "VOLTAGE" "1.0V"
					( Units "uVoltage" "V" 1.000000)
					( Origin gFrontEnd )
				)
				( objectFlag fObjectAlias )
				( objectStatus "page169_pvnn_pch_stby" )
			)
			( signal "@baseboard_fab2_lib.baseboard_fab2(sch_1):page236_pvnn_pch_stby"
				( attribute "VOLTAGE" "1.0V"
					( Units "uVoltage" "V" 1.000000)
					( Origin gFrontEnd )
				)
				( objectFlag fObjectAlias )
				( objectStatus "page236_pvnn_pch_stby" )
			)
			( signal "@baseboard_fab2_lib.baseboard_fab2(sch_1):vsense_pvnn_pch_stby_fpk"
				( attribute "CDS_PHYS_NET_NAME" "VSENSE_PVNN_PCH_STBY_FPK"
					( Origin gPackager )
				)
				( objectStatus "VSENSE_PVNN_PCH_STBY_FPK" )
			)
			( signal "@baseboard_fab2_lib.baseboard_fab2(sch_1):vsense_pvnn_pch_stby_qat"
				( attribute "CDS_PHYS_NET_NAME" "VSENSE_PVNN_PCH_STBY_QAT"
					( Origin gPackager )
				)
				( objectStatus "VSENSE_PVNN_PCH_STBY_QAT" )
			)
			( signal "@baseboard_fab2_lib.baseboard_fab2(sch_1):rst_rsmrst_dly"
				( attribute "CDS_PHYS_NET_NAME" "RST_RSMRST_DLY"
					( Origin gPackager )
				)
				( objectStatus "RST_RSMRST_DLY" )
			)
			( signal "@baseboard_fab2_lib.baseboard_fab2(sch_1):fm_thermtrip_dly"
				( attribute "CDS_PHYS_NET_NAME" "FM_THERMTRIP_DLY"
					( Origin gPackager )
				)
				( objectStatus "FM_THERMTRIP_DLY" )
			)
			( signal "@baseboard_fab2_lib.baseboard_fab2(sch_1):fm_thermtrip_dly_r"
				( attribute "CDS_PHYS_NET_NAME" "FM_THERMTRIP_DLY_R"
					( Origin gPackager )
				)
				( objectStatus "FM_THERMTRIP_DLY_R" )
			)
			( signal "@baseboard_fab2_lib.baseboard_fab2(sch_1):rst_pltrst_buf_n"
				( attribute "CDS_PHYS_NET_NAME" "RST_PLTRST_BUF_N"
					( Origin gPackager )
				)
				( objectStatus "RST_PLTRST_BUF_N" )
			)
			( signal "@baseboard_fab2_lib.baseboard_fab2(sch_1):fm_cpld_uart_ch_lock_n"
				( attribute "CDS_PHYS_NET_NAME" "FM_CPLD_UART_CH_LOCK_N"
					( Origin gPackager )
				)
				( objectStatus "FM_CPLD_UART_CH_LOCK_N" )
			)
			( signal "@baseboard_fab2_lib.baseboard_fab2(sch_1):fm_dis_adr_dly"
				( attribute "CDS_PHYS_NET_NAME" "FM_DIS_ADR_DLY"
					( Origin gPackager )
				)
				( objectStatus "FM_DIS_ADR_DLY" )
			)
			( signal "@baseboard_fab2_lib.baseboard_fab2(sch_1):fm_pch_sata_raid_key_r"
				( attribute "CDS_PHYS_NET_NAME" "FM_PCH_SATA_RAID_KEY_R"
					( Origin gPackager )
				)
				( objectStatus "FM_PCH_SATA_RAID_KEY_R" )
			)
			( signal "@baseboard_fab2_lib.baseboard_fab2(sch_1):pu_key_conn_pin2_r"
				( attribute "CDS_PHYS_NET_NAME" "PU_KEY_CONN_PIN2_R"
					( Origin gPackager )
				)
				( objectStatus "PU_KEY_CONN_PIN2_R" )
			)
			( signal "@baseboard_fab2_lib.baseboard_fab2(sch_1):\tp_jumper_block_ 1_7\"
				( attribute "CDS_PHYS_NET_NAME" "TP_JUMPER_BLOCK_1_7"
					( Origin gPackager )
				)
				( attribute "PNN" "TP_JUMPER_BLOCK_1_7"
					( Origin gPackager )
				)
				( objectStatus "TP_JUMPER_BLOCK_1_7" )
			)
			( signal "@baseboard_fab2_lib.baseboard_fab2(sch_1):tp_jumper_block_1_1"
				( attribute "CDS_PHYS_NET_NAME" "TP_JUMPER_BLOCK_1_1"
					( Origin gPackager )
				)
				( objectStatus "TP_JUMPER_BLOCK_1_1" )
			)
			( signal "@baseboard_fab2_lib.baseboard_fab2(sch_1):tp_jumper_block_1_2"
				( attribute "CDS_PHYS_NET_NAME" "TP_JUMPER_BLOCK_1_2"
					( Origin gPackager )
				)
				( objectStatus "TP_JUMPER_BLOCK_1_2" )
			)
			( signal "@baseboard_fab2_lib.baseboard_fab2(sch_1):tp_jumper_block_1_8"
				( attribute "CDS_PHYS_NET_NAME" "TP_JUMPER_BLOCK_1_8"
					( Origin gPackager )
				)
				( objectStatus "TP_JUMPER_BLOCK_1_8" )
			)
			( signal "@baseboard_fab2_lib.baseboard_fab2(sch_1):fm_bios_top_swap_spkr_r"
				( attribute "CDS_PHYS_NET_NAME" "FM_BIOS_TOP_SWAP_SPKR_R"
					( Origin gPackager )
				)
				( objectStatus "FM_BIOS_TOP_SWAP_SPKR_R" )
			)
			( signal "@baseboard_fab2_lib.baseboard_fab2(sch_1):pd_me_rcvr_n"
				( attribute "CDS_PHYS_NET_NAME" "PD_ME_RCVR_N"
					( Origin gPackager )
				)
				( objectStatus "PD_ME_RCVR_N" )
			)
			( signal "@baseboard_fab2_lib.baseboard_fab2(sch_1):pd_password_clear"
				( attribute "CDS_PHYS_NET_NAME" "PD_PASSWORD_CLEAR"
					( Origin gPackager )
				)
				( objectStatus "PD_PASSWORD_CLEAR" )
			)
			( signal "@baseboard_fab2_lib.baseboard_fab2(sch_1):pu_bios_recover_boot"
				( attribute "CDS_PHYS_NET_NAME" "PU_BIOS_RECOVER_BOOT"
					( Origin gPackager )
				)
				( objectStatus "PU_BIOS_RECOVER_BOOT" )
			)
			( signal "@baseboard_fab2_lib.baseboard_fab2(sch_1):pu_bios_usb_recovery"
				( attribute "CDS_PHYS_NET_NAME" "PU_BIOS_USB_RECOVERY"
					( Origin gPackager )
				)
				( objectStatus "PU_BIOS_USB_RECOVERY" )
			)
			( signal "@baseboard_fab2_lib.baseboard_fab2(sch_1):rst_pltrst_top_swap"
				( attribute "CDS_PHYS_NET_NAME" "RST_PLTRST_TOP_SWAP"
					( Origin gPackager )
				)
				( objectStatus "RST_PLTRST_TOP_SWAP" )
			)
			( signal "@baseboard_fab2_lib.baseboard_fab2(sch_1):tp_bios_recover_boot"
				( attribute "CDS_PHYS_NET_NAME" "TP_BIOS_RECOVER_BOOT"
					( Origin gPackager )
				)
				( objectStatus "TP_BIOS_RECOVER_BOOT" )
			)
			( signal "@baseboard_fab2_lib.baseboard_fab2(sch_1):tp_bios_usb_recovery"
				( attribute "CDS_PHYS_NET_NAME" "TP_BIOS_USB_RECOVERY"
					( Origin gPackager )
				)
				( objectStatus "TP_BIOS_USB_RECOVERY" )
			)
			( signal "@baseboard_fab2_lib.baseboard_fab2(sch_1):tp_me_rcvr_boot"
				( attribute "CDS_PHYS_NET_NAME" "TP_ME_RCVR_BOOT"
					( Origin gPackager )
				)
				( objectStatus "TP_ME_RCVR_BOOT" )
			)
			( signal "@baseboard_fab2_lib.baseboard_fab2(sch_1):tp_password_clear"
				( attribute "CDS_PHYS_NET_NAME" "TP_PASSWORD_CLEAR"
					( Origin gPackager )
				)
				( objectStatus "TP_PASSWORD_CLEAR" )
			)
			( signal "@baseboard_fab2_lib.baseboard_fab2(sch_1):pwrgd_p2v5_bmc_stby_r"
				( attribute "CDS_PHYS_NET_NAME" "PWRGD_P2V5_BMC_STBY_R"
					( Origin gPackager )
				)
				( objectStatus "PWRGD_P2V5_BMC_STBY_R" )
			)
			( signal "@baseboard_fab2_lib.baseboard_fab2(sch_1):pd_ie_debug_mode"
				( attribute "CDS_PHYS_NET_NAME" "PD_IE_DEBUG_MODE"
					( Origin gPackager )
				)
				( objectStatus "PD_IE_DEBUG_MODE" )
			)
			( signal "@baseboard_fab2_lib.baseboard_fab2(sch_1):pd_rst_rtcrst_n"
				( attribute "CDS_PHYS_NET_NAME" "PD_RST_RTCRST_N"
					( Origin gPackager )
				)
				( objectStatus "PD_RST_RTCRST_N" )
			)
			( signal "@baseboard_fab2_lib.baseboard_fab2(sch_1):tp_ie_debug_mode"
				( attribute "CDS_PHYS_NET_NAME" "TP_IE_DEBUG_MODE"
					( Origin gPackager )
				)
				( objectStatus "TP_IE_DEBUG_MODE" )
			)
			( signal "@baseboard_fab2_lib.baseboard_fab2(sch_1):pd_spi_bmc_bt_cs0_n"
				( attribute "CDS_PHYS_NET_NAME" "PD_SPI_BMC_BT_CS0_N"
					( Origin gPackager )
				)
				( objectStatus "PD_SPI_BMC_BT_CS0_N" )
			)
			( signal "@baseboard_fab2_lib.baseboard_fab2(sch_1):tp_rst_rtcrst_n"
				( attribute "CDS_PHYS_NET_NAME" "TP_RST_RTCRST_N"
					( Origin gPackager )
				)
				( objectStatus "TP_RST_RTCRST_N" )
			)
			( signal "@baseboard_fab2_lib.baseboard_fab2(sch_1):smb_bmc_pmbus_stby_lvc3_scl"
				( alias ( signalRef "@baseboard_fab2_lib.baseboard_fab2(sch_1):page247_smb_bmc_pmbus_stby_lvc3_scl") )
				( attribute "CDS_PHYS_NET_NAME" "SMB_BMC_PMBUS_STBY_LVC3_SCL"
					( Origin gPackager )
				)
				( objectStatus "SMB_BMC_PMBUS_STBY_LVC3_SCL" )
			)
			( signal "@baseboard_fab2_lib.baseboard_fab2(sch_1):page247_smb_bmc_pmbus_stby_lvc3_scl"
				( attribute "CDS_PHYS_NET_NAME" "SMB_BMC_PMBUS_STBY_LVC3_SCL"
					( Origin gPackager )
				)
				( objectFlag fObjectAlias )
				( objectStatus "page247_smb_bmc_pmbus_stby_lvc3_scl" )
			)
			( signal "@baseboard_fab2_lib.baseboard_fab2(sch_1):smb_bmc_pmbus_stby_lvc3_sda"
				( alias ( signalRef "@baseboard_fab2_lib.baseboard_fab2(sch_1):page247_smb_bmc_pmbus_stby_lvc3_sda") )
				( attribute "CDS_PHYS_NET_NAME" "SMB_BMC_PMBUS_STBY_LVC3_SDA"
					( Origin gPackager )
				)
				( objectStatus "SMB_BMC_PMBUS_STBY_LVC3_SDA" )
			)
			( signal "@baseboard_fab2_lib.baseboard_fab2(sch_1):page247_smb_bmc_pmbus_stby_lvc3_sda"
				( attribute "CDS_PHYS_NET_NAME" "SMB_BMC_PMBUS_STBY_LVC3_SDA"
					( Origin gPackager )
				)
				( objectFlag fObjectAlias )
				( objectStatus "page247_smb_bmc_pmbus_stby_lvc3_sda" )
			)
			( signal "@baseboard_fab2_lib.baseboard_fab2(sch_1):smb_lan_stby_lvc3_scl"
				( attribute "CDS_PHYS_NET_NAME" "SMB_LAN_STBY_LVC3_SCL"
					( Origin gPackager )
				)
				( objectStatus "SMB_LAN_STBY_LVC3_SCL" )
			)
			( signal "@baseboard_fab2_lib.baseboard_fab2(sch_1):smb_lan_stby_lvc3_sda"
				( attribute "CDS_PHYS_NET_NAME" "SMB_LAN_STBY_LVC3_SDA"
					( Origin gPackager )
				)
				( objectStatus "SMB_LAN_STBY_LVC3_SDA" )
			)
			( signal "@baseboard_fab2_lib.baseboard_fab2(sch_1):smb_smlink0_stby_lvc3_scl"
				( attribute "CDS_PHYS_NET_NAME" "SMB_SMLINK0_STBY_LVC3_SCL"
					( Origin gPackager )
				)
				( objectStatus "SMB_SMLINK0_STBY_LVC3_SCL" )
			)
			( signal "@baseboard_fab2_lib.baseboard_fab2(sch_1):smb_smlink0_stby_lvc3_sda"
				( attribute "CDS_PHYS_NET_NAME" "SMB_SMLINK0_STBY_LVC3_SDA"
					( Origin gPackager )
				)
				( objectStatus "SMB_SMLINK0_STBY_LVC3_SDA" )
			)
			( signal "@baseboard_fab2_lib.baseboard_fab2(sch_1):smb_vr_stby_lvc3_scl"
				( attribute "CDS_PHYS_NET_NAME" "SMB_VR_STBY_LVC3_SCL"
					( Origin gPackager )
				)
				( objectStatus "SMB_VR_STBY_LVC3_SCL" )
			)
			( signal "@baseboard_fab2_lib.baseboard_fab2(sch_1):smb_vr_stby_lvc3_sda"
				( attribute "CDS_PHYS_NET_NAME" "SMB_VR_STBY_LVC3_SDA"
					( Origin gPackager )
				)
				( objectStatus "SMB_VR_STBY_LVC3_SDA" )
			)
			( signal "@baseboard_fab2_lib.baseboard_fab2(sch_1):a_cbot"
				( attribute "CDS_PHYS_NET_NAME" "A_CBOT"
					( Origin gPackager )
				)
				( objectStatus "A_CBOT" )
			)
			( signal "@baseboard_fab2_lib.baseboard_fab2(sch_1):a_ctop"
				( attribute "CDS_PHYS_NET_NAME" "A_CTOP"
					( Origin gPackager )
				)
				( objectStatus "A_CTOP" )
			)
			( signal "@baseboard_fab2_lib.baseboard_fab2(sch_1):fm_pe_sprv_wake_n"
				( attribute "CDS_PHYS_NET_NAME" "FM_PE_SPRV_WAKE_N"
					( Origin gPackager )
				)
				( objectStatus "FM_PE_SPRV_WAKE_N" )
			)
			( signal "@baseboard_fab2_lib.baseboard_fab2(sch_1):led_lan_0_n"
				( attribute "CDS_PHYS_NET_NAME" "LED_LAN_0_N"
					( Origin gPackager )
				)
				( objectStatus "LED_LAN_0_N" )
			)
			( signal "@baseboard_fab2_lib.baseboard_fab2(sch_1):led_lan_1_n"
				( attribute "CDS_PHYS_NET_NAME" "LED_LAN_1_N"
					( Origin gPackager )
				)
				( objectStatus "LED_LAN_1_N" )
			)
			( signal "@baseboard_fab2_lib.baseboard_fab2(sch_1):led_lan_2_n"
				( attribute "CDS_PHYS_NET_NAME" "LED_LAN_2_N"
					( Origin gPackager )
				)
				( objectStatus "LED_LAN_2_N" )
			)
			( signal "@baseboard_fab2_lib.baseboard_fab2(sch_1):nic_mdi_sprv_rj45_0_dn"
				( attribute "CDS_PHYS_NET_NAME" "NIC_MDI_SPRV_RJ45_0_DN"
					( Origin gPackager )
				)
				( objectStatus "NIC_MDI_SPRV_RJ45_0_DN" )
			)
			( signal "@baseboard_fab2_lib.baseboard_fab2(sch_1):nic_mdi_sprv_rj45_0_dp"
				( attribute "CDS_PHYS_NET_NAME" "NIC_MDI_SPRV_RJ45_0_DP"
					( Origin gPackager )
				)
				( objectStatus "NIC_MDI_SPRV_RJ45_0_DP" )
			)
			( signal "@baseboard_fab2_lib.baseboard_fab2(sch_1):nic_mdi_sprv_rj45_1_dn"
				( attribute "CDS_PHYS_NET_NAME" "NIC_MDI_SPRV_RJ45_1_DN"
					( Origin gPackager )
				)
				( objectStatus "NIC_MDI_SPRV_RJ45_1_DN" )
			)
			( signal "@baseboard_fab2_lib.baseboard_fab2(sch_1):nic_mdi_sprv_rj45_1_dp"
				( attribute "CDS_PHYS_NET_NAME" "NIC_MDI_SPRV_RJ45_1_DP"
					( Origin gPackager )
				)
				( objectStatus "NIC_MDI_SPRV_RJ45_1_DP" )
			)
			( signal "@baseboard_fab2_lib.baseboard_fab2(sch_1):nic_ser_n_mdi_3_dn"
				( attribute "CDS_PHYS_NET_NAME" "NIC_SER_N_MDI_3_DN"
					( Origin gPackager )
				)
				( objectStatus "NIC_SER_N_MDI_3_DN" )
			)
			( signal "@baseboard_fab2_lib.baseboard_fab2(sch_1):nic_ser_p_mdi_3_dp"
				( attribute "CDS_PHYS_NET_NAME" "NIC_SER_P_MDI_3_DP"
					( Origin gPackager )
				)
				( objectStatus "NIC_SER_P_MDI_3_DP" )
			)
			( signal "@baseboard_fab2_lib.baseboard_fab2(sch_1):nic_set_n_mdi_2_dn"
				( attribute "CDS_PHYS_NET_NAME" "NIC_SET_N_MDI_2_DN"
					( Origin gPackager )
				)
				( objectStatus "NIC_SET_N_MDI_2_DN" )
			)
			( signal "@baseboard_fab2_lib.baseboard_fab2(sch_1):nic_set_p_mdi_2_dp"
				( attribute "CDS_PHYS_NET_NAME" "NIC_SET_P_MDI_2_DP"
					( Origin gPackager )
				)
				( objectStatus "NIC_SET_P_MDI_2_DP" )
			)
			( signal "@baseboard_fab2_lib.baseboard_fab2(sch_1):p0v9_lan"
				( alias ( signalRef "@baseboard_fab2_lib.baseboard_fab2(sch_1):page139_p0v9_lan") )
				( attribute "VOLTAGE" "0.9V"
					( Units "uVoltage" "V" 1.000000)
					( Status sAliasFlattened )
					( Origin gFrontEnd )
				)
				( attribute "CDS_PHYS_NET_NAME" "P0V9_LAN"
					( Origin gPackager )
				)
				( objectStatus "P0V9_LAN" )
			)
			( signal "@baseboard_fab2_lib.baseboard_fab2(sch_1):page139_p0v9_lan"
				( attribute "VOLTAGE" "0.9V"
					( Units "uVoltage" "V" 1.000000)
					( Origin gFrontEnd )
				)
				( objectFlag fObjectAlias )
				( objectStatus "page139_p0v9_lan" )
			)
			( signal "@baseboard_fab2_lib.baseboard_fab2(sch_1):p0v9_lan_i210"
				( alias ( signalRef "@baseboard_fab2_lib.baseboard_fab2(sch_1):page139_p0v9_lan_i210") )
				( attribute "VOLTAGE" "0.9"
					( Units "uVoltage" "V" 1.000000)
					( Status sAliasFlattened )
					( Origin gFrontEnd )
				)
				( attribute "CDS_PHYS_NET_NAME" "P0V9_LAN_I210"
					( Origin gPackager )
				)
				( objectStatus "P0V9_LAN_I210" )
			)
			( signal "@baseboard_fab2_lib.baseboard_fab2(sch_1):page139_p0v9_lan_i210"
				( attribute "VOLTAGE" "0.9"
					( Units "uVoltage" "V" 1.000000)
					( Origin gFrontEnd )
				)
				( objectFlag fObjectAlias )
				( objectStatus "page139_p0v9_lan_i210" )
			)
			( signal "@baseboard_fab2_lib.baseboard_fab2(sch_1):p1v5_lan"
				( alias ( signalRef "@baseboard_fab2_lib.baseboard_fab2(sch_1):page139_p1v5_lan") )
				( attribute "VOLTAGE" "1.5V"
					( Units "uVoltage" "V" 1.000000)
					( Status sAliasFlattened )
					( Origin gFrontEnd )
				)
				( attribute "CDS_PHYS_NET_NAME" "P1V5_LAN"
					( Origin gPackager )
				)
				( objectStatus "P1V5_LAN" )
			)
			( signal "@baseboard_fab2_lib.baseboard_fab2(sch_1):page139_p1v5_lan"
				( attribute "VOLTAGE" "1.5V"
					( Units "uVoltage" "V" 1.000000)
					( Origin gFrontEnd )
				)
				( objectFlag fObjectAlias )
				( objectStatus "page139_p1v5_lan" )
			)
			( signal "@baseboard_fab2_lib.baseboard_fab2(sch_1):p1v5_lan_i210"
				( alias ( signalRef "@baseboard_fab2_lib.baseboard_fab2(sch_1):page139_p1v5_lan_i210") )
				( attribute "VOLTAGE" "1.5"
					( Units "uVoltage" "V" 1.000000)
					( Status sAliasFlattened )
					( Origin gFrontEnd )
				)
				( attribute "CDS_PHYS_NET_NAME" "P1V5_LAN_I210"
					( Origin gPackager )
				)
				( objectStatus "P1V5_LAN_I210" )
			)
			( signal "@baseboard_fab2_lib.baseboard_fab2(sch_1):page139_p1v5_lan_i210"
				( attribute "VOLTAGE" "1.5"
					( Units "uVoltage" "V" 1.000000)
					( Origin gFrontEnd )
				)
				( objectFlag fObjectAlias )
				( objectStatus "page139_p1v5_lan_i210" )
			)
			( signal "@baseboard_fab2_lib.baseboard_fab2(sch_1):p3v3_stby_p1v5_lan_i210"
				( alias ( signalRef "@baseboard_fab2_lib.baseboard_fab2(sch_1):page139_p3v3_stby_p1v5_lan_i210") )
				( attribute "VOLTAGE" "3.3"
					( Units "uVoltage" "V" 1.000000)
					( Status sAliasFlattened )
					( Origin gFrontEnd )
				)
				( attribute "CDS_PHYS_NET_NAME" "P3V3_STBY_P1V5_LAN_I210"
					( Origin gPackager )
				)
				( objectStatus "P3V3_STBY_P1V5_LAN_I210" )
			)
			( signal "@baseboard_fab2_lib.baseboard_fab2(sch_1):page139_p3v3_stby_p1v5_lan_i210"
				( attribute "VOLTAGE" "3.3"
					( Units "uVoltage" "V" 1.000000)
					( Origin gFrontEnd )
				)
				( objectFlag fObjectAlias )
				( objectStatus "page139_p3v3_stby_p1v5_lan_i210" )
			)
			( signal "@baseboard_fab2_lib.baseboard_fab2(sch_1):pd_sprv_rset"
				( attribute "CDS_PHYS_NET_NAME" "PD_SPRV_RSET"
					( Origin gPackager )
				)
				( objectStatus "PD_SPRV_RSET" )
			)
			( signal "@baseboard_fab2_lib.baseboard_fab2(sch_1):pe_pch_sprv_rx_dn"
				( attribute "CDS_PHYS_NET_NAME" "PE_PCH_SPRV_RX_DN"
					( Origin gPackager )
				)
				( objectStatus "PE_PCH_SPRV_RX_DN" )
			)
			( signal "@baseboard_fab2_lib.baseboard_fab2(sch_1):pe_pch_sprv_rx_dp"
				( attribute "CDS_PHYS_NET_NAME" "PE_PCH_SPRV_RX_DP"
					( Origin gPackager )
				)
				( objectStatus "PE_PCH_SPRV_RX_DP" )
			)
			( signal "@baseboard_fab2_lib.baseboard_fab2(sch_1):pe_pch_sprv_tx_c_dn"
				( attribute "CDS_PHYS_NET_NAME" "PE_PCH_SPRV_TX_C_DN"
					( Origin gPackager )
				)
				( objectStatus "PE_PCH_SPRV_TX_C_DN" )
			)
			( signal "@baseboard_fab2_lib.baseboard_fab2(sch_1):pe_pch_sprv_tx_c_dp"
				( attribute "CDS_PHYS_NET_NAME" "PE_PCH_SPRV_TX_C_DP"
					( Origin gPackager )
				)
				( objectStatus "PE_PCH_SPRV_TX_C_DP" )
			)
			( signal "@baseboard_fab2_lib.baseboard_fab2(sch_1):pu_jtag_sprv_tck"
				( attribute "CDS_PHYS_NET_NAME" "PU_JTAG_SPRV_TCK"
					( Origin gPackager )
				)
				( objectStatus "PU_JTAG_SPRV_TCK" )
			)
			( signal "@baseboard_fab2_lib.baseboard_fab2(sch_1):pu_jtag_sprv_tdi"
				( attribute "CDS_PHYS_NET_NAME" "PU_JTAG_SPRV_TDI"
					( Origin gPackager )
				)
				( objectStatus "PU_JTAG_SPRV_TDI" )
			)
			( signal "@baseboard_fab2_lib.baseboard_fab2(sch_1):pu_jtag_sprv_tdo"
				( attribute "CDS_PHYS_NET_NAME" "PU_JTAG_SPRV_TDO"
					( Origin gPackager )
				)
				( objectStatus "PU_JTAG_SPRV_TDO" )
			)
			( signal "@baseboard_fab2_lib.baseboard_fab2(sch_1):pu_jtag_sprv_tms"
				( attribute "CDS_PHYS_NET_NAME" "PU_JTAG_SPRV_TMS"
					( Origin gPackager )
				)
				( objectStatus "PU_JTAG_SPRV_TMS" )
			)
			( signal "@baseboard_fab2_lib.baseboard_fab2(sch_1):pu_sprv_lan_pwr_good"
				( attribute "CDS_PHYS_NET_NAME" "PU_SPRV_LAN_PWR_GOOD"
					( Origin gPackager )
				)
				( objectStatus "PU_SPRV_LAN_PWR_GOOD" )
			)
			( signal "@baseboard_fab2_lib.baseboard_fab2(sch_1):rmii_bmc_pch_sprngvlle_crsdv_r"
				( attribute "CDS_PHYS_NET_NAME" "RMII_BMC_PCH_SPRNGVLLE_CRSDV_R"
					( Origin gPackager )
				)
				( objectStatus "RMII_BMC_PCH_SPRNGVLLE_CRSDV_R" )
			)
			( signal "@baseboard_fab2_lib.baseboard_fab2(sch_1):rmii_pch_sprngvlle_arb_in_r"
				( attribute "CDS_PHYS_NET_NAME" "RMII_PCH_SPRNGVLLE_ARB_IN_R"
					( Origin gPackager )
				)
				( objectStatus "RMII_PCH_SPRNGVLLE_ARB_IN_R" )
			)
			( signal "@baseboard_fab2_lib.baseboard_fab2(sch_1):rmii_sprngvlle_bmc_pch_rxd0_r"
				( attribute "CDS_PHYS_NET_NAME" "RMII_SPRNGVLLE_BMC_PCH_RXD0_R"
					( Origin gPackager )
				)
				( objectStatus "RMII_SPRNGVLLE_BMC_PCH_RXD0_R" )
			)
			( signal "@baseboard_fab2_lib.baseboard_fab2(sch_1):rmii_sprngvlle_bmc_pch_rxd1_r"
				( attribute "CDS_PHYS_NET_NAME" "RMII_SPRNGVLLE_BMC_PCH_RXD1_R"
					( Origin gPackager )
				)
				( objectStatus "RMII_SPRNGVLLE_BMC_PCH_RXD1_R" )
			)
			( signal "@baseboard_fab2_lib.baseboard_fab2(sch_1):rst_pltrst_sprv_r_n"
				( attribute "CDS_PHYS_NET_NAME" "RST_PLTRST_SPRV_R_N"
					( Origin gPackager )
				)
				( objectStatus "RST_PLTRST_SPRV_R_N" )
			)
			( signal "@baseboard_fab2_lib.baseboard_fab2(sch_1):smb_springville_stby_lvc3_scl"
				( attribute "CDS_PHYS_NET_NAME" "SMB_SPRINGVILLE_STBY_LVC3_SCL"
					( Origin gPackager )
				)
				( objectStatus "SMB_SPRINGVILLE_STBY_LVC3_SCL" )
			)
			( signal "@baseboard_fab2_lib.baseboard_fab2(sch_1):smb_springville_stby_lvc3_sda"
				( attribute "CDS_PHYS_NET_NAME" "SMB_SPRINGVILLE_STBY_LVC3_SDA"
					( Origin gPackager )
				)
				( objectStatus "SMB_SPRINGVILLE_STBY_LVC3_SDA" )
			)
			( signal "@baseboard_fab2_lib.baseboard_fab2(sch_1):spi_nic_cs_n"
				( attribute "CDS_PHYS_NET_NAME" "SPI_NIC_CS_N"
					( Origin gPackager )
				)
				( objectStatus "SPI_NIC_CS_N" )
			)
			( signal "@baseboard_fab2_lib.baseboard_fab2(sch_1):spi_nic_cs_r_n"
				( attribute "CDS_PHYS_NET_NAME" "SPI_NIC_CS_R_N"
					( Origin gPackager )
				)
				( objectStatus "SPI_NIC_CS_R_N" )
			)
			( signal "@baseboard_fab2_lib.baseboard_fab2(sch_1):spi_nic_miso"
				( attribute "CDS_PHYS_NET_NAME" "SPI_NIC_MISO"
					( Origin gPackager )
				)
				( objectStatus "SPI_NIC_MISO" )
			)
			( signal "@baseboard_fab2_lib.baseboard_fab2(sch_1):spi_nic_mosi"
				( attribute "CDS_PHYS_NET_NAME" "SPI_NIC_MOSI"
					( Origin gPackager )
				)
				( objectStatus "SPI_NIC_MOSI" )
			)
			( signal "@baseboard_fab2_lib.baseboard_fab2(sch_1):spi_nic_mosi_r"
				( attribute "CDS_PHYS_NET_NAME" "SPI_NIC_MOSI_R"
					( Origin gPackager )
				)
				( objectStatus "SPI_NIC_MOSI_R" )
			)
			( signal "@baseboard_fab2_lib.baseboard_fab2(sch_1):spi_nic_sclk"
				( attribute "CDS_PHYS_NET_NAME" "SPI_NIC_SCLK"
					( Origin gPackager )
				)
				( objectStatus "SPI_NIC_SCLK" )
			)
			( signal "@baseboard_fab2_lib.baseboard_fab2(sch_1):spi_nic_sclk_r"
				( attribute "CDS_PHYS_NET_NAME" "SPI_NIC_SCLK_R"
					( Origin gPackager )
				)
				( objectStatus "SPI_NIC_SCLK_R" )
			)
			( signal "@baseboard_fab2_lib.baseboard_fab2(sch_1):tp_sprv_sdp0"
				( attribute "CDS_PHYS_NET_NAME" "TP_SPRV_SDP0"
					( Origin gPackager )
				)
				( objectStatus "TP_SPRV_SDP0" )
			)
			( signal "@baseboard_fab2_lib.baseboard_fab2(sch_1):tp_sprv_sdp2"
				( attribute "CDS_PHYS_NET_NAME" "TP_SPRV_SDP2"
					( Origin gPackager )
				)
				( objectStatus "TP_SPRV_SDP2" )
			)
			( signal "@baseboard_fab2_lib.baseboard_fab2(sch_1):tp_sprv_sdp3"
				( attribute "CDS_PHYS_NET_NAME" "TP_SPRV_SDP3"
					( Origin gPackager )
				)
				( objectStatus "TP_SPRV_SDP3" )
			)
			( signal "@baseboard_fab2_lib.baseboard_fab2(sch_1):xtal_25mhz_in"
				( attribute "CDS_PHYS_NET_NAME" "XTAL_25MHZ_IN"
					( Origin gPackager )
				)
				( objectStatus "XTAL_25MHZ_IN" )
			)
			( signal "@baseboard_fab2_lib.baseboard_fab2(sch_1):xtal_25mhz_in_r"
				( attribute "CDS_PHYS_NET_NAME" "XTAL_25MHZ_IN_R"
					( Origin gPackager )
				)
				( objectStatus "XTAL_25MHZ_IN_R" )
			)
			( signal "@baseboard_fab2_lib.baseboard_fab2(sch_1):xtal_25mhz_out"
				( attribute "CDS_PHYS_NET_NAME" "XTAL_25MHZ_OUT"
					( Origin gPackager )
				)
				( objectStatus "XTAL_25MHZ_OUT" )
			)
			( signal "@baseboard_fab2_lib.baseboard_fab2(sch_1):xtal_25mhz_out_r"
				( attribute "CDS_PHYS_NET_NAME" "XTAL_25MHZ_OUT_R"
					( Origin gPackager )
				)
				( objectStatus "XTAL_25MHZ_OUT_R" )
			)
			( signal "@baseboard_fab2_lib.baseboard_fab2(sch_1):pu_nv_hold_n"
				( attribute "CDS_PHYS_NET_NAME" "PU_NV_HOLD_N"
					( Origin gPackager )
				)
				( objectStatus "PU_NV_HOLD_N" )
			)
			( signal "@baseboard_fab2_lib.baseboard_fab2(sch_1):pu_nv_wp_n"
				( attribute "CDS_PHYS_NET_NAME" "PU_NV_WP_N"
					( Origin gPackager )
				)
				( objectStatus "PU_NV_WP_N" )
			)
			( signal "@baseboard_fab2_lib.baseboard_fab2(sch_1):spi_nic_miso_r"
				( attribute "CDS_PHYS_NET_NAME" "SPI_NIC_MISO_R"
					( Origin gPackager )
				)
				( objectStatus "SPI_NIC_MISO_R" )
			)
			( signal "@baseboard_fab2_lib.baseboard_fab2(sch_1):gnd_lan_trct1234_c"
				( alias ( signalRef "@baseboard_fab2_lib.baseboard_fab2(sch_1):page141_gnd_lan_trct1234_c") )
				( attribute "VOLTAGE" "0"
					( Units "uVoltage" "V" 1.000000)
					( Status sAliasFlattened )
					( Origin gFrontEnd )
				)
				( attribute "CDS_PHYS_NET_NAME" "GND_LAN_TRCT1234_C"
					( Origin gPackager )
				)
				( objectStatus "GND_LAN_TRCT1234_C" )
			)
			( signal "@baseboard_fab2_lib.baseboard_fab2(sch_1):page141_gnd_lan_trct1234_c"
				( attribute "VOLTAGE" "0"
					( Units "uVoltage" "V" 1.000000)
					( Origin gFrontEnd )
				)
				( objectFlag fObjectAlias )
				( objectStatus "page141_gnd_lan_trct1234_c" )
			)
			( signal "@baseboard_fab2_lib.baseboard_fab2(sch_1):led_lan_0_r_n"
				( attribute "CDS_PHYS_NET_NAME" "LED_LAN_0_R_N"
					( Origin gPackager )
				)
				( objectStatus "LED_LAN_0_R_N" )
			)
			( signal "@baseboard_fab2_lib.baseboard_fab2(sch_1):led_lan_1_r_n"
				( attribute "CDS_PHYS_NET_NAME" "LED_LAN_1_R_N"
					( Origin gPackager )
				)
				( objectStatus "LED_LAN_1_R_N" )
			)
			( signal "@baseboard_fab2_lib.baseboard_fab2(sch_1):led_lan_2_r_n"
				( attribute "CDS_PHYS_NET_NAME" "LED_LAN_2_R_N"
					( Origin gPackager )
				)
				( objectStatus "LED_LAN_2_R_N" )
			)
			( signal "@baseboard_fab2_lib.baseboard_fab2(sch_1):nic_led_act_anode_r"
				( attribute "CDS_PHYS_NET_NAME" "NIC_LED_ACT_ANODE_R"
					( Origin gPackager )
				)
				( objectStatus "NIC_LED_ACT_ANODE_R" )
			)
			( signal "@baseboard_fab2_lib.baseboard_fab2(sch_1):nic_mdi_mng_rx_dn"
				( attribute "CDS_PHYS_NET_NAME" "NIC_MDI_MNG_RX_DN"
					( Origin gPackager )
				)
				( objectStatus "NIC_MDI_MNG_RX_DN" )
			)
			( signal "@baseboard_fab2_lib.baseboard_fab2(sch_1):nic_mdi_mng_rx_dp"
				( attribute "CDS_PHYS_NET_NAME" "NIC_MDI_MNG_RX_DP"
					( Origin gPackager )
				)
				( objectStatus "NIC_MDI_MNG_RX_DP" )
			)
			( signal "@baseboard_fab2_lib.baseboard_fab2(sch_1):nic_mdi_mng_tx_dn"
				( attribute "CDS_PHYS_NET_NAME" "NIC_MDI_MNG_TX_DN"
					( Origin gPackager )
				)
				( objectStatus "NIC_MDI_MNG_TX_DN" )
			)
			( signal "@baseboard_fab2_lib.baseboard_fab2(sch_1):nic_mdi_mng_tx_dp"
				( attribute "CDS_PHYS_NET_NAME" "NIC_MDI_MNG_TX_DP"
					( Origin gPackager )
				)
				( objectStatus "NIC_MDI_MNG_TX_DP" )
			)
			( signal "@baseboard_fab2_lib.baseboard_fab2(sch_1):nic_mdi_sprv_rj45_0_r_dn"
				( attribute "CDS_PHYS_NET_NAME" "NIC_MDI_SPRV_RJ45_0_R_DN"
					( Origin gPackager )
				)
				( objectStatus "NIC_MDI_SPRV_RJ45_0_R_DN" )
			)
			( signal "@baseboard_fab2_lib.baseboard_fab2(sch_1):nic_mdi_sprv_rj45_0_r_dp"
				( attribute "CDS_PHYS_NET_NAME" "NIC_MDI_SPRV_RJ45_0_R_DP"
					( Origin gPackager )
				)
				( objectStatus "NIC_MDI_SPRV_RJ45_0_R_DP" )
			)
			( signal "@baseboard_fab2_lib.baseboard_fab2(sch_1):clk_24m_25m_bmc_clkin"
				( attribute "CDS_PHYS_NET_NAME" "CLK_24M_25M_BMC_CLKIN"
					( Origin gPackager )
				)
				( objectStatus "CLK_24M_25M_BMC_CLKIN" )
			)
			( signal "@baseboard_fab2_lib.baseboard_fab2(sch_1):nic_mdi_sprv_rj45_1_r_dp"
				( attribute "CDS_PHYS_NET_NAME" "NIC_MDI_SPRV_RJ45_1_R_DP"
					( Origin gPackager )
				)
				( objectStatus "NIC_MDI_SPRV_RJ45_1_R_DP" )
			)
			( signal "@baseboard_fab2_lib.baseboard_fab2(sch_1):tp_rgmii1txd3_gpiot5"
				( attribute "CDS_PHYS_NET_NAME" "TP_RGMII1TXD3_GPIOT5"
					( Origin gPackager )
				)
				( attribute "PHYS_NET_NAME" "TP_RGMII1TXD3_GPIOT5"
					( Origin gPackager )
				)
				( objectStatus "TP_RGMII1TXD3_GPIOT5" )
			)
			( signal "@baseboard_fab2_lib.baseboard_fab2(sch_1):rst_bmc_sysrst_btn_out_n"
				( attribute "CDS_PHYS_NET_NAME" "RST_BMC_SYSRST_BTN_OUT_N"
					( Origin gPackager )
				)
				( attribute "PHYS_NET_NAME" "RST_BMC_SYSRST_BTN_OUT_N"
					( Origin gPackager )
				)
				( objectStatus "RST_BMC_SYSRST_BTN_OUT_N" )
			)
			( signal "@baseboard_fab2_lib.baseboard_fab2(sch_1):uart_bmc_rxd5"
				( attribute "CDS_PHYS_NET_NAME" "UART_BMC_RXD5"
					( Origin gPackager )
				)
				( objectStatus "UART_BMC_RXD5" )
			)
			( signal "@baseboard_fab2_lib.baseboard_fab2(sch_1):tp_tpm_spi_5"
				( attribute "CDS_PHYS_NET_NAME" "TP_TPM_SPI_5"
					( Origin gPackager )
				)
				( objectStatus "TP_TPM_SPI_5" )
			)
			( signal "@baseboard_fab2_lib.baseboard_fab2(sch_1):tp_rgmii1txd2_gpiot4"
				( attribute "CDS_PHYS_NET_NAME" "TP_RGMII1TXD2_GPIOT4"
					( Origin gPackager )
				)
				( attribute "PHYS_NET_NAME" "TP_RGMII1TXD2_GPIOT4"
					( Origin gPackager )
				)
				( objectStatus "TP_RGMII1TXD2_GPIOT4" )
			)
			( signal "@baseboard_fab2_lib.baseboard_fab2(sch_1):bmc_m_mact_n"
				( attribute "CDS_PHYS_NET_NAME" "BMC_M_MACT_N"
					( Origin gPackager )
				)
				( objectStatus "BMC_M_MACT_N" )
			)
			( signal "@baseboard_fab2_lib.baseboard_fab2(sch_1):vcc_dacav3v3"
				( alias ( signalRef "@baseboard_fab2_lib.baseboard_fab2(sch_1):page148_vcc_dacav3v3") )
				( alias ( signalRef "@baseboard_fab2_lib.baseboard_fab2(sch_1):page149_vcc_dacav3v3") )
				( attribute "CDS_PHYS_NET_NAME" "VCC_DACAV3V3"
					( Origin gPackager )
				)
				( objectStatus "VCC_DACAV3V3" )
			)
			( signal "@baseboard_fab2_lib.baseboard_fab2(sch_1):rst_bmc_ddr3_buf_in_n"
				( attribute "CDS_PHYS_NET_NAME" "RST_BMC_DDR3_BUF_IN_N"
					( Origin gPackager )
				)
				( objectStatus "RST_BMC_DDR3_BUF_IN_N" )
			)
			( signal "@baseboard_fab2_lib.baseboard_fab2(sch_1):nic_mdi_sprv_rj45_2_r_dn"
				( attribute "CDS_PHYS_NET_NAME" "NIC_MDI_SPRV_RJ45_2_R_DN"
					( Origin gPackager )
				)
				( objectStatus "NIC_MDI_SPRV_RJ45_2_R_DN" )
			)
			( signal "@baseboard_fab2_lib.baseboard_fab2(sch_1):nic_mdi_sprv_rj45_2_r_dp"
				( attribute "CDS_PHYS_NET_NAME" "NIC_MDI_SPRV_RJ45_2_R_DP"
					( Origin gPackager )
				)
				( objectStatus "NIC_MDI_SPRV_RJ45_2_R_DP" )
			)
			( signal "@baseboard_fab2_lib.baseboard_fab2(sch_1):nic_mdi_sprv_rj45_3_r_dn"
				( attribute "CDS_PHYS_NET_NAME" "NIC_MDI_SPRV_RJ45_3_R_DN"
					( Origin gPackager )
				)
				( objectStatus "NIC_MDI_SPRV_RJ45_3_R_DN" )
			)
			( signal "@baseboard_fab2_lib.baseboard_fab2(sch_1):fm_all_wake_n"
				( attribute "CDS_PHYS_NET_NAME" "FM_ALL_WAKE_N"
					( Origin gPackager )
				)
				( objectStatus "FM_ALL_WAKE_N" )
			)
			( signal "@baseboard_fab2_lib.baseboard_fab2(sch_1):fm_pe_m2_wake_n"
				( attribute "CDS_PHYS_NET_NAME" "FM_PE_M2_WAKE_N"
					( Origin gPackager )
				)
				( objectStatus "FM_PE_M2_WAKE_N" )
			)
			( signal "@baseboard_fab2_lib.baseboard_fab2(sch_1):jtag_bmc_tdo"
				( attribute "CDS_PHYS_NET_NAME" "JTAG_BMC_TDO"
					( Origin gPackager )
				)
				( objectStatus "JTAG_BMC_TDO" )
			)
			( signal "@baseboard_fab2_lib.baseboard_fab2(sch_1):jtag_bmc_tms"
				( attribute "CDS_PHYS_NET_NAME" "JTAG_BMC_TMS"
					( Origin gPackager )
				)
				( objectStatus "JTAG_BMC_TMS" )
			)
			( signal "@baseboard_fab2_lib.baseboard_fab2(sch_1):page149_vcc_adcav3v3"
				( objectFlag fObjectAlias )
				( objectStatus "page149_vcc_adcav3v3" )
			)
			( signal "@baseboard_fab2_lib.baseboard_fab2(sch_1):jtag_bmc_trst_n"
				( attribute "CDS_PHYS_NET_NAME" "JTAG_BMC_TRST_N"
					( Origin gPackager )
				)
				( objectStatus "JTAG_BMC_TRST_N" )
			)
			( signal "@baseboard_fab2_lib.baseboard_fab2(sch_1):sgpio_bmc_dout"
				( attribute "CDS_PHYS_NET_NAME" "SGPIO_BMC_DOUT"
					( Origin gPackager )
				)
				( objectStatus "SGPIO_BMC_DOUT" )
			)
			( signal "@baseboard_fab2_lib.baseboard_fab2(sch_1):smb_bmc_pmbus_stby_lvc3_sda_r"
				( attribute "CDS_PHYS_NET_NAME" "SMB_BMC_PMBUS_STBY_LVC3_SDA_R"
					( Origin gPackager )
				)
				( objectStatus "SMB_BMC_PMBUS_STBY_LVC3_SDA_R" )
			)
			( signal "@baseboard_fab2_lib.baseboard_fab2(sch_1):smb_lan_stby_lvc3_scl_r"
				( alias ( signalRef "@baseboard_fab2_lib.baseboard_fab2(sch_1):page144_smb_lan_stby_lvc3_scl_r") )
				( attribute "CDS_PHYS_NET_NAME" "SMB_LAN_STBY_LVC3_SCL_R"
					( Origin gPackager )
				)
				( objectStatus "SMB_LAN_STBY_LVC3_SCL_R" )
			)
			( signal "@baseboard_fab2_lib.baseboard_fab2(sch_1):smb_ocp_fru_stby_lvc3_sda_r"
				( attribute "CDS_PHYS_NET_NAME" "SMB_OCP_FRU_STBY_LVC3_SDA_R"
					( Origin gPackager )
				)
				( objectStatus "SMB_OCP_FRU_STBY_LVC3_SDA_R" )
			)
			( signal "@baseboard_fab2_lib.baseboard_fab2(sch_1):smb_ocp_lan_stby_lvc3_sda_r"
				( attribute "CDS_PHYS_NET_NAME" "SMB_OCP_LAN_STBY_LVC3_SDA_R"
					( Origin gPackager )
				)
				( objectStatus "SMB_OCP_LAN_STBY_LVC3_SDA_R" )
			)
			( signal "@baseboard_fab2_lib.baseboard_fab2(sch_1):smb_sensor_bmc_stby_lvc3_scl"
				( attribute "CDS_PHYS_NET_NAME" "SMB_SENSOR_BMC_STBY_LVC3_SCL"
					( Origin gPackager )
				)
				( attribute "PHYS_NET_NAME" "SMB_SENSOR_BMC_STBY_LVC3_SCL"
					( Origin gPackager )
				)
				( objectStatus "SMB_SENSOR_BMC_STBY_LVC3_SCL" )
			)
			( signal "@baseboard_fab2_lib.baseboard_fab2(sch_1):smb_sensor_bmc_stby_lvc3_sda"
				( attribute "CDS_PHYS_NET_NAME" "SMB_SENSOR_BMC_STBY_LVC3_SDA"
					( Origin gPackager )
				)
				( attribute "PHYS_NET_NAME" "SMB_SENSOR_BMC_STBY_LVC3_SDA"
					( Origin gPackager )
				)
				( objectStatus "SMB_SENSOR_BMC_STBY_LVC3_SDA" )
			)
			( signal "@baseboard_fab2_lib.baseboard_fab2(sch_1):fm_heartbeat_led_k"
				( attribute "CDS_PHYS_NET_NAME" "FM_HEARTBEAT_LED_K"
					( Origin gPackager )
				)
				( objectStatus "FM_HEARTBEAT_LED_K" )
			)
			( signal "@baseboard_fab2_lib.baseboard_fab2(sch_1):bmc_m_dqs1_dn"
				( attribute "CDS_PHYS_NET_NAME" "BMC_M_DQS1_DN"
					( Origin gPackager )
				)
				( objectStatus "BMC_M_DQS1_DN" )
			)
			( signal "@baseboard_fab2_lib.baseboard_fab2(sch_1):smb_slotx24_stby_lvc3_scl_r"
				( alias ( signalRef "@baseboard_fab2_lib.baseboard_fab2(sch_1):page144_smb_slotx24_stby_lvc3_scl_r") )
				( attribute "CDS_PHYS_NET_NAME" "SMB_SLOTX24_STBY_LVC3_SCL_R"
					( Origin gPackager )
				)
				( objectStatus "SMB_SLOTX24_STBY_LVC3_SCL_R" )
			)
			( signal "@baseboard_fab2_lib.baseboard_fab2(sch_1):smb_slotx24_stby_lvc3_sda_r"
				( alias ( signalRef "@baseboard_fab2_lib.baseboard_fab2(sch_1):page144_smb_slotx24_stby_lvc3_sda_r") )
				( attribute "CDS_PHYS_NET_NAME" "SMB_SLOTX24_STBY_LVC3_SDA_R"
					( Origin gPackager )
				)
				( objectStatus "SMB_SLOTX24_STBY_LVC3_SDA_R" )
			)
			( signal "@baseboard_fab2_lib.baseboard_fab2(sch_1):smb_smlink0_stby_lvc3_scl_r"
				( attribute "CDS_PHYS_NET_NAME" "SMB_SMLINK0_STBY_LVC3_SCL_R"
					( Origin gPackager )
				)
				( attribute "PHYS_NET_NAME" "SMB_SMLINK0_STBY_LVC3_SCL_R"
					( Origin gPackager )
				)
				( objectStatus "SMB_SMLINK0_STBY_LVC3_SCL_R" )
			)
			( signal "@baseboard_fab2_lib.baseboard_fab2(sch_1):p2v5_aux_bmc"
				( alias ( signalRef "@baseboard_fab2_lib.baseboard_fab2(sch_1):page239_p2v5_aux_bmc") )
				( alias ( signalRef "@baseboard_fab2_lib.baseboard_fab2(sch_1):page151_p2v5_aux_bmc") )
				( attribute "CDS_PHYS_NET_NAME" "P2V5_AUX_BMC"
					( Origin gPackager )
				)
				( objectStatus "P2V5_AUX_BMC" )
			)
			( signal "@baseboard_fab2_lib.baseboard_fab2(sch_1):page239_p2v5_aux_bmc"
				( objectFlag fObjectAlias )
				( objectStatus "page239_p2v5_aux_bmc" )
			)
			( signal "@baseboard_fab2_lib.baseboard_fab2(sch_1):page151_p2v5_aux_bmc"
				( objectFlag fObjectAlias )
				( objectStatus "page151_p2v5_aux_bmc" )
			)
			( signal "@baseboard_fab2_lib.baseboard_fab2(sch_1):smb_smlink0_stby_lvc3_sda_r"
				( attribute "CDS_PHYS_NET_NAME" "SMB_SMLINK0_STBY_LVC3_SDA_R"
					( Origin gPackager )
				)
				( attribute "PHYS_NET_NAME" "SMB_SMLINK0_STBY_LVC3_SDA_R"
					( Origin gPackager )
				)
				( objectStatus "SMB_SMLINK0_STBY_LVC3_SDA_R" )
			)
			( signal "@baseboard_fab2_lib.baseboard_fab2(sch_1):smb_vr_stby_lvc3_scl_r"
				( attribute "CDS_PHYS_NET_NAME" "SMB_VR_STBY_LVC3_SCL_R"
					( Origin gPackager )
				)
				( attribute "PHYS_NET_NAME" "SMB_VR_STBY_LVC3_SCL_R"
					( Origin gPackager )
				)
				( objectStatus "SMB_VR_STBY_LVC3_SCL_R" )
			)
			( signal "@baseboard_fab2_lib.baseboard_fab2(sch_1):smb_vr_stby_lvc3_sda_r"
				( attribute "CDS_PHYS_NET_NAME" "SMB_VR_STBY_LVC3_SDA_R"
					( Origin gPackager )
				)
				( attribute "PHYS_NET_NAME" "SMB_VR_STBY_LVC3_SDA_R"
					( Origin gPackager )
				)
				( objectStatus "SMB_VR_STBY_LVC3_SDA_R" )
			)
			( signal "@baseboard_fab2_lib.baseboard_fab2(sch_1):spi_bmc_clk"
				( attribute "CDS_PHYS_NET_NAME" "SPI_BMC_CLK"
					( Origin gPackager )
				)
				( objectStatus "SPI_BMC_CLK" )
			)
			( signal "@baseboard_fab2_lib.baseboard_fab2(sch_1):spi_bmc_cs0_n"
				( attribute "CDS_PHYS_NET_NAME" "SPI_BMC_CS0_N"
					( Origin gPackager )
				)
				( objectStatus "SPI_BMC_CS0_N" )
			)
			( signal "@baseboard_fab2_lib.baseboard_fab2(sch_1):spi_bmc_di"
				( attribute "CDS_PHYS_NET_NAME" "SPI_BMC_DI"
					( Origin gPackager )
				)
				( objectStatus "SPI_BMC_DI" )
			)
			( signal "@baseboard_fab2_lib.baseboard_fab2(sch_1):spi_bmc_do"
				( alias ( signalRef "@baseboard_fab2_lib.baseboard_fab2(sch_1):page144_spi_bmc_do") )
				( attribute "CDS_PHYS_NET_NAME" "SPI_BMC_DO"
					( Origin gPackager )
				)
				( objectStatus "SPI_BMC_DO" )
			)
			( signal "@baseboard_fab2_lib.baseboard_fab2(sch_1):page144_spi_bmc_do"
				( attribute "CDS_PHYS_NET_NAME" "SPI_BMC_DO"
					( Origin gPackager )
				)
				( objectFlag fObjectAlias )
				( objectStatus "page144_spi_bmc_do" )
			)
			( signal "@baseboard_fab2_lib.baseboard_fab2(sch_1):fm_bmc_onctl_n"
				( attribute "CDS_PHYS_NET_NAME" "FM_BMC_ONCTL_N"
					( Origin gPackager )
				)
				( objectStatus "FM_BMC_ONCTL_N" )
			)
			( signal "@baseboard_fab2_lib.baseboard_fab2(sch_1):fm_bmc_pwrbtn_out_n"
				( attribute "CDS_PHYS_NET_NAME" "FM_BMC_PWRBTN_OUT_N"
					( Origin gPackager )
				)
				( attribute "PHYS_NET_NAME" "FM_BMC_PWRBTN_OUT_N"
					( Origin gPackager )
				)
				( objectStatus "FM_BMC_PWRBTN_OUT_N" )
			)
			( signal "@baseboard_fab2_lib.baseboard_fab2(sch_1):h_cpu0_memabc_memhot_lvt3_bmc_n"
				( attribute "CDS_PHYS_NET_NAME" "H_CPU0_MEMABC_MEMHOT_LVT3_BMC_N"
					( Origin gPackager )
				)
				( attribute "PHYS_NET_NAME" "H_CPU0_MEMABC_MEMHOT_LVT3_BMC_N"
					( Origin gPackager )
				)
				( objectStatus "H_CPU0_MEMABC_MEMHOT_LVT3_BMC_N" )
			)
			( signal "@baseboard_fab2_lib.baseboard_fab2(sch_1):h_cpu0_memdef_memhot_lvt3_bmc_n"
				( attribute "CDS_PHYS_NET_NAME" "H_CPU0_MEMDEF_MEMHOT_LVT3_BMC_N"
					( Origin gPackager )
				)
				( attribute "PHYS_NET_NAME" "H_CPU0_MEMDEF_MEMHOT_LVT3_BMC_N"
					( Origin gPackager )
				)
				( objectStatus "H_CPU0_MEMDEF_MEMHOT_LVT3_BMC_N" )
			)
			( signal "@baseboard_fab2_lib.baseboard_fab2(sch_1):fm_cpu1_fivr_fault_lvt3_r_n"
				( attribute "CDS_PHYS_NET_NAME" "FM_CPU1_FIVR_FAULT_LVT3_R_N"
					( Origin gPackager )
				)
				( objectStatus "FM_CPU1_FIVR_FAULT_LVT3_R_N" )
			)
			( signal "@baseboard_fab2_lib.baseboard_fab2(sch_1):h_cpu1_memghj_memhot_lvt3_bmc_n"
				( attribute "CDS_PHYS_NET_NAME" "H_CPU1_MEMGHJ_MEMHOT_LVT3_BMC_N"
					( Origin gPackager )
				)
				( attribute "PHYS_NET_NAME" "H_CPU1_MEMGHJ_MEMHOT_LVT3_BMC_N"
					( Origin gPackager )
				)
				( objectStatus "H_CPU1_MEMGHJ_MEMHOT_LVT3_BMC_N" )
			)
			( signal "@baseboard_fab2_lib.baseboard_fab2(sch_1):fm_cpu0_fivr_fault_lvt3_r_n"
				( attribute "CDS_PHYS_NET_NAME" "FM_CPU0_FIVR_FAULT_LVT3_R_N"
					( Origin gPackager )
				)
				( objectStatus "FM_CPU0_FIVR_FAULT_LVT3_R_N" )
			)
			( signal "@baseboard_fab2_lib.baseboard_fab2(sch_1):h_cpu1_memklm_memhot_lvt3_bmc_n"
				( attribute "CDS_PHYS_NET_NAME" "H_CPU1_MEMKLM_MEMHOT_LVT3_BMC_N"
					( Origin gPackager )
				)
				( attribute "PHYS_NET_NAME" "H_CPU1_MEMKLM_MEMHOT_LVT3_BMC_N"
					( Origin gPackager )
				)
				( objectStatus "H_CPU1_MEMKLM_MEMHOT_LVT3_BMC_N" )
			)
			( signal "@baseboard_fab2_lib.baseboard_fab2(sch_1):p2e_ssb_bmc_rx_dn"
				( attribute "CDS_PHYS_NET_NAME" "P2E_SSB_BMC_RX_DN"
					( Origin gPackager )
				)
				( objectStatus "P2E_SSB_BMC_RX_DN" )
			)
			( signal "@baseboard_fab2_lib.baseboard_fab2(sch_1):clk_24m_bmc_clkin_r"
				( attribute "CDS_PHYS_NET_NAME" "CLK_24M_BMC_CLKIN_R"
					( Origin gPackager )
				)
				( objectStatus "CLK_24M_BMC_CLKIN_R" )
			)
			( signal "@baseboard_fab2_lib.baseboard_fab2(sch_1):uart_bmc_txd5"
				( attribute "CDS_PHYS_NET_NAME" "UART_BMC_TXD5"
					( Origin gPackager )
				)
				( attribute "PHYS_NET_NAME" "UART_BMC_TXD5"
					( Origin gPackager )
				)
				( objectStatus "UART_BMC_TXD5" )
			)
			( signal "@baseboard_fab2_lib.baseboard_fab2(sch_1):tp_tpm_spi_4"
				( attribute "CDS_PHYS_NET_NAME" "TP_TPM_SPI_4"
					( Origin gPackager )
				)
				( objectStatus "TP_TPM_SPI_4" )
			)
			( signal "@baseboard_fab2_lib.baseboard_fab2(sch_1):tp_tpm_spi_1"
				( attribute "CDS_PHYS_NET_NAME" "TP_TPM_SPI_1"
					( Origin gPackager )
				)
				( objectStatus "TP_TPM_SPI_1" )
			)
			( signal "@baseboard_fab2_lib.baseboard_fab2(sch_1):tp_tpm_spi_0"
				( attribute "CDS_PHYS_NET_NAME" "TP_TPM_SPI_0"
					( Origin gPackager )
				)
				( objectStatus "TP_TPM_SPI_0" )
			)
			( signal "@baseboard_fab2_lib.baseboard_fab2(sch_1):pu_tpm_spi_flash_reset_2_n"
				( attribute "CDS_PHYS_NET_NAME" "PU_TPM_SPI_FLASH_RESET_2_N"
					( Origin gPackager )
				)
				( objectStatus "PU_TPM_SPI_FLASH_RESET_2_N" )
			)
			( signal "@baseboard_fab2_lib.baseboard_fab2(sch_1):p3v3_usb2a_alg"
				( alias ( signalRef "@baseboard_fab2_lib.baseboard_fab2(sch_1):page148_p3v3_usb2a_alg") )
				( alias ( signalRef "@baseboard_fab2_lib.baseboard_fab2(sch_1):page149_p3v3_usb2a_alg") )
				( attribute "CDS_PHYS_NET_NAME" "P3V3_USB2A_ALG"
					( Origin gPackager )
				)
				( objectStatus "P3V3_USB2A_ALG" )
			)
			( signal "@baseboard_fab2_lib.baseboard_fab2(sch_1):spi_bmc_bt_do_r"
				( attribute "CDS_PHYS_NET_NAME" "SPI_BMC_BT_DO_R"
					( Origin gPackager )
				)
				( objectStatus "SPI_BMC_BT_DO_R" )
			)
			( signal "@baseboard_fab2_lib.baseboard_fab2(sch_1):bmc_zq"
				( attribute "CDS_PHYS_NET_NAME" "BMC_ZQ"
					( Origin gPackager )
				)
				( objectStatus "BMC_ZQ" )
			)
			( signal "@baseboard_fab2_lib.baseboard_fab2(sch_1):vcc_adcav3v3"
				( alias ( signalRef "@baseboard_fab2_lib.baseboard_fab2(sch_1):page147_vcc_adcav3v3") )
				( alias ( signalRef "@baseboard_fab2_lib.baseboard_fab2(sch_1):page148_vcc_adcav3v3") )
				( alias ( signalRef "@baseboard_fab2_lib.baseboard_fab2(sch_1):page149_vcc_adcav3v3") )
				( attribute "CDS_PHYS_NET_NAME" "VCC_ADCAV3V3"
					( Origin gPackager )
				)
				( attribute "VOLTAGE" "+3.3V"
					( Units "uVoltage" "V" 1.000000)
					( Status sAliasFlattened )
					( Origin gFrontEnd )
				)
				( objectStatus "VCC_ADCAV3V3" )
			)
			( signal "@baseboard_fab2_lib.baseboard_fab2(sch_1):page148_vcc_adcav3v3"
				( objectFlag fObjectAlias )
				( objectStatus "page148_vcc_adcav3v3" )
			)
			( signal "@baseboard_fab2_lib.baseboard_fab2(sch_1):bmc_m_par"
				( attribute "CDS_PHYS_NET_NAME" "BMC_M_PAR"
					( Origin gPackager )
				)
				( objectStatus "BMC_M_PAR" )
			)
			( signal "@baseboard_fab2_lib.baseboard_fab2(sch_1):h_cpu0_abc_memhot_lvt3_r_n"
				( attribute "CDS_PHYS_NET_NAME" "H_CPU0_ABC_MEMHOT_LVT3_R_N"
					( Origin gPackager )
				)
				( objectStatus "H_CPU0_ABC_MEMHOT_LVT3_R_N" )
			)
			( signal "@baseboard_fab2_lib.baseboard_fab2(sch_1):h_cpu0_def_memhot_lvt3_r_n"
				( attribute "CDS_PHYS_NET_NAME" "H_CPU0_DEF_MEMHOT_LVT3_R_N"
					( Origin gPackager )
				)
				( objectStatus "H_CPU0_DEF_MEMHOT_LVT3_R_N" )
			)
			( signal "@baseboard_fab2_lib.baseboard_fab2(sch_1):h_cpu0_memabc_memhot_g_pch_n"
				( attribute "CDS_PHYS_NET_NAME" "H_CPU0_MEMABC_MEMHOT_G_PCH_N"
					( Origin gPackager )
				)
				( objectStatus "H_CPU0_MEMABC_MEMHOT_G_PCH_N" )
			)
			( signal "@baseboard_fab2_lib.baseboard_fab2(sch_1):h_cpu0_memabc_memhot_g_r_n"
				( attribute "CDS_PHYS_NET_NAME" "H_CPU0_MEMABC_MEMHOT_G_R_N"
					( Origin gPackager )
				)
				( objectStatus "H_CPU0_MEMABC_MEMHOT_G_R_N" )
			)
			( signal "@baseboard_fab2_lib.baseboard_fab2(sch_1):h_cpu0_memabc_memhot_lvt3_k_n"
				( attribute "CDS_PHYS_NET_NAME" "H_CPU0_MEMABC_MEMHOT_LVT3_K_N"
					( Origin gPackager )
				)
				( objectStatus "H_CPU0_MEMABC_MEMHOT_LVT3_K_N" )
			)
			( signal "@baseboard_fab2_lib.baseboard_fab2(sch_1):h_cpu0_memabc_memhot_lvt3_n"
				( attribute "CDS_PHYS_NET_NAME" "H_CPU0_MEMABC_MEMHOT_LVT3_N"
					( Origin gPackager )
				)
				( objectStatus "H_CPU0_MEMABC_MEMHOT_LVT3_N" )
			)
			( signal "@baseboard_fab2_lib.baseboard_fab2(sch_1):h_cpu0_memdef_memhot_g_pch_n"
				( attribute "CDS_PHYS_NET_NAME" "H_CPU0_MEMDEF_MEMHOT_G_PCH_N"
					( Origin gPackager )
				)
				( objectStatus "H_CPU0_MEMDEF_MEMHOT_G_PCH_N" )
			)
			( signal "@baseboard_fab2_lib.baseboard_fab2(sch_1):h_cpu0_memdef_memhot_g_r_n"
				( attribute "CDS_PHYS_NET_NAME" "H_CPU0_MEMDEF_MEMHOT_G_R_N"
					( Origin gPackager )
				)
				( objectStatus "H_CPU0_MEMDEF_MEMHOT_G_R_N" )
			)
			( signal "@baseboard_fab2_lib.baseboard_fab2(sch_1):h_cpu0_memdef_memhot_lvt3_k_n"
				( attribute "CDS_PHYS_NET_NAME" "H_CPU0_MEMDEF_MEMHOT_LVT3_K_N"
					( Origin gPackager )
				)
				( objectStatus "H_CPU0_MEMDEF_MEMHOT_LVT3_K_N" )
			)
			( signal "@baseboard_fab2_lib.baseboard_fab2(sch_1):h_cpu0_memdef_memhot_lvt3_n"
				( attribute "CDS_PHYS_NET_NAME" "H_CPU0_MEMDEF_MEMHOT_LVT3_N"
					( Origin gPackager )
				)
				( objectStatus "H_CPU0_MEMDEF_MEMHOT_LVT3_N" )
			)
			( signal "@baseboard_fab2_lib.baseboard_fab2(sch_1):h_cpu1_ghj_memhot_lvt3_r_n"
				( attribute "CDS_PHYS_NET_NAME" "H_CPU1_GHJ_MEMHOT_LVT3_R_N"
					( Origin gPackager )
				)
				( objectStatus "H_CPU1_GHJ_MEMHOT_LVT3_R_N" )
			)
			( signal "@baseboard_fab2_lib.baseboard_fab2(sch_1):h_cpu1_klm_memhot_lvt3_r_n"
				( attribute "CDS_PHYS_NET_NAME" "H_CPU1_KLM_MEMHOT_LVT3_R_N"
					( Origin gPackager )
				)
				( objectStatus "H_CPU1_KLM_MEMHOT_LVT3_R_N" )
			)
			( signal "@baseboard_fab2_lib.baseboard_fab2(sch_1):h_cpu1_memghj_memhot_g_pch_n"
				( attribute "CDS_PHYS_NET_NAME" "H_CPU1_MEMGHJ_MEMHOT_G_PCH_N"
					( Origin gPackager )
				)
				( objectStatus "H_CPU1_MEMGHJ_MEMHOT_G_PCH_N" )
			)
			( signal "@baseboard_fab2_lib.baseboard_fab2(sch_1):h_cpu1_memghj_memhot_g_r_n"
				( attribute "CDS_PHYS_NET_NAME" "H_CPU1_MEMGHJ_MEMHOT_G_R_N"
					( Origin gPackager )
				)
				( objectStatus "H_CPU1_MEMGHJ_MEMHOT_G_R_N" )
			)
			( signal "@baseboard_fab2_lib.baseboard_fab2(sch_1):h_cpu1_memghj_memhot_lvt3_k_n"
				( attribute "CDS_PHYS_NET_NAME" "H_CPU1_MEMGHJ_MEMHOT_LVT3_K_N"
					( Origin gPackager )
				)
				( objectStatus "H_CPU1_MEMGHJ_MEMHOT_LVT3_K_N" )
			)
			( signal "@baseboard_fab2_lib.baseboard_fab2(sch_1):h_cpu1_memghj_memhot_lvt3_n"
				( attribute "CDS_PHYS_NET_NAME" "H_CPU1_MEMGHJ_MEMHOT_LVT3_N"
					( Origin gPackager )
				)
				( objectStatus "H_CPU1_MEMGHJ_MEMHOT_LVT3_N" )
			)
			( signal "@baseboard_fab2_lib.baseboard_fab2(sch_1):h_cpu1_memklm_memhot_g_pch_n"
				( attribute "CDS_PHYS_NET_NAME" "H_CPU1_MEMKLM_MEMHOT_G_PCH_N"
					( Origin gPackager )
				)
				( objectStatus "H_CPU1_MEMKLM_MEMHOT_G_PCH_N" )
			)
			( signal "@baseboard_fab2_lib.baseboard_fab2(sch_1):h_cpu1_memklm_memhot_g_r_n"
				( attribute "CDS_PHYS_NET_NAME" "H_CPU1_MEMKLM_MEMHOT_G_R_N"
					( Origin gPackager )
				)
				( objectStatus "H_CPU1_MEMKLM_MEMHOT_G_R_N" )
			)
			( signal "@baseboard_fab2_lib.baseboard_fab2(sch_1):h_cpu1_memklm_memhot_lvt3_k_n"
				( attribute "CDS_PHYS_NET_NAME" "H_CPU1_MEMKLM_MEMHOT_LVT3_K_N"
					( Origin gPackager )
				)
				( objectStatus "H_CPU1_MEMKLM_MEMHOT_LVT3_K_N" )
			)
			( signal "@baseboard_fab2_lib.baseboard_fab2(sch_1):h_cpu1_memklm_memhot_lvt3_n"
				( attribute "CDS_PHYS_NET_NAME" "H_CPU1_MEMKLM_MEMHOT_LVT3_N"
					( Origin gPackager )
				)
				( objectStatus "H_CPU1_MEMKLM_MEMHOT_LVT3_N" )
			)
			( signal "@baseboard_fab2_lib.baseboard_fab2(sch_1):p0v7_gtl2014_2"
				( alias ( signalRef "@baseboard_fab2_lib.baseboard_fab2(sch_1):page152_p0v7_gtl2014_2") )
				( attribute "VOLTAGE" "+0.7"
					( Units "uVoltage" "V" 1.000000)
					( Status sAliasFlattened )
					( Origin gFrontEnd )
				)
				( attribute "CDS_PHYS_NET_NAME" "P0V7_GTL2014_2"
					( Origin gPackager )
				)
				( objectStatus "P0V7_GTL2014_2" )
			)
			( signal "@baseboard_fab2_lib.baseboard_fab2(sch_1):page152_p0v7_gtl2014_2"
				( attribute "VOLTAGE" "+0.7"
					( Units "uVoltage" "V" 1.000000)
					( Origin gFrontEnd )
				)
				( objectFlag fObjectAlias )
				( objectStatus "page152_p0v7_gtl2014_2" )
			)
			( signal "@baseboard_fab2_lib.baseboard_fab2(sch_1):pd_dir_2"
				( attribute "CDS_PHYS_NET_NAME" "PD_DIR_2"
					( Origin gPackager )
				)
				( objectStatus "PD_DIR_2" )
			)
			( signal "@baseboard_fab2_lib.baseboard_fab2(sch_1):pu_bios_spi_hold0_n"
				( attribute "CDS_PHYS_NET_NAME" "PU_BIOS_SPI_HOLD0_N"
					( Origin gPackager )
				)
				( objectStatus "PU_BIOS_SPI_HOLD0_N" )
			)
			( signal "@baseboard_fab2_lib.baseboard_fab2(sch_1):pu_bios_spi_hold1_n"
				( attribute "CDS_PHYS_NET_NAME" "PU_BIOS_SPI_HOLD1_N"
					( Origin gPackager )
				)
				( objectStatus "PU_BIOS_SPI_HOLD1_N" )
			)
			( signal "@baseboard_fab2_lib.baseboard_fab2(sch_1):pu_bios_spi_wp0_n"
				( attribute "CDS_PHYS_NET_NAME" "PU_BIOS_SPI_WP0_N"
					( Origin gPackager )
				)
				( objectStatus "PU_BIOS_SPI_WP0_N" )
			)
			( signal "@baseboard_fab2_lib.baseboard_fab2(sch_1):pu_bios_spi_wp1_n"
				( attribute "CDS_PHYS_NET_NAME" "PU_BIOS_SPI_WP1_N"
					( Origin gPackager )
				)
				( objectStatus "PU_BIOS_SPI_WP1_N" )
			)
			( signal "@baseboard_fab2_lib.baseboard_fab2(sch_1):pu_spi0_rst"
				( attribute "CDS_PHYS_NET_NAME" "PU_SPI0_RST"
					( Origin gPackager )
				)
				( objectStatus "PU_SPI0_RST" )
			)
			( signal "@baseboard_fab2_lib.baseboard_fab2(sch_1):pu_spi1_rst"
				( attribute "CDS_PHYS_NET_NAME" "PU_SPI1_RST"
					( Origin gPackager )
				)
				( objectStatus "PU_SPI1_RST" )
			)
			( signal "@baseboard_fab2_lib.baseboard_fab2(sch_1):spi_bios_socket_io2"
				( attribute "CDS_PHYS_NET_NAME" "SPI_BIOS_SOCKET_IO2"
					( Origin gPackager )
				)
				( objectStatus "SPI_BIOS_SOCKET_IO2" )
			)
			( signal "@baseboard_fab2_lib.baseboard_fab2(sch_1):spi_bios_socket_io3"
				( attribute "CDS_PHYS_NET_NAME" "SPI_BIOS_SOCKET_IO3"
					( Origin gPackager )
				)
				( objectStatus "SPI_BIOS_SOCKET_IO3" )
			)
			( signal "@baseboard_fab2_lib.baseboard_fab2(sch_1):spi_clk_r0"
				( attribute "CDS_PHYS_NET_NAME" "SPI_CLK_R0"
					( Origin gPackager )
				)
				( objectStatus "SPI_CLK_R0" )
			)
			( signal "@baseboard_fab2_lib.baseboard_fab2(sch_1):spi_clk_r1"
				( attribute "CDS_PHYS_NET_NAME" "SPI_CLK_R1"
					( Origin gPackager )
				)
				( objectStatus "SPI_CLK_R1" )
			)
			( signal "@baseboard_fab2_lib.baseboard_fab2(sch_1):spi_cs0_primary_r_n"
				( attribute "CDS_PHYS_NET_NAME" "SPI_CS0_PRIMARY_R_N"
					( Origin gPackager )
				)
				( objectStatus "SPI_CS0_PRIMARY_R_N" )
			)
			( signal "@baseboard_fab2_lib.baseboard_fab2(sch_1):spi_cs0_secondary_r_n"
				( attribute "CDS_PHYS_NET_NAME" "SPI_CS0_SECONDARY_R_N"
					( Origin gPackager )
				)
				( objectStatus "SPI_CS0_SECONDARY_R_N" )
			)
			( signal "@baseboard_fab2_lib.baseboard_fab2(sch_1):spi_miso_r0"
				( attribute "CDS_PHYS_NET_NAME" "SPI_MISO_R0"
					( Origin gPackager )
				)
				( objectStatus "SPI_MISO_R0" )
			)
			( signal "@baseboard_fab2_lib.baseboard_fab2(sch_1):spi_miso_r1"
				( attribute "CDS_PHYS_NET_NAME" "SPI_MISO_R1"
					( Origin gPackager )
				)
				( objectStatus "SPI_MISO_R1" )
			)
			( signal "@baseboard_fab2_lib.baseboard_fab2(sch_1):spi_switch_clk"
				( attribute "CDS_PHYS_NET_NAME" "SPI_SWITCH_CLK"
					( Origin gPackager )
				)
				( objectStatus "SPI_SWITCH_CLK" )
			)
			( signal "@baseboard_fab2_lib.baseboard_fab2(sch_1):spi_switch_miso"
				( attribute "CDS_PHYS_NET_NAME" "SPI_SWITCH_MISO"
					( Origin gPackager )
				)
				( objectStatus "SPI_SWITCH_MISO" )
			)
			( signal "@baseboard_fab2_lib.baseboard_fab2(sch_1):spi_switch_mosi"
				( attribute "CDS_PHYS_NET_NAME" "SPI_SWITCH_MOSI"
					( Origin gPackager )
				)
				( objectStatus "SPI_SWITCH_MOSI" )
			)
			( signal "@baseboard_fab2_lib.baseboard_fab2(sch_1):spi_switch_mosi_r0"
				( attribute "CDS_PHYS_NET_NAME" "SPI_SWITCH_MOSI_R0"
					( Origin gPackager )
				)
				( objectStatus "SPI_SWITCH_MOSI_R0" )
			)
			( signal "@baseboard_fab2_lib.baseboard_fab2(sch_1):spi_switch_mosi_r1"
				( attribute "CDS_PHYS_NET_NAME" "SPI_SWITCH_MOSI_R1"
					( Origin gPackager )
				)
				( objectStatus "SPI_SWITCH_MOSI_R1" )
			)
			( signal "@baseboard_fab2_lib.baseboard_fab2(sch_1):tp_spi_0_0"
				( attribute "CDS_PHYS_NET_NAME" "TP_SPI_0_0"
					( Origin gPackager )
				)
				( objectStatus "TP_SPI_0_0" )
			)
			( signal "@baseboard_fab2_lib.baseboard_fab2(sch_1):tp_spi_0_1"
				( attribute "CDS_PHYS_NET_NAME" "TP_SPI_0_1"
					( Origin gPackager )
				)
				( objectStatus "TP_SPI_0_1" )
			)
			( signal "@baseboard_fab2_lib.baseboard_fab2(sch_1):tp_spi_0_2"
				( attribute "CDS_PHYS_NET_NAME" "TP_SPI_0_2"
					( Origin gPackager )
				)
				( objectStatus "TP_SPI_0_2" )
			)
			( signal "@baseboard_fab2_lib.baseboard_fab2(sch_1):tp_spi_0_3"
				( attribute "CDS_PHYS_NET_NAME" "TP_SPI_0_3"
					( Origin gPackager )
				)
				( objectStatus "TP_SPI_0_3" )
			)
			( signal "@baseboard_fab2_lib.baseboard_fab2(sch_1):tp_spi_0_4"
				( attribute "CDS_PHYS_NET_NAME" "TP_SPI_0_4"
					( Origin gPackager )
				)
				( objectStatus "TP_SPI_0_4" )
			)
			( signal "@baseboard_fab2_lib.baseboard_fab2(sch_1):tp_spi_0_5"
				( attribute "CDS_PHYS_NET_NAME" "TP_SPI_0_5"
					( Origin gPackager )
				)
				( objectStatus "TP_SPI_0_5" )
			)
			( signal "@baseboard_fab2_lib.baseboard_fab2(sch_1):tp_spi_0_6"
				( attribute "CDS_PHYS_NET_NAME" "TP_SPI_0_6"
					( Origin gPackager )
				)
				( objectStatus "TP_SPI_0_6" )
			)
			( signal "@baseboard_fab2_lib.baseboard_fab2(sch_1):tp_spi_1_0"
				( attribute "CDS_PHYS_NET_NAME" "TP_SPI_1_0"
					( Origin gPackager )
				)
				( objectStatus "TP_SPI_1_0" )
			)
			( signal "@baseboard_fab2_lib.baseboard_fab2(sch_1):tp_spi_1_1"
				( attribute "CDS_PHYS_NET_NAME" "TP_SPI_1_1"
					( Origin gPackager )
				)
				( objectStatus "TP_SPI_1_1" )
			)
			( signal "@baseboard_fab2_lib.baseboard_fab2(sch_1):tp_spi_1_2"
				( attribute "CDS_PHYS_NET_NAME" "TP_SPI_1_2"
					( Origin gPackager )
				)
				( objectStatus "TP_SPI_1_2" )
			)
			( signal "@baseboard_fab2_lib.baseboard_fab2(sch_1):tp_spi_1_3"
				( attribute "CDS_PHYS_NET_NAME" "TP_SPI_1_3"
					( Origin gPackager )
				)
				( objectStatus "TP_SPI_1_3" )
			)
			( signal "@baseboard_fab2_lib.baseboard_fab2(sch_1):tp_spi_1_4"
				( attribute "CDS_PHYS_NET_NAME" "TP_SPI_1_4"
					( Origin gPackager )
				)
				( objectStatus "TP_SPI_1_4" )
			)
			( signal "@baseboard_fab2_lib.baseboard_fab2(sch_1):tp_spi_1_5"
				( attribute "CDS_PHYS_NET_NAME" "TP_SPI_1_5"
					( Origin gPackager )
				)
				( objectStatus "TP_SPI_1_5" )
			)
			( signal "@baseboard_fab2_lib.baseboard_fab2(sch_1):tp_spi_1_6"
				( attribute "CDS_PHYS_NET_NAME" "TP_SPI_1_6"
					( Origin gPackager )
				)
				( objectStatus "TP_SPI_1_6" )
			)
			( signal "@baseboard_fab2_lib.baseboard_fab2(sch_1):fm_dual_bios_sel_n"
				( attribute "CDS_PHYS_NET_NAME" "FM_DUAL_BIOS_SEL_N"
					( Origin gPackager )
				)
				( objectStatus "FM_DUAL_BIOS_SEL_N" )
			)
			( signal "@baseboard_fab2_lib.baseboard_fab2(sch_1):spi_cs0_primary_n"
				( attribute "CDS_PHYS_NET_NAME" "SPI_CS0_PRIMARY_N"
					( Origin gPackager )
				)
				( objectStatus "SPI_CS0_PRIMARY_N" )
			)
			( signal "@baseboard_fab2_lib.baseboard_fab2(sch_1):spi_cs0_secondary_n"
				( attribute "CDS_PHYS_NET_NAME" "SPI_CS0_SECONDARY_N"
					( Origin gPackager )
				)
				( objectStatus "SPI_CS0_SECONDARY_N" )
			)
			( signal "@baseboard_fab2_lib.baseboard_fab2(sch_1):spi_pch_io2_r1"
				( attribute "CDS_PHYS_NET_NAME" "SPI_PCH_IO2_R1"
					( Origin gPackager )
				)
				( objectStatus "SPI_PCH_IO2_R1" )
			)
			( signal "@baseboard_fab2_lib.baseboard_fab2(sch_1):spi_pch_io3_r1"
				( attribute "CDS_PHYS_NET_NAME" "SPI_PCH_IO3_R1"
					( Origin gPackager )
				)
				( objectStatus "SPI_PCH_IO3_R1" )
			)
			( signal "@baseboard_fab2_lib.baseboard_fab2(sch_1):spi_pch_miso_r"
				( attribute "CDS_PHYS_NET_NAME" "SPI_PCH_MISO_R"
					( Origin gPackager )
				)
				( objectStatus "SPI_PCH_MISO_R" )
			)
			( signal "@baseboard_fab2_lib.baseboard_fab2(sch_1):spi_switch_cs0_n"
				( attribute "CDS_PHYS_NET_NAME" "SPI_SWITCH_CS0_N"
					( Origin gPackager )
				)
				( objectStatus "SPI_SWITCH_CS0_N" )
			)
			( signal "@baseboard_fab2_lib.baseboard_fab2(sch_1):tp_spi_switch1_10"
				( attribute "CDS_PHYS_NET_NAME" "TP_SPI_SWITCH1_10"
					( Origin gPackager )
				)
				( objectStatus "TP_SPI_SWITCH1_10" )
			)
			( signal "@baseboard_fab2_lib.baseboard_fab2(sch_1):tp_spi_switch1_11"
				( attribute "CDS_PHYS_NET_NAME" "TP_SPI_SWITCH1_11"
					( Origin gPackager )
				)
				( objectStatus "TP_SPI_SWITCH1_11" )
			)
			( signal "@baseboard_fab2_lib.baseboard_fab2(sch_1):tp_spi_switch1_12"
				( attribute "CDS_PHYS_NET_NAME" "TP_SPI_SWITCH1_12"
					( Origin gPackager )
				)
				( objectStatus "TP_SPI_SWITCH1_12" )
			)
			( signal "@baseboard_fab2_lib.baseboard_fab2(sch_1):tp_spi_switch1_13"
				( attribute "CDS_PHYS_NET_NAME" "TP_SPI_SWITCH1_13"
					( Origin gPackager )
				)
				( objectStatus "TP_SPI_SWITCH1_13" )
			)
			( signal "@baseboard_fab2_lib.baseboard_fab2(sch_1):tp_spi_switch1_14"
				( attribute "CDS_PHYS_NET_NAME" "TP_SPI_SWITCH1_14"
					( Origin gPackager )
				)
				( objectStatus "TP_SPI_SWITCH1_14" )
			)
			( signal "@baseboard_fab2_lib.baseboard_fab2(sch_1):tp_spi_switch1_3"
				( attribute "CDS_PHYS_NET_NAME" "TP_SPI_SWITCH1_3"
					( Origin gPackager )
				)
				( objectStatus "TP_SPI_SWITCH1_3" )
			)
			( signal "@baseboard_fab2_lib.baseboard_fab2(sch_1):tp_spi_switch1_6"
				( attribute "CDS_PHYS_NET_NAME" "TP_SPI_SWITCH1_6"
					( Origin gPackager )
				)
				( objectStatus "TP_SPI_SWITCH1_6" )
			)
			( signal "@baseboard_fab2_lib.baseboard_fab2(sch_1):tp_spi_switch1_9"
				( attribute "CDS_PHYS_NET_NAME" "TP_SPI_SWITCH1_9"
					( Origin gPackager )
				)
				( objectStatus "TP_SPI_SWITCH1_9" )
			)
			( signal "@baseboard_fab2_lib.baseboard_fab2(sch_1):fm_cpld_dbg_pwr_en"
				( attribute "CDS_PHYS_NET_NAME" "FM_CPLD_DBG_PWR_EN"
					( Origin gPackager )
				)
				( objectStatus "FM_CPLD_DBG_PWR_EN" )
			)
			( signal "@baseboard_fab2_lib.baseboard_fab2(sch_1):fm_cpld_dbg_pwr_en_n"
				( attribute "CDS_PHYS_NET_NAME" "FM_CPLD_DBG_PWR_EN_N"
					( Origin gPackager )
				)
				( objectStatus "FM_CPLD_DBG_PWR_EN_N" )
			)
			( signal "@baseboard_fab2_lib.baseboard_fab2(sch_1):fm_cpld_dbg_pwr_en_r_n"
				( attribute "CDS_PHYS_NET_NAME" "FM_CPLD_DBG_PWR_EN_R_N"
					( Origin gPackager )
				)
				( objectStatus "FM_CPLD_DBG_PWR_EN_R_N" )
			)
			( signal "@baseboard_fab2_lib.baseboard_fab2(sch_1):fm_uart_switch_n"
				( attribute "CDS_PHYS_NET_NAME" "FM_UART_SWITCH_N"
					( Origin gPackager )
				)
				( objectStatus "FM_UART_SWITCH_N" )
			)
			( signal "@baseboard_fab2_lib.baseboard_fab2(sch_1):led_postcode_0_r"
				( attribute "CDS_PHYS_NET_NAME" "LED_POSTCODE_0_R"
					( Origin gPackager )
				)
				( objectStatus "LED_POSTCODE_0_R" )
			)
			( signal "@baseboard_fab2_lib.baseboard_fab2(sch_1):led_postcode_1_r"
				( attribute "CDS_PHYS_NET_NAME" "LED_POSTCODE_1_R"
					( Origin gPackager )
				)
				( objectStatus "LED_POSTCODE_1_R" )
			)
			( signal "@baseboard_fab2_lib.baseboard_fab2(sch_1):led_postcode_2_r"
				( attribute "CDS_PHYS_NET_NAME" "LED_POSTCODE_2_R"
					( Origin gPackager )
				)
				( objectStatus "LED_POSTCODE_2_R" )
			)
			( signal "@baseboard_fab2_lib.baseboard_fab2(sch_1):led_postcode_3_r"
				( attribute "CDS_PHYS_NET_NAME" "LED_POSTCODE_3_R"
					( Origin gPackager )
				)
				( objectStatus "LED_POSTCODE_3_R" )
			)
			( signal "@baseboard_fab2_lib.baseboard_fab2(sch_1):led_postcode_4_r"
				( attribute "CDS_PHYS_NET_NAME" "LED_POSTCODE_4_R"
					( Origin gPackager )
				)
				( objectStatus "LED_POSTCODE_4_R" )
			)
			( signal "@baseboard_fab2_lib.baseboard_fab2(sch_1):led_postcode_5_r"
				( attribute "CDS_PHYS_NET_NAME" "LED_POSTCODE_5_R"
					( Origin gPackager )
				)
				( objectStatus "LED_POSTCODE_5_R" )
			)
			( signal "@baseboard_fab2_lib.baseboard_fab2(sch_1):led_postcode_6_r"
				( attribute "CDS_PHYS_NET_NAME" "LED_POSTCODE_6_R"
					( Origin gPackager )
				)
				( objectStatus "LED_POSTCODE_6_R" )
			)
			( signal "@baseboard_fab2_lib.baseboard_fab2(sch_1):led_postcode_7_r"
				( attribute "CDS_PHYS_NET_NAME" "LED_POSTCODE_7_R"
					( Origin gPackager )
				)
				( objectStatus "LED_POSTCODE_7_R" )
			)
			( signal "@baseboard_fab2_lib.baseboard_fab2(sch_1):p12v_stby"
				( alias ( signalRef "@baseboard_fab2_lib.baseboard_fab2(sch_1):page155_p12v_stby") )
				( alias ( signalRef "@baseboard_fab2_lib.baseboard_fab2(sch_1):page169_p12v_stby") )
				( alias ( signalRef "@baseboard_fab2_lib.baseboard_fab2(sch_1):page186_p12v_stby") )
				( alias ( signalRef "@baseboard_fab2_lib.baseboard_fab2(sch_1):page187_p12v_stby") )
				( alias ( signalRef "@baseboard_fab2_lib.baseboard_fab2(sch_1):page188_p12v_stby") )
				( alias ( signalRef "@baseboard_fab2_lib.baseboard_fab2(sch_1):page193_p12v_stby") )
				( alias ( signalRef "@baseboard_fab2_lib.baseboard_fab2(sch_1):page194_p12v_stby") )
				( alias ( signalRef "@baseboard_fab2_lib.baseboard_fab2(sch_1):page195_p12v_stby") )
				( alias ( signalRef "@baseboard_fab2_lib.baseboard_fab2(sch_1):page196_p12v_stby") )
				( alias ( signalRef "@baseboard_fab2_lib.baseboard_fab2(sch_1):page197_p12v_stby") )
				( alias ( signalRef "@baseboard_fab2_lib.baseboard_fab2(sch_1):page198_p12v_stby") )
				( alias ( signalRef "@baseboard_fab2_lib.baseboard_fab2(sch_1):page199_p12v_stby") )
				( alias ( signalRef "@baseboard_fab2_lib.baseboard_fab2(sch_1):page200_p12v_stby") )
				( alias ( signalRef "@baseboard_fab2_lib.baseboard_fab2(sch_1):page204_p12v_stby") )
				( alias ( signalRef "@baseboard_fab2_lib.baseboard_fab2(sch_1):page209_p12v_stby") )
				( alias ( signalRef "@baseboard_fab2_lib.baseboard_fab2(sch_1):page212_p12v_stby") )
				( alias ( signalRef "@baseboard_fab2_lib.baseboard_fab2(sch_1):page217_p12v_stby") )
				( alias ( signalRef "@baseboard_fab2_lib.baseboard_fab2(sch_1):page220_p12v_stby") )
				( alias ( signalRef "@baseboard_fab2_lib.baseboard_fab2(sch_1):page225_p12v_stby") )
				( alias ( signalRef "@baseboard_fab2_lib.baseboard_fab2(sch_1):page228_p12v_stby") )
				( alias ( signalRef "@baseboard_fab2_lib.baseboard_fab2(sch_1):page231_p12v_stby") )
				( alias ( signalRef "@baseboard_fab2_lib.baseboard_fab2(sch_1):page232_p12v_stby") )
				( alias ( signalRef "@baseboard_fab2_lib.baseboard_fab2(sch_1):page233_p12v_stby") )
				( alias ( signalRef "@baseboard_fab2_lib.baseboard_fab2(sch_1):page234_p12v_stby") )
				( alias ( signalRef "@baseboard_fab2_lib.baseboard_fab2(sch_1):page240_p12v_stby") )
				( alias ( signalRef "@baseboard_fab2_lib.baseboard_fab2(sch_1):page241_p12v_stby") )
				( attribute "CDS_PHYS_NET_NAME" "P12V_STBY"
					( Origin gPackager )
				)
				( attribute "VOLTAGE" "12.0V"
					( Units "uVoltage" "V" 1.000000)
					( Status sAliasFlattened )
					( Origin gFrontEnd )
				)
				( objectStatus "P12V_STBY" )
			)
			( signal "@baseboard_fab2_lib.baseboard_fab2(sch_1):page155_p12v_stby"
				( attribute "VOLTAGE" "12.0V"
					( Units "uVoltage" "V" 1.000000)
					( Origin gFrontEnd )
				)
				( objectFlag fObjectAlias )
				( objectStatus "page155_p12v_stby" )
			)
			( signal "@baseboard_fab2_lib.baseboard_fab2(sch_1):page169_p12v_stby"
				( attribute "VOLTAGE" "12.0V"
					( Units "uVoltage" "V" 1.000000)
					( Origin gFrontEnd )
				)
				( objectFlag fObjectAlias )
				( objectStatus "page169_p12v_stby" )
			)
			( signal "@baseboard_fab2_lib.baseboard_fab2(sch_1):page186_p12v_stby"
				( attribute "VOLTAGE" "12.0V"
					( Units "uVoltage" "V" 1.000000)
					( Origin gFrontEnd )
				)
				( objectFlag fObjectAlias )
				( objectStatus "page186_p12v_stby" )
			)
			( signal "@baseboard_fab2_lib.baseboard_fab2(sch_1):page187_p12v_stby"
				( attribute "VOLTAGE" "12.0V"
					( Units "uVoltage" "V" 1.000000)
					( Origin gFrontEnd )
				)
				( objectFlag fObjectAlias )
				( objectStatus "page187_p12v_stby" )
			)
			( signal "@baseboard_fab2_lib.baseboard_fab2(sch_1):page188_p12v_stby"
				( attribute "VOLTAGE" "12.0V"
					( Units "uVoltage" "V" 1.000000)
					( Origin gFrontEnd )
				)
				( objectFlag fObjectAlias )
				( objectStatus "page188_p12v_stby" )
			)
			( signal "@baseboard_fab2_lib.baseboard_fab2(sch_1):page193_p12v_stby"
				( attribute "VOLTAGE" "12.0V"
					( Units "uVoltage" "V" 1.000000)
					( Origin gFrontEnd )
				)
				( objectFlag fObjectAlias )
				( objectStatus "page193_p12v_stby" )
			)
			( signal "@baseboard_fab2_lib.baseboard_fab2(sch_1):page194_p12v_stby"
				( attribute "VOLTAGE" "12.0V"
					( Units "uVoltage" "V" 1.000000)
					( Origin gFrontEnd )
				)
				( objectFlag fObjectAlias )
				( objectStatus "page194_p12v_stby" )
			)
			( signal "@baseboard_fab2_lib.baseboard_fab2(sch_1):page195_p12v_stby"
				( attribute "VOLTAGE" "12.0V"
					( Units "uVoltage" "V" 1.000000)
					( Origin gFrontEnd )
				)
				( objectFlag fObjectAlias )
				( objectStatus "page195_p12v_stby" )
			)
			( signal "@baseboard_fab2_lib.baseboard_fab2(sch_1):page196_p12v_stby"
				( attribute "VOLTAGE" "12.0V"
					( Units "uVoltage" "V" 1.000000)
					( Origin gFrontEnd )
				)
				( objectFlag fObjectAlias )
				( objectStatus "page196_p12v_stby" )
			)
			( signal "@baseboard_fab2_lib.baseboard_fab2(sch_1):page197_p12v_stby"
				( attribute "VOLTAGE" "12.0V"
					( Units "uVoltage" "V" 1.000000)
					( Origin gFrontEnd )
				)
				( objectFlag fObjectAlias )
				( objectStatus "page197_p12v_stby" )
			)
			( signal "@baseboard_fab2_lib.baseboard_fab2(sch_1):page198_p12v_stby"
				( attribute "VOLTAGE" "12.0V"
					( Units "uVoltage" "V" 1.000000)
					( Origin gFrontEnd )
				)
				( objectFlag fObjectAlias )
				( objectStatus "page198_p12v_stby" )
			)
			( signal "@baseboard_fab2_lib.baseboard_fab2(sch_1):page199_p12v_stby"
				( attribute "VOLTAGE" "12.0V"
					( Units "uVoltage" "V" 1.000000)
					( Origin gFrontEnd )
				)
				( objectFlag fObjectAlias )
				( objectStatus "page199_p12v_stby" )
			)
			( signal "@baseboard_fab2_lib.baseboard_fab2(sch_1):page200_p12v_stby"
				( attribute "VOLTAGE" "12.0V"
					( Units "uVoltage" "V" 1.000000)
					( Origin gFrontEnd )
				)
				( objectFlag fObjectAlias )
				( objectStatus "page200_p12v_stby" )
			)
			( signal "@baseboard_fab2_lib.baseboard_fab2(sch_1):page204_p12v_stby"
				( attribute "VOLTAGE" "12.0V"
					( Units "uVoltage" "V" 1.000000)
					( Origin gFrontEnd )
				)
				( objectFlag fObjectAlias )
				( objectStatus "page204_p12v_stby" )
			)
			( signal "@baseboard_fab2_lib.baseboard_fab2(sch_1):page209_p12v_stby"
				( attribute "VOLTAGE" "12.0V"
					( Units "uVoltage" "V" 1.000000)
					( Origin gFrontEnd )
				)
				( objectFlag fObjectAlias )
				( objectStatus "page209_p12v_stby" )
			)
			( signal "@baseboard_fab2_lib.baseboard_fab2(sch_1):page212_p12v_stby"
				( attribute "VOLTAGE" "12.0V"
					( Units "uVoltage" "V" 1.000000)
					( Origin gFrontEnd )
				)
				( objectFlag fObjectAlias )
				( objectStatus "page212_p12v_stby" )
			)
			( signal "@baseboard_fab2_lib.baseboard_fab2(sch_1):page217_p12v_stby"
				( attribute "VOLTAGE" "12.0V"
					( Units "uVoltage" "V" 1.000000)
					( Origin gFrontEnd )
				)
				( objectFlag fObjectAlias )
				( objectStatus "page217_p12v_stby" )
			)
			( signal "@baseboard_fab2_lib.baseboard_fab2(sch_1):page220_p12v_stby"
				( attribute "VOLTAGE" "12.0V"
					( Units "uVoltage" "V" 1.000000)
					( Origin gFrontEnd )
				)
				( objectFlag fObjectAlias )
				( objectStatus "page220_p12v_stby" )
			)
			( signal "@baseboard_fab2_lib.baseboard_fab2(sch_1):page225_p12v_stby"
				( attribute "VOLTAGE" "12.0V"
					( Units "uVoltage" "V" 1.000000)
					( Origin gFrontEnd )
				)
				( objectFlag fObjectAlias )
				( objectStatus "page225_p12v_stby" )
			)
			( signal "@baseboard_fab2_lib.baseboard_fab2(sch_1):page228_p12v_stby"
				( attribute "VOLTAGE" "12.0V"
					( Units "uVoltage" "V" 1.000000)
					( Origin gFrontEnd )
				)
				( objectFlag fObjectAlias )
				( objectStatus "page228_p12v_stby" )
			)
			( signal "@baseboard_fab2_lib.baseboard_fab2(sch_1):page231_p12v_stby"
				( attribute "VOLTAGE" "12.0V"
					( Units "uVoltage" "V" 1.000000)
					( Origin gFrontEnd )
				)
				( objectFlag fObjectAlias )
				( objectStatus "page231_p12v_stby" )
			)
			( signal "@baseboard_fab2_lib.baseboard_fab2(sch_1):page232_p12v_stby"
				( attribute "VOLTAGE" "12.0V"
					( Units "uVoltage" "V" 1.000000)
					( Origin gFrontEnd )
				)
				( objectFlag fObjectAlias )
				( objectStatus "page232_p12v_stby" )
			)
			( signal "@baseboard_fab2_lib.baseboard_fab2(sch_1):page233_p12v_stby"
				( attribute "VOLTAGE" "12.0V"
					( Units "uVoltage" "V" 1.000000)
					( Origin gFrontEnd )
				)
				( objectFlag fObjectAlias )
				( objectStatus "page233_p12v_stby" )
			)
			( signal "@baseboard_fab2_lib.baseboard_fab2(sch_1):page234_p12v_stby"
				( attribute "VOLTAGE" "12.0V"
					( Units "uVoltage" "V" 1.000000)
					( Origin gFrontEnd )
				)
				( objectFlag fObjectAlias )
				( objectStatus "page234_p12v_stby" )
			)
			( signal "@baseboard_fab2_lib.baseboard_fab2(sch_1):page240_p12v_stby"
				( attribute "VOLTAGE" "12.0V"
					( Units "uVoltage" "V" 1.000000)
					( Origin gFrontEnd )
				)
				( objectFlag fObjectAlias )
				( objectStatus "page240_p12v_stby" )
			)
			( signal "@baseboard_fab2_lib.baseboard_fab2(sch_1):page241_p12v_stby"
				( attribute "VOLTAGE" "12.0V"
					( Units "uVoltage" "V" 1.000000)
					( Origin gFrontEnd )
				)
				( objectFlag fObjectAlias )
				( objectStatus "page241_p12v_stby" )
			)
			( signal "@baseboard_fab2_lib.baseboard_fab2(sch_1):spa_mid_dbg1_rx"
				( attribute "CDS_PHYS_NET_NAME" "SPA_MID_DBG1_RX"
					( Origin gPackager )
				)
				( attribute "PHYS_NET_NAME" "SPA_MID_DBG1_RX"
					( Origin gPackager )
				)
				( objectStatus "SPA_MID_DBG1_RX" )
			)
			( signal "@baseboard_fab2_lib.baseboard_fab2(sch_1):p5v_stby"
				( alias ( signalRef "@baseboard_fab2_lib.baseboard_fab2(sch_1):page155_p5v_stby") )
				( alias ( signalRef "@baseboard_fab2_lib.baseboard_fab2(sch_1):page161_p5v_stby") )
				( alias ( signalRef "@baseboard_fab2_lib.baseboard_fab2(sch_1):page169_p5v_stby") )
				( alias ( signalRef "@baseboard_fab2_lib.baseboard_fab2(sch_1):page175_p5v_stby") )
				( alias ( signalRef "@baseboard_fab2_lib.baseboard_fab2(sch_1):page177_p5v_stby") )
				( alias ( signalRef "@baseboard_fab2_lib.baseboard_fab2(sch_1):page186_p5v_stby") )
				( alias ( signalRef "@baseboard_fab2_lib.baseboard_fab2(sch_1):page193_p5v_stby") )
				( alias ( signalRef "@baseboard_fab2_lib.baseboard_fab2(sch_1):page194_p5v_stby") )
				( alias ( signalRef "@baseboard_fab2_lib.baseboard_fab2(sch_1):page198_p5v_stby") )
				( alias ( signalRef "@baseboard_fab2_lib.baseboard_fab2(sch_1):page202_p5v_stby") )
				( alias ( signalRef "@baseboard_fab2_lib.baseboard_fab2(sch_1):page203_p5v_stby") )
				( alias ( signalRef "@baseboard_fab2_lib.baseboard_fab2(sch_1):page204_p5v_stby") )
				( alias ( signalRef "@baseboard_fab2_lib.baseboard_fab2(sch_1):page205_p5v_stby") )
				( alias ( signalRef "@baseboard_fab2_lib.baseboard_fab2(sch_1):page207_p5v_stby") )
				( alias ( signalRef "@baseboard_fab2_lib.baseboard_fab2(sch_1):page208_p5v_stby") )
				( alias ( signalRef "@baseboard_fab2_lib.baseboard_fab2(sch_1):page209_p5v_stby") )
				( alias ( signalRef "@baseboard_fab2_lib.baseboard_fab2(sch_1):page210_p5v_stby") )
				( alias ( signalRef "@baseboard_fab2_lib.baseboard_fab2(sch_1):page212_p5v_stby") )
				( alias ( signalRef "@baseboard_fab2_lib.baseboard_fab2(sch_1):page214_p5v_stby") )
				( alias ( signalRef "@baseboard_fab2_lib.baseboard_fab2(sch_1):page216_p5v_stby") )
				( alias ( signalRef "@baseboard_fab2_lib.baseboard_fab2(sch_1):page219_p5v_stby") )
				( alias ( signalRef "@baseboard_fab2_lib.baseboard_fab2(sch_1):page224_p5v_stby") )
				( alias ( signalRef "@baseboard_fab2_lib.baseboard_fab2(sch_1):page227_p5v_stby") )
				( alias ( signalRef "@baseboard_fab2_lib.baseboard_fab2(sch_1):page236_p5v_stby") )
				( alias ( signalRef "@baseboard_fab2_lib.baseboard_fab2(sch_1):page240_p5v_stby") )
				( alias ( signalRef "@baseboard_fab2_lib.baseboard_fab2(sch_1):page241_p5v_stby") )
				( alias ( signalRef "@baseboard_fab2_lib.baseboard_fab2(sch_1):page176_p5v_stby") )
				( alias ( signalRef "@baseboard_fab2_lib.baseboard_fab2(sch_1):page249_p5v_stby") )
				( alias ( signalRef "@baseboard_fab2_lib.baseboard_fab2(sch_1):page251_p5v_stby") )
				( alias ( signalRef "@baseboard_fab2_lib.baseboard_fab2(sch_1):page253_p5v_stby") )
				( attribute "CDS_PHYS_NET_NAME" "P5V_STBY"
					( Origin gPackager )
				)
				( attribute "VOLTAGE" "5.0V"
					( Units "uVoltage" "V" 1.000000)
					( Status sAliasFlattened )
					( Status sAliasConflict )
					( Origin gFrontEnd )
				)
				( objectStatus "P5V_STBY" )
			)
			( signal "@baseboard_fab2_lib.baseboard_fab2(sch_1):page155_p5v_stby"
				( attribute "VOLTAGE" "5.0V"
					( Units "uVoltage" "V" 1.000000)
					( Origin gFrontEnd )
				)
				( objectFlag fObjectAlias )
				( objectStatus "page155_p5v_stby" )
			)
			( signal "@baseboard_fab2_lib.baseboard_fab2(sch_1):page161_p5v_stby"
				( attribute "VOLTAGE" "5.0V"
					( Units "uVoltage" "V" 1.000000)
					( Origin gFrontEnd )
				)
				( objectFlag fObjectAlias )
				( objectStatus "page161_p5v_stby" )
			)
			( signal "@baseboard_fab2_lib.baseboard_fab2(sch_1):page169_p5v_stby"
				( attribute "VOLTAGE" "5.0V"
					( Units "uVoltage" "V" 1.000000)
					( Origin gFrontEnd )
				)
				( objectFlag fObjectAlias )
				( objectStatus "page169_p5v_stby" )
			)
			( signal "@baseboard_fab2_lib.baseboard_fab2(sch_1):page175_p5v_stby"
				( attribute "VOLTAGE" "5.0V"
					( Units "uVoltage" "V" 1.000000)
					( Origin gFrontEnd )
				)
				( objectFlag fObjectAlias )
				( objectStatus "page175_p5v_stby" )
			)
			( signal "@baseboard_fab2_lib.baseboard_fab2(sch_1):page177_p5v_stby"
				( attribute "VOLTAGE" "5.0V"
					( Units "uVoltage" "V" 1.000000)
					( Origin gFrontEnd )
				)
				( objectFlag fObjectAlias )
				( objectStatus "page177_p5v_stby" )
			)
			( signal "@baseboard_fab2_lib.baseboard_fab2(sch_1):page186_p5v_stby"
				( attribute "VOLTAGE" "5.0V"
					( Units "uVoltage" "V" 1.000000)
					( Origin gFrontEnd )
				)
				( objectFlag fObjectAlias )
				( objectStatus "page186_p5v_stby" )
			)
			( signal "@baseboard_fab2_lib.baseboard_fab2(sch_1):page193_p5v_stby"
				( attribute "VOLTAGE" "+5.0V"
					( Units "uVoltage" "V" 1.000000)
					( Origin gFrontEnd )
				)
				( objectFlag fObjectAlias )
				( objectStatus "page193_p5v_stby" )
			)
			( signal "@baseboard_fab2_lib.baseboard_fab2(sch_1):page194_p5v_stby"
				( attribute "VOLTAGE" "+5.0V"
					( Units "uVoltage" "V" 1.000000)
					( Origin gFrontEnd )
				)
				( objectFlag fObjectAlias )
				( objectStatus "page194_p5v_stby" )
			)
			( signal "@baseboard_fab2_lib.baseboard_fab2(sch_1):page198_p5v_stby"
				( attribute "VOLTAGE" "5.0V"
					( Units "uVoltage" "V" 1.000000)
					( Origin gFrontEnd )
				)
				( objectFlag fObjectAlias )
				( objectStatus "page198_p5v_stby" )
			)
			( signal "@baseboard_fab2_lib.baseboard_fab2(sch_1):page202_p5v_stby"
				( attribute "VOLTAGE" "5.0V"
					( Units "uVoltage" "V" 1.000000)
					( Origin gFrontEnd )
				)
				( objectFlag fObjectAlias )
				( objectStatus "page202_p5v_stby" )
			)
			( signal "@baseboard_fab2_lib.baseboard_fab2(sch_1):page203_p5v_stby"
				( attribute "VOLTAGE" "5.0V"
					( Units "uVoltage" "V" 1.000000)
					( Origin gFrontEnd )
				)
				( objectFlag fObjectAlias )
				( objectStatus "page203_p5v_stby" )
			)
			( signal "@baseboard_fab2_lib.baseboard_fab2(sch_1):page204_p5v_stby"
				( attribute "VOLTAGE" "5.0V"
					( Units "uVoltage" "V" 1.000000)
					( Origin gFrontEnd )
				)
				( objectFlag fObjectAlias )
				( objectStatus "page204_p5v_stby" )
			)
			( signal "@baseboard_fab2_lib.baseboard_fab2(sch_1):page205_p5v_stby"
				( attribute "VOLTAGE" "5.0V"
					( Units "uVoltage" "V" 1.000000)
					( Origin gFrontEnd )
				)
				( objectFlag fObjectAlias )
				( objectStatus "page205_p5v_stby" )
			)
			( signal "@baseboard_fab2_lib.baseboard_fab2(sch_1):page207_p5v_stby"
				( attribute "VOLTAGE" "5.0V"
					( Units "uVoltage" "V" 1.000000)
					( Origin gFrontEnd )
				)
				( objectFlag fObjectAlias )
				( objectStatus "page207_p5v_stby" )
			)
			( signal "@baseboard_fab2_lib.baseboard_fab2(sch_1):page208_p5v_stby"
				( attribute "VOLTAGE" "5.0V"
					( Units "uVoltage" "V" 1.000000)
					( Origin gFrontEnd )
				)
				( objectFlag fObjectAlias )
				( objectStatus "page208_p5v_stby" )
			)
			( signal "@baseboard_fab2_lib.baseboard_fab2(sch_1):page209_p5v_stby"
				( attribute "VOLTAGE" "5.0V"
					( Units "uVoltage" "V" 1.000000)
					( Origin gFrontEnd )
				)
				( objectFlag fObjectAlias )
				( objectStatus "page209_p5v_stby" )
			)
			( signal "@baseboard_fab2_lib.baseboard_fab2(sch_1):page210_p5v_stby"
				( attribute "VOLTAGE" "5.0V"
					( Units "uVoltage" "V" 1.000000)
					( Origin gFrontEnd )
				)
				( objectFlag fObjectAlias )
				( objectStatus "page210_p5v_stby" )
			)
			( signal "@baseboard_fab2_lib.baseboard_fab2(sch_1):page212_p5v_stby"
				( attribute "VOLTAGE" "5.0V"
					( Units "uVoltage" "V" 1.000000)
					( Origin gFrontEnd )
				)
				( objectFlag fObjectAlias )
				( objectStatus "page212_p5v_stby" )
			)
			( signal "@baseboard_fab2_lib.baseboard_fab2(sch_1):page214_p5v_stby"
				( attribute "VOLTAGE" "5.0V"
					( Units "uVoltage" "V" 1.000000)
					( Origin gFrontEnd )
				)
				( objectFlag fObjectAlias )
				( objectStatus "page214_p5v_stby" )
			)
			( signal "@baseboard_fab2_lib.baseboard_fab2(sch_1):page216_p5v_stby"
				( attribute "VOLTAGE" "5.0V"
					( Units "uVoltage" "V" 1.000000)
					( Origin gFrontEnd )
				)
				( objectFlag fObjectAlias )
				( objectStatus "page216_p5v_stby" )
			)
			( signal "@baseboard_fab2_lib.baseboard_fab2(sch_1):page219_p5v_stby"
				( attribute "VOLTAGE" "5.0V"
					( Units "uVoltage" "V" 1.000000)
					( Origin gFrontEnd )
				)
				( objectFlag fObjectAlias )
				( objectStatus "page219_p5v_stby" )
			)
			( signal "@baseboard_fab2_lib.baseboard_fab2(sch_1):page224_p5v_stby"
				( attribute "VOLTAGE" "5.0V"
					( Units "uVoltage" "V" 1.000000)
					( Origin gFrontEnd )
				)
				( objectFlag fObjectAlias )
				( objectStatus "page224_p5v_stby" )
			)
			( signal "@baseboard_fab2_lib.baseboard_fab2(sch_1):page227_p5v_stby"
				( attribute "VOLTAGE" "5.0V"
					( Units "uVoltage" "V" 1.000000)
					( Origin gFrontEnd )
				)
				( objectFlag fObjectAlias )
				( objectStatus "page227_p5v_stby" )
			)
			( signal "@baseboard_fab2_lib.baseboard_fab2(sch_1):page236_p5v_stby"
				( attribute "VOLTAGE" "5.0V"
					( Units "uVoltage" "V" 1.000000)
					( Origin gFrontEnd )
				)
				( objectFlag fObjectAlias )
				( objectStatus "page236_p5v_stby" )
			)
			( signal "@baseboard_fab2_lib.baseboard_fab2(sch_1):page240_p5v_stby"
				( attribute "VOLTAGE" "+5.0V"
					( Units "uVoltage" "V" 1.000000)
					( Origin gFrontEnd )
				)
				( objectFlag fObjectAlias )
				( objectStatus "page240_p5v_stby" )
			)
			( signal "@baseboard_fab2_lib.baseboard_fab2(sch_1):page241_p5v_stby"
				( attribute "VOLTAGE" "+5"
					( Units "uVoltage" "V" 1.000000)
					( Origin gFrontEnd )
				)
				( objectFlag fObjectAlias )
				( objectStatus "page241_p5v_stby" )
			)
			( signal "@baseboard_fab2_lib.baseboard_fab2(sch_1):page176_p5v_stby"
				( attribute "VOLTAGE" "5.0V"
					( Units "uVoltage" "V" 1.000000)
					( Origin gFrontEnd )
				)
				( objectFlag fObjectAlias )
				( objectStatus "page176_p5v_stby" )
			)
			( signal "@baseboard_fab2_lib.baseboard_fab2(sch_1):page249_p5v_stby"
				( attribute "VOLTAGE" "5.0V"
					( Units "uVoltage" "V" 1.000000)
					( Origin gFrontEnd )
				)
				( objectFlag fObjectAlias )
				( objectStatus "page249_p5v_stby" )
			)
			( signal "@baseboard_fab2_lib.baseboard_fab2(sch_1):page251_p5v_stby"
				( attribute "VOLTAGE" "5.0V"
					( Units "uVoltage" "V" 1.000000)
					( Origin gFrontEnd )
				)
				( objectFlag fObjectAlias )
				( objectStatus "page251_p5v_stby" )
			)
			( signal "@baseboard_fab2_lib.baseboard_fab2(sch_1):page253_p5v_stby"
				( attribute "VOLTAGE" "5.0V"
					( Units "uVoltage" "V" 1.000000)
					( Origin gFrontEnd )
				)
				( objectFlag fObjectAlias )
				( objectStatus "page253_p5v_stby" )
			)
			( signal "@baseboard_fab2_lib.baseboard_fab2(sch_1):pca9554_a2"
				( attribute "CDS_PHYS_NET_NAME" "PCA9554_A2"
					( Origin gPackager )
				)
				( objectStatus "PCA9554_A2" )
			)
			( signal "@baseboard_fab2_lib.baseboard_fab2(sch_1):pump_pwm_out_buf"
				( attribute "CDS_PHYS_NET_NAME" "PUMP_PWM_OUT_BUF"
					( Origin gPackager )
				)
				( objectStatus "PUMP_PWM_OUT_BUF" )
			)
			( signal "@baseboard_fab2_lib.baseboard_fab2(sch_1):p5v_stby_dbg"
				( alias ( signalRef "@baseboard_fab2_lib.baseboard_fab2(sch_1):page155_p5v_stby_dbg") )
				( attribute "VOLTAGE" "5"
					( Units "uVoltage" "V" 1.000000)
					( Status sAliasFlattened )
					( Origin gFrontEnd )
				)
				( attribute "CDS_PHYS_NET_NAME" "P5V_STBY_DBG"
					( Origin gPackager )
				)
				( objectStatus "P5V_STBY_DBG" )
			)
			( signal "@baseboard_fab2_lib.baseboard_fab2(sch_1):page155_p5v_stby_dbg"
				( attribute "VOLTAGE" "5"
					( Units "uVoltage" "V" 1.000000)
					( Origin gFrontEnd )
				)
				( objectFlag fObjectAlias )
				( objectStatus "page155_p5v_stby_dbg" )
			)
			( signal "@baseboard_fab2_lib.baseboard_fab2(sch_1):p5v_stby_dgb_fs"
				( alias ( signalRef "@baseboard_fab2_lib.baseboard_fab2(sch_1):page155_p5v_stby_dgb_fs") )
				( attribute "VOLTAGE" "5"
					( Units "uVoltage" "V" 1.000000)
					( Status sAliasFlattened )
					( Origin gFrontEnd )
				)
				( attribute "CDS_PHYS_NET_NAME" "P5V_STBY_DGB_FS"
					( Origin gPackager )
				)
				( objectStatus "P5V_STBY_DGB_FS" )
			)
			( signal "@baseboard_fab2_lib.baseboard_fab2(sch_1):page155_p5v_stby_dgb_fs"
				( attribute "VOLTAGE" "5"
					( Units "uVoltage" "V" 1.000000)
					( Origin gFrontEnd )
				)
				( objectFlag fObjectAlias )
				( objectStatus "page155_p5v_stby_dgb_fs" )
			)
			( signal "@baseboard_fab2_lib.baseboard_fab2(sch_1):spa_5v_sin_sw"
				( attribute "CDS_PHYS_NET_NAME" "SPA_5V_SIN_SW"
					( Origin gPackager )
				)
				( objectStatus "SPA_5V_SIN_SW" )
			)
			( signal "@baseboard_fab2_lib.baseboard_fab2(sch_1):spa_mid_dbg_rx"
				( attribute "CDS_PHYS_NET_NAME" "SPA_MID_DBG_RX"
					( Origin gPackager )
				)
				( attribute "PHYS_NET_NAME" "SPA_MID_DBG_RX"
					( Origin gPackager )
				)
				( objectStatus "SPA_MID_DBG_RX" )
			)
			( signal "@baseboard_fab2_lib.baseboard_fab2(sch_1):spa_mid_dbg_tx"
				( attribute "CDS_PHYS_NET_NAME" "SPA_MID_DBG_TX"
					( Origin gPackager )
				)
				( objectStatus "SPA_MID_DBG_TX" )
			)
			( signal "@baseboard_fab2_lib.baseboard_fab2(sch_1):spa_sin_sw_r"
				( attribute "CDS_PHYS_NET_NAME" "SPA_SIN_SW_R"
					( Origin gPackager )
				)
				( objectStatus "SPA_SIN_SW_R" )
			)
			( signal "@baseboard_fab2_lib.baseboard_fab2(sch_1):fm_pch_pwrbtn_r_n"
				( attribute "CDS_PHYS_NET_NAME" "FM_PCH_PWRBTN_R_N"
					( Origin gPackager )
				)
				( objectStatus "FM_PCH_PWRBTN_R_N" )
			)
			( signal "@baseboard_fab2_lib.baseboard_fab2(sch_1):rst_bmc_sysrst_btn_out_b_r_n"
				( attribute "CDS_PHYS_NET_NAME" "RST_BMC_SYSRST_BTN_OUT_B_R_N"
					( Origin gPackager )
				)
				( objectStatus "RST_BMC_SYSRST_BTN_OUT_B_R_N" )
			)
			( signal "@baseboard_fab2_lib.baseboard_fab2(sch_1):fp_nmi_btn"
				( attribute "CDS_PHYS_NET_NAME" "FP_NMI_BTN"
					( Origin gPackager )
				)
				( objectStatus "FP_NMI_BTN" )
			)
			( signal "@baseboard_fab2_lib.baseboard_fab2(sch_1):fp_nmi_btn_out_n"
				( attribute "CDS_PHYS_NET_NAME" "FP_NMI_BTN_OUT_N"
					( Origin gPackager )
				)
				( objectStatus "FP_NMI_BTN_OUT_N" )
			)
			( signal "@baseboard_fab2_lib.baseboard_fab2(sch_1):fp_nmi_btn_out_r_n"
				( attribute "CDS_PHYS_NET_NAME" "FP_NMI_BTN_OUT_R_N"
					( Origin gPackager )
				)
				( objectStatus "FP_NMI_BTN_OUT_R_N" )
			)
			( signal "@baseboard_fab2_lib.baseboard_fab2(sch_1):fp_nmi_btn_r_n"
				( attribute "CDS_PHYS_NET_NAME" "FP_NMI_BTN_R_N"
					( Origin gPackager )
				)
				( objectStatus "FP_NMI_BTN_R_N" )
			)
			( signal "@baseboard_fab2_lib.baseboard_fab2(sch_1):h_cpu0_fast_wake"
				( attribute "CDS_PHYS_NET_NAME" "H_CPU0_FAST_WAKE"
					( Origin gPackager )
				)
				( objectStatus "H_CPU0_FAST_WAKE" )
			)
			( signal "@baseboard_fab2_lib.baseboard_fab2(sch_1):h_cpu0_fast_wake_b_n"
				( attribute "CDS_PHYS_NET_NAME" "H_CPU0_FAST_WAKE_B_N"
					( Origin gPackager )
				)
				( objectStatus "H_CPU0_FAST_WAKE_B_N" )
			)
			( signal "@baseboard_fab2_lib.baseboard_fab2(sch_1):rst_bmc_srst_r2_n"
				( attribute "CDS_PHYS_NET_NAME" "RST_BMC_SRST_R2_N"
					( Origin gPackager )
				)
				( objectStatus "RST_BMC_SRST_R2_N" )
			)
			( signal "@baseboard_fab2_lib.baseboard_fab2(sch_1):fm_uartsw_lsb_r_n"
				( attribute "CDS_PHYS_NET_NAME" "FM_UARTSW_LSB_R_N"
					( Origin gPackager )
				)
				( objectStatus "FM_UARTSW_LSB_R_N" )
			)
			( signal "@baseboard_fab2_lib.baseboard_fab2(sch_1):fm_uartsw_msb_r_n"
				( attribute "CDS_PHYS_NET_NAME" "FM_UARTSW_MSB_R_N"
					( Origin gPackager )
				)
				( objectStatus "FM_UARTSW_MSB_R_N" )
			)
			( signal "@baseboard_fab2_lib.baseboard_fab2(sch_1):sp2_bmc_cm_uart_rx_r"
				( attribute "CDS_PHYS_NET_NAME" "SP2_BMC_CM_UART_RX_R"
					( Origin gPackager )
				)
				( objectStatus "SP2_BMC_CM_UART_RX_R" )
			)
			( signal "@baseboard_fab2_lib.baseboard_fab2(sch_1):sp2_bmc_cm_uart_rx_r1"
				( attribute "CDS_PHYS_NET_NAME" "SP2_BMC_CM_UART_RX_R1"
					( Origin gPackager )
				)
				( objectStatus "SP2_BMC_CM_UART_RX_R1" )
			)
			( signal "@baseboard_fab2_lib.baseboard_fab2(sch_1):sp2_bmc_cm_uart_tx_r"
				( attribute "CDS_PHYS_NET_NAME" "SP2_BMC_CM_UART_TX_R"
					( Origin gPackager )
				)
				( objectStatus "SP2_BMC_CM_UART_TX_R" )
			)
			( signal "@baseboard_fab2_lib.baseboard_fab2(sch_1):sp2_bmc_cm_uart_tx_r1"
				( attribute "CDS_PHYS_NET_NAME" "SP2_BMC_CM_UART_TX_R1"
					( Origin gPackager )
				)
				( objectStatus "SP2_BMC_CM_UART_TX_R1" )
			)
			( signal "@baseboard_fab2_lib.baseboard_fab2(sch_1):uart_mux_in_r"
				( attribute "CDS_PHYS_NET_NAME" "UART_MUX_IN_R"
					( Origin gPackager )
				)
				( objectStatus "UART_MUX_IN_R" )
			)
			( signal "@baseboard_fab2_lib.baseboard_fab2(sch_1):uart_mux_out_r"
				( attribute "CDS_PHYS_NET_NAME" "UART_MUX_OUT_R"
					( Origin gPackager )
				)
				( objectStatus "UART_MUX_OUT_R" )
			)
			( signal "@baseboard_fab2_lib.baseboard_fab2(sch_1):smb_ocp_lan_stby_lvc3_scl"
				( attribute "CDS_PHYS_NET_NAME" "SMB_OCP_LAN_STBY_LVC3_SCL"
					( Origin gPackager )
				)
				( objectStatus "SMB_OCP_LAN_STBY_LVC3_SCL" )
			)
			( signal "@baseboard_fab2_lib.baseboard_fab2(sch_1):smb_ocp_lan_stby_lvc3_sda"
				( attribute "CDS_PHYS_NET_NAME" "SMB_OCP_LAN_STBY_LVC3_SDA"
					( Origin gPackager )
				)
				( objectStatus "SMB_OCP_LAN_STBY_LVC3_SDA" )
			)
			( signal "@baseboard_fab2_lib.baseboard_fab2(sch_1):fan_pwm_out_sys0_buf"
				( attribute "CDS_PHYS_NET_NAME" "FAN_PWM_OUT_SYS0_BUF"
					( Origin gPackager )
				)
				( objectStatus "FAN_PWM_OUT_SYS0_BUF" )
			)
			( signal "@baseboard_fab2_lib.baseboard_fab2(sch_1):fan_pwm_out_sys0_r"
				( attribute "CDS_PHYS_NET_NAME" "FAN_PWM_OUT_SYS0_R"
					( Origin gPackager )
				)
				( objectStatus "FAN_PWM_OUT_SYS0_R" )
			)
			( signal "@baseboard_fab2_lib.baseboard_fab2(sch_1):fan_pwm_out_sys1_buf"
				( attribute "CDS_PHYS_NET_NAME" "FAN_PWM_OUT_SYS1_BUF"
					( Origin gPackager )
				)
				( objectStatus "FAN_PWM_OUT_SYS1_BUF" )
			)
			( signal "@baseboard_fab2_lib.baseboard_fab2(sch_1):fan_pwm_out_sys1_r"
				( attribute "CDS_PHYS_NET_NAME" "FAN_PWM_OUT_SYS1_R"
					( Origin gPackager )
				)
				( objectStatus "FAN_PWM_OUT_SYS1_R" )
			)
			( signal "@baseboard_fab2_lib.baseboard_fab2(sch_1):fan_tach0_cpu0_d1"
				( attribute "CDS_PHYS_NET_NAME" "FAN_TACH0_CPU0_D1"
					( Origin gPackager )
				)
				( objectStatus "FAN_TACH0_CPU0_D1" )
			)
			( signal "@baseboard_fab2_lib.baseboard_fab2(sch_1):fan_tach0_cpu0_d2"
				( attribute "CDS_PHYS_NET_NAME" "FAN_TACH0_CPU0_D2"
					( Origin gPackager )
				)
				( objectStatus "FAN_TACH0_CPU0_D2" )
			)
			( signal "@baseboard_fab2_lib.baseboard_fab2(sch_1):fan_tach2_cpu1_d1"
				( attribute "CDS_PHYS_NET_NAME" "FAN_TACH2_CPU1_D1"
					( Origin gPackager )
				)
				( objectStatus "FAN_TACH2_CPU1_D1" )
			)
			( signal "@baseboard_fab2_lib.baseboard_fab2(sch_1):fan_tach2_cpu1_d2"
				( attribute "CDS_PHYS_NET_NAME" "FAN_TACH2_CPU1_D2"
					( Origin gPackager )
				)
				( objectStatus "FAN_TACH2_CPU1_D2" )
			)
			( signal "@baseboard_fab2_lib.baseboard_fab2(sch_1):fm_ctnr_ps_on"
				( attribute "CDS_PHYS_NET_NAME" "FM_CTNR_PS_ON"
					( Origin gPackager )
				)
				( objectStatus "FM_CTNR_PS_ON" )
			)
			( signal "@baseboard_fab2_lib.baseboard_fab2(sch_1):fm_disable_fan_n"
				( attribute "CDS_PHYS_NET_NAME" "FM_DISABLE_FAN_N"
					( Origin gPackager )
				)
				( objectStatus "FM_DISABLE_FAN_N" )
			)
			( signal "@baseboard_fab2_lib.baseboard_fab2(sch_1):fm_enable_fan_power"
				( attribute "CDS_PHYS_NET_NAME" "FM_ENABLE_FAN_POWER"
					( Origin gPackager )
				)
				( objectStatus "FM_ENABLE_FAN_POWER" )
			)
			( signal "@baseboard_fab2_lib.baseboard_fab2(sch_1):p12v_fan"
				( alias ( signalRef "@baseboard_fab2_lib.baseboard_fab2(sch_1):page161_p12v_fan") )
				( alias ( signalRef "@baseboard_fab2_lib.baseboard_fab2(sch_1):page198_p12v_fan") )
				( alias ( signalRef "@baseboard_fab2_lib.baseboard_fab2(sch_1):page251_p12v_fan") )
				( attribute "CDS_PHYS_NET_NAME" "P12V_FAN"
					( Origin gPackager )
				)
				( attribute "VOLTAGE" "12.0V"
					( Units "uVoltage" "V" 1.000000)
					( Status sAliasFlattened )
					( Origin gFrontEnd )
				)
				( objectStatus "P12V_FAN" )
			)
			( signal "@baseboard_fab2_lib.baseboard_fab2(sch_1):page161_p12v_fan"
				( attribute "VOLTAGE" "12.0V"
					( Units "uVoltage" "V" 1.000000)
					( Origin gFrontEnd )
				)
				( objectFlag fObjectAlias )
				( objectStatus "page161_p12v_fan" )
			)
			( signal "@baseboard_fab2_lib.baseboard_fab2(sch_1):page198_p12v_fan"
				( attribute "VOLTAGE" "12.0V"
					( Units "uVoltage" "V" 1.000000)
					( Origin gFrontEnd )
				)
				( objectFlag fObjectAlias )
				( objectStatus "page198_p12v_fan" )
			)
			( signal "@baseboard_fab2_lib.baseboard_fab2(sch_1):page251_p12v_fan"
				( attribute "VOLTAGE" "12.0V"
					( Units "uVoltage" "V" 1.000000)
					( Origin gFrontEnd )
				)
				( objectFlag fObjectAlias )
				( objectStatus "page251_p12v_fan" )
			)
			( signal "@baseboard_fab2_lib.baseboard_fab2(sch_1):pump_pwm_out_r"
				( attribute "CDS_PHYS_NET_NAME" "PUMP_PWM_OUT_R"
					( Origin gPackager )
				)
				( objectStatus "PUMP_PWM_OUT_R" )
			)
			( signal "@baseboard_fab2_lib.baseboard_fab2(sch_1):pump_tach0"
				( attribute "CDS_PHYS_NET_NAME" "PUMP_TACH0"
					( Origin gPackager )
				)
				( objectStatus "PUMP_TACH0" )
			)
			( signal "@baseboard_fab2_lib.baseboard_fab2(sch_1):pu_spi_bmc_bt_hold_n"
				( attribute "CDS_PHYS_NET_NAME" "PU_SPI_BMC_BT_HOLD_N"
					( Origin gPackager )
				)
				( objectStatus "PU_SPI_BMC_BT_HOLD_N" )
			)
			( signal "@baseboard_fab2_lib.baseboard_fab2(sch_1):pu_spi_bmc_bt_wp_n"
				( attribute "CDS_PHYS_NET_NAME" "PU_SPI_BMC_BT_WP_N"
					( Origin gPackager )
				)
				( objectStatus "PU_SPI_BMC_BT_WP_N" )
			)
			( signal "@baseboard_fab2_lib.baseboard_fab2(sch_1):pu_spi_flash_reset_2_n"
				( attribute "CDS_PHYS_NET_NAME" "PU_SPI_FLASH_RESET_2_N"
					( Origin gPackager )
				)
				( objectStatus "PU_SPI_FLASH_RESET_2_N" )
			)
			( signal "@baseboard_fab2_lib.baseboard_fab2(sch_1):spi_bmc_bt_di_r"
				( attribute "CDS_PHYS_NET_NAME" "SPI_BMC_BT_DI_R"
					( Origin gPackager )
				)
				( objectStatus "SPI_BMC_BT_DI_R" )
			)
			( signal "@baseboard_fab2_lib.baseboard_fab2(sch_1):tp_spi_2_0"
				( attribute "CDS_PHYS_NET_NAME" "TP_SPI_2_0"
					( Origin gPackager )
				)
				( objectStatus "TP_SPI_2_0" )
			)
			( signal "@baseboard_fab2_lib.baseboard_fab2(sch_1):tp_spi_2_1"
				( attribute "CDS_PHYS_NET_NAME" "TP_SPI_2_1"
					( Origin gPackager )
				)
				( objectStatus "TP_SPI_2_1" )
			)
			( signal "@baseboard_fab2_lib.baseboard_fab2(sch_1):tp_spi_2_2"
				( attribute "CDS_PHYS_NET_NAME" "TP_SPI_2_2"
					( Origin gPackager )
				)
				( objectStatus "TP_SPI_2_2" )
			)
			( signal "@baseboard_fab2_lib.baseboard_fab2(sch_1):tp_spi_2_3"
				( attribute "CDS_PHYS_NET_NAME" "TP_SPI_2_3"
					( Origin gPackager )
				)
				( objectStatus "TP_SPI_2_3" )
			)
			( signal "@baseboard_fab2_lib.baseboard_fab2(sch_1):tp_spi_2_4"
				( attribute "CDS_PHYS_NET_NAME" "TP_SPI_2_4"
					( Origin gPackager )
				)
				( objectStatus "TP_SPI_2_4" )
			)
			( signal "@baseboard_fab2_lib.baseboard_fab2(sch_1):tp_spi_2_5"
				( attribute "CDS_PHYS_NET_NAME" "TP_SPI_2_5"
					( Origin gPackager )
				)
				( objectStatus "TP_SPI_2_5" )
			)
			( signal "@baseboard_fab2_lib.baseboard_fab2(sch_1):tp_spi_2_6"
				( attribute "CDS_PHYS_NET_NAME" "TP_SPI_2_6"
					( Origin gPackager )
				)
				( objectStatus "TP_SPI_2_6" )
			)
			( signal "@baseboard_fab2_lib.baseboard_fab2(sch_1):smb_cpu1_pe_hp_gtl_r_scl"
				( attribute "CDS_PHYS_NET_NAME" "SMB_CPU1_PE_HP_GTL_R_SCL"
					( Origin gPackager )
				)
				( objectStatus "SMB_CPU1_PE_HP_GTL_R_SCL" )
			)
			( signal "@baseboard_fab2_lib.baseboard_fab2(sch_1):smb_cpu1_pe_hp_gtl_r_sda"
				( attribute "CDS_PHYS_NET_NAME" "SMB_CPU1_PE_HP_GTL_R_SDA"
					( Origin gPackager )
				)
				( objectStatus "SMB_CPU1_PE_HP_GTL_R_SDA" )
			)
			( signal "@baseboard_fab2_lib.baseboard_fab2(sch_1):smb_pehpcpu1_stby_lvc3_r_scl"
				( attribute "CDS_PHYS_NET_NAME" "SMB_PEHPCPU1_STBY_LVC3_R_SCL"
					( Origin gPackager )
				)
				( objectStatus "SMB_PEHPCPU1_STBY_LVC3_R_SCL" )
			)
			( signal "@baseboard_fab2_lib.baseboard_fab2(sch_1):smb_pehpcpu1_stby_lvc3_r_sda"
				( attribute "CDS_PHYS_NET_NAME" "SMB_PEHPCPU1_STBY_LVC3_R_SDA"
					( Origin gPackager )
				)
				( objectStatus "SMB_PEHPCPU1_STBY_LVC3_R_SDA" )
			)
			( signal "@baseboard_fab2_lib.baseboard_fab2(sch_1):smb_pehpcpu1_stby_lvc3_scl"
				( attribute "CDS_PHYS_NET_NAME" "SMB_PEHPCPU1_STBY_LVC3_SCL"
					( Origin gPackager )
				)
				( objectStatus "SMB_PEHPCPU1_STBY_LVC3_SCL" )
			)
			( signal "@baseboard_fab2_lib.baseboard_fab2(sch_1):smb_pehpcpu1_stby_lvc3_sda"
				( attribute "CDS_PHYS_NET_NAME" "SMB_PEHPCPU1_STBY_LVC3_SDA"
					( Origin gPackager )
				)
				( objectStatus "SMB_PEHPCPU1_STBY_LVC3_SDA" )
			)
			( signal "@baseboard_fab2_lib.baseboard_fab2(sch_1):tp_smb_pehpcpu1_en"
				( attribute "CDS_PHYS_NET_NAME" "TP_SMB_PEHPCPU1_EN"
					( Origin gPackager )
				)
				( objectStatus "TP_SMB_PEHPCPU1_EN" )
			)
			( signal "@baseboard_fab2_lib.baseboard_fab2(sch_1):isense_tmp421_1_bc"
				( attribute "CDS_PHYS_NET_NAME" "ISENSE_TMP421_1_BC"
					( Origin gPackager )
				)
				( objectStatus "ISENSE_TMP421_1_BC" )
			)
			( signal "@baseboard_fab2_lib.baseboard_fab2(sch_1):isense_tmp421_1_dxn"
				( attribute "CDS_PHYS_NET_NAME" "ISENSE_TMP421_1_DXN"
					( Origin gPackager )
				)
				( objectStatus "ISENSE_TMP421_1_DXN" )
			)
			( signal "@baseboard_fab2_lib.baseboard_fab2(sch_1):isense_tmp421_1_dxp"
				( attribute "CDS_PHYS_NET_NAME" "ISENSE_TMP421_1_DXP"
					( Origin gPackager )
				)
				( objectStatus "ISENSE_TMP421_1_DXP" )
			)
			( signal "@baseboard_fab2_lib.baseboard_fab2(sch_1):isense_tmp421_1_e"
				( attribute "CDS_PHYS_NET_NAME" "ISENSE_TMP421_1_E"
					( Origin gPackager )
				)
				( objectStatus "ISENSE_TMP421_1_E" )
			)
			( signal "@baseboard_fab2_lib.baseboard_fab2(sch_1):isense_tmp421_2_bc"
				( attribute "CDS_PHYS_NET_NAME" "ISENSE_TMP421_2_BC"
					( Origin gPackager )
				)
				( objectStatus "ISENSE_TMP421_2_BC" )
			)
			( signal "@baseboard_fab2_lib.baseboard_fab2(sch_1):isense_tmp421_2_dxn"
				( attribute "CDS_PHYS_NET_NAME" "ISENSE_TMP421_2_DXN"
					( Origin gPackager )
				)
				( objectStatus "ISENSE_TMP421_2_DXN" )
			)
			( signal "@baseboard_fab2_lib.baseboard_fab2(sch_1):isense_tmp421_2_dxp"
				( attribute "CDS_PHYS_NET_NAME" "ISENSE_TMP421_2_DXP"
					( Origin gPackager )
				)
				( objectStatus "ISENSE_TMP421_2_DXP" )
			)
			( signal "@baseboard_fab2_lib.baseboard_fab2(sch_1):isense_tmp421_2_e"
				( attribute "CDS_PHYS_NET_NAME" "ISENSE_TMP421_2_E"
					( Origin gPackager )
				)
				( objectStatus "ISENSE_TMP421_2_E" )
			)
			( signal "@baseboard_fab2_lib.baseboard_fab2(sch_1):pd_fru_wp"
				( attribute "CDS_PHYS_NET_NAME" "PD_FRU_WP"
					( Origin gPackager )
				)
				( objectStatus "PD_FRU_WP" )
			)
			( signal "@baseboard_fab2_lib.baseboard_fab2(sch_1):pd_tmp421_1_a0"
				( attribute "CDS_PHYS_NET_NAME" "PD_TMP421_1_A0"
					( Origin gPackager )
				)
				( objectStatus "PD_TMP421_1_A0" )
			)
			( signal "@baseboard_fab2_lib.baseboard_fab2(sch_1):pd_tmp421_2_a1"
				( attribute "CDS_PHYS_NET_NAME" "PD_TMP421_2_A1"
					( Origin gPackager )
				)
				( objectStatus "PD_TMP421_2_A1" )
			)
			( signal "@baseboard_fab2_lib.baseboard_fab2(sch_1):pu_at24c64_a2"
				( attribute "CDS_PHYS_NET_NAME" "PU_AT24C64_A2"
					( Origin gPackager )
				)
				( objectStatus "PU_AT24C64_A2" )
			)
			( signal "@baseboard_fab2_lib.baseboard_fab2(sch_1):pu_tmp421_1_a1"
				( attribute "CDS_PHYS_NET_NAME" "PU_TMP421_1_A1"
					( Origin gPackager )
				)
				( objectStatus "PU_TMP421_1_A1" )
			)
			( signal "@baseboard_fab2_lib.baseboard_fab2(sch_1):pu_tmp421_2_a0"
				( attribute "CDS_PHYS_NET_NAME" "PU_TMP421_2_A0"
					( Origin gPackager )
				)
				( objectStatus "PU_TMP421_2_A0" )
			)
			( signal "@baseboard_fab2_lib.baseboard_fab2(sch_1):smb_sensor_stby_lvc3_scl"
				( attribute "CDS_PHYS_NET_NAME" "SMB_SENSOR_STBY_LVC3_SCL"
					( Origin gPackager )
				)
				( objectStatus "SMB_SENSOR_STBY_LVC3_SCL" )
			)
			( signal "@baseboard_fab2_lib.baseboard_fab2(sch_1):smb_sensor_stby_lvc3_scl_r2"
				( attribute "CDS_PHYS_NET_NAME" "SMB_SENSOR_STBY_LVC3_SCL_R2"
					( Origin gPackager )
				)
				( objectStatus "SMB_SENSOR_STBY_LVC3_SCL_R2" )
			)
			( signal "@baseboard_fab2_lib.baseboard_fab2(sch_1):smb_sensor_stby_lvc3_sda"
				( attribute "CDS_PHYS_NET_NAME" "SMB_SENSOR_STBY_LVC3_SDA"
					( Origin gPackager )
				)
				( objectStatus "SMB_SENSOR_STBY_LVC3_SDA" )
			)
			( signal "@baseboard_fab2_lib.baseboard_fab2(sch_1):smb_sensor_stby_lvc3_sda_r2"
				( attribute "CDS_PHYS_NET_NAME" "SMB_SENSOR_STBY_LVC3_SDA_R2"
					( Origin gPackager )
				)
				( objectStatus "SMB_SENSOR_STBY_LVC3_SDA_R2" )
			)
			( signal "@baseboard_fab2_lib.baseboard_fab2(sch_1):smb_sensor_tmp421_1_scl"
				( attribute "CDS_PHYS_NET_NAME" "SMB_SENSOR_TMP421_1_SCL"
					( Origin gPackager )
				)
				( objectStatus "SMB_SENSOR_TMP421_1_SCL" )
			)
			( signal "@baseboard_fab2_lib.baseboard_fab2(sch_1):smb_sensor_tmp421_1_sda"
				( attribute "CDS_PHYS_NET_NAME" "SMB_SENSOR_TMP421_1_SDA"
					( Origin gPackager )
				)
				( objectStatus "SMB_SENSOR_TMP421_1_SDA" )
			)
			( signal "@baseboard_fab2_lib.baseboard_fab2(sch_1):smb_sensor_tmp421_2_scl"
				( attribute "CDS_PHYS_NET_NAME" "SMB_SENSOR_TMP421_2_SCL"
					( Origin gPackager )
				)
				( objectStatus "SMB_SENSOR_TMP421_2_SCL" )
			)
			( signal "@baseboard_fab2_lib.baseboard_fab2(sch_1):smb_sensor_tmp421_2_sda"
				( attribute "CDS_PHYS_NET_NAME" "SMB_SENSOR_TMP421_2_SDA"
					( Origin gPackager )
				)
				( objectStatus "SMB_SENSOR_TMP421_2_SDA" )
			)
			( signal "@baseboard_fab2_lib.baseboard_fab2(sch_1):fm_db_present"
				( attribute "CDS_PHYS_NET_NAME" "FM_DB_PRESENT"
					( Origin gPackager )
				)
				( objectStatus "FM_DB_PRESENT" )
			)
			( signal "@baseboard_fab2_lib.baseboard_fab2(sch_1):fm_db_uart_sel0_n"
				( attribute "CDS_PHYS_NET_NAME" "FM_DB_UART_SEL0_N"
					( Origin gPackager )
				)
				( objectStatus "FM_DB_UART_SEL0_N" )
			)
			( signal "@baseboard_fab2_lib.baseboard_fab2(sch_1):fm_db_uart_sel1_n"
				( attribute "CDS_PHYS_NET_NAME" "FM_DB_UART_SEL1_N"
					( Origin gPackager )
				)
				( objectStatus "FM_DB_UART_SEL1_N" )
			)
			( signal "@baseboard_fab2_lib.baseboard_fab2(sch_1):fm_db_uart_sel2_n"
				( attribute "CDS_PHYS_NET_NAME" "FM_DB_UART_SEL2_N"
					( Origin gPackager )
				)
				( objectStatus "FM_DB_UART_SEL2_N" )
			)
			( signal "@baseboard_fab2_lib.baseboard_fab2(sch_1):fm_db_uart_sel3_n"
				( attribute "CDS_PHYS_NET_NAME" "FM_DB_UART_SEL3_N"
					( Origin gPackager )
				)
				( objectStatus "FM_DB_UART_SEL3_N" )
			)
			( signal "@baseboard_fab2_lib.baseboard_fab2(sch_1):fm_db_uart_sel4_n"
				( attribute "CDS_PHYS_NET_NAME" "FM_DB_UART_SEL4_N"
					( Origin gPackager )
				)
				( objectStatus "FM_DB_UART_SEL4_N" )
			)
			( signal "@baseboard_fab2_lib.baseboard_fab2(sch_1):fm_uart_sel_n"
				( attribute "CDS_PHYS_NET_NAME" "FM_UART_SEL_N"
					( Origin gPackager )
				)
				( objectStatus "FM_UART_SEL_N" )
			)
			( signal "@baseboard_fab2_lib.baseboard_fab2(sch_1):tp_fet_q56_3"
				( attribute "CDS_PHYS_NET_NAME" "TP_FET_Q56_3"
					( Origin gPackager )
				)
				( objectStatus "TP_FET_Q56_3" )
			)
			( signal "@baseboard_fab2_lib.baseboard_fab2(sch_1):tp_fet_q56_4"
				( attribute "CDS_PHYS_NET_NAME" "TP_FET_Q56_4"
					( Origin gPackager )
				)
				( objectStatus "TP_FET_Q56_4" )
			)
			( signal "@baseboard_fab2_lib.baseboard_fab2(sch_1):a_p3v_bat_r"
				( alias ( signalRef "@baseboard_fab2_lib.baseboard_fab2(sch_1):page196_a_p3v_bat_r") )
				( attribute "VOLTAGE" "+3 V"
					( Units "uVoltage" "V" 1.000000)
					( Status sAliasFlattened )
					( Origin gFrontEnd )
				)
				( attribute "CDS_PHYS_NET_NAME" "A_P3V_BAT_R"
					( Origin gPackager )
				)
				( objectStatus "A_P3V_BAT_R" )
			)
			( signal "@baseboard_fab2_lib.baseboard_fab2(sch_1):page196_a_p3v_bat_r"
				( attribute "VOLTAGE" "+3 V"
					( Units "uVoltage" "V" 1.000000)
					( Origin gFrontEnd )
				)
				( objectFlag fObjectAlias )
				( objectStatus "page196_a_p3v_bat_r" )
			)
			( signal "@baseboard_fab2_lib.baseboard_fab2(sch_1):fm_battery_sense_en"
				( attribute "CDS_PHYS_NET_NAME" "FM_BATTERY_SENSE_EN"
					( Origin gPackager )
				)
				( objectStatus "FM_BATTERY_SENSE_EN" )
			)
			( signal "@baseboard_fab2_lib.baseboard_fab2(sch_1):p3v_bat_source_r"
				( alias ( signalRef "@baseboard_fab2_lib.baseboard_fab2(sch_1):page169_p3v_bat_source_r") )
				( attribute "VOLTAGE" "+3V"
					( Units "uVoltage" "V" 1.000000)
					( Status sAliasFlattened )
					( Origin gFrontEnd )
				)
				( attribute "CDS_PHYS_NET_NAME" "P3V_BAT_SOURCE_R"
					( Origin gPackager )
				)
				( objectStatus "P3V_BAT_SOURCE_R" )
			)
			( signal "@baseboard_fab2_lib.baseboard_fab2(sch_1):page169_p3v_bat_source_r"
				( attribute "VOLTAGE" "+3V"
					( Units "uVoltage" "V" 1.000000)
					( Origin gFrontEnd )
				)
				( objectFlag fObjectAlias )
				( objectStatus "page169_p3v_bat_source_r" )
			)
			( signal "@baseboard_fab2_lib.baseboard_fab2(sch_1):p5v"
				( alias ( signalRef "@baseboard_fab2_lib.baseboard_fab2(sch_1):page169_p5v") )
				( alias ( signalRef "@baseboard_fab2_lib.baseboard_fab2(sch_1):page172_p5v") )
				( alias ( signalRef "@baseboard_fab2_lib.baseboard_fab2(sch_1):page176_p5v") )
				( alias ( signalRef "@baseboard_fab2_lib.baseboard_fab2(sch_1):page196_p5v") )
				( alias ( signalRef "@baseboard_fab2_lib.baseboard_fab2(sch_1):page198_p5v") )
				( alias ( signalRef "@baseboard_fab2_lib.baseboard_fab2(sch_1):page255_p5v") )
				( attribute "CDS_PHYS_NET_NAME" "P5V"
					( Origin gPackager )
				)
				( attribute "VOLTAGE" "5.0V"
					( Units "uVoltage" "V" 1.000000)
					( Status sAliasFlattened )
					( Status sAliasConflict )
					( Origin gFrontEnd )
				)
				( objectStatus "P5V" )
			)
			( signal "@baseboard_fab2_lib.baseboard_fab2(sch_1):page169_p5v"
				( attribute "VOLTAGE" "5.0V"
					( Units "uVoltage" "V" 1.000000)
					( Origin gFrontEnd )
				)
				( objectFlag fObjectAlias )
				( objectStatus "page169_p5v" )
			)
			( signal "@baseboard_fab2_lib.baseboard_fab2(sch_1):page172_p5v"
				( attribute "VOLTAGE" "+5.0V"
					( Units "uVoltage" "V" 1.000000)
					( Origin gFrontEnd )
				)
				( objectFlag fObjectAlias )
				( objectStatus "page172_p5v" )
			)
			( signal "@baseboard_fab2_lib.baseboard_fab2(sch_1):page176_p5v"
				( attribute "VOLTAGE" "5.0V"
					( Units "uVoltage" "V" 1.000000)
					( Origin gFrontEnd )
				)
				( objectFlag fObjectAlias )
				( objectStatus "page176_p5v" )
			)
			( signal "@baseboard_fab2_lib.baseboard_fab2(sch_1):page196_p5v"
				( attribute "VOLTAGE" "5.0V"
					( Units "uVoltage" "V" 1.000000)
					( Origin gFrontEnd )
				)
				( objectFlag fObjectAlias )
				( objectStatus "page196_p5v" )
			)
			( signal "@baseboard_fab2_lib.baseboard_fab2(sch_1):page198_p5v"
				( attribute "VOLTAGE" "+5.0V"
					( Units "uVoltage" "V" 1.000000)
					( Origin gFrontEnd )
				)
				( objectFlag fObjectAlias )
				( objectStatus "page198_p5v" )
			)
			( signal "@baseboard_fab2_lib.baseboard_fab2(sch_1):page255_p5v"
				( attribute "VOLTAGE" "+5.0V"
					( Units "uVoltage" "V" 1.000000)
					( Origin gFrontEnd )
				)
				( objectFlag fObjectAlias )
				( objectStatus "page255_p5v" )
			)
			( signal "@baseboard_fab2_lib.baseboard_fab2(sch_1):spi_bmc_bt_wp0_n"
				( attribute "CDS_PHYS_NET_NAME" "SPI_BMC_BT_WP0_N"
					( Origin gPackager )
				)
				( objectStatus "SPI_BMC_BT_WP0_N" )
			)
			( signal "@baseboard_fab2_lib.baseboard_fab2(sch_1):fm_fast_prochot_and_out_0_n"
				( attribute "CDS_PHYS_NET_NAME" "FM_FAST_PROCHOT_AND_OUT_0_N"
					( Origin gPackager )
				)
				( objectStatus "FM_FAST_PROCHOT_AND_OUT_0_N" )
			)
			( signal "@baseboard_fab2_lib.baseboard_fab2(sch_1):fm_fast_prochot_and_out_1_n"
				( attribute "CDS_PHYS_NET_NAME" "FM_FAST_PROCHOT_AND_OUT_1_N"
					( Origin gPackager )
				)
				( objectStatus "FM_FAST_PROCHOT_AND_OUT_1_N" )
			)
			( signal "@baseboard_fab2_lib.baseboard_fab2(sch_1):fm_fast_prochot_en"
				( attribute "CDS_PHYS_NET_NAME" "FM_FAST_PROCHOT_EN"
					( Origin gPackager )
				)
				( objectStatus "FM_FAST_PROCHOT_EN" )
			)
			( signal "@baseboard_fab2_lib.baseboard_fab2(sch_1):fm_fast_prochot_throttle_dly_buf_n"
				( attribute "CDS_PHYS_NET_NAME" "FM_FAST_PROCHOT_THROTTLE_DLY_BU"
					( Origin gPackager )
				)
				( attribute "PNN" "FM_FAST_PROCHOT_THROTTLE_DLY_BU"
					( Origin gPackager )
				)
				( objectStatus "FM_FAST_PROCHOT_THROTTLE_DLY_BU" )
			)
			( signal "@baseboard_fab2_lib.baseboard_fab2(sch_1):fm_fast_prochot_throttle_dly_n"
				( attribute "CDS_PHYS_NET_NAME" "FM_FAST_PROCHOT_THROTTLE_DLY_N"
					( Origin gPackager )
				)
				( objectStatus "FM_FAST_PROCHOT_THROTTLE_DLY_N" )
			)
			( signal "@baseboard_fab2_lib.baseboard_fab2(sch_1):fm_fast_prochot_throttle_in_n"
				( attribute "CDS_PHYS_NET_NAME" "FM_FAST_PROCHOT_THROTTLE_IN_N"
					( Origin gPackager )
				)
				( objectStatus "FM_FAST_PROCHOT_THROTTLE_IN_N" )
			)
			( signal "@baseboard_fab2_lib.baseboard_fab2(sch_1):fm_oc_detect_n"
				( attribute "CDS_PHYS_NET_NAME" "FM_OC_DETECT_N"
					( Origin gPackager )
				)
				( objectStatus "FM_OC_DETECT_N" )
			)
			( signal "@baseboard_fab2_lib.baseboard_fab2(sch_1):fm_pmbus_alert_buf_en"
				( attribute "CDS_PHYS_NET_NAME" "FM_PMBUS_ALERT_BUF_EN"
					( Origin gPackager )
				)
				( objectStatus "FM_PMBUS_ALERT_BUF_EN" )
			)
			( signal "@baseboard_fab2_lib.baseboard_fab2(sch_1):fm_throttle_r1_n"
				( attribute "CDS_PHYS_NET_NAME" "FM_THROTTLE_R1_N"
					( Origin gPackager )
				)
				( objectStatus "FM_THROTTLE_R1_N" )
			)
			( signal "@baseboard_fab2_lib.baseboard_fab2(sch_1):irq_force_nm_throttle_r_n"
				( attribute "CDS_PHYS_NET_NAME" "IRQ_FORCE_NM_THROTTLE_R_N"
					( Origin gPackager )
				)
				( objectStatus "IRQ_FORCE_NM_THROTTLE_R_N" )
			)
			( signal "@baseboard_fab2_lib.baseboard_fab2(sch_1):irq_sml1_pmbus_alert_buf_n"
				( attribute "CDS_PHYS_NET_NAME" "IRQ_SML1_PMBUS_ALERT_BUF_N"
					( Origin gPackager )
				)
				( objectStatus "IRQ_SML1_PMBUS_ALERT_BUF_N" )
			)
			( signal "@baseboard_fab2_lib.baseboard_fab2(sch_1):p12v_hdd_sata"
				( alias ( signalRef "@baseboard_fab2_lib.baseboard_fab2(sch_1):page172_p12v_hdd_sata") )
				( attribute "VOLTAGE" "12"
					( Units "uVoltage" "V" 1.000000)
					( Status sAliasFlattened )
					( Origin gFrontEnd )
				)
				( attribute "CDS_PHYS_NET_NAME" "P12V_HDD_SATA"
					( Origin gPackager )
				)
				( objectStatus "P12V_HDD_SATA" )
			)
			( signal "@baseboard_fab2_lib.baseboard_fab2(sch_1):page172_p12v_hdd_sata"
				( attribute "VOLTAGE" "12"
					( Units "uVoltage" "V" 1.000000)
					( Origin gFrontEnd )
				)
				( objectFlag fObjectAlias )
				( objectStatus "page172_p12v_hdd_sata" )
			)
			( signal "@baseboard_fab2_lib.baseboard_fab2(sch_1):p5v_hdd_sata"
				( alias ( signalRef "@baseboard_fab2_lib.baseboard_fab2(sch_1):page172_p5v_hdd_sata") )
				( attribute "VOLTAGE" "5"
					( Units "uVoltage" "V" 1.000000)
					( Status sAliasFlattened )
					( Origin gFrontEnd )
				)
				( attribute "CDS_PHYS_NET_NAME" "P5V_HDD_SATA"
					( Origin gPackager )
				)
				( objectStatus "P5V_HDD_SATA" )
			)
			( signal "@baseboard_fab2_lib.baseboard_fab2(sch_1):page172_p5v_hdd_sata"
				( attribute "VOLTAGE" "5"
					( Units "uVoltage" "V" 1.000000)
					( Origin gFrontEnd )
				)
				( objectFlag fObjectAlias )
				( objectStatus "page172_p5v_hdd_sata" )
			)
			( signal "@baseboard_fab2_lib.baseboard_fab2(sch_1):sata6g_s1_rx_c_dn"
				( attribute "CDS_PHYS_NET_NAME" "SATA6G_S1_RX_C_DN"
					( Origin gPackager )
				)
				( objectStatus "SATA6G_S1_RX_C_DN" )
			)
			( signal "@baseboard_fab2_lib.baseboard_fab2(sch_1):sata6g_s1_rx_c_dp"
				( attribute "CDS_PHYS_NET_NAME" "SATA6G_S1_RX_C_DP"
					( Origin gPackager )
				)
				( objectStatus "SATA6G_S1_RX_C_DP" )
			)
			( signal "@baseboard_fab2_lib.baseboard_fab2(sch_1):sata6g_s1_tx_c_dn"
				( attribute "CDS_PHYS_NET_NAME" "SATA6G_S1_TX_C_DN"
					( Origin gPackager )
				)
				( objectStatus "SATA6G_S1_TX_C_DN" )
			)
			( signal "@baseboard_fab2_lib.baseboard_fab2(sch_1):sata6g_s1_tx_c_dp"
				( attribute "CDS_PHYS_NET_NAME" "SATA6G_S1_TX_C_DP"
					( Origin gPackager )
				)
				( objectStatus "SATA6G_S1_TX_C_DP" )
			)
			( signal "@baseboard_fab2_lib.baseboard_fab2(sch_1):pd_sata0_controller_type_r"
				( attribute "CDS_PHYS_NET_NAME" "PD_SATA0_CONTROLLER_TYPE_R"
					( Origin gPackager )
				)
				( objectStatus "PD_SATA0_CONTROLLER_TYPE_R" )
			)
			( signal "@baseboard_fab2_lib.baseboard_fab2(sch_1):pd_sata1_controller_type_r"
				( attribute "CDS_PHYS_NET_NAME" "PD_SATA1_CONTROLLER_TYPE_R"
					( Origin gPackager )
				)
				( objectStatus "PD_SATA1_CONTROLLER_TYPE_R" )
			)
			( signal "@baseboard_fab2_lib.baseboard_fab2(sch_1):pu_datain1_sata_0_r"
				( attribute "CDS_PHYS_NET_NAME" "PU_DATAIN1_SATA_0_R"
					( Origin gPackager )
				)
				( objectStatus "PU_DATAIN1_SATA_0_R" )
			)
			( signal "@baseboard_fab2_lib.baseboard_fab2(sch_1):pu_datain1_sata_1_r"
				( attribute "CDS_PHYS_NET_NAME" "PU_DATAIN1_SATA_1_R"
					( Origin gPackager )
				)
				( objectStatus "PU_DATAIN1_SATA_1_R" )
			)
			( signal "@baseboard_fab2_lib.baseboard_fab2(sch_1):sata6g_p0_rx_c_dn"
				( attribute "CDS_PHYS_NET_NAME" "SATA6G_P0_RX_C_DN"
					( Origin gPackager )
				)
				( objectStatus "SATA6G_P0_RX_C_DN" )
			)
			( signal "@baseboard_fab2_lib.baseboard_fab2(sch_1):sata6g_p0_rx_c_dp"
				( attribute "CDS_PHYS_NET_NAME" "SATA6G_P0_RX_C_DP"
					( Origin gPackager )
				)
				( objectStatus "SATA6G_P0_RX_C_DP" )
			)
			( signal "@baseboard_fab2_lib.baseboard_fab2(sch_1):sata6g_p0_tx_c_dn"
				( attribute "CDS_PHYS_NET_NAME" "SATA6G_P0_TX_C_DN"
					( Origin gPackager )
				)
				( objectStatus "SATA6G_P0_TX_C_DN" )
			)
			( signal "@baseboard_fab2_lib.baseboard_fab2(sch_1):sata6g_p0_tx_c_dp"
				( attribute "CDS_PHYS_NET_NAME" "SATA6G_P0_TX_C_DP"
					( Origin gPackager )
				)
				( objectStatus "SATA6G_P0_TX_C_DP" )
			)
			( signal "@baseboard_fab2_lib.baseboard_fab2(sch_1):sata6g_p1_rx_c_dn"
				( attribute "CDS_PHYS_NET_NAME" "SATA6G_P1_RX_C_DN"
					( Origin gPackager )
				)
				( objectStatus "SATA6G_P1_RX_C_DN" )
			)
			( signal "@baseboard_fab2_lib.baseboard_fab2(sch_1):sata6g_p1_rx_c_dp"
				( attribute "CDS_PHYS_NET_NAME" "SATA6G_P1_RX_C_DP"
					( Origin gPackager )
				)
				( objectStatus "SATA6G_P1_RX_C_DP" )
			)
			( signal "@baseboard_fab2_lib.baseboard_fab2(sch_1):sata6g_p1_tx_c_dn"
				( attribute "CDS_PHYS_NET_NAME" "SATA6G_P1_TX_C_DN"
					( Origin gPackager )
				)
				( objectStatus "SATA6G_P1_TX_C_DN" )
			)
			( signal "@baseboard_fab2_lib.baseboard_fab2(sch_1):sata6g_p1_tx_c_dp"
				( attribute "CDS_PHYS_NET_NAME" "SATA6G_P1_TX_C_DP"
					( Origin gPackager )
				)
				( objectStatus "SATA6G_P1_TX_C_DP" )
			)
			( signal "@baseboard_fab2_lib.baseboard_fab2(sch_1):sata6g_p2_rx_c_dn"
				( attribute "CDS_PHYS_NET_NAME" "SATA6G_P2_RX_C_DN"
					( Origin gPackager )
				)
				( objectStatus "SATA6G_P2_RX_C_DN" )
			)
			( signal "@baseboard_fab2_lib.baseboard_fab2(sch_1):sata6g_p2_rx_c_dp"
				( attribute "CDS_PHYS_NET_NAME" "SATA6G_P2_RX_C_DP"
					( Origin gPackager )
				)
				( objectStatus "SATA6G_P2_RX_C_DP" )
			)
			( signal "@baseboard_fab2_lib.baseboard_fab2(sch_1):sata6g_p2_tx_c_dn"
				( attribute "CDS_PHYS_NET_NAME" "SATA6G_P2_TX_C_DN"
					( Origin gPackager )
				)
				( objectStatus "SATA6G_P2_TX_C_DN" )
			)
			( signal "@baseboard_fab2_lib.baseboard_fab2(sch_1):sata6g_p2_tx_c_dp"
				( attribute "CDS_PHYS_NET_NAME" "SATA6G_P2_TX_C_DP"
					( Origin gPackager )
				)
				( objectStatus "SATA6G_P2_TX_C_DP" )
			)
			( signal "@baseboard_fab2_lib.baseboard_fab2(sch_1):sata6g_p3_rx_c_dn"
				( attribute "CDS_PHYS_NET_NAME" "SATA6G_P3_RX_C_DN"
					( Origin gPackager )
				)
				( objectStatus "SATA6G_P3_RX_C_DN" )
			)
			( signal "@baseboard_fab2_lib.baseboard_fab2(sch_1):sata6g_p3_rx_c_dp"
				( attribute "CDS_PHYS_NET_NAME" "SATA6G_P3_RX_C_DP"
					( Origin gPackager )
				)
				( objectStatus "SATA6G_P3_RX_C_DP" )
			)
			( signal "@baseboard_fab2_lib.baseboard_fab2(sch_1):sata6g_p3_tx_c_dn"
				( attribute "CDS_PHYS_NET_NAME" "SATA6G_P3_TX_C_DN"
					( Origin gPackager )
				)
				( objectStatus "SATA6G_P3_TX_C_DN" )
			)
			( signal "@baseboard_fab2_lib.baseboard_fab2(sch_1):sata6g_p3_tx_c_dp"
				( attribute "CDS_PHYS_NET_NAME" "SATA6G_P3_TX_C_DP"
					( Origin gPackager )
				)
				( objectStatus "SATA6G_P3_TX_C_DP" )
			)
			( signal "@baseboard_fab2_lib.baseboard_fab2(sch_1):sata6g_p4_rx_c_dn"
				( attribute "CDS_PHYS_NET_NAME" "SATA6G_P4_RX_C_DN"
					( Origin gPackager )
				)
				( objectStatus "SATA6G_P4_RX_C_DN" )
			)
			( signal "@baseboard_fab2_lib.baseboard_fab2(sch_1):sata6g_p4_rx_c_dp"
				( attribute "CDS_PHYS_NET_NAME" "SATA6G_P4_RX_C_DP"
					( Origin gPackager )
				)
				( objectStatus "SATA6G_P4_RX_C_DP" )
			)
			( signal "@baseboard_fab2_lib.baseboard_fab2(sch_1):sata6g_p4_tx_c_dn"
				( attribute "CDS_PHYS_NET_NAME" "SATA6G_P4_TX_C_DN"
					( Origin gPackager )
				)
				( objectStatus "SATA6G_P4_TX_C_DN" )
			)
			( signal "@baseboard_fab2_lib.baseboard_fab2(sch_1):sata6g_p4_tx_c_dp"
				( attribute "CDS_PHYS_NET_NAME" "SATA6G_P4_TX_C_DP"
					( Origin gPackager )
				)
				( objectStatus "SATA6G_P4_TX_C_DP" )
			)
			( signal "@baseboard_fab2_lib.baseboard_fab2(sch_1):sata6g_p5_rx_c_dn"
				( attribute "CDS_PHYS_NET_NAME" "SATA6G_P5_RX_C_DN"
					( Origin gPackager )
				)
				( objectStatus "SATA6G_P5_RX_C_DN" )
			)
			( signal "@baseboard_fab2_lib.baseboard_fab2(sch_1):sata6g_p5_rx_c_dp"
				( attribute "CDS_PHYS_NET_NAME" "SATA6G_P5_RX_C_DP"
					( Origin gPackager )
				)
				( objectStatus "SATA6G_P5_RX_C_DP" )
			)
			( signal "@baseboard_fab2_lib.baseboard_fab2(sch_1):sata6g_p5_tx_c_dn"
				( attribute "CDS_PHYS_NET_NAME" "SATA6G_P5_TX_C_DN"
					( Origin gPackager )
				)
				( objectStatus "SATA6G_P5_TX_C_DN" )
			)
			( signal "@baseboard_fab2_lib.baseboard_fab2(sch_1):sata6g_p5_tx_c_dp"
				( attribute "CDS_PHYS_NET_NAME" "SATA6G_P5_TX_C_DP"
					( Origin gPackager )
				)
				( objectStatus "SATA6G_P5_TX_C_DP" )
			)
			( signal "@baseboard_fab2_lib.baseboard_fab2(sch_1):sata6g_p6_rx_c_dn"
				( attribute "CDS_PHYS_NET_NAME" "SATA6G_P6_RX_C_DN"
					( Origin gPackager )
				)
				( objectStatus "SATA6G_P6_RX_C_DN" )
			)
			( signal "@baseboard_fab2_lib.baseboard_fab2(sch_1):sata6g_p6_rx_c_dp"
				( attribute "CDS_PHYS_NET_NAME" "SATA6G_P6_RX_C_DP"
					( Origin gPackager )
				)
				( objectStatus "SATA6G_P6_RX_C_DP" )
			)
			( signal "@baseboard_fab2_lib.baseboard_fab2(sch_1):sata6g_p6_tx_c_dn"
				( attribute "CDS_PHYS_NET_NAME" "SATA6G_P6_TX_C_DN"
					( Origin gPackager )
				)
				( objectStatus "SATA6G_P6_TX_C_DN" )
			)
			( signal "@baseboard_fab2_lib.baseboard_fab2(sch_1):sata6g_p6_tx_c_dp"
				( attribute "CDS_PHYS_NET_NAME" "SATA6G_P6_TX_C_DP"
					( Origin gPackager )
				)
				( objectStatus "SATA6G_P6_TX_C_DP" )
			)
			( signal "@baseboard_fab2_lib.baseboard_fab2(sch_1):sata6g_p7_rx_c_dn"
				( attribute "CDS_PHYS_NET_NAME" "SATA6G_P7_RX_C_DN"
					( Origin gPackager )
				)
				( objectStatus "SATA6G_P7_RX_C_DN" )
			)
			( signal "@baseboard_fab2_lib.baseboard_fab2(sch_1):sata6g_p7_rx_c_dp"
				( attribute "CDS_PHYS_NET_NAME" "SATA6G_P7_RX_C_DP"
					( Origin gPackager )
				)
				( objectStatus "SATA6G_P7_RX_C_DP" )
			)
			( signal "@baseboard_fab2_lib.baseboard_fab2(sch_1):sata6g_p7_tx_c_dn"
				( attribute "CDS_PHYS_NET_NAME" "SATA6G_P7_TX_C_DN"
					( Origin gPackager )
				)
				( objectStatus "SATA6G_P7_TX_C_DN" )
			)
			( signal "@baseboard_fab2_lib.baseboard_fab2(sch_1):sata6g_p7_tx_c_dp"
				( attribute "CDS_PHYS_NET_NAME" "SATA6G_P7_TX_C_DP"
					( Origin gPackager )
				)
				( objectStatus "SATA6G_P7_TX_C_DP" )
			)
			( signal "@baseboard_fab2_lib.baseboard_fab2(sch_1):sgpio_pch_sata_clock_r"
				( attribute "CDS_PHYS_NET_NAME" "SGPIO_PCH_SATA_CLOCK_R"
					( Origin gPackager )
				)
				( objectStatus "SGPIO_PCH_SATA_CLOCK_R" )
			)
			( signal "@baseboard_fab2_lib.baseboard_fab2(sch_1):sgpio_pch_sata_dout0_r"
				( attribute "CDS_PHYS_NET_NAME" "SGPIO_PCH_SATA_DOUT0_R"
					( Origin gPackager )
				)
				( objectStatus "SGPIO_PCH_SATA_DOUT0_R" )
			)
			( signal "@baseboard_fab2_lib.baseboard_fab2(sch_1):sgpio_pch_sata_load_r"
				( attribute "CDS_PHYS_NET_NAME" "SGPIO_PCH_SATA_LOAD_R"
					( Origin gPackager )
				)
				( objectStatus "SGPIO_PCH_SATA_LOAD_R" )
			)
			( signal "@baseboard_fab2_lib.baseboard_fab2(sch_1):tp_fm_qat_cbl_prsnt0_r_n"
				( attribute "CDS_PHYS_NET_NAME" "TP_FM_QAT_CBL_PRSNT0_R_N"
					( Origin gPackager )
				)
				( objectStatus "TP_FM_QAT_CBL_PRSNT0_R_N" )
			)
			( signal "@baseboard_fab2_lib.baseboard_fab2(sch_1):tp_fm_qat_cbl_prsnt1_n_r"
				( attribute "CDS_PHYS_NET_NAME" "TP_FM_QAT_CBL_PRSNT1_N_R"
					( Origin gPackager )
				)
				( objectStatus "TP_FM_QAT_CBL_PRSNT1_N_R" )
			)
			( signal "@baseboard_fab2_lib.baseboard_fab2(sch_1):tp_sgpio_sata_clock1_r"
				( attribute "CDS_PHYS_NET_NAME" "TP_SGPIO_SATA_CLOCK1_R"
					( Origin gPackager )
				)
				( objectStatus "TP_SGPIO_SATA_CLOCK1_R" )
			)
			( signal "@baseboard_fab2_lib.baseboard_fab2(sch_1):tp_sgpio_sata_data1_r"
				( attribute "CDS_PHYS_NET_NAME" "TP_SGPIO_SATA_DATA1_R"
					( Origin gPackager )
				)
				( objectStatus "TP_SGPIO_SATA_DATA1_R" )
			)
			( signal "@baseboard_fab2_lib.baseboard_fab2(sch_1):tp_sgpio_sata_load1_r"
				( attribute "CDS_PHYS_NET_NAME" "TP_SGPIO_SATA_LOAD1_R"
					( Origin gPackager )
				)
				( objectStatus "TP_SGPIO_SATA_LOAD1_R" )
			)
			( signal "@baseboard_fab2_lib.baseboard_fab2(sch_1):sgpio_pch_ssata_clock_r"
				( attribute "CDS_PHYS_NET_NAME" "SGPIO_PCH_SSATA_CLOCK_R"
					( Origin gPackager )
				)
				( objectStatus "SGPIO_PCH_SSATA_CLOCK_R" )
			)
			( signal "@baseboard_fab2_lib.baseboard_fab2(sch_1):sgpio_pch_ssata_dout0_r"
				( attribute "CDS_PHYS_NET_NAME" "SGPIO_PCH_SSATA_DOUT0_R"
					( Origin gPackager )
				)
				( objectStatus "SGPIO_PCH_SSATA_DOUT0_R" )
			)
			( signal "@baseboard_fab2_lib.baseboard_fab2(sch_1):sgpio_pch_ssata_load_r"
				( attribute "CDS_PHYS_NET_NAME" "SGPIO_PCH_SSATA_LOAD_R"
					( Origin gPackager )
				)
				( objectStatus "SGPIO_PCH_SSATA_LOAD_R" )
			)
			( signal "@baseboard_fab2_lib.baseboard_fab2(sch_1):fm_beep_led_p"
				( attribute "CDS_PHYS_NET_NAME" "FM_BEEP_LED_P"
					( Origin gPackager )
				)
				( objectStatus "FM_BEEP_LED_P" )
			)
			( signal "@baseboard_fab2_lib.baseboard_fab2(sch_1):fm_pwr_btn_r_n"
				( attribute "CDS_PHYS_NET_NAME" "FM_PWR_BTN_R_N"
					( Origin gPackager )
				)
				( objectStatus "FM_PWR_BTN_R_N" )
			)
			( signal "@baseboard_fab2_lib.baseboard_fab2(sch_1):fm_speaker_pch_n"
				( attribute "CDS_PHYS_NET_NAME" "FM_SPEAKER_PCH_N"
					( Origin gPackager )
				)
				( objectStatus "FM_SPEAKER_PCH_N" )
			)
			( signal "@baseboard_fab2_lib.baseboard_fab2(sch_1):fp_id_led_p5v_stby_n"
				( attribute "CDS_PHYS_NET_NAME" "FP_ID_LED_P5V_STBY_N"
					( Origin gPackager )
				)
				( objectStatus "FP_ID_LED_P5V_STBY_N" )
			)
			( signal "@baseboard_fab2_lib.baseboard_fab2(sch_1):fp_id_led_xor_r"
				( attribute "CDS_PHYS_NET_NAME" "FP_ID_LED_XOR_R"
					( Origin gPackager )
				)
				( objectStatus "FP_ID_LED_XOR_R" )
			)
			( signal "@baseboard_fab2_lib.baseboard_fab2(sch_1):fp_pwr_btn_buf1_n"
				( attribute "CDS_PHYS_NET_NAME" "FP_PWR_BTN_BUF1_N"
					( Origin gPackager )
				)
				( objectStatus "FP_PWR_BTN_BUF1_N" )
			)
			( signal "@baseboard_fab2_lib.baseboard_fab2(sch_1):fp_pwr_btn_r1_n"
				( attribute "CDS_PHYS_NET_NAME" "FP_PWR_BTN_R1_N"
					( Origin gPackager )
				)
				( objectStatus "FP_PWR_BTN_R1_N" )
			)
			( signal "@baseboard_fab2_lib.baseboard_fab2(sch_1):fp_pwr_btn_r_n"
				( attribute "CDS_PHYS_NET_NAME" "FP_PWR_BTN_R_N"
					( Origin gPackager )
				)
				( objectStatus "FP_PWR_BTN_R_N" )
			)
			( signal "@baseboard_fab2_lib.baseboard_fab2(sch_1):fp_rst_btn_buf1_n"
				( attribute "CDS_PHYS_NET_NAME" "FP_RST_BTN_BUF1_N"
					( Origin gPackager )
				)
				( objectStatus "FP_RST_BTN_BUF1_N" )
			)
			( signal "@baseboard_fab2_lib.baseboard_fab2(sch_1):fp_rst_btn_r_n"
				( attribute "CDS_PHYS_NET_NAME" "FP_RST_BTN_R_N"
					( Origin gPackager )
				)
				( objectStatus "FP_RST_BTN_R_N" )
			)
			( signal "@baseboard_fab2_lib.baseboard_fab2(sch_1):pwrgd_p3v3"
				( attribute "CDS_PHYS_NET_NAME" "PWRGD_P3V3"
					( Origin gPackager )
				)
				( objectStatus "PWRGD_P3V3" )
			)
			( signal "@baseboard_fab2_lib.baseboard_fab2(sch_1):pwrgd_p3v3_r"
				( attribute "CDS_PHYS_NET_NAME" "PWRGD_P3V3_R"
					( Origin gPackager )
				)
				( objectStatus "PWRGD_P3V3_R" )
			)
			( signal "@baseboard_fab2_lib.baseboard_fab2(sch_1):rst_system_btn_buf_n"
				( attribute "CDS_PHYS_NET_NAME" "RST_SYSTEM_BTN_BUF_N"
					( Origin gPackager )
				)
				( objectStatus "RST_SYSTEM_BTN_BUF_N" )
			)
			( signal "@baseboard_fab2_lib.baseboard_fab2(sch_1):p5v_usb"
				( alias ( signalRef "@baseboard_fab2_lib.baseboard_fab2(sch_1):page176_p5v_usb") )
				( attribute "CDS_PHYS_NET_NAME" "P5V_USB"
					( Origin gPackager )
				)
				( attribute "VOLTAGE" "5V"
					( Units "uVoltage" "V" 1.000000)
					( Status sAliasFlattened )
					( Origin gFrontEnd )
				)
				( objectStatus "P5V_USB" )
			)
			( signal "@baseboard_fab2_lib.baseboard_fab2(sch_1):page176_p5v_usb"
				( attribute "VOLTAGE" "5V"
					( Units "uVoltage" "V" 1.000000)
					( Origin gFrontEnd )
				)
				( objectFlag fObjectAlias )
				( objectStatus "page176_p5v_usb" )
			)
			( signal "@baseboard_fab2_lib.baseboard_fab2(sch_1):tp_usb_esd_ac2"
				( attribute "CDS_PHYS_NET_NAME" "TP_USB_ESD_AC2"
					( Origin gPackager )
				)
				( objectStatus "TP_USB_ESD_AC2" )
			)
			( signal "@baseboard_fab2_lib.baseboard_fab2(sch_1):tp_usb_esd_ac3"
				( attribute "CDS_PHYS_NET_NAME" "TP_USB_ESD_AC3"
					( Origin gPackager )
				)
				( objectStatus "TP_USB_ESD_AC3" )
			)
			( signal "@baseboard_fab2_lib.baseboard_fab2(sch_1):tp_usb_esd_out2"
				( attribute "CDS_PHYS_NET_NAME" "TP_USB_ESD_OUT2"
					( Origin gPackager )
				)
				( objectStatus "TP_USB_ESD_OUT2" )
			)
			( signal "@baseboard_fab2_lib.baseboard_fab2(sch_1):tp_usb_esd_out3"
				( attribute "CDS_PHYS_NET_NAME" "TP_USB_ESD_OUT3"
					( Origin gPackager )
				)
				( objectStatus "TP_USB_ESD_OUT3" )
			)
			( signal "@baseboard_fab2_lib.baseboard_fab2(sch_1):usb2_p01_esd_dn"
				( attribute "CDS_PHYS_NET_NAME" "USB2_P01_ESD_DN"
					( Origin gPackager )
				)
				( objectStatus "USB2_P01_ESD_DN" )
			)
			( signal "@baseboard_fab2_lib.baseboard_fab2(sch_1):usb2_p01_esd_dp"
				( attribute "CDS_PHYS_NET_NAME" "USB2_P01_ESD_DP"
					( Origin gPackager )
				)
				( objectStatus "USB2_P01_ESD_DP" )
			)
			( signal "@baseboard_fab2_lib.baseboard_fab2(sch_1):fm_bmc_fault_led"
				( attribute "CDS_PHYS_NET_NAME" "FM_BMC_FAULT_LED"
					( Origin gPackager )
				)
				( objectStatus "FM_BMC_FAULT_LED" )
			)
			( signal "@baseboard_fab2_lib.baseboard_fab2(sch_1):fm_red_led_anode"
				( attribute "CDS_PHYS_NET_NAME" "FM_RED_LED_ANODE"
					( Origin gPackager )
				)
				( objectStatus "FM_RED_LED_ANODE" )
			)
			( signal "@baseboard_fab2_lib.baseboard_fab2(sch_1):fm_red_led_cathode"
				( attribute "CDS_PHYS_NET_NAME" "FM_RED_LED_CATHODE"
					( Origin gPackager )
				)
				( objectStatus "FM_RED_LED_CATHODE" )
			)
			( signal "@baseboard_fab2_lib.baseboard_fab2(sch_1):fp_led_hdd_activity_and_n"
				( attribute "CDS_PHYS_NET_NAME" "FP_LED_HDD_ACTIVITY_AND_N"
					( Origin gPackager )
				)
				( objectStatus "FP_LED_HDD_ACTIVITY_AND_N" )
			)
			( signal "@baseboard_fab2_lib.baseboard_fab2(sch_1):fp_led_hdd_activity_and_r_n"
				( attribute "CDS_PHYS_NET_NAME" "FP_LED_HDD_ACTIVITY_AND_R_N"
					( Origin gPackager )
				)
				( objectStatus "FP_LED_HDD_ACTIVITY_AND_R_N" )
			)
			( signal "@baseboard_fab2_lib.baseboard_fab2(sch_1):led_p5v_stby"
				( attribute "CDS_PHYS_NET_NAME" "LED_P5V_STBY"
					( Origin gPackager )
				)
				( objectStatus "LED_P5V_STBY" )
			)
			( signal "@baseboard_fab2_lib.baseboard_fab2(sch_1):led_sas_act_r_n"
				( attribute "CDS_PHYS_NET_NAME" "LED_SAS_ACT_R_N"
					( Origin gPackager )
				)
				( objectStatus "LED_SAS_ACT_R_N" )
			)
			( signal "@baseboard_fab2_lib.baseboard_fab2(sch_1):led_sata_act_r_n"
				( attribute "CDS_PHYS_NET_NAME" "LED_SATA_ACT_R_N"
					( Origin gPackager )
				)
				( objectStatus "LED_SATA_ACT_R_N" )
			)
			( signal "@baseboard_fab2_lib.baseboard_fab2(sch_1):fan_pwm_out_sys0_r1"
				( attribute "CDS_PHYS_NET_NAME" "FAN_PWM_OUT_SYS0_R1"
					( Origin gPackager )
				)
				( objectStatus "FAN_PWM_OUT_SYS0_R1" )
			)
			( signal "@baseboard_fab2_lib.baseboard_fab2(sch_1):fan_tach0_r"
				( attribute "CDS_PHYS_NET_NAME" "FAN_TACH0_R"
					( Origin gPackager )
				)
				( objectStatus "FAN_TACH0_R" )
			)
			( signal "@baseboard_fab2_lib.baseboard_fab2(sch_1):fan_tach1_r"
				( attribute "CDS_PHYS_NET_NAME" "FAN_TACH1_R"
					( Origin gPackager )
				)
				( objectStatus "FAN_TACH1_R" )
			)
			( signal "@baseboard_fab2_lib.baseboard_fab2(sch_1):fan_tach2_r"
				( attribute "CDS_PHYS_NET_NAME" "FAN_TACH2_R"
					( Origin gPackager )
				)
				( objectStatus "FAN_TACH2_R" )
			)
			( signal "@baseboard_fab2_lib.baseboard_fab2(sch_1):fan_tach3_r"
				( attribute "CDS_PHYS_NET_NAME" "FAN_TACH3_R"
					( Origin gPackager )
				)
				( objectStatus "FAN_TACH3_R" )
			)
			( signal "@baseboard_fab2_lib.baseboard_fab2(sch_1):fm_ctnr_ps_on_r"
				( attribute "CDS_PHYS_NET_NAME" "FM_CTNR_PS_ON_R"
					( Origin gPackager )
				)
				( objectStatus "FM_CTNR_PS_ON_R" )
			)
			( signal "@baseboard_fab2_lib.baseboard_fab2(sch_1):fm_mated_in_d1_n"
				( attribute "CDS_PHYS_NET_NAME" "FM_MATED_IN_D1_N"
					( Origin gPackager )
				)
				( objectStatus "FM_MATED_IN_D1_N" )
			)
			( signal "@baseboard_fab2_lib.baseboard_fab2(sch_1):fm_mated_in_d2_n"
				( attribute "CDS_PHYS_NET_NAME" "FM_MATED_IN_D2_N"
					( Origin gPackager )
				)
				( objectStatus "FM_MATED_IN_D2_N" )
			)
			( signal "@baseboard_fab2_lib.baseboard_fab2(sch_1):fm_mated_in_n"
				( attribute "CDS_PHYS_NET_NAME" "FM_MATED_IN_N"
					( Origin gPackager )
				)
				( objectStatus "FM_MATED_IN_N" )
			)
			( signal "@baseboard_fab2_lib.baseboard_fab2(sch_1):fm_p12v_hotswap0_en"
				( attribute "CDS_PHYS_NET_NAME" "FM_P12V_HOTSWAP0_EN"
					( Origin gPackager )
				)
				( objectStatus "FM_P12V_HOTSWAP0_EN" )
			)
			( signal "@baseboard_fab2_lib.baseboard_fab2(sch_1):fm_ps_en"
				( attribute "CDS_PHYS_NET_NAME" "FM_PS_EN"
					( Origin gPackager )
				)
				( objectStatus "FM_PS_EN" )
			)
			( signal "@baseboard_fab2_lib.baseboard_fab2(sch_1):irq_sml1_pmbus_alert_r_n"
				( attribute "CDS_PHYS_NET_NAME" "IRQ_SML1_PMBUS_ALERT_R_N"
					( Origin gPackager )
				)
				( objectStatus "IRQ_SML1_PMBUS_ALERT_R_N" )
			)
			( signal "@baseboard_fab2_lib.baseboard_fab2(sch_1):p12v_psu"
				( alias ( signalRef "@baseboard_fab2_lib.baseboard_fab2(sch_1):page181_p12v_psu") )
				( alias ( signalRef "@baseboard_fab2_lib.baseboard_fab2(sch_1):page195_p12v_psu") )
				( alias ( signalRef "@baseboard_fab2_lib.baseboard_fab2(sch_1):page199_p12v_psu") )
				( alias ( signalRef "@baseboard_fab2_lib.baseboard_fab2(sch_1):page200_p12v_psu") )
				( attribute "VOLTAGE" "12.0"
					( Units "uVoltage" "V" 1.000000)
					( Status sAliasFlattened )
					( Origin gFrontEnd )
				)
				( attribute "CDS_PHYS_NET_NAME" "P12V_PSU"
					( Origin gPackager )
				)
				( objectStatus "P12V_PSU" )
			)
			( signal "@baseboard_fab2_lib.baseboard_fab2(sch_1):page181_p12v_psu"
				( attribute "VOLTAGE" "12.0"
					( Units "uVoltage" "V" 1.000000)
					( Origin gFrontEnd )
				)
				( objectFlag fObjectAlias )
				( objectStatus "page181_p12v_psu" )
			)
			( signal "@baseboard_fab2_lib.baseboard_fab2(sch_1):page195_p12v_psu"
				( attribute "VOLTAGE" "12.0"
					( Units "uVoltage" "V" 1.000000)
					( Origin gFrontEnd )
				)
				( objectFlag fObjectAlias )
				( objectStatus "page195_p12v_psu" )
			)
			( signal "@baseboard_fab2_lib.baseboard_fab2(sch_1):page199_p12v_psu"
				( attribute "VOLTAGE" "12.0"
					( Units "uVoltage" "V" 1.000000)
					( Origin gFrontEnd )
				)
				( objectFlag fObjectAlias )
				( objectStatus "page199_p12v_psu" )
			)
			( signal "@baseboard_fab2_lib.baseboard_fab2(sch_1):page200_p12v_psu"
				( attribute "VOLTAGE" "12.0"
					( Units "uVoltage" "V" 1.000000)
					( Origin gFrontEnd )
				)
				( objectFlag fObjectAlias )
				( objectStatus "page200_p12v_psu" )
			)
			( signal "@baseboard_fab2_lib.baseboard_fab2(sch_1):p3e_cpu1_pe3_mp_c_txn(0)"
				( attribute "CDS_PHYS_NET_NAME" "P3E_CPU1_PE3_MP_C_TXN<0>"
					( Origin gPackager )
				)
				( attribute "PNN" "P3E_CPU1_PE3_MP_C_TXN<0>"
					( Origin gPackager )
				)
				( objectStatus "P3E_CPU1_PE3_MP_C_TXN<0>" )
			)
			( signal "@baseboard_fab2_lib.baseboard_fab2(sch_1):p3e_cpu1_pe3_mp_c_txn(1)"
				( attribute "CDS_PHYS_NET_NAME" "P3E_CPU1_PE3_MP_C_TXN<1>"
					( Origin gPackager )
				)
				( attribute "PNN" "P3E_CPU1_PE3_MP_C_TXN<1>"
					( Origin gPackager )
				)
				( objectStatus "P3E_CPU1_PE3_MP_C_TXN<1>" )
			)
			( signal "@baseboard_fab2_lib.baseboard_fab2(sch_1):p3e_cpu1_pe3_mp_c_txn(2)"
				( attribute "CDS_PHYS_NET_NAME" "P3E_CPU1_PE3_MP_C_TXN<2>"
					( Origin gPackager )
				)
				( attribute "PNN" "P3E_CPU1_PE3_MP_C_TXN<2>"
					( Origin gPackager )
				)
				( objectStatus "P3E_CPU1_PE3_MP_C_TXN<2>" )
			)
			( signal "@baseboard_fab2_lib.baseboard_fab2(sch_1):p3e_cpu1_pe3_mp_c_txn(3)"
				( attribute "CDS_PHYS_NET_NAME" "P3E_CPU1_PE3_MP_C_TXN<3>"
					( Origin gPackager )
				)
				( attribute "PNN" "P3E_CPU1_PE3_MP_C_TXN<3>"
					( Origin gPackager )
				)
				( objectStatus "P3E_CPU1_PE3_MP_C_TXN<3>" )
			)
			( signal "@baseboard_fab2_lib.baseboard_fab2(sch_1):p3e_cpu1_pe3_mp_c_txn(4)"
				( attribute "CDS_PHYS_NET_NAME" "P3E_CPU1_PE3_MP_C_TXN<4>"
					( Origin gPackager )
				)
				( attribute "PNN" "P3E_CPU1_PE3_MP_C_TXN<4>"
					( Origin gPackager )
				)
				( objectStatus "P3E_CPU1_PE3_MP_C_TXN<4>" )
			)
			( signal "@baseboard_fab2_lib.baseboard_fab2(sch_1):p3e_cpu1_pe3_mp_c_txn(5)"
				( attribute "CDS_PHYS_NET_NAME" "P3E_CPU1_PE3_MP_C_TXN<5>"
					( Origin gPackager )
				)
				( attribute "PNN" "P3E_CPU1_PE3_MP_C_TXN<5>"
					( Origin gPackager )
				)
				( objectStatus "P3E_CPU1_PE3_MP_C_TXN<5>" )
			)
			( signal "@baseboard_fab2_lib.baseboard_fab2(sch_1):p3e_cpu1_pe3_mp_c_txn(6)"
				( attribute "CDS_PHYS_NET_NAME" "P3E_CPU1_PE3_MP_C_TXN<6>"
					( Origin gPackager )
				)
				( attribute "PNN" "P3E_CPU1_PE3_MP_C_TXN<6>"
					( Origin gPackager )
				)
				( objectStatus "P3E_CPU1_PE3_MP_C_TXN<6>" )
			)
			( signal "@baseboard_fab2_lib.baseboard_fab2(sch_1):p3e_cpu1_pe3_mp_c_txn(7)"
				( attribute "CDS_PHYS_NET_NAME" "P3E_CPU1_PE3_MP_C_TXN<7>"
					( Origin gPackager )
				)
				( attribute "PNN" "P3E_CPU1_PE3_MP_C_TXN<7>"
					( Origin gPackager )
				)
				( objectStatus "P3E_CPU1_PE3_MP_C_TXN<7>" )
			)
			( signal "@baseboard_fab2_lib.baseboard_fab2(sch_1):p3e_cpu1_pe3_mp_c_txp(0)"
				( attribute "CDS_PHYS_NET_NAME" "P3E_CPU1_PE3_MP_C_TXP<0>"
					( Origin gPackager )
				)
				( attribute "PNN" "P3E_CPU1_PE3_MP_C_TXP<0>"
					( Origin gPackager )
				)
				( objectStatus "P3E_CPU1_PE3_MP_C_TXP<0>" )
			)
			( signal "@baseboard_fab2_lib.baseboard_fab2(sch_1):p3e_cpu1_pe3_mp_c_txp(1)"
				( attribute "CDS_PHYS_NET_NAME" "P3E_CPU1_PE3_MP_C_TXP<1>"
					( Origin gPackager )
				)
				( attribute "PNN" "P3E_CPU1_PE3_MP_C_TXP<1>"
					( Origin gPackager )
				)
				( objectStatus "P3E_CPU1_PE3_MP_C_TXP<1>" )
			)
			( signal "@baseboard_fab2_lib.baseboard_fab2(sch_1):p3e_cpu1_pe3_mp_c_txp(2)"
				( attribute "CDS_PHYS_NET_NAME" "P3E_CPU1_PE3_MP_C_TXP<2>"
					( Origin gPackager )
				)
				( attribute "PNN" "P3E_CPU1_PE3_MP_C_TXP<2>"
					( Origin gPackager )
				)
				( objectStatus "P3E_CPU1_PE3_MP_C_TXP<2>" )
			)
			( signal "@baseboard_fab2_lib.baseboard_fab2(sch_1):p3e_cpu1_pe3_mp_c_txp(3)"
				( attribute "CDS_PHYS_NET_NAME" "P3E_CPU1_PE3_MP_C_TXP<3>"
					( Origin gPackager )
				)
				( attribute "PNN" "P3E_CPU1_PE3_MP_C_TXP<3>"
					( Origin gPackager )
				)
				( objectStatus "P3E_CPU1_PE3_MP_C_TXP<3>" )
			)
			( signal "@baseboard_fab2_lib.baseboard_fab2(sch_1):p3e_cpu1_pe3_mp_c_txp(4)"
				( attribute "CDS_PHYS_NET_NAME" "P3E_CPU1_PE3_MP_C_TXP<4>"
					( Origin gPackager )
				)
				( attribute "PNN" "P3E_CPU1_PE3_MP_C_TXP<4>"
					( Origin gPackager )
				)
				( objectStatus "P3E_CPU1_PE3_MP_C_TXP<4>" )
			)
			( signal "@baseboard_fab2_lib.baseboard_fab2(sch_1):p3e_cpu1_pe3_mp_c_txp(5)"
				( attribute "CDS_PHYS_NET_NAME" "P3E_CPU1_PE3_MP_C_TXP<5>"
					( Origin gPackager )
				)
				( attribute "PNN" "P3E_CPU1_PE3_MP_C_TXP<5>"
					( Origin gPackager )
				)
				( objectStatus "P3E_CPU1_PE3_MP_C_TXP<5>" )
			)
			( signal "@baseboard_fab2_lib.baseboard_fab2(sch_1):p3e_cpu1_pe3_mp_c_txp(6)"
				( attribute "CDS_PHYS_NET_NAME" "P3E_CPU1_PE3_MP_C_TXP<6>"
					( Origin gPackager )
				)
				( attribute "PNN" "P3E_CPU1_PE3_MP_C_TXP<6>"
					( Origin gPackager )
				)
				( objectStatus "P3E_CPU1_PE3_MP_C_TXP<6>" )
			)
			( signal "@baseboard_fab2_lib.baseboard_fab2(sch_1):p3e_cpu1_pe3_mp_c_txp(7)"
				( attribute "CDS_PHYS_NET_NAME" "P3E_CPU1_PE3_MP_C_TXP<7>"
					( Origin gPackager )
				)
				( attribute "PNN" "P3E_CPU1_PE3_MP_C_TXP<7>"
					( Origin gPackager )
				)
				( objectStatus "P3E_CPU1_PE3_MP_C_TXP<7>" )
			)
			( signal "@baseboard_fab2_lib.baseboard_fab2(sch_1):pwrgd_p12v_hsc_dly"
				( attribute "CDS_PHYS_NET_NAME" "PWRGD_P12V_HSC_DLY"
					( Origin gPackager )
				)
				( objectStatus "PWRGD_P12V_HSC_DLY" )
			)
			( signal "@baseboard_fab2_lib.baseboard_fab2(sch_1):rst_pcie_midplane_n"
				( attribute "CDS_PHYS_NET_NAME" "RST_PCIE_MIDPLANE_N"
					( Origin gPackager )
				)
				( objectStatus "RST_PCIE_MIDPLANE_N" )
			)
			( signal "@baseboard_fab2_lib.baseboard_fab2(sch_1):spa_mid_dbg_rx_r"
				( attribute "CDS_PHYS_NET_NAME" "SPA_MID_DBG_RX_R"
					( Origin gPackager )
				)
				( objectStatus "SPA_MID_DBG_RX_R" )
			)
			( signal "@baseboard_fab2_lib.baseboard_fab2(sch_1):spa_mid_dbg_tx_r"
				( attribute "CDS_PHYS_NET_NAME" "SPA_MID_DBG_TX_R"
					( Origin gPackager )
				)
				( objectStatus "SPA_MID_DBG_TX_R" )
			)
			( signal "@baseboard_fab2_lib.baseboard_fab2(sch_1):p3e_cpu1_pe3_mp_c_txn(8)"
				( attribute "CDS_PHYS_NET_NAME" "P3E_CPU1_PE3_MP_C_TXN<8>"
					( Origin gPackager )
				)
				( attribute "PNN" "P3E_CPU1_PE3_MP_C_TXN<8>"
					( Origin gPackager )
				)
				( objectStatus "P3E_CPU1_PE3_MP_C_TXN<8>" )
			)
			( signal "@baseboard_fab2_lib.baseboard_fab2(sch_1):p3e_cpu1_pe3_mp_c_txn(9)"
				( attribute "CDS_PHYS_NET_NAME" "P3E_CPU1_PE3_MP_C_TXN<9>"
					( Origin gPackager )
				)
				( attribute "PNN" "P3E_CPU1_PE3_MP_C_TXN<9>"
					( Origin gPackager )
				)
				( objectStatus "P3E_CPU1_PE3_MP_C_TXN<9>" )
			)
			( signal "@baseboard_fab2_lib.baseboard_fab2(sch_1):p3e_cpu1_pe3_mp_c_txn(10)"
				( attribute "CDS_PHYS_NET_NAME" "P3E_CPU1_PE3_MP_C_TXN<10>"
					( Origin gPackager )
				)
				( attribute "PNN" "P3E_CPU1_PE3_MP_C_TXN<10>"
					( Origin gPackager )
				)
				( objectStatus "P3E_CPU1_PE3_MP_C_TXN<10>" )
			)
			( signal "@baseboard_fab2_lib.baseboard_fab2(sch_1):p3e_cpu1_pe3_mp_c_txn(11)"
				( attribute "CDS_PHYS_NET_NAME" "P3E_CPU1_PE3_MP_C_TXN<11>"
					( Origin gPackager )
				)
				( attribute "PNN" "P3E_CPU1_PE3_MP_C_TXN<11>"
					( Origin gPackager )
				)
				( objectStatus "P3E_CPU1_PE3_MP_C_TXN<11>" )
			)
			( signal "@baseboard_fab2_lib.baseboard_fab2(sch_1):p3e_cpu1_pe3_mp_c_txn(12)"
				( attribute "CDS_PHYS_NET_NAME" "P3E_CPU1_PE3_MP_C_TXN<12>"
					( Origin gPackager )
				)
				( attribute "PNN" "P3E_CPU1_PE3_MP_C_TXN<12>"
					( Origin gPackager )
				)
				( objectStatus "P3E_CPU1_PE3_MP_C_TXN<12>" )
			)
			( signal "@baseboard_fab2_lib.baseboard_fab2(sch_1):p3e_cpu1_pe3_mp_c_txn(13)"
				( attribute "CDS_PHYS_NET_NAME" "P3E_CPU1_PE3_MP_C_TXN<13>"
					( Origin gPackager )
				)
				( attribute "PNN" "P3E_CPU1_PE3_MP_C_TXN<13>"
					( Origin gPackager )
				)
				( objectStatus "P3E_CPU1_PE3_MP_C_TXN<13>" )
			)
			( signal "@baseboard_fab2_lib.baseboard_fab2(sch_1):p3e_cpu1_pe3_mp_c_txn(14)"
				( attribute "CDS_PHYS_NET_NAME" "P3E_CPU1_PE3_MP_C_TXN<14>"
					( Origin gPackager )
				)
				( attribute "PNN" "P3E_CPU1_PE3_MP_C_TXN<14>"
					( Origin gPackager )
				)
				( objectStatus "P3E_CPU1_PE3_MP_C_TXN<14>" )
			)
			( signal "@baseboard_fab2_lib.baseboard_fab2(sch_1):p3e_cpu1_pe3_mp_c_txn(15)"
				( attribute "CDS_PHYS_NET_NAME" "P3E_CPU1_PE3_MP_C_TXN<15>"
					( Origin gPackager )
				)
				( attribute "PNN" "P3E_CPU1_PE3_MP_C_TXN<15>"
					( Origin gPackager )
				)
				( objectStatus "P3E_CPU1_PE3_MP_C_TXN<15>" )
			)
			( signal "@baseboard_fab2_lib.baseboard_fab2(sch_1):p3e_cpu1_pe3_mp_c_txp(8)"
				( attribute "CDS_PHYS_NET_NAME" "P3E_CPU1_PE3_MP_C_TXP<8>"
					( Origin gPackager )
				)
				( attribute "PNN" "P3E_CPU1_PE3_MP_C_TXP<8>"
					( Origin gPackager )
				)
				( objectStatus "P3E_CPU1_PE3_MP_C_TXP<8>" )
			)
			( signal "@baseboard_fab2_lib.baseboard_fab2(sch_1):p3e_cpu1_pe3_mp_c_txp(9)"
				( attribute "CDS_PHYS_NET_NAME" "P3E_CPU1_PE3_MP_C_TXP<9>"
					( Origin gPackager )
				)
				( attribute "PNN" "P3E_CPU1_PE3_MP_C_TXP<9>"
					( Origin gPackager )
				)
				( objectStatus "P3E_CPU1_PE3_MP_C_TXP<9>" )
			)
			( signal "@baseboard_fab2_lib.baseboard_fab2(sch_1):p3e_cpu1_pe3_mp_c_txp(10)"
				( attribute "CDS_PHYS_NET_NAME" "P3E_CPU1_PE3_MP_C_TXP<10>"
					( Origin gPackager )
				)
				( attribute "PNN" "P3E_CPU1_PE3_MP_C_TXP<10>"
					( Origin gPackager )
				)
				( objectStatus "P3E_CPU1_PE3_MP_C_TXP<10>" )
			)
			( signal "@baseboard_fab2_lib.baseboard_fab2(sch_1):p3e_cpu1_pe3_mp_c_txp(11)"
				( attribute "CDS_PHYS_NET_NAME" "P3E_CPU1_PE3_MP_C_TXP<11>"
					( Origin gPackager )
				)
				( attribute "PNN" "P3E_CPU1_PE3_MP_C_TXP<11>"
					( Origin gPackager )
				)
				( objectStatus "P3E_CPU1_PE3_MP_C_TXP<11>" )
			)
			( signal "@baseboard_fab2_lib.baseboard_fab2(sch_1):p3e_cpu1_pe3_mp_c_txp(12)"
				( attribute "CDS_PHYS_NET_NAME" "P3E_CPU1_PE3_MP_C_TXP<12>"
					( Origin gPackager )
				)
				( attribute "PNN" "P3E_CPU1_PE3_MP_C_TXP<12>"
					( Origin gPackager )
				)
				( objectStatus "P3E_CPU1_PE3_MP_C_TXP<12>" )
			)
			( signal "@baseboard_fab2_lib.baseboard_fab2(sch_1):p3e_cpu1_pe3_mp_c_txp(13)"
				( attribute "CDS_PHYS_NET_NAME" "P3E_CPU1_PE3_MP_C_TXP<13>"
					( Origin gPackager )
				)
				( attribute "PNN" "P3E_CPU1_PE3_MP_C_TXP<13>"
					( Origin gPackager )
				)
				( objectStatus "P3E_CPU1_PE3_MP_C_TXP<13>" )
			)
			( signal "@baseboard_fab2_lib.baseboard_fab2(sch_1):p3e_cpu1_pe3_mp_c_txp(14)"
				( attribute "CDS_PHYS_NET_NAME" "P3E_CPU1_PE3_MP_C_TXP<14>"
					( Origin gPackager )
				)
				( attribute "PNN" "P3E_CPU1_PE3_MP_C_TXP<14>"
					( Origin gPackager )
				)
				( objectStatus "P3E_CPU1_PE3_MP_C_TXP<14>" )
			)
			( signal "@baseboard_fab2_lib.baseboard_fab2(sch_1):p3e_cpu1_pe3_mp_c_txp(15)"
				( attribute "CDS_PHYS_NET_NAME" "P3E_CPU1_PE3_MP_C_TXP<15>"
					( Origin gPackager )
				)
				( attribute "PNN" "P3E_CPU1_PE3_MP_C_TXP<15>"
					( Origin gPackager )
				)
				( objectStatus "P3E_CPU1_PE3_MP_C_TXP<15>" )
			)
			( signal "@baseboard_fab2_lib.baseboard_fab2(sch_1):tp_fm_wake_n"
				( attribute "CDS_PHYS_NET_NAME" "TP_FM_WAKE_N"
					( Origin gPackager )
				)
				( objectStatus "TP_FM_WAKE_N" )
			)
			( signal "@baseboard_fab2_lib.baseboard_fab2(sch_1):tp_ioa5"
				( attribute "CDS_PHYS_NET_NAME" "TP_IOA5"
					( Origin gPackager )
				)
				( objectStatus "TP_IOA5" )
			)
			( signal "@baseboard_fab2_lib.baseboard_fab2(sch_1):tp_ioe4"
				( attribute "CDS_PHYS_NET_NAME" "TP_IOE4"
					( Origin gPackager )
				)
				( objectStatus "TP_IOE4" )
			)
			( signal "@baseboard_fab2_lib.baseboard_fab2(sch_1):tp_iof4"
				( attribute "CDS_PHYS_NET_NAME" "TP_IOF4"
					( Origin gPackager )
				)
				( objectStatus "TP_IOF4" )
			)
			( signal "@baseboard_fab2_lib.baseboard_fab2(sch_1):tp_iog3"
				( attribute "CDS_PHYS_NET_NAME" "TP_IOG3"
					( Origin gPackager )
				)
				( objectStatus "TP_IOG3" )
			)
			( signal "@baseboard_fab2_lib.baseboard_fab2(sch_1):tp_ioh3"
				( attribute "CDS_PHYS_NET_NAME" "TP_IOH3"
					( Origin gPackager )
				)
				( objectStatus "TP_IOH3" )
			)
			( signal "@baseboard_fab2_lib.baseboard_fab2(sch_1):tp_ioh4"
				( attribute "CDS_PHYS_NET_NAME" "TP_IOH4"
					( Origin gPackager )
				)
				( objectStatus "TP_IOH4" )
			)
			( signal "@baseboard_fab2_lib.baseboard_fab2(sch_1):tp_ioi4"
				( attribute "CDS_PHYS_NET_NAME" "TP_IOI4"
					( Origin gPackager )
				)
				( objectStatus "TP_IOI4" )
			)
			( signal "@baseboard_fab2_lib.baseboard_fab2(sch_1):irq_spi_tpm_n_r"
				( attribute "CDS_PHYS_NET_NAME" "IRQ_SPI_TPM_N_R"
					( Origin gPackager )
				)
				( objectStatus "IRQ_SPI_TPM_N_R" )
			)
			( signal "@baseboard_fab2_lib.baseboard_fab2(sch_1):spi_pch_tpm_clk_r"
				( attribute "CDS_PHYS_NET_NAME" "SPI_PCH_TPM_CLK_R"
					( Origin gPackager )
				)
				( objectStatus "SPI_PCH_TPM_CLK_R" )
			)
			( signal "@baseboard_fab2_lib.baseboard_fab2(sch_1):spi_pch_tpm_cs_r_n"
				( attribute "CDS_PHYS_NET_NAME" "SPI_PCH_TPM_CS_R_N"
					( Origin gPackager )
				)
				( objectStatus "SPI_PCH_TPM_CS_R_N" )
			)
			( signal "@baseboard_fab2_lib.baseboard_fab2(sch_1):spi_pch_tpm_miso_r"
				( attribute "CDS_PHYS_NET_NAME" "SPI_PCH_TPM_MISO_R"
					( Origin gPackager )
				)
				( objectStatus "SPI_PCH_TPM_MISO_R" )
			)
			( signal "@baseboard_fab2_lib.baseboard_fab2(sch_1):spi_pch_tpm_mosi_r"
				( attribute "CDS_PHYS_NET_NAME" "SPI_PCH_TPM_MOSI_R"
					( Origin gPackager )
				)
				( objectStatus "SPI_PCH_TPM_MOSI_R" )
			)
			( signal "@baseboard_fab2_lib.baseboard_fab2(sch_1):fm_m2_det_lvc3"
				( attribute "CDS_PHYS_NET_NAME" "FM_M2_DET_LVC3"
					( Origin gPackager )
				)
				( objectStatus "FM_M2_DET_LVC3" )
			)
			( signal "@baseboard_fab2_lib.baseboard_fab2(sch_1):fm_m2_ssd_pedet"
				( attribute "CDS_PHYS_NET_NAME" "FM_M2_SSD_PEDET"
					( Origin gPackager )
				)
				( objectStatus "FM_M2_SSD_PEDET" )
			)
			( signal "@baseboard_fab2_lib.baseboard_fab2(sch_1):nc_m2(0)"
				( attribute "CDS_PHYS_NET_NAME" "NC_M2<0>"
					( Origin gPackager )
				)
				( attribute "PNN" "NC_M2<0>"
					( Origin gPackager )
				)
				( objectStatus "NC_M2<0>" )
			)
			( signal "@baseboard_fab2_lib.baseboard_fab2(sch_1):nc_m2(1)"
				( attribute "CDS_PHYS_NET_NAME" "NC_M2<1>"
					( Origin gPackager )
				)
				( attribute "PNN" "NC_M2<1>"
					( Origin gPackager )
				)
				( objectStatus "NC_M2<1>" )
			)
			( signal "@baseboard_fab2_lib.baseboard_fab2(sch_1):p3e_pch_m2_sata6g_rx_r_dn"
				( attribute "CDS_PHYS_NET_NAME" "P3E_PCH_M2_SATA6G_RX_R_DN"
					( Origin gPackager )
				)
				( objectStatus "P3E_PCH_M2_SATA6G_RX_R_DN" )
			)
			( signal "@baseboard_fab2_lib.baseboard_fab2(sch_1):p3e_pch_m2_sata6g_rx_r_dp"
				( attribute "CDS_PHYS_NET_NAME" "P3E_PCH_M2_SATA6G_RX_R_DP"
					( Origin gPackager )
				)
				( objectStatus "P3E_PCH_M2_SATA6G_RX_R_DP" )
			)
			( signal "@baseboard_fab2_lib.baseboard_fab2(sch_1):p3e_pch_m2_sata6g_tx_r_dn"
				( attribute "CDS_PHYS_NET_NAME" "P3E_PCH_M2_SATA6G_TX_R_DN"
					( Origin gPackager )
				)
				( objectStatus "P3E_PCH_M2_SATA6G_TX_R_DN" )
			)
			( signal "@baseboard_fab2_lib.baseboard_fab2(sch_1):p3e_pch_m2_sata6g_tx_r_dp"
				( attribute "CDS_PHYS_NET_NAME" "P3E_PCH_M2_SATA6G_TX_R_DP"
					( Origin gPackager )
				)
				( objectStatus "P3E_PCH_M2_SATA6G_TX_R_DP" )
			)
			( signal "@baseboard_fab2_lib.baseboard_fab2(sch_1):p3e_pch_m2_tx_c_dn(1)"
				( attribute "CDS_PHYS_NET_NAME" "P3E_PCH_M2_TX_C_DN<1>"
					( Origin gPackager )
				)
				( attribute "PNN" "P3E_PCH_M2_TX_C_DN<1>"
					( Origin gPackager )
				)
				( objectStatus "P3E_PCH_M2_TX_C_DN<1>" )
			)
			( signal "@baseboard_fab2_lib.baseboard_fab2(sch_1):p3e_pch_m2_tx_c_dn(2)"
				( attribute "CDS_PHYS_NET_NAME" "P3E_PCH_M2_TX_C_DN<2>"
					( Origin gPackager )
				)
				( attribute "PNN" "P3E_PCH_M2_TX_C_DN<2>"
					( Origin gPackager )
				)
				( objectStatus "P3E_PCH_M2_TX_C_DN<2>" )
			)
			( signal "@baseboard_fab2_lib.baseboard_fab2(sch_1):p3e_pch_m2_tx_c_dn(3)"
				( attribute "CDS_PHYS_NET_NAME" "P3E_PCH_M2_TX_C_DN<3>"
					( Origin gPackager )
				)
				( attribute "PNN" "P3E_PCH_M2_TX_C_DN<3>"
					( Origin gPackager )
				)
				( objectStatus "P3E_PCH_M2_TX_C_DN<3>" )
			)
			( signal "@baseboard_fab2_lib.baseboard_fab2(sch_1):p3e_pch_m2_tx_c_dp(1)"
				( attribute "CDS_PHYS_NET_NAME" "P3E_PCH_M2_TX_C_DP<1>"
					( Origin gPackager )
				)
				( attribute "PNN" "P3E_PCH_M2_TX_C_DP<1>"
					( Origin gPackager )
				)
				( objectStatus "P3E_PCH_M2_TX_C_DP<1>" )
			)
			( signal "@baseboard_fab2_lib.baseboard_fab2(sch_1):p3e_pch_m2_tx_c_dp(2)"
				( attribute "CDS_PHYS_NET_NAME" "P3E_PCH_M2_TX_C_DP<2>"
					( Origin gPackager )
				)
				( attribute "PNN" "P3E_PCH_M2_TX_C_DP<2>"
					( Origin gPackager )
				)
				( objectStatus "P3E_PCH_M2_TX_C_DP<2>" )
			)
			( signal "@baseboard_fab2_lib.baseboard_fab2(sch_1):p3e_pch_m2_tx_c_dp(3)"
				( attribute "CDS_PHYS_NET_NAME" "P3E_PCH_M2_TX_C_DP<3>"
					( Origin gPackager )
				)
				( attribute "PNN" "P3E_PCH_M2_TX_C_DP<3>"
					( Origin gPackager )
				)
				( objectStatus "P3E_PCH_M2_TX_C_DP<3>" )
			)
			( signal "@baseboard_fab2_lib.baseboard_fab2(sch_1):pu_m2_clk_req_n"
				( attribute "CDS_PHYS_NET_NAME" "PU_M2_CLK_REQ_N"
					( Origin gPackager )
				)
				( objectStatus "PU_M2_CLK_REQ_N" )
			)
			( signal "@baseboard_fab2_lib.baseboard_fab2(sch_1):rst_pcie_m2_dev_n"
				( attribute "CDS_PHYS_NET_NAME" "RST_PCIE_M2_DEV_N"
					( Origin gPackager )
				)
				( objectStatus "RST_PCIE_M2_DEV_N" )
			)
			( signal "@baseboard_fab2_lib.baseboard_fab2(sch_1):tp_led_m2_act_n"
				( attribute "CDS_PHYS_NET_NAME" "TP_LED_M2_ACT_N"
					( Origin gPackager )
				)
				( objectStatus "TP_LED_M2_ACT_N" )
			)
			( signal "@baseboard_fab2_lib.baseboard_fab2(sch_1):tp_m2_32m_susclk"
				( attribute "CDS_PHYS_NET_NAME" "TP_M2_32M_SUSCLK"
					( Origin gPackager )
				)
				( objectStatus "TP_M2_32M_SUSCLK" )
			)
			( signal "@baseboard_fab2_lib.baseboard_fab2(sch_1):tp_m2_devslp"
				( attribute "CDS_PHYS_NET_NAME" "TP_M2_DEVSLP"
					( Origin gPackager )
				)
				( objectStatus "TP_M2_DEVSLP" )
			)
			( signal "@baseboard_fab2_lib.baseboard_fab2(sch_1):fm_mezza_prsnt1_n"
				( attribute "CDS_PHYS_NET_NAME" "FM_MEZZA_PRSNT1_N"
					( Origin gPackager )
				)
				( objectStatus "FM_MEZZA_PRSNT1_N" )
			)
			( signal "@baseboard_fab2_lib.baseboard_fab2(sch_1):rmii_bmc_ocp_crsdv_r"
				( attribute "CDS_PHYS_NET_NAME" "RMII_BMC_OCP_CRSDV_R"
					( Origin gPackager )
				)
				( objectStatus "RMII_BMC_OCP_CRSDV_R" )
			)
			( signal "@baseboard_fab2_lib.baseboard_fab2(sch_1):rmii_bmc_ocp_rxd0_r"
				( attribute "CDS_PHYS_NET_NAME" "RMII_BMC_OCP_RXD0_R"
					( Origin gPackager )
				)
				( objectStatus "RMII_BMC_OCP_RXD0_R" )
			)
			( signal "@baseboard_fab2_lib.baseboard_fab2(sch_1):rmii_bmc_ocp_rxd1_r"
				( attribute "CDS_PHYS_NET_NAME" "RMII_BMC_OCP_RXD1_R"
					( Origin gPackager )
				)
				( objectStatus "RMII_BMC_OCP_RXD1_R" )
			)
			( signal "@baseboard_fab2_lib.baseboard_fab2(sch_1):rmii_bmc_ocp_rxer_r"
				( attribute "CDS_PHYS_NET_NAME" "RMII_BMC_OCP_RXER_R"
					( Origin gPackager )
				)
				( objectStatus "RMII_BMC_OCP_RXER_R" )
			)
			( signal "@baseboard_fab2_lib.baseboard_fab2(sch_1):rst_pcie_cpu_dev0_n"
				( attribute "CDS_PHYS_NET_NAME" "RST_PCIE_CPU_DEV0_N"
					( Origin gPackager )
				)
				( objectStatus "RST_PCIE_CPU_DEV0_N" )
			)
			( signal "@baseboard_fab2_lib.baseboard_fab2(sch_1):rst_pcie_cpu_dev0_r_n"
				( attribute "CDS_PHYS_NET_NAME" "RST_PCIE_CPU_DEV0_R_N"
					( Origin gPackager )
				)
				( objectStatus "RST_PCIE_CPU_DEV0_R_N" )
			)
			( signal "@baseboard_fab2_lib.baseboard_fab2(sch_1):rst_pcie_cpu_dev1_n"
				( attribute "CDS_PHYS_NET_NAME" "RST_PCIE_CPU_DEV1_N"
					( Origin gPackager )
				)
				( objectStatus "RST_PCIE_CPU_DEV1_N" )
			)
			( signal "@baseboard_fab2_lib.baseboard_fab2(sch_1):rst_pcie_cpu_dev1_r_n"
				( attribute "CDS_PHYS_NET_NAME" "RST_PCIE_CPU_DEV1_R_N"
					( Origin gPackager )
				)
				( objectStatus "RST_PCIE_CPU_DEV1_R_N" )
			)
			( signal "@baseboard_fab2_lib.baseboard_fab2(sch_1):rst_pcie_cpu_dev2_n"
				( attribute "CDS_PHYS_NET_NAME" "RST_PCIE_CPU_DEV2_N"
					( Origin gPackager )
				)
				( objectStatus "RST_PCIE_CPU_DEV2_N" )
			)
			( signal "@baseboard_fab2_lib.baseboard_fab2(sch_1):rst_pcie_cpu_dev2_r_n"
				( attribute "CDS_PHYS_NET_NAME" "RST_PCIE_CPU_DEV2_R_N"
					( Origin gPackager )
				)
				( objectStatus "RST_PCIE_CPU_DEV2_R_N" )
			)
			( signal "@baseboard_fab2_lib.baseboard_fab2(sch_1):rst_pcie_cpu_dev3_n"
				( attribute "CDS_PHYS_NET_NAME" "RST_PCIE_CPU_DEV3_N"
					( Origin gPackager )
				)
				( objectStatus "RST_PCIE_CPU_DEV3_N" )
			)
			( signal "@baseboard_fab2_lib.baseboard_fab2(sch_1):rst_pcie_cpu_dev3_r_n"
				( attribute "CDS_PHYS_NET_NAME" "RST_PCIE_CPU_DEV3_R_N"
					( Origin gPackager )
				)
				( objectStatus "RST_PCIE_CPU_DEV3_R_N" )
			)
			( signal "@baseboard_fab2_lib.baseboard_fab2(sch_1):tp_rsvd_b1"
				( attribute "CDS_PHYS_NET_NAME" "TP_RSVD_B1"
					( Origin gPackager )
				)
				( objectStatus "TP_RSVD_B1" )
			)
			( signal "@baseboard_fab2_lib.baseboard_fab2(sch_1):kr_p0_ocp_rx_dn"
				( attribute "CDS_PHYS_NET_NAME" "KR_P0_OCP_RX_DN"
					( Origin gPackager )
				)
				( objectStatus "KR_P0_OCP_RX_DN" )
			)
			( signal "@baseboard_fab2_lib.baseboard_fab2(sch_1):kr_p0_ocp_rx_dp"
				( attribute "CDS_PHYS_NET_NAME" "KR_P0_OCP_RX_DP"
					( Origin gPackager )
				)
				( objectStatus "KR_P0_OCP_RX_DP" )
			)
			( signal "@baseboard_fab2_lib.baseboard_fab2(sch_1):v_io_r_j"
				( attribute "CDS_PHYS_NET_NAME" "V_IO_R_J"
					( Origin gPackager )
				)
				( objectStatus "V_IO_R_J" )
			)
			( signal "@baseboard_fab2_lib.baseboard_fab2(sch_1):v_io_g_j"
				( attribute "CDS_PHYS_NET_NAME" "V_IO_G_J"
					( Origin gPackager )
				)
				( objectStatus "V_IO_G_J" )
			)
			( signal "@baseboard_fab2_lib.baseboard_fab2(sch_1):v_io_b_j"
				( attribute "CDS_PHYS_NET_NAME" "V_IO_B_J"
					( Origin gPackager )
				)
				( objectStatus "V_IO_B_J" )
			)
			( signal "@baseboard_fab2_lib.baseboard_fab2(sch_1):bmc_vga_red"
				( attribute "CDS_PHYS_NET_NAME" "BMC_VGA_RED"
					( Origin gPackager )
				)
				( objectStatus "BMC_VGA_RED" )
			)
			( signal "@baseboard_fab2_lib.baseboard_fab2(sch_1):bmc_vga_green"
				( attribute "CDS_PHYS_NET_NAME" "BMC_VGA_GREEN"
					( Origin gPackager )
				)
				( objectStatus "BMC_VGA_GREEN" )
			)
			( signal "@baseboard_fab2_lib.baseboard_fab2(sch_1):bmc_vga_blue"
				( attribute "CDS_PHYS_NET_NAME" "BMC_VGA_BLUE"
					( Origin gPackager )
				)
				( objectStatus "BMC_VGA_BLUE" )
			)
			( signal "@baseboard_fab2_lib.baseboard_fab2(sch_1):tp_rsvd(0)"
				( attribute "CDS_PHYS_NET_NAME" "TP_RSVD<0>"
					( Origin gPackager )
				)
				( attribute "PNN" "TP_RSVD<0>"
					( Origin gPackager )
				)
				( objectStatus "TP_RSVD<0>" )
			)
			( signal "@baseboard_fab2_lib.baseboard_fab2(sch_1):tp_shared_kr_mdc_0"
				( attribute "CDS_PHYS_NET_NAME" "TP_SHARED_KR_MDC_0"
					( Origin gPackager )
				)
				( objectStatus "TP_SHARED_KR_MDC_0" )
			)
			( signal "@baseboard_fab2_lib.baseboard_fab2(sch_1):tp_shared_kr_mdio_0"
				( attribute "CDS_PHYS_NET_NAME" "TP_SHARED_KR_MDIO_0"
					( Origin gPackager )
				)
				( objectStatus "TP_SHARED_KR_MDIO_0" )
			)
			( signal "@baseboard_fab2_lib.baseboard_fab2(sch_1):fm_jtag_pld_en_debug"
				( attribute "CDS_PHYS_NET_NAME" "FM_JTAG_PLD_EN_DEBUG"
					( Origin gPackager )
				)
				( objectStatus "FM_JTAG_PLD_EN_DEBUG" )
			)
			( signal "@baseboard_fab2_lib.baseboard_fab2(sch_1):jtag_pld_tck"
				( attribute "CDS_PHYS_NET_NAME" "JTAG_PLD_TCK"
					( Origin gPackager )
				)
				( objectStatus "JTAG_PLD_TCK" )
			)
			( signal "@baseboard_fab2_lib.baseboard_fab2(sch_1):jtag_pld_tdi"
				( attribute "CDS_PHYS_NET_NAME" "JTAG_PLD_TDI"
					( Origin gPackager )
				)
				( objectStatus "JTAG_PLD_TDI" )
			)
			( signal "@baseboard_fab2_lib.baseboard_fab2(sch_1):jtag_pld_tdo"
				( attribute "CDS_PHYS_NET_NAME" "JTAG_PLD_TDO"
					( Origin gPackager )
				)
				( objectStatus "JTAG_PLD_TDO" )
			)
			( signal "@baseboard_fab2_lib.baseboard_fab2(sch_1):jtag_pld_tms"
				( attribute "CDS_PHYS_NET_NAME" "JTAG_PLD_TMS"
					( Origin gPackager )
				)
				( objectStatus "JTAG_PLD_TMS" )
			)
			( signal "@baseboard_fab2_lib.baseboard_fab2(sch_1):jtag_tck"
				( attribute "CDS_PHYS_NET_NAME" "JTAG_TCK"
					( Origin gPackager )
				)
				( objectStatus "JTAG_TCK" )
			)
			( signal "@baseboard_fab2_lib.baseboard_fab2(sch_1):jtag_tck_r"
				( attribute "CDS_PHYS_NET_NAME" "JTAG_TCK_R"
					( Origin gPackager )
				)
				( objectStatus "JTAG_TCK_R" )
			)
			( signal "@baseboard_fab2_lib.baseboard_fab2(sch_1):jtag_tdi"
				( attribute "CDS_PHYS_NET_NAME" "JTAG_TDI"
					( Origin gPackager )
				)
				( objectStatus "JTAG_TDI" )
			)
			( signal "@baseboard_fab2_lib.baseboard_fab2(sch_1):jtag_tdi_r"
				( attribute "CDS_PHYS_NET_NAME" "JTAG_TDI_R"
					( Origin gPackager )
				)
				( objectStatus "JTAG_TDI_R" )
			)
			( signal "@baseboard_fab2_lib.baseboard_fab2(sch_1):jtag_tdo"
				( attribute "CDS_PHYS_NET_NAME" "JTAG_TDO"
					( Origin gPackager )
				)
				( objectStatus "JTAG_TDO" )
			)
			( signal "@baseboard_fab2_lib.baseboard_fab2(sch_1):jtag_tdo_r"
				( attribute "CDS_PHYS_NET_NAME" "JTAG_TDO_R"
					( Origin gPackager )
				)
				( objectStatus "JTAG_TDO_R" )
			)
			( signal "@baseboard_fab2_lib.baseboard_fab2(sch_1):jtag_tms"
				( attribute "CDS_PHYS_NET_NAME" "JTAG_TMS"
					( Origin gPackager )
				)
				( objectStatus "JTAG_TMS" )
			)
			( signal "@baseboard_fab2_lib.baseboard_fab2(sch_1):jtag_tms_r"
				( attribute "CDS_PHYS_NET_NAME" "JTAG_TMS_R"
					( Origin gPackager )
				)
				( objectStatus "JTAG_TMS_R" )
			)
			( signal "@baseboard_fab2_lib.baseboard_fab2(sch_1):jtag_trst_n"
				( attribute "CDS_PHYS_NET_NAME" "JTAG_TRST_N"
					( Origin gPackager )
				)
				( objectStatus "JTAG_TRST_N" )
			)
			( signal "@baseboard_fab2_lib.baseboard_fab2(sch_1):p3v3_stby_pld_d"
				( alias ( signalRef "@baseboard_fab2_lib.baseboard_fab2(sch_1):page189_p3v3_stby_pld_d") )
				( attribute "VOLTAGE" "3.3"
					( Units "uVoltage" "V" 1.000000)
					( Status sAliasFlattened )
					( Origin gFrontEnd )
				)
				( attribute "CDS_PHYS_NET_NAME" "P3V3_STBY_PLD_D"
					( Origin gPackager )
				)
				( objectStatus "P3V3_STBY_PLD_D" )
			)
			( signal "@baseboard_fab2_lib.baseboard_fab2(sch_1):page189_p3v3_stby_pld_d"
				( attribute "VOLTAGE" "3.3"
					( Units "uVoltage" "V" 1.000000)
					( Origin gFrontEnd )
				)
				( objectFlag fObjectAlias )
				( objectStatus "page189_p3v3_stby_pld_d" )
			)
			( signal "@baseboard_fab2_lib.baseboard_fab2(sch_1):fm_mem_event_func"
				( attribute "CDS_PHYS_NET_NAME" "FM_MEM_EVENT_FUNC"
					( Origin gPackager )
				)
				( objectStatus "FM_MEM_EVENT_FUNC" )
			)
			( signal "@baseboard_fab2_lib.baseboard_fab2(sch_1):fm_pvccio_cpu0_en"
				( attribute "CDS_PHYS_NET_NAME" "FM_PVCCIO_CPU0_EN"
					( Origin gPackager )
				)
				( objectStatus "FM_PVCCIO_CPU0_EN" )
			)
			( signal "@baseboard_fab2_lib.baseboard_fab2(sch_1):fm_pvccio_cpu1_en"
				( attribute "CDS_PHYS_NET_NAME" "FM_PVCCIO_CPU1_EN"
					( Origin gPackager )
				)
				( objectStatus "FM_PVCCIO_CPU1_EN" )
			)
			( signal "@baseboard_fab2_lib.baseboard_fab2(sch_1):fm_pvcciomcp_cpu0_en"
				( attribute "CDS_PHYS_NET_NAME" "FM_PVCCIOMCP_CPU0_EN"
					( Origin gPackager )
				)
				( objectStatus "FM_PVCCIOMCP_CPU0_EN" )
			)
			( signal "@baseboard_fab2_lib.baseboard_fab2(sch_1):fm_pvcciomcp_cpu1_en"
				( attribute "CDS_PHYS_NET_NAME" "FM_PVCCIOMCP_CPU1_EN"
					( Origin gPackager )
				)
				( objectStatus "FM_PVCCIOMCP_CPU1_EN" )
			)
			( signal "@baseboard_fab2_lib.baseboard_fab2(sch_1):fm_pvccmcp_cpu0_en"
				( attribute "CDS_PHYS_NET_NAME" "FM_PVCCMCP_CPU0_EN"
					( Origin gPackager )
				)
				( objectStatus "FM_PVCCMCP_CPU0_EN" )
			)
			( signal "@baseboard_fab2_lib.baseboard_fab2(sch_1):fm_pvccmcp_cpu1_en"
				( attribute "CDS_PHYS_NET_NAME" "FM_PVCCMCP_CPU1_EN"
					( Origin gPackager )
				)
				( objectStatus "FM_PVCCMCP_CPU1_EN" )
			)
			( signal "@baseboard_fab2_lib.baseboard_fab2(sch_1):pu_rst_perst_bit0"
				( attribute "CDS_PHYS_NET_NAME" "PU_RST_PERST_BIT0"
					( Origin gPackager )
				)
				( objectStatus "PU_RST_PERST_BIT0" )
			)
			( signal "@baseboard_fab2_lib.baseboard_fab2(sch_1):pwrgd_p5v"
				( attribute "CDS_PHYS_NET_NAME" "PWRGD_P5V"
					( Origin gPackager )
				)
				( objectStatus "PWRGD_P5V" )
			)
			( signal "@baseboard_fab2_lib.baseboard_fab2(sch_1):pwrgd_pvccin_cpu1"
				( attribute "CDS_PHYS_NET_NAME" "PWRGD_PVCCIN_CPU1"
					( Origin gPackager )
				)
				( objectStatus "PWRGD_PVCCIN_CPU1" )
			)
			( signal "@baseboard_fab2_lib.baseboard_fab2(sch_1):pwrgd_pvcciomcp_cpu0"
				( attribute "CDS_PHYS_NET_NAME" "PWRGD_PVCCIOMCP_CPU0"
					( Origin gPackager )
				)
				( objectStatus "PWRGD_PVCCIOMCP_CPU0" )
			)
			( signal "@baseboard_fab2_lib.baseboard_fab2(sch_1):pwrgd_pvcciomcp_cpu1"
				( attribute "CDS_PHYS_NET_NAME" "PWRGD_PVCCIOMCP_CPU1"
					( Origin gPackager )
				)
				( objectStatus "PWRGD_PVCCIOMCP_CPU1" )
			)
			( signal "@baseboard_fab2_lib.baseboard_fab2(sch_1):pwrgd_pvccmcp_cpu0"
				( attribute "CDS_PHYS_NET_NAME" "PWRGD_PVCCMCP_CPU0"
					( Origin gPackager )
				)
				( objectStatus "PWRGD_PVCCMCP_CPU0" )
			)
			( signal "@baseboard_fab2_lib.baseboard_fab2(sch_1):pwrgd_pvccmcp_cpu1"
				( attribute "CDS_PHYS_NET_NAME" "PWRGD_PVCCMCP_CPU1"
					( Origin gPackager )
				)
				( objectStatus "PWRGD_PVCCMCP_CPU1" )
			)
			( signal "@baseboard_fab2_lib.baseboard_fab2(sch_1):pwrgd_pvnn_p1v05_pch"
				( attribute "CDS_PHYS_NET_NAME" "PWRGD_PVNN_P1V05_PCH"
					( Origin gPackager )
				)
				( objectStatus "PWRGD_PVNN_P1V05_PCH" )
			)
			( signal "@baseboard_fab2_lib.baseboard_fab2(sch_1):pwrgd_pvpp_def"
				( attribute "CDS_PHYS_NET_NAME" "PWRGD_PVPP_DEF"
					( Origin gPackager )
				)
				( objectStatus "PWRGD_PVPP_DEF" )
			)
			( signal "@baseboard_fab2_lib.baseboard_fab2(sch_1):pwrgd_pvpp_ghj"
				( attribute "CDS_PHYS_NET_NAME" "PWRGD_PVPP_GHJ"
					( Origin gPackager )
				)
				( objectStatus "PWRGD_PVPP_GHJ" )
			)
			( signal "@baseboard_fab2_lib.baseboard_fab2(sch_1):pwrgd_pvpp_klm"
				( attribute "CDS_PHYS_NET_NAME" "PWRGD_PVPP_KLM"
					( Origin gPackager )
				)
				( objectStatus "PWRGD_PVPP_KLM" )
			)
			( signal "@baseboard_fab2_lib.baseboard_fab2(sch_1):pwrgd_pvsa_cpu0"
				( attribute "CDS_PHYS_NET_NAME" "PWRGD_PVSA_CPU0"
					( Origin gPackager )
				)
				( objectStatus "PWRGD_PVSA_CPU0" )
			)
			( signal "@baseboard_fab2_lib.baseboard_fab2(sch_1):pwrgd_pvsa_cpu1"
				( attribute "CDS_PHYS_NET_NAME" "PWRGD_PVSA_CPU1"
					( Origin gPackager )
				)
				( objectStatus "PWRGD_PVSA_CPU1" )
			)
			( signal "@baseboard_fab2_lib.baseboard_fab2(sch_1):pwrgd_pvtt_cpu1"
				( attribute "CDS_PHYS_NET_NAME" "PWRGD_PVTT_CPU1"
					( Origin gPackager )
				)
				( objectStatus "PWRGD_PVTT_CPU1" )
			)
			( signal "@baseboard_fab2_lib.baseboard_fab2(sch_1):rst_cpu0_lvc3_r1_n"
				( attribute "CDS_PHYS_NET_NAME" "RST_CPU0_LVC3_R1_N"
					( Origin gPackager )
				)
				( objectStatus "RST_CPU0_LVC3_R1_N" )
			)
			( signal "@baseboard_fab2_lib.baseboard_fab2(sch_1):rst_cpu1_lvc3_r1_n"
				( attribute "CDS_PHYS_NET_NAME" "RST_CPU1_LVC3_R1_N"
					( Origin gPackager )
				)
				( objectStatus "RST_CPU1_LVC3_R1_N" )
			)
			( signal "@baseboard_fab2_lib.baseboard_fab2(sch_1):rst_rsmrst_r_n"
				( attribute "CDS_PHYS_NET_NAME" "RST_RSMRST_R_N"
					( Origin gPackager )
				)
				( objectStatus "RST_RSMRST_R_N" )
			)
			( signal "@baseboard_fab2_lib.baseboard_fab2(sch_1):pvccio_cpu0_r"
				( attribute "CDS_PHYS_NET_NAME" "PVCCIO_CPU0_R"
					( Origin gPackager )
				)
				( objectStatus "PVCCIO_CPU0_R" )
			)
			( signal "@baseboard_fab2_lib.baseboard_fab2(sch_1):tp_cpld1_pb16a_pclkt2_1"
				( attribute "CDS_PHYS_NET_NAME" "TP_CPLD1_PB16A_PCLKT2_1"
					( Origin gPackager )
				)
				( objectStatus "TP_CPLD1_PB16A_PCLKT2_1" )
			)
			( signal "@baseboard_fab2_lib.baseboard_fab2(sch_1):tp_cpld1_pb16b_pclkc2_1"
				( attribute "CDS_PHYS_NET_NAME" "TP_CPLD1_PB16B_PCLKC2_1"
					( Origin gPackager )
				)
				( objectStatus "TP_CPLD1_PB16B_PCLKC2_1" )
			)
			( signal "@baseboard_fab2_lib.baseboard_fab2(sch_1):tp_cpld1_pb25b_si_sispi"
				( attribute "CDS_PHYS_NET_NAME" "TP_CPLD1_PB25B_SI_SISPI"
					( Origin gPackager )
				)
				( objectStatus "TP_CPLD1_PB25B_SI_SISPI" )
			)
			( signal "@baseboard_fab2_lib.baseboard_fab2(sch_1):tp_cpld1_pb5a_csspin"
				( attribute "CDS_PHYS_NET_NAME" "TP_CPLD1_PB5A_CSSPIN"
					( Origin gPackager )
				)
				( objectStatus "TP_CPLD1_PB5A_CSSPIN" )
			)
			( signal "@baseboard_fab2_lib.baseboard_fab2(sch_1):tp_cpld1_pb8a_mclk_cclk"
				( attribute "CDS_PHYS_NET_NAME" "TP_CPLD1_PB8A_MCLK_CCLK"
					( Origin gPackager )
				)
				( objectStatus "TP_CPLD1_PB8A_MCLK_CCLK" )
			)
			( signal "@baseboard_fab2_lib.baseboard_fab2(sch_1):tp_cpld1_pb8b_so_spiso"
				( attribute "CDS_PHYS_NET_NAME" "TP_CPLD1_PB8B_SO_SPISO"
					( Origin gPackager )
				)
				( objectStatus "TP_CPLD1_PB8B_SO_SPISO" )
			)
			( signal "@baseboard_fab2_lib.baseboard_fab2(sch_1):fm_cpld_usb_p0_en_n"
				( attribute "CDS_PHYS_NET_NAME" "FM_CPLD_USB_P0_EN_N"
					( Origin gPackager )
				)
				( objectStatus "FM_CPLD_USB_P0_EN_N" )
			)
			( signal "@baseboard_fab2_lib.baseboard_fab2(sch_1):tp_cpld1_pl11a"
				( attribute "CDS_PHYS_NET_NAME" "TP_CPLD1_PL11A"
					( Origin gPackager )
				)
				( objectStatus "TP_CPLD1_PL11A" )
			)
			( signal "@baseboard_fab2_lib.baseboard_fab2(sch_1):tp_cpld1_pl1a_l_gpllt_fb"
				( attribute "CDS_PHYS_NET_NAME" "TP_CPLD1_PL1A_L_GPLLT_FB"
					( Origin gPackager )
				)
				( objectStatus "TP_CPLD1_PL1A_L_GPLLT_FB" )
			)
			( signal "@baseboard_fab2_lib.baseboard_fab2(sch_1):tp_cpld1_pl1b_l_gpllc_fb"
				( attribute "CDS_PHYS_NET_NAME" "TP_CPLD1_PL1B_L_GPLLC_FB"
					( Origin gPackager )
				)
				( objectStatus "TP_CPLD1_PL1B_L_GPLLC_FB" )
			)
			( signal "@baseboard_fab2_lib.baseboard_fab2(sch_1):tp_cpld1_pl2b_l_gpllc_in"
				( attribute "CDS_PHYS_NET_NAME" "TP_CPLD1_PL2B_L_GPLLC_IN"
					( Origin gPackager )
				)
				( objectStatus "TP_CPLD1_PL2B_L_GPLLC_IN" )
			)
			( signal "@baseboard_fab2_lib.baseboard_fab2(sch_1):tp_cpld1_pl7d_pclkt4_0"
				( attribute "CDS_PHYS_NET_NAME" "TP_CPLD1_PL7D_PCLKT4_0"
					( Origin gPackager )
				)
				( objectStatus "TP_CPLD1_PL7D_PCLKT4_0" )
			)
			( signal "@baseboard_fab2_lib.baseboard_fab2(sch_1):fm_adr_smi_gpio_r_n"
				( attribute "CDS_PHYS_NET_NAME" "FM_ADR_SMI_GPIO_R_N"
					( Origin gPackager )
				)
				( objectStatus "FM_ADR_SMI_GPIO_R_N" )
			)
			( signal "@baseboard_fab2_lib.baseboard_fab2(sch_1):fm_p12v_main_sw_en"
				( attribute "CDS_PHYS_NET_NAME" "FM_P12V_MAIN_SW_EN"
					( Origin gPackager )
				)
				( objectStatus "FM_P12V_MAIN_SW_EN" )
			)
			( signal "@baseboard_fab2_lib.baseboard_fab2(sch_1):fm_p1v8mcp_cpu0_en"
				( attribute "CDS_PHYS_NET_NAME" "FM_P1V8MCP_CPU0_EN"
					( Origin gPackager )
				)
				( objectStatus "FM_P1V8MCP_CPU0_EN" )
			)
			( signal "@baseboard_fab2_lib.baseboard_fab2(sch_1):fm_p1v8mcp_cpu1_en"
				( attribute "CDS_PHYS_NET_NAME" "FM_P1V8MCP_CPU1_EN"
					( Origin gPackager )
				)
				( objectStatus "FM_P1V8MCP_CPU1_EN" )
			)
			( signal "@baseboard_fab2_lib.baseboard_fab2(sch_1):fm_p3v3_cpld_en"
				( attribute "CDS_PHYS_NET_NAME" "FM_P3V3_CPLD_EN"
					( Origin gPackager )
				)
				( objectStatus "FM_P3V3_CPLD_EN" )
			)
			( signal "@baseboard_fab2_lib.baseboard_fab2(sch_1):fm_pld_debug_mode_n"
				( attribute "CDS_PHYS_NET_NAME" "FM_PLD_DEBUG_MODE_N"
					( Origin gPackager )
				)
				( objectStatus "FM_PLD_DEBUG_MODE_N" )
			)
			( signal "@baseboard_fab2_lib.baseboard_fab2(sch_1):fm_pvccin_pvccsa_cpu0_en_lvc1"
				( attribute "CDS_PHYS_NET_NAME" "FM_PVCCIN_PVCCSA_CPU0_EN_LVC1"
					( Origin gPackager )
				)
				( objectStatus "FM_PVCCIN_PVCCSA_CPU0_EN_LVC1" )
			)
			( signal "@baseboard_fab2_lib.baseboard_fab2(sch_1):fm_pvccin_pvccsa_cpu1_en_lvc1"
				( attribute "CDS_PHYS_NET_NAME" "FM_PVCCIN_PVCCSA_CPU1_EN_LVC1"
					( Origin gPackager )
				)
				( objectStatus "FM_PVCCIN_PVCCSA_CPU1_EN_LVC1" )
			)
			( signal "@baseboard_fab2_lib.baseboard_fab2(sch_1):fm_pvddq_abc_en"
				( attribute "CDS_PHYS_NET_NAME" "FM_PVDDQ_ABC_EN"
					( Origin gPackager )
				)
				( objectStatus "FM_PVDDQ_ABC_EN" )
			)
			( signal "@baseboard_fab2_lib.baseboard_fab2(sch_1):fm_pvddq_def_en"
				( attribute "CDS_PHYS_NET_NAME" "FM_PVDDQ_DEF_EN"
					( Origin gPackager )
				)
				( objectStatus "FM_PVDDQ_DEF_EN" )
			)
			( signal "@baseboard_fab2_lib.baseboard_fab2(sch_1):fm_pvddq_ghj_en"
				( attribute "CDS_PHYS_NET_NAME" "FM_PVDDQ_GHJ_EN"
					( Origin gPackager )
				)
				( objectStatus "FM_PVDDQ_GHJ_EN" )
			)
			( signal "@baseboard_fab2_lib.baseboard_fab2(sch_1):fm_pvddq_klm_en"
				( attribute "CDS_PHYS_NET_NAME" "FM_PVDDQ_KLM_EN"
					( Origin gPackager )
				)
				( objectStatus "FM_PVDDQ_KLM_EN" )
			)
			( signal "@baseboard_fab2_lib.baseboard_fab2(sch_1):fm_pvpp_cpu0_en"
				( attribute "CDS_PHYS_NET_NAME" "FM_PVPP_CPU0_EN"
					( Origin gPackager )
				)
				( objectStatus "FM_PVPP_CPU0_EN" )
			)
			( signal "@baseboard_fab2_lib.baseboard_fab2(sch_1):fm_pvpp_cpu1_en"
				( attribute "CDS_PHYS_NET_NAME" "FM_PVPP_CPU1_EN"
					( Origin gPackager )
				)
				( objectStatus "FM_PVPP_CPU1_EN" )
			)
			( signal "@baseboard_fab2_lib.baseboard_fab2(sch_1):fm_uv_adr_trigger_n"
				( attribute "CDS_PHYS_NET_NAME" "FM_UV_ADR_TRIGGER_N"
					( Origin gPackager )
				)
				( objectStatus "FM_UV_ADR_TRIGGER_N" )
			)
			( signal "@baseboard_fab2_lib.baseboard_fab2(sch_1):pu_fab2_marker_cpld"
				( attribute "CDS_PHYS_NET_NAME" "PU_FAB2_MARKER_CPLD"
					( Origin gPackager )
				)
				( objectStatus "PU_FAB2_MARKER_CPLD" )
			)
			( signal "@baseboard_fab2_lib.baseboard_fab2(sch_1):pu_rst_perst_bit1"
				( attribute "CDS_PHYS_NET_NAME" "PU_RST_PERST_BIT1"
					( Origin gPackager )
				)
				( objectStatus "PU_RST_PERST_BIT1" )
			)
			( signal "@baseboard_fab2_lib.baseboard_fab2(sch_1):pu_thermtrip_force_n"
				( attribute "CDS_PHYS_NET_NAME" "PU_THERMTRIP_FORCE_N"
					( Origin gPackager )
				)
				( objectStatus "PU_THERMTRIP_FORCE_N" )
			)
			( signal "@baseboard_fab2_lib.baseboard_fab2(sch_1):pwrgd_p12v_main"
				( attribute "CDS_PHYS_NET_NAME" "PWRGD_P12V_MAIN"
					( Origin gPackager )
				)
				( objectStatus "PWRGD_P12V_MAIN" )
			)
			( signal "@baseboard_fab2_lib.baseboard_fab2(sch_1):pwrgd_p1v15_bmc_stby"
				( attribute "CDS_PHYS_NET_NAME" "PWRGD_P1V15_BMC_STBY"
					( Origin gPackager )
				)
				( objectStatus "PWRGD_P1V15_BMC_STBY" )
			)
			( signal "@baseboard_fab2_lib.baseboard_fab2(sch_1):pwrgd_p1v8mcp_cpu0"
				( attribute "CDS_PHYS_NET_NAME" "PWRGD_P1V8MCP_CPU0"
					( Origin gPackager )
				)
				( objectStatus "PWRGD_P1V8MCP_CPU0" )
			)
			( signal "@baseboard_fab2_lib.baseboard_fab2(sch_1):pwrgd_p1v8mcp_cpu1"
				( attribute "CDS_PHYS_NET_NAME" "PWRGD_P1V8MCP_CPU1"
					( Origin gPackager )
				)
				( objectStatus "PWRGD_P1V8MCP_CPU1" )
			)
			( signal "@baseboard_fab2_lib.baseboard_fab2(sch_1):pwrgd_pvccio_cpu1"
				( attribute "CDS_PHYS_NET_NAME" "PWRGD_PVCCIO_CPU1"
					( Origin gPackager )
				)
				( objectStatus "PWRGD_PVCCIO_CPU1" )
			)
			( signal "@baseboard_fab2_lib.baseboard_fab2(sch_1):pwrgd_pvtt_cpu0"
				( attribute "CDS_PHYS_NET_NAME" "PWRGD_PVTT_CPU0"
					( Origin gPackager )
				)
				( objectStatus "PWRGD_PVTT_CPU0" )
			)
			( signal "@baseboard_fab2_lib.baseboard_fab2(sch_1):sgpio_bmc_din_r"
				( attribute "CDS_PHYS_NET_NAME" "SGPIO_BMC_DIN_R"
					( Origin gPackager )
				)
				( objectStatus "SGPIO_BMC_DIN_R" )
			)
			( signal "@baseboard_fab2_lib.baseboard_fab2(sch_1):tp_cpld1_pr10c"
				( attribute "CDS_PHYS_NET_NAME" "TP_CPLD1_PR10C"
					( Origin gPackager )
				)
				( objectStatus "TP_CPLD1_PR10C" )
			)
			( signal "@baseboard_fab2_lib.baseboard_fab2(sch_1):tp_cpld1_pr11b"
				( attribute "CDS_PHYS_NET_NAME" "TP_CPLD1_PR11B"
					( Origin gPackager )
				)
				( objectStatus "TP_CPLD1_PR11B" )
			)
			( signal "@baseboard_fab2_lib.baseboard_fab2(sch_1):tp_cpld1_pr12d"
				( attribute "CDS_PHYS_NET_NAME" "TP_CPLD1_PR12D"
					( Origin gPackager )
				)
				( objectStatus "TP_CPLD1_PR12D" )
			)
			( signal "@baseboard_fab2_lib.baseboard_fab2(sch_1):tp_cpld1_pr7a_pclkt1_0"
				( attribute "CDS_PHYS_NET_NAME" "TP_CPLD1_PR7A_PCLKT1_0"
					( Origin gPackager )
				)
				( objectStatus "TP_CPLD1_PR7A_PCLKT1_0" )
			)
			( signal "@baseboard_fab2_lib.baseboard_fab2(sch_1):tp_cpld1_pr7b_pclkc1_0"
				( attribute "CDS_PHYS_NET_NAME" "TP_CPLD1_PR7B_PCLKC1_0"
					( Origin gPackager )
				)
				( objectStatus "TP_CPLD1_PR7B_PCLKC1_0" )
			)
			( signal "@baseboard_fab2_lib.baseboard_fab2(sch_1):tp_cpld1_pr7c"
				( attribute "CDS_PHYS_NET_NAME" "TP_CPLD1_PR7C"
					( Origin gPackager )
				)
				( objectStatus "TP_CPLD1_PR7C" )
			)
			( signal "@baseboard_fab2_lib.baseboard_fab2(sch_1):tp_cpld1_pr7d"
				( attribute "CDS_PHYS_NET_NAME" "TP_CPLD1_PR7D"
					( Origin gPackager )
				)
				( objectStatus "TP_CPLD1_PR7D" )
			)
			( signal "@baseboard_fab2_lib.baseboard_fab2(sch_1):tp_cpld1_pr9a"
				( attribute "CDS_PHYS_NET_NAME" "TP_CPLD1_PR9A"
					( Origin gPackager )
				)
				( objectStatus "TP_CPLD1_PR9A" )
			)
			( signal "@baseboard_fab2_lib.baseboard_fab2(sch_1):tp_cpld1_pr9c"
				( attribute "CDS_PHYS_NET_NAME" "TP_CPLD1_PR9C"
					( Origin gPackager )
				)
				( objectStatus "TP_CPLD1_PR9C" )
			)
			( signal "@baseboard_fab2_lib.baseboard_fab2(sch_1):tp_cpld1_pr9d"
				( attribute "CDS_PHYS_NET_NAME" "TP_CPLD1_PR9D"
					( Origin gPackager )
				)
				( objectStatus "TP_CPLD1_PR9D" )
			)
			( signal "@baseboard_fab2_lib.baseboard_fab2(sch_1):tp_cpld1_pt11a"
				( attribute "CDS_PHYS_NET_NAME" "TP_CPLD1_PT11A"
					( Origin gPackager )
				)
				( objectStatus "TP_CPLD1_PT11A" )
			)
			( signal "@baseboard_fab2_lib.baseboard_fab2(sch_1):tp_cpld1_pt11b"
				( attribute "CDS_PHYS_NET_NAME" "TP_CPLD1_PT11B"
					( Origin gPackager )
				)
				( objectStatus "TP_CPLD1_PT11B" )
			)
			( signal "@baseboard_fab2_lib.baseboard_fab2(sch_1):tp_cpld1_pt13a"
				( attribute "CDS_PHYS_NET_NAME" "TP_CPLD1_PT13A"
					( Origin gPackager )
				)
				( objectStatus "TP_CPLD1_PT13A" )
			)
			( signal "@baseboard_fab2_lib.baseboard_fab2(sch_1):tp_cpld1_pt16b"
				( attribute "CDS_PHYS_NET_NAME" "TP_CPLD1_PT16B"
					( Origin gPackager )
				)
				( objectStatus "TP_CPLD1_PT16B" )
			)
			( signal "@baseboard_fab2_lib.baseboard_fab2(sch_1):tp_cpld1_pt17b_pclkc0_1"
				( attribute "CDS_PHYS_NET_NAME" "TP_CPLD1_PT17B_PCLKC0_1"
					( Origin gPackager )
				)
				( objectStatus "TP_CPLD1_PT17B_PCLKC0_1" )
			)
			( signal "@baseboard_fab2_lib.baseboard_fab2(sch_1):tp_cpld1_pt17c"
				( attribute "CDS_PHYS_NET_NAME" "TP_CPLD1_PT17C"
					( Origin gPackager )
				)
				( objectStatus "TP_CPLD1_PT17C" )
			)
			( signal "@baseboard_fab2_lib.baseboard_fab2(sch_1):tp_cpld1_pt19d"
				( attribute "CDS_PHYS_NET_NAME" "TP_CPLD1_PT19D"
					( Origin gPackager )
				)
				( objectStatus "TP_CPLD1_PT19D" )
			)
			( signal "@baseboard_fab2_lib.baseboard_fab2(sch_1):tp_cpld1_pt20a"
				( attribute "CDS_PHYS_NET_NAME" "TP_CPLD1_PT20A"
					( Origin gPackager )
				)
				( objectStatus "TP_CPLD1_PT20A" )
			)
			( signal "@baseboard_fab2_lib.baseboard_fab2(sch_1):tp_cpld1_pt20b"
				( attribute "CDS_PHYS_NET_NAME" "TP_CPLD1_PT20B"
					( Origin gPackager )
				)
				( objectStatus "TP_CPLD1_PT20B" )
			)
			( signal "@baseboard_fab2_lib.baseboard_fab2(sch_1):tp_cpld1_pt22c"
				( attribute "CDS_PHYS_NET_NAME" "TP_CPLD1_PT22C"
					( Origin gPackager )
				)
				( objectStatus "TP_CPLD1_PT22C" )
			)
			( signal "@baseboard_fab2_lib.baseboard_fab2(sch_1):tp_cpld1_pt22d"
				( attribute "CDS_PHYS_NET_NAME" "TP_CPLD1_PT22D"
					( Origin gPackager )
				)
				( objectStatus "TP_CPLD1_PT22D" )
			)
			( signal "@baseboard_fab2_lib.baseboard_fab2(sch_1):tp_cpld1_pt24b"
				( attribute "CDS_PHYS_NET_NAME" "TP_CPLD1_PT24B"
					( Origin gPackager )
				)
				( objectStatus "TP_CPLD1_PT24B" )
			)
			( signal "@baseboard_fab2_lib.baseboard_fab2(sch_1):tp_cpld1_pt24c_initn"
				( attribute "CDS_PHYS_NET_NAME" "TP_CPLD1_PT24C_INITN"
					( Origin gPackager )
				)
				( objectStatus "TP_CPLD1_PT24C_INITN" )
			)
			( signal "@baseboard_fab2_lib.baseboard_fab2(sch_1):tp_cpld1_pt24d_done"
				( attribute "CDS_PHYS_NET_NAME" "TP_CPLD1_PT24D_DONE"
					( Origin gPackager )
				)
				( objectStatus "TP_CPLD1_PT24D_DONE" )
			)
			( signal "@baseboard_fab2_lib.baseboard_fab2(sch_1):vr_pvcciomcp_cpu1_xaddr1"
				( attribute "CDS_PHYS_NET_NAME" "VR_PVCCIOMCP_CPU1_XADDR1"
					( Origin gPackager )
				)
				( objectStatus "VR_PVCCIOMCP_CPU1_XADDR1" )
			)
			( signal "@baseboard_fab2_lib.baseboard_fab2(sch_1):vr_pvccmcp_cpu1_xaddr2"
				( attribute "CDS_PHYS_NET_NAME" "VR_PVCCMCP_CPU1_XADDR2"
					( Origin gPackager )
				)
				( objectStatus "VR_PVCCMCP_CPU1_XADDR2" )
			)
			( signal "@baseboard_fab2_lib.baseboard_fab2(sch_1):vr_pvcciomcp_cpu0_xaddr1"
				( attribute "CDS_PHYS_NET_NAME" "VR_PVCCIOMCP_CPU0_XADDR1"
					( Origin gPackager )
				)
				( objectStatus "VR_PVCCIOMCP_CPU0_XADDR1" )
			)
			( signal "@baseboard_fab2_lib.baseboard_fab2(sch_1):vr_pvccmcp_cpu0_xaddr2"
				( attribute "CDS_PHYS_NET_NAME" "VR_PVCCMCP_CPU0_XADDR2"
					( Origin gPackager )
				)
				( objectStatus "VR_PVCCMCP_CPU0_XADDR2" )
			)
			( signal "@baseboard_fab2_lib.baseboard_fab2(sch_1):a_adm1085_cext"
				( attribute "CDS_PHYS_NET_NAME" "A_ADM1085_CEXT"
					( Origin gPackager )
				)
				( objectStatus "A_ADM1085_CEXT" )
			)
			( signal "@baseboard_fab2_lib.baseboard_fab2(sch_1):a_pg_p12v_main"
				( attribute "CDS_PHYS_NET_NAME" "A_PG_P12V_MAIN"
					( Origin gPackager )
				)
				( objectStatus "A_PG_P12V_MAIN" )
			)
			( signal "@baseboard_fab2_lib.baseboard_fab2(sch_1):a_pg_p5v"
				( attribute "CDS_PHYS_NET_NAME" "A_PG_P5V"
					( Origin gPackager )
				)
				( objectStatus "A_PG_P5V" )
			)
			( signal "@baseboard_fab2_lib.baseboard_fab2(sch_1):p3v_bat_source"
				( alias ( signalRef "@baseboard_fab2_lib.baseboard_fab2(sch_1):page196_p3v_bat_source") )
				( attribute "VOLTAGE" "+3 V"
					( Units "uVoltage" "V" 1.000000)
					( Status sAliasFlattened )
					( Origin gFrontEnd )
				)
				( attribute "CDS_PHYS_NET_NAME" "P3V_BAT_SOURCE"
					( Origin gPackager )
				)
				( objectStatus "P3V_BAT_SOURCE" )
			)
			( signal "@baseboard_fab2_lib.baseboard_fab2(sch_1):page196_p3v_bat_source"
				( attribute "CDS_PHYS_NET_NAME" "P3V_BAT_SOURCE"
					( Origin gPackager )
				)
				( attribute "VOLTAGE" "+3 V"
					( Units "uVoltage" "V" 1.000000)
					( Origin gFrontEnd )
				)
				( objectFlag fObjectAlias )
				( objectStatus "page196_p3v_bat_source" )
			)
			( signal "@baseboard_fab2_lib.baseboard_fab2(sch_1):pwrgd_p12v_hsc"
				( attribute "CDS_PHYS_NET_NAME" "PWRGD_P12V_HSC"
					( Origin gPackager )
				)
				( objectStatus "PWRGD_P12V_HSC" )
			)
			( signal "@baseboard_fab2_lib.baseboard_fab2(sch_1):pwrgd_p12v_hsc_dly_r"
				( attribute "CDS_PHYS_NET_NAME" "PWRGD_P12V_HSC_DLY_R"
					( Origin gPackager )
				)
				( objectStatus "PWRGD_P12V_HSC_DLY_R" )
			)
			( signal "@baseboard_fab2_lib.baseboard_fab2(sch_1):pwrgd_p12v_main_r"
				( attribute "CDS_PHYS_NET_NAME" "PWRGD_P12V_MAIN_R"
					( Origin gPackager )
				)
				( objectStatus "PWRGD_P12V_MAIN_R" )
			)
			( signal "@baseboard_fab2_lib.baseboard_fab2(sch_1):pwrgd_p3v3_r1"
				( attribute "CDS_PHYS_NET_NAME" "PWRGD_P3V3_R1"
					( Origin gPackager )
				)
				( objectStatus "PWRGD_P3V3_R1" )
			)
			( signal "@baseboard_fab2_lib.baseboard_fab2(sch_1):pwrgd_p5v_n"
				( attribute "CDS_PHYS_NET_NAME" "PWRGD_P5V_N"
					( Origin gPackager )
				)
				( objectStatus "PWRGD_P5V_N" )
			)
			( signal "@baseboard_fab2_lib.baseboard_fab2(sch_1):pwrgd_p5v_r"
				( attribute "CDS_PHYS_NET_NAME" "PWRGD_P5V_R"
					( Origin gPackager )
				)
				( objectStatus "PWRGD_P5V_R" )
			)
			( signal "@baseboard_fab2_lib.baseboard_fab2(sch_1):vsense_p12v_adm1085"
				( attribute "CDS_PHYS_NET_NAME" "VSENSE_P12V_ADM1085"
					( Origin gPackager )
				)
				( objectStatus "VSENSE_P12V_ADM1085" )
			)
			( signal "@baseboard_fab2_lib.baseboard_fab2(sch_1):vr_pvddq_abc_aiinsen"
				( attribute "CDS_PHYS_NET_NAME" "VR_PVDDQ_ABC_AIINSEN"
					( Origin gPackager )
				)
				( objectStatus "VR_PVDDQ_ABC_AIINSEN" )
			)
			( signal "@baseboard_fab2_lib.baseboard_fab2(sch_1):pwrgd_pvddq_def_n"
				( attribute "CDS_PHYS_NET_NAME" "PWRGD_PVDDQ_DEF_N"
					( Origin gPackager )
				)
				( objectStatus "PWRGD_PVDDQ_DEF_N" )
			)
			( signal "@baseboard_fab2_lib.baseboard_fab2(sch_1):vr_pvddq_def_aiinsen"
				( attribute "CDS_PHYS_NET_NAME" "VR_PVDDQ_DEF_AIINSEN"
					( Origin gPackager )
				)
				( objectStatus "VR_PVDDQ_DEF_AIINSEN" )
			)
			( signal "@baseboard_fab2_lib.baseboard_fab2(sch_1):p12v_nvdimm_klm_d"
				( attribute "CDS_PHYS_NET_NAME" "P12V_NVDIMM_KLM_D"
					( Origin gPackager )
				)
				( objectStatus "P12V_NVDIMM_KLM_D" )
			)
			( signal "@baseboard_fab2_lib.baseboard_fab2(sch_1):vr_pvddq_ghj_aiinsen"
				( attribute "CDS_PHYS_NET_NAME" "VR_PVDDQ_GHJ_AIINSEN"
					( Origin gPackager )
				)
				( objectStatus "VR_PVDDQ_GHJ_AIINSEN" )
			)
			( signal "@baseboard_fab2_lib.baseboard_fab2(sch_1):p12v_nvdimm_ghj_d"
				( attribute "CDS_PHYS_NET_NAME" "P12V_NVDIMM_GHJ_D"
					( Origin gPackager )
				)
				( objectStatus "P12V_NVDIMM_GHJ_D" )
			)
			( signal "@baseboard_fab2_lib.baseboard_fab2(sch_1):vr_pvddq_klm_aiinsen"
				( attribute "CDS_PHYS_NET_NAME" "VR_PVDDQ_KLM_AIINSEN"
					( Origin gPackager )
				)
				( objectStatus "VR_PVDDQ_KLM_AIINSEN" )
			)
			( signal "@baseboard_fab2_lib.baseboard_fab2(sch_1):p12v_nvdimm_def_d"
				( attribute "CDS_PHYS_NET_NAME" "P12V_NVDIMM_DEF_D"
					( Origin gPackager )
				)
				( objectStatus "P12V_NVDIMM_DEF_D" )
			)
			( signal "@baseboard_fab2_lib.baseboard_fab2(sch_1):p12v_fan_switch_g"
				( alias ( signalRef "@baseboard_fab2_lib.baseboard_fab2(sch_1):page198_p12v_fan_switch_g") )
				( attribute "VOLTAGE" "+5V"
					( Units "uVoltage" "V" 1.000000)
					( Status sAliasFlattened )
					( Origin gFrontEnd )
				)
				( attribute "CDS_PHYS_NET_NAME" "P12V_FAN_SWITCH_G"
					( Origin gPackager )
				)
				( objectStatus "P12V_FAN_SWITCH_G" )
			)
			( signal "@baseboard_fab2_lib.baseboard_fab2(sch_1):page198_p12v_fan_switch_g"
				( attribute "VOLTAGE" "+5V"
					( Units "uVoltage" "V" 1.000000)
					( Origin gFrontEnd )
				)
				( objectFlag fObjectAlias )
				( objectStatus "page198_p12v_fan_switch_g" )
			)
			( signal "@baseboard_fab2_lib.baseboard_fab2(sch_1):p12v_switch_g"
				( alias ( signalRef "@baseboard_fab2_lib.baseboard_fab2(sch_1):page198_p12v_switch_g") )
				( attribute "VOLTAGE" "+3.3V"
					( Units "uVoltage" "V" 1.000000)
					( Status sAliasFlattened )
					( Origin gFrontEnd )
				)
				( attribute "CDS_PHYS_NET_NAME" "P12V_SWITCH_G"
					( Origin gPackager )
				)
				( objectStatus "P12V_SWITCH_G" )
			)
			( signal "@baseboard_fab2_lib.baseboard_fab2(sch_1):page198_p12v_switch_g"
				( attribute "VOLTAGE" "+3.3V"
					( Units "uVoltage" "V" 1.000000)
					( Origin gFrontEnd )
				)
				( objectFlag fObjectAlias )
				( objectStatus "page198_p12v_switch_g" )
			)
			( signal "@baseboard_fab2_lib.baseboard_fab2(sch_1):p3v3_switch_g"
				( alias ( signalRef "@baseboard_fab2_lib.baseboard_fab2(sch_1):page198_p3v3_switch_g") )
				( attribute "VOLTAGE" "3.3"
					( Units "uVoltage" "V" 1.000000)
					( Status sAliasFlattened )
					( Origin gFrontEnd )
				)
				( attribute "CDS_PHYS_NET_NAME" "P3V3_SWITCH_G"
					( Origin gPackager )
				)
				( objectStatus "P3V3_SWITCH_G" )
			)
			( signal "@baseboard_fab2_lib.baseboard_fab2(sch_1):page198_p3v3_switch_g"
				( attribute "VOLTAGE" "3.3"
					( Units "uVoltage" "V" 1.000000)
					( Origin gFrontEnd )
				)
				( objectFlag fObjectAlias )
				( objectStatus "page198_p3v3_switch_g" )
			)
			( signal "@baseboard_fab2_lib.baseboard_fab2(sch_1):p5v_switch_g"
				( alias ( signalRef "@baseboard_fab2_lib.baseboard_fab2(sch_1):page198_p5v_switch_g") )
				( attribute "VOLTAGE" "+5V"
					( Units "uVoltage" "V" 1.000000)
					( Status sAliasFlattened )
					( Origin gFrontEnd )
				)
				( attribute "CDS_PHYS_NET_NAME" "P5V_SWITCH_G"
					( Origin gPackager )
				)
				( objectStatus "P5V_SWITCH_G" )
			)
			( signal "@baseboard_fab2_lib.baseboard_fab2(sch_1):page198_p5v_switch_g"
				( attribute "VOLTAGE" "+5V"
					( Units "uVoltage" "V" 1.000000)
					( Origin gFrontEnd )
				)
				( objectFlag fObjectAlias )
				( objectStatus "page198_p5v_switch_g" )
			)
			( signal "@baseboard_fab2_lib.baseboard_fab2(sch_1):tp_slg55021_p12v_fan_8"
				( attribute "CDS_PHYS_NET_NAME" "TP_SLG55021_P12V_FAN_8"
					( Origin gPackager )
				)
				( objectStatus "TP_SLG55021_P12V_FAN_8" )
			)
			( signal "@baseboard_fab2_lib.baseboard_fab2(sch_1):tp_slg55021_p12v_main_8"
				( attribute "CDS_PHYS_NET_NAME" "TP_SLG55021_P12V_MAIN_8"
					( Origin gPackager )
				)
				( objectStatus "TP_SLG55021_P12V_MAIN_8" )
			)
			( signal "@baseboard_fab2_lib.baseboard_fab2(sch_1):tp_slg55021_p3v3_8"
				( attribute "CDS_PHYS_NET_NAME" "TP_SLG55021_P3V3_8"
					( Origin gPackager )
				)
				( objectStatus "TP_SLG55021_P3V3_8" )
			)
			( signal "@baseboard_fab2_lib.baseboard_fab2(sch_1):tp_slg55021_p5v_8"
				( attribute "CDS_PHYS_NET_NAME" "TP_SLG55021_P5V_8"
					( Origin gPackager )
				)
				( objectStatus "TP_SLG55021_P5V_8" )
			)
			( signal "@baseboard_fab2_lib.baseboard_fab2(sch_1):a_hsc_csout"
				( attribute "CDS_PHYS_NET_NAME" "A_HSC_CSOUT"
					( Origin gPackager )
				)
				( objectStatus "A_HSC_CSOUT" )
			)
			( signal "@baseboard_fab2_lib.baseboard_fab2(sch_1):a_hsc_gate"
				( attribute "CDS_PHYS_NET_NAME" "A_HSC_GATE"
					( Origin gPackager )
				)
				( objectStatus "A_HSC_GATE" )
			)
			( signal "@baseboard_fab2_lib.baseboard_fab2(sch_1):a_hsc_high_en"
				( attribute "CDS_PHYS_NET_NAME" "A_HSC_HIGH_EN"
					( Origin gPackager )
				)
				( objectStatus "A_HSC_HIGH_EN" )
			)
			( signal "@baseboard_fab2_lib.baseboard_fab2(sch_1):a_hsc_hsn"
				( attribute "CDS_PHYS_NET_NAME" "A_HSC_HSN"
					( Origin gPackager )
				)
				( objectStatus "A_HSC_HSN" )
			)
			( signal "@baseboard_fab2_lib.baseboard_fab2(sch_1):a_hsc_hsp"
				( attribute "CDS_PHYS_NET_NAME" "A_HSC_HSP"
					( Origin gPackager )
				)
				( objectStatus "A_HSC_HSP" )
			)
			( signal "@baseboard_fab2_lib.baseboard_fab2(sch_1):a_hsc_iset"
				( attribute "CDS_PHYS_NET_NAME" "A_HSC_ISET"
					( Origin gPackager )
				)
				( objectStatus "A_HSC_ISET" )
			)
			( signal "@baseboard_fab2_lib.baseboard_fab2(sch_1):a_hsc_iset_s"
				( attribute "CDS_PHYS_NET_NAME" "A_HSC_ISET_S"
					( Origin gPackager )
				)
				( objectStatus "A_HSC_ISET_S" )
			)
			( signal "@baseboard_fab2_lib.baseboard_fab2(sch_1):a_hsc_iset_s2"
				( attribute "CDS_PHYS_NET_NAME" "A_HSC_ISET_S2"
					( Origin gPackager )
				)
				( objectStatus "A_HSC_ISET_S2" )
			)
			( signal "@baseboard_fab2_lib.baseboard_fab2(sch_1):a_hsc_istart"
				( attribute "CDS_PHYS_NET_NAME" "A_HSC_ISTART"
					( Origin gPackager )
				)
				( objectStatus "A_HSC_ISTART" )
			)
			( signal "@baseboard_fab2_lib.baseboard_fab2(sch_1):a_hsc_low_en"
				( attribute "CDS_PHYS_NET_NAME" "A_HSC_LOW_EN"
					( Origin gPackager )
				)
				( objectStatus "A_HSC_LOW_EN" )
			)
			( signal "@baseboard_fab2_lib.baseboard_fab2(sch_1):a_hsc_mon"
				( attribute "CDS_PHYS_NET_NAME" "A_HSC_MON"
					( Origin gPackager )
				)
				( objectStatus "A_HSC_MON" )
			)
			( signal "@baseboard_fab2_lib.baseboard_fab2(sch_1):a_hsc_mop"
				( attribute "CDS_PHYS_NET_NAME" "A_HSC_MOP"
					( Origin gPackager )
				)
				( objectStatus "A_HSC_MOP" )
			)
			( signal "@baseboard_fab2_lib.baseboard_fab2(sch_1):a_hsc_ocp_sel"
				( attribute "CDS_PHYS_NET_NAME" "A_HSC_OCP_SEL"
					( Origin gPackager )
				)
				( objectStatus "A_HSC_OCP_SEL" )
			)
			( signal "@baseboard_fab2_lib.baseboard_fab2(sch_1):a_hsc_ov"
				( attribute "CDS_PHYS_NET_NAME" "A_HSC_OV"
					( Origin gPackager )
				)
				( objectStatus "A_HSC_OV" )
			)
			( signal "@baseboard_fab2_lib.baseboard_fab2(sch_1):a_hsc_pset"
				( attribute "CDS_PHYS_NET_NAME" "A_HSC_PSET"
					( Origin gPackager )
				)
				( objectStatus "A_HSC_PSET" )
			)
			( signal "@baseboard_fab2_lib.baseboard_fab2(sch_1):a_hsc_pwgin"
				( attribute "CDS_PHYS_NET_NAME" "A_HSC_PWGIN"
					( Origin gPackager )
				)
				( objectStatus "A_HSC_PWGIN" )
			)
			( signal "@baseboard_fab2_lib.baseboard_fab2(sch_1):a_hsc_temp"
				( attribute "CDS_PHYS_NET_NAME" "A_HSC_TEMP"
					( Origin gPackager )
				)
				( objectStatus "A_HSC_TEMP" )
			)
			( signal "@baseboard_fab2_lib.baseboard_fab2(sch_1):a_hsc_timer"
				( attribute "CDS_PHYS_NET_NAME" "A_HSC_TIMER"
					( Origin gPackager )
				)
				( objectStatus "A_HSC_TIMER" )
			)
			( signal "@baseboard_fab2_lib.baseboard_fab2(sch_1):a_hsc_uv"
				( attribute "CDS_PHYS_NET_NAME" "A_HSC_UV"
					( Origin gPackager )
				)
				( objectStatus "A_HSC_UV" )
			)
			( signal "@baseboard_fab2_lib.baseboard_fab2(sch_1):a_hsc_vcap"
				( attribute "CDS_PHYS_NET_NAME" "A_HSC_VCAP"
					( Origin gPackager )
				)
				( objectStatus "A_HSC_VCAP" )
			)
			( signal "@baseboard_fab2_lib.baseboard_fab2(sch_1):a_hsc_vout"
				( attribute "CDS_PHYS_NET_NAME" "A_HSC_VOUT"
					( Origin gPackager )
				)
				( objectStatus "A_HSC_VOUT" )
			)
			( signal "@baseboard_fab2_lib.baseboard_fab2(sch_1):agnd_hsc"
				( alias ( signalRef "@baseboard_fab2_lib.baseboard_fab2(sch_1):page199_agnd_hsc") )
				( alias ( signalRef "@baseboard_fab2_lib.baseboard_fab2(sch_1):page200_agnd_hsc") )
				( attribute "VOLTAGE" "0"
					( Units "uVoltage" "V" 1.000000)
					( Status sAliasFlattened )
					( Origin gFrontEnd )
				)
				( attribute "CDS_PHYS_NET_NAME" "AGND_HSC"
					( Origin gPackager )
				)
				( objectStatus "AGND_HSC" )
			)
			( signal "@baseboard_fab2_lib.baseboard_fab2(sch_1):page199_agnd_hsc"
				( attribute "VOLTAGE" "0"
					( Units "uVoltage" "V" 1.000000)
					( Origin gFrontEnd )
				)
				( objectFlag fObjectAlias )
				( objectStatus "page199_agnd_hsc" )
			)
			( signal "@baseboard_fab2_lib.baseboard_fab2(sch_1):page200_agnd_hsc"
				( attribute "VOLTAGE" "0"
					( Units "uVoltage" "V" 1.000000)
					( Origin gFrontEnd )
				)
				( objectFlag fObjectAlias )
				( objectStatus "page200_agnd_hsc" )
			)
			( signal "@baseboard_fab2_lib.baseboard_fab2(sch_1):fm_p12v_hsc_adr1"
				( attribute "CDS_PHYS_NET_NAME" "FM_P12V_HSC_ADR1"
					( Origin gPackager )
				)
				( objectStatus "FM_P12V_HSC_ADR1" )
			)
			( signal "@baseboard_fab2_lib.baseboard_fab2(sch_1):fm_p12v_hsc_adr2"
				( attribute "CDS_PHYS_NET_NAME" "FM_P12V_HSC_ADR2"
					( Origin gPackager )
				)
				( objectStatus "FM_P12V_HSC_ADR2" )
			)
			( signal "@baseboard_fab2_lib.baseboard_fab2(sch_1):irq_hsc_fault_r_n"
				( attribute "CDS_PHYS_NET_NAME" "IRQ_HSC_FAULT_R_N"
					( Origin gPackager )
				)
				( objectStatus "IRQ_HSC_FAULT_R_N" )
			)
			( signal "@baseboard_fab2_lib.baseboard_fab2(sch_1):p12v_hsc_vcc"
				( alias ( signalRef "@baseboard_fab2_lib.baseboard_fab2(sch_1):page199_p12v_hsc_vcc") )
				( attribute "VOLTAGE" "+12V"
					( Units "uVoltage" "V" 1.000000)
					( Status sAliasFlattened )
					( Origin gFrontEnd )
				)
				( attribute "CDS_PHYS_NET_NAME" "P12V_HSC_VCC"
					( Origin gPackager )
				)
				( objectStatus "P12V_HSC_VCC" )
			)
			( signal "@baseboard_fab2_lib.baseboard_fab2(sch_1):page199_p12v_hsc_vcc"
				( attribute "VOLTAGE" "+12V"
					( Units "uVoltage" "V" 1.000000)
					( Origin gFrontEnd )
				)
				( objectFlag fObjectAlias )
				( objectStatus "page199_p12v_hsc_vcc" )
			)
			( signal "@baseboard_fab2_lib.baseboard_fab2(sch_1):pd_hsc_retry_n"
				( attribute "CDS_PHYS_NET_NAME" "PD_HSC_RETRY_N"
					( Origin gPackager )
				)
				( objectStatus "PD_HSC_RETRY_N" )
			)
			( signal "@baseboard_fab2_lib.baseboard_fab2(sch_1):pwrgd_p12v_r"
				( attribute "CDS_PHYS_NET_NAME" "PWRGD_P12V_R"
					( Origin gPackager )
				)
				( objectStatus "PWRGD_P12V_R" )
			)
			( signal "@baseboard_fab2_lib.baseboard_fab2(sch_1):smb_3v3sb_hsc_scl_r"
				( attribute "CDS_PHYS_NET_NAME" "SMB_3V3SB_HSC_SCL_R"
					( Origin gPackager )
				)
				( objectStatus "SMB_3V3SB_HSC_SCL_R" )
			)
			( signal "@baseboard_fab2_lib.baseboard_fab2(sch_1):smb_3v3sb_hsc_sda_r"
				( attribute "CDS_PHYS_NET_NAME" "SMB_3V3SB_HSC_SDA_R"
					( Origin gPackager )
				)
				( objectStatus "SMB_3V3SB_HSC_SDA_R" )
			)
			( signal "@baseboard_fab2_lib.baseboard_fab2(sch_1):tp_hsc_alert2_n"
				( attribute "CDS_PHYS_NET_NAME" "TP_HSC_ALERT2_N"
					( Origin gPackager )
				)
				( objectStatus "TP_HSC_ALERT2_N" )
			)
			( signal "@baseboard_fab2_lib.baseboard_fab2(sch_1):tp_hsc_mclk"
				( attribute "CDS_PHYS_NET_NAME" "TP_HSC_MCLK"
					( Origin gPackager )
				)
				( objectStatus "TP_HSC_MCLK" )
			)
			( signal "@baseboard_fab2_lib.baseboard_fab2(sch_1):tp_hsc_mdat"
				( attribute "CDS_PHYS_NET_NAME" "TP_HSC_MDAT"
					( Origin gPackager )
				)
				( objectStatus "TP_HSC_MDAT" )
			)
			( signal "@baseboard_fab2_lib.baseboard_fab2(sch_1):tp_hsc_spissn"
				( attribute "CDS_PHYS_NET_NAME" "TP_HSC_SPISSN"
					( Origin gPackager )
				)
				( objectStatus "TP_HSC_SPISSN" )
			)
			( signal "@baseboard_fab2_lib.baseboard_fab2(sch_1):a_hsc_c"
				( attribute "CDS_PHYS_NET_NAME" "A_HSC_C"
					( Origin gPackager )
				)
				( objectStatus "A_HSC_C" )
			)
			( signal "@baseboard_fab2_lib.baseboard_fab2(sch_1):a_hsc_gate1_r"
				( attribute "CDS_PHYS_NET_NAME" "A_HSC_GATE1_R"
					( Origin gPackager )
				)
				( objectStatus "A_HSC_GATE1_R" )
			)
			( signal "@baseboard_fab2_lib.baseboard_fab2(sch_1):a_hsc_gate2_r"
				( attribute "CDS_PHYS_NET_NAME" "A_HSC_GATE2_R"
					( Origin gPackager )
				)
				( objectStatus "A_HSC_GATE2_R" )
			)
			( signal "@baseboard_fab2_lib.baseboard_fab2(sch_1):a_hsc_gate3_r"
				( attribute "CDS_PHYS_NET_NAME" "A_HSC_GATE3_R"
					( Origin gPackager )
				)
				( objectStatus "A_HSC_GATE3_R" )
			)
			( signal "@baseboard_fab2_lib.baseboard_fab2(sch_1):a_hsc_high"
				( attribute "CDS_PHYS_NET_NAME" "A_HSC_HIGH"
					( Origin gPackager )
				)
				( objectStatus "A_HSC_HIGH" )
			)
			( signal "@baseboard_fab2_lib.baseboard_fab2(sch_1):a_hsc_inap"
				( attribute "CDS_PHYS_NET_NAME" "A_HSC_INAP"
					( Origin gPackager )
				)
				( objectStatus "A_HSC_INAP" )
			)
			( signal "@baseboard_fab2_lib.baseboard_fab2(sch_1):a_hsc_low"
				( attribute "CDS_PHYS_NET_NAME" "A_HSC_LOW"
					( Origin gPackager )
				)
				( objectStatus "A_HSC_LOW" )
			)
			( signal "@baseboard_fab2_lib.baseboard_fab2(sch_1):a_hsc_low_drain"
				( attribute "CDS_PHYS_NET_NAME" "A_HSC_LOW_DRAIN"
					( Origin gPackager )
				)
				( objectStatus "A_HSC_LOW_DRAIN" )
			)
			( signal "@baseboard_fab2_lib.baseboard_fab2(sch_1):a_hsc_low_gate"
				( attribute "CDS_PHYS_NET_NAME" "A_HSC_LOW_GATE"
					( Origin gPackager )
				)
				( objectStatus "A_HSC_LOW_GATE" )
			)
			( signal "@baseboard_fab2_lib.baseboard_fab2(sch_1):a_hsc_timer_r"
				( attribute "CDS_PHYS_NET_NAME" "A_HSC_TIMER_R"
					( Origin gPackager )
				)
				( objectStatus "A_HSC_TIMER_R" )
			)
			( signal "@baseboard_fab2_lib.baseboard_fab2(sch_1):a_p12v_stby_adr_trigger"
				( attribute "CDS_PHYS_NET_NAME" "A_P12V_STBY_ADR_TRIGGER"
					( Origin gPackager )
				)
				( objectStatus "A_P12V_STBY_ADR_TRIGGER" )
			)
			( signal "@baseboard_fab2_lib.baseboard_fab2(sch_1):a_p12v_stby_fp_trigger"
				( attribute "CDS_PHYS_NET_NAME" "A_P12V_STBY_FP_TRIGGER"
					( Origin gPackager )
				)
				( objectStatus "A_P12V_STBY_FP_TRIGGER" )
			)
			( signal "@baseboard_fab2_lib.baseboard_fab2(sch_1):a_p12v_stby_fph_gate"
				( attribute "CDS_PHYS_NET_NAME" "A_P12V_STBY_FPH_GATE"
					( Origin gPackager )
				)
				( objectStatus "A_P12V_STBY_FPH_GATE" )
			)
			( signal "@baseboard_fab2_lib.baseboard_fab2(sch_1):fm_oc_detect_en"
				( attribute "CDS_PHYS_NET_NAME" "FM_OC_DETECT_EN"
					( Origin gPackager )
				)
				( objectStatus "FM_OC_DETECT_EN" )
			)
			( signal "@baseboard_fab2_lib.baseboard_fab2(sch_1):p12v_hsc_senn0"
				( alias ( signalRef "@baseboard_fab2_lib.baseboard_fab2(sch_1):page200_p12v_hsc_senn0") )
				( attribute "VOLTAGE" "+12V"
					( Units "uVoltage" "V" 1.000000)
					( Status sAliasFlattened )
					( Origin gFrontEnd )
				)
				( attribute "CDS_PHYS_NET_NAME" "P12V_HSC_SENN0"
					( Origin gPackager )
				)
				( objectStatus "P12V_HSC_SENN0" )
			)
			( signal "@baseboard_fab2_lib.baseboard_fab2(sch_1):page200_p12v_hsc_senn0"
				( attribute "VOLTAGE" "+12V"
					( Units "uVoltage" "V" 1.000000)
					( Origin gFrontEnd )
				)
				( objectFlag fObjectAlias )
				( objectStatus "page200_p12v_hsc_senn0" )
			)
			( signal "@baseboard_fab2_lib.baseboard_fab2(sch_1):p12v_hsc_senn1"
				( alias ( signalRef "@baseboard_fab2_lib.baseboard_fab2(sch_1):page200_p12v_hsc_senn1") )
				( attribute "VOLTAGE" "+12V"
					( Units "uVoltage" "V" 1.000000)
					( Status sAliasFlattened )
					( Origin gFrontEnd )
				)
				( attribute "CDS_PHYS_NET_NAME" "P12V_HSC_SENN1"
					( Origin gPackager )
				)
				( objectStatus "P12V_HSC_SENN1" )
			)
			( signal "@baseboard_fab2_lib.baseboard_fab2(sch_1):page200_p12v_hsc_senn1"
				( attribute "VOLTAGE" "+12V"
					( Units "uVoltage" "V" 1.000000)
					( Origin gFrontEnd )
				)
				( objectFlag fObjectAlias )
				( objectStatus "page200_p12v_hsc_senn1" )
			)
			( signal "@baseboard_fab2_lib.baseboard_fab2(sch_1):p12v_hsc_senp0"
				( alias ( signalRef "@baseboard_fab2_lib.baseboard_fab2(sch_1):page200_p12v_hsc_senp0") )
				( attribute "VOLTAGE" "+12V"
					( Units "uVoltage" "V" 1.000000)
					( Status sAliasFlattened )
					( Origin gFrontEnd )
				)
				( attribute "CDS_PHYS_NET_NAME" "P12V_HSC_SENP0"
					( Origin gPackager )
				)
				( objectStatus "P12V_HSC_SENP0" )
			)
			( signal "@baseboard_fab2_lib.baseboard_fab2(sch_1):page200_p12v_hsc_senp0"
				( attribute "VOLTAGE" "+12V"
					( Units "uVoltage" "V" 1.000000)
					( Origin gFrontEnd )
				)
				( objectFlag fObjectAlias )
				( objectStatus "page200_p12v_hsc_senp0" )
			)
			( signal "@baseboard_fab2_lib.baseboard_fab2(sch_1):p12v_hsc_senp1"
				( alias ( signalRef "@baseboard_fab2_lib.baseboard_fab2(sch_1):page200_p12v_hsc_senp1") )
				( attribute "VOLTAGE" "+12V"
					( Units "uVoltage" "V" 1.000000)
					( Status sAliasFlattened )
					( Origin gFrontEnd )
				)
				( attribute "CDS_PHYS_NET_NAME" "P12V_HSC_SENP1"
					( Origin gPackager )
				)
				( objectStatus "P12V_HSC_SENP1" )
			)
			( signal "@baseboard_fab2_lib.baseboard_fab2(sch_1):page200_p12v_hsc_senp1"
				( attribute "VOLTAGE" "+12V"
					( Units "uVoltage" "V" 1.000000)
					( Origin gFrontEnd )
				)
				( objectFlag fObjectAlias )
				( objectStatus "page200_p12v_hsc_senp1" )
			)
			( signal "@baseboard_fab2_lib.baseboard_fab2(sch_1):p12v_mb0_sw"
				( alias ( signalRef "@baseboard_fab2_lib.baseboard_fab2(sch_1):page200_p12v_mb0_sw") )
				( attribute "VOLTAGE" "+12V"
					( Units "uVoltage" "V" 1.000000)
					( Status sAliasFlattened )
					( Origin gFrontEnd )
				)
				( attribute "CDS_PHYS_NET_NAME" "P12V_MB0_SW"
					( Origin gPackager )
				)
				( objectStatus "P12V_MB0_SW" )
			)
			( signal "@baseboard_fab2_lib.baseboard_fab2(sch_1):page200_p12v_mb0_sw"
				( attribute "VOLTAGE" "+12V"
					( Units "uVoltage" "V" 1.000000)
					( Origin gFrontEnd )
				)
				( objectFlag fObjectAlias )
				( objectStatus "page200_p12v_mb0_sw" )
			)
			( signal "@baseboard_fab2_lib.baseboard_fab2(sch_1):a_tsense_pvccin_cpu0"
				( attribute "CDS_PHYS_NET_NAME" "A_TSENSE_PVCCIN_CPU0"
					( Origin gPackager )
				)
				( objectStatus "A_TSENSE_PVCCIN_CPU0" )
			)
			( signal "@baseboard_fab2_lib.baseboard_fab2(sch_1):a_tsense_pvsa_cpu0"
				( attribute "CDS_PHYS_NET_NAME" "A_TSENSE_PVSA_CPU0"
					( Origin gPackager )
				)
				( objectStatus "A_TSENSE_PVSA_CPU0" )
			)
			( signal "@baseboard_fab2_lib.baseboard_fab2(sch_1):irq_pvccin_cpu0_vrhot_lvc3_r_n"
				( attribute "CDS_PHYS_NET_NAME" "IRQ_PVCCIN_CPU0_VRHOT_LVC3_R_N"
					( Origin gPackager )
				)
				( objectStatus "IRQ_PVCCIN_CPU0_VRHOT_LVC3_R_N" )
			)
			( signal "@baseboard_fab2_lib.baseboard_fab2(sch_1):isense_pvccin_cpu0_ph1_imon"
				( attribute "CDS_PHYS_NET_NAME" "ISENSE_PVCCIN_CPU0_PH1_IMON"
					( Origin gPackager )
				)
				( objectStatus "ISENSE_PVCCIN_CPU0_PH1_IMON" )
			)
			( signal "@baseboard_fab2_lib.baseboard_fab2(sch_1):isense_pvccin_cpu0_ph2_imon"
				( attribute "CDS_PHYS_NET_NAME" "ISENSE_PVCCIN_CPU0_PH2_IMON"
					( Origin gPackager )
				)
				( objectStatus "ISENSE_PVCCIN_CPU0_PH2_IMON" )
			)
			( signal "@baseboard_fab2_lib.baseboard_fab2(sch_1):isense_pvccin_cpu0_ph3_imon"
				( attribute "CDS_PHYS_NET_NAME" "ISENSE_PVCCIN_CPU0_PH3_IMON"
					( Origin gPackager )
				)
				( objectStatus "ISENSE_PVCCIN_CPU0_PH3_IMON" )
			)
			( signal "@baseboard_fab2_lib.baseboard_fab2(sch_1):isense_pvccin_cpu0_ph4_imon"
				( attribute "CDS_PHYS_NET_NAME" "ISENSE_PVCCIN_CPU0_PH4_IMON"
					( Origin gPackager )
				)
				( objectStatus "ISENSE_PVCCIN_CPU0_PH4_IMON" )
			)
			( signal "@baseboard_fab2_lib.baseboard_fab2(sch_1):isense_pvccin_cpu0_ph5_imon"
				( attribute "CDS_PHYS_NET_NAME" "ISENSE_PVCCIN_CPU0_PH5_IMON"
					( Origin gPackager )
				)
				( objectStatus "ISENSE_PVCCIN_CPU0_PH5_IMON" )
			)
			( signal "@baseboard_fab2_lib.baseboard_fab2(sch_1):isense_pvsa_cpu0_imon"
				( attribute "CDS_PHYS_NET_NAME" "ISENSE_PVSA_CPU0_IMON"
					( Origin gPackager )
				)
				( objectStatus "ISENSE_PVSA_CPU0_IMON" )
			)
			( signal "@baseboard_fab2_lib.baseboard_fab2(sch_1):pu_vr_pvccin_cpu0_flt1_smbalt_n_imon"
				( attribute "CDS_PHYS_NET_NAME" "PU_VR_PVCCIN_CPU0_FLT1_SMBALT_N"
					( Origin gPackager )
				)
				( attribute "PNN" "PU_VR_PVCCIN_CPU0_FLT1_SMBALT_N"
					( Origin gPackager )
				)
				( objectStatus "PU_VR_PVCCIN_CPU0_FLT1_SMBALT_N" )
			)
			( signal "@baseboard_fab2_lib.baseboard_fab2(sch_1):pu_vr_pvccin_cpu0_imon"
				( attribute "CDS_PHYS_NET_NAME" "PU_VR_PVCCIN_CPU0_IMON"
					( Origin gPackager )
				)
				( objectStatus "PU_VR_PVCCIN_CPU0_IMON" )
			)
			( signal "@baseboard_fab2_lib.baseboard_fab2(sch_1):pwrgd_pvsa_cpu0_r"
				( attribute "CDS_PHYS_NET_NAME" "PWRGD_PVSA_CPU0_R"
					( Origin gPackager )
				)
				( objectStatus "PWRGD_PVSA_CPU0_R" )
			)
			( signal "@baseboard_fab2_lib.baseboard_fab2(sch_1):svid_valert_vccin_cpu0"
				( attribute "CDS_PHYS_NET_NAME" "SVID_VALERT_VCCIN_CPU0"
					( Origin gPackager )
				)
				( objectStatus "SVID_VALERT_VCCIN_CPU0" )
			)
			( signal "@baseboard_fab2_lib.baseboard_fab2(sch_1):svid_vclk_pvccin_cpu0"
				( attribute "CDS_PHYS_NET_NAME" "SVID_VCLK_PVCCIN_CPU0"
					( Origin gPackager )
				)
				( objectStatus "SVID_VCLK_PVCCIN_CPU0" )
			)
			( signal "@baseboard_fab2_lib.baseboard_fab2(sch_1):svid_vdio_pvccin_cpu0"
				( attribute "CDS_PHYS_NET_NAME" "SVID_VDIO_PVCCIN_CPU0"
					( Origin gPackager )
				)
				( objectStatus "SVID_VDIO_PVCCIN_CPU0" )
			)
			( signal "@baseboard_fab2_lib.baseboard_fab2(sch_1):vr_fet_sw_p12v_stby_pvccin_cpu0"
				( alias ( signalRef "@baseboard_fab2_lib.baseboard_fab2(sch_1):page201_vr_fet_sw_p12v_stby_pvccin_cpu0") )
				( alias ( signalRef "@baseboard_fab2_lib.baseboard_fab2(sch_1):page202_vr_fet_sw_p12v_stby_pvccin_cpu0") )
				( alias ( signalRef "@baseboard_fab2_lib.baseboard_fab2(sch_1):page203_vr_fet_sw_p12v_stby_pvccin_cpu0") )
				( alias ( signalRef "@baseboard_fab2_lib.baseboard_fab2(sch_1):page204_vr_fet_sw_p12v_stby_pvccin_cpu0") )
				( alias ( signalRef "@baseboard_fab2_lib.baseboard_fab2(sch_1):page205_vr_fet_sw_p12v_stby_pvccin_cpu0") )
				( alias ( signalRef "@baseboard_fab2_lib.baseboard_fab2(sch_1):page213_vr_fet_sw_p12v_stby_pvccin_cpu0") )
				( alias ( signalRef "@baseboard_fab2_lib.baseboard_fab2(sch_1):page214_vr_fet_sw_p12v_stby_pvccin_cpu0") )
				( attribute "CDS_PHYS_NET_NAME" "VR_FET_SW_P12V_STBY_PVCCIN_CPU0"
					( Origin gPackager )
				)
				( objectStatus "VR_FET_SW_P12V_STBY_PVCCIN_CPU0" )
			)
			( signal "@baseboard_fab2_lib.baseboard_fab2(sch_1):page201_vr_fet_sw_p12v_stby_pvccin_cpu0"
				( objectFlag fObjectAlias )
				( objectStatus "page201_vr_fet_sw_p12v_stby_pvccin_cpu0" )
			)
			( signal "@baseboard_fab2_lib.baseboard_fab2(sch_1):page202_vr_fet_sw_p12v_stby_pvccin_cpu0"
				( objectFlag fObjectAlias )
				( objectStatus "page202_vr_fet_sw_p12v_stby_pvccin_cpu0" )
			)
			( signal "@baseboard_fab2_lib.baseboard_fab2(sch_1):page203_vr_fet_sw_p12v_stby_pvccin_cpu0"
				( objectFlag fObjectAlias )
				( objectStatus "page203_vr_fet_sw_p12v_stby_pvccin_cpu0" )
			)
			( signal "@baseboard_fab2_lib.baseboard_fab2(sch_1):page204_vr_fet_sw_p12v_stby_pvccin_cpu0"
				( objectFlag fObjectAlias )
				( objectStatus "page204_vr_fet_sw_p12v_stby_pvccin_cpu0" )
			)
			( signal "@baseboard_fab2_lib.baseboard_fab2(sch_1):page205_vr_fet_sw_p12v_stby_pvccin_cpu0"
				( objectFlag fObjectAlias )
				( objectStatus "page205_vr_fet_sw_p12v_stby_pvccin_cpu0" )
			)
			( signal "@baseboard_fab2_lib.baseboard_fab2(sch_1):page213_vr_fet_sw_p12v_stby_pvccin_cpu0"
				( objectFlag fObjectAlias )
				( objectStatus "page213_vr_fet_sw_p12v_stby_pvccin_cpu0" )
			)
			( signal "@baseboard_fab2_lib.baseboard_fab2(sch_1):page214_vr_fet_sw_p12v_stby_pvccin_cpu0"
				( objectFlag fObjectAlias )
				( objectStatus "page214_vr_fet_sw_p12v_stby_pvccin_cpu0" )
			)
			( signal "@baseboard_fab2_lib.baseboard_fab2(sch_1):vr_pvccin_cpu0_airef1"
				( attribute "CDS_PHYS_NET_NAME" "VR_PVCCIN_CPU0_AIREF1"
					( Origin gPackager )
				)
				( objectStatus "VR_PVCCIN_CPU0_AIREF1" )
			)
			( signal "@baseboard_fab2_lib.baseboard_fab2(sch_1):vr_pvccin_cpu0_airef2"
				( attribute "CDS_PHYS_NET_NAME" "VR_PVCCIN_CPU0_AIREF2"
					( Origin gPackager )
				)
				( objectStatus "VR_PVCCIN_CPU0_AIREF2" )
			)
			( signal "@baseboard_fab2_lib.baseboard_fab2(sch_1):vr_pvccin_cpu0_airef3"
				( attribute "CDS_PHYS_NET_NAME" "VR_PVCCIN_CPU0_AIREF3"
					( Origin gPackager )
				)
				( objectStatus "VR_PVCCIN_CPU0_AIREF3" )
			)
			( signal "@baseboard_fab2_lib.baseboard_fab2(sch_1):vr_pvccin_cpu0_airef4"
				( attribute "CDS_PHYS_NET_NAME" "VR_PVCCIN_CPU0_AIREF4"
					( Origin gPackager )
				)
				( objectStatus "VR_PVCCIN_CPU0_AIREF4" )
			)
			( signal "@baseboard_fab2_lib.baseboard_fab2(sch_1):vr_pvccin_cpu0_airef5"
				( attribute "CDS_PHYS_NET_NAME" "VR_PVCCIN_CPU0_AIREF5"
					( Origin gPackager )
				)
				( objectStatus "VR_PVCCIN_CPU0_AIREF5" )
			)
			( signal "@baseboard_fab2_lib.baseboard_fab2(sch_1):vr_pvccin_cpu0_avinsen"
				( alias ( signalRef "@baseboard_fab2_lib.baseboard_fab2(sch_1):page201_vr_pvccin_cpu0_avinsen") )
				( attribute "VOLTAGE" "0.8"
					( Units "uVoltage" "V" 1.000000)
					( Status sAliasFlattened )
					( Origin gFrontEnd )
				)
				( attribute "CDS_PHYS_NET_NAME" "VR_PVCCIN_CPU0_AVINSEN"
					( Origin gPackager )
				)
				( objectStatus "VR_PVCCIN_CPU0_AVINSEN" )
			)
			( signal "@baseboard_fab2_lib.baseboard_fab2(sch_1):page201_vr_pvccin_cpu0_avinsen"
				( attribute "VOLTAGE" "0.8"
					( Units "uVoltage" "V" 1.000000)
					( Origin gFrontEnd )
				)
				( objectFlag fObjectAlias )
				( objectStatus "page201_vr_pvccin_cpu0_avinsen" )
			)
			( signal "@baseboard_fab2_lib.baseboard_fab2(sch_1):vr_pvccin_cpu0_pwm1"
				( alias ( signalRef "@baseboard_fab2_lib.baseboard_fab2(sch_1):page201_vr_pvccin_cpu0_pwm1") )
				( attribute "VOLTAGE" "3.6"
					( Units "uVoltage" "V" 1.000000)
					( Status sAliasFlattened )
					( Origin gFrontEnd )
				)
				( attribute "CDS_PHYS_NET_NAME" "VR_PVCCIN_CPU0_PWM1"
					( Origin gPackager )
				)
				( objectStatus "VR_PVCCIN_CPU0_PWM1" )
			)
			( signal "@baseboard_fab2_lib.baseboard_fab2(sch_1):page201_vr_pvccin_cpu0_pwm1"
				( attribute "VOLTAGE" "3.6"
					( Units "uVoltage" "V" 1.000000)
					( Origin gFrontEnd )
				)
				( objectFlag fObjectAlias )
				( objectStatus "page201_vr_pvccin_cpu0_pwm1" )
			)
			( signal "@baseboard_fab2_lib.baseboard_fab2(sch_1):vr_pvccin_cpu0_pwm2"
				( alias ( signalRef "@baseboard_fab2_lib.baseboard_fab2(sch_1):page201_vr_pvccin_cpu0_pwm2") )
				( attribute "VOLTAGE" "3.6"
					( Units "uVoltage" "V" 1.000000)
					( Status sAliasFlattened )
					( Origin gFrontEnd )
				)
				( attribute "CDS_PHYS_NET_NAME" "VR_PVCCIN_CPU0_PWM2"
					( Origin gPackager )
				)
				( objectStatus "VR_PVCCIN_CPU0_PWM2" )
			)
			( signal "@baseboard_fab2_lib.baseboard_fab2(sch_1):page201_vr_pvccin_cpu0_pwm2"
				( attribute "VOLTAGE" "3.6"
					( Units "uVoltage" "V" 1.000000)
					( Origin gFrontEnd )
				)
				( objectFlag fObjectAlias )
				( objectStatus "page201_vr_pvccin_cpu0_pwm2" )
			)
			( signal "@baseboard_fab2_lib.baseboard_fab2(sch_1):vr_pvccin_cpu0_pwm3"
				( alias ( signalRef "@baseboard_fab2_lib.baseboard_fab2(sch_1):page201_vr_pvccin_cpu0_pwm3") )
				( attribute "VOLTAGE" "3.6"
					( Units "uVoltage" "V" 1.000000)
					( Status sAliasFlattened )
					( Origin gFrontEnd )
				)
				( attribute "CDS_PHYS_NET_NAME" "VR_PVCCIN_CPU0_PWM3"
					( Origin gPackager )
				)
				( objectStatus "VR_PVCCIN_CPU0_PWM3" )
			)
			( signal "@baseboard_fab2_lib.baseboard_fab2(sch_1):page201_vr_pvccin_cpu0_pwm3"
				( attribute "VOLTAGE" "3.6"
					( Units "uVoltage" "V" 1.000000)
					( Origin gFrontEnd )
				)
				( objectFlag fObjectAlias )
				( objectStatus "page201_vr_pvccin_cpu0_pwm3" )
			)
			( signal "@baseboard_fab2_lib.baseboard_fab2(sch_1):vr_pvccin_cpu0_pwm4"
				( alias ( signalRef "@baseboard_fab2_lib.baseboard_fab2(sch_1):page201_vr_pvccin_cpu0_pwm4") )
				( attribute "VOLTAGE" "3.6"
					( Units "uVoltage" "V" 1.000000)
					( Status sAliasFlattened )
					( Origin gFrontEnd )
				)
				( attribute "CDS_PHYS_NET_NAME" "VR_PVCCIN_CPU0_PWM4"
					( Origin gPackager )
				)
				( objectStatus "VR_PVCCIN_CPU0_PWM4" )
			)
			( signal "@baseboard_fab2_lib.baseboard_fab2(sch_1):page201_vr_pvccin_cpu0_pwm4"
				( attribute "VOLTAGE" "3.6"
					( Units "uVoltage" "V" 1.000000)
					( Origin gFrontEnd )
				)
				( objectFlag fObjectAlias )
				( objectStatus "page201_vr_pvccin_cpu0_pwm4" )
			)
			( signal "@baseboard_fab2_lib.baseboard_fab2(sch_1):vr_pvccin_cpu0_pwm5"
				( alias ( signalRef "@baseboard_fab2_lib.baseboard_fab2(sch_1):page201_vr_pvccin_cpu0_pwm5") )
				( attribute "VOLTAGE" "3.6"
					( Units "uVoltage" "V" 1.000000)
					( Status sAliasFlattened )
					( Origin gFrontEnd )
				)
				( attribute "CDS_PHYS_NET_NAME" "VR_PVCCIN_CPU0_PWM5"
					( Origin gPackager )
				)
				( objectStatus "VR_PVCCIN_CPU0_PWM5" )
			)
			( signal "@baseboard_fab2_lib.baseboard_fab2(sch_1):page201_vr_pvccin_cpu0_pwm5"
				( attribute "VOLTAGE" "3.6"
					( Units "uVoltage" "V" 1.000000)
					( Origin gFrontEnd )
				)
				( objectFlag fObjectAlias )
				( objectStatus "page201_vr_pvccin_cpu0_pwm5" )
			)
			( signal "@baseboard_fab2_lib.baseboard_fab2(sch_1):vr_pvccin_cpu0_vd12"
				( attribute "CDS_PHYS_NET_NAME" "VR_PVCCIN_CPU0_VD12"
					( Origin gPackager )
				)
				( objectStatus "VR_PVCCIN_CPU0_VD12" )
			)
			( signal "@baseboard_fab2_lib.baseboard_fab2(sch_1):vr_pvccin_cpu0_vdd"
				( alias ( signalRef "@baseboard_fab2_lib.baseboard_fab2(sch_1):page201_vr_pvccin_cpu0_vdd") )
				( attribute "VOLTAGE" "3.3"
					( Units "uVoltage" "V" 1.000000)
					( Status sAliasFlattened )
					( Origin gFrontEnd )
				)
				( attribute "CDS_PHYS_NET_NAME" "VR_PVCCIN_CPU0_VDD"
					( Origin gPackager )
				)
				( objectStatus "VR_PVCCIN_CPU0_VDD" )
			)
			( signal "@baseboard_fab2_lib.baseboard_fab2(sch_1):page201_vr_pvccin_cpu0_vdd"
				( attribute "VOLTAGE" "3.3"
					( Units "uVoltage" "V" 1.000000)
					( Origin gFrontEnd )
				)
				( objectFlag fObjectAlias )
				( objectStatus "page201_vr_pvccin_cpu0_vdd" )
			)
			( signal "@baseboard_fab2_lib.baseboard_fab2(sch_1):vr_pvccin_cpu0_vren"
				( alias ( signalRef "@baseboard_fab2_lib.baseboard_fab2(sch_1):page201_vr_pvccin_cpu0_vren") )
				( attribute "VOLTAGE" "3.3"
					( Units "uVoltage" "V" 1.000000)
					( Status sAliasFlattened )
					( Origin gFrontEnd )
				)
				( attribute "CDS_PHYS_NET_NAME" "VR_PVCCIN_CPU0_VREN"
					( Origin gPackager )
				)
				( objectStatus "VR_PVCCIN_CPU0_VREN" )
			)
			( signal "@baseboard_fab2_lib.baseboard_fab2(sch_1):page201_vr_pvccin_cpu0_vren"
				( attribute "VOLTAGE" "3.3"
					( Units "uVoltage" "V" 1.000000)
					( Origin gFrontEnd )
				)
				( objectFlag fObjectAlias )
				( objectStatus "page201_vr_pvccin_cpu0_vren" )
			)
			( signal "@baseboard_fab2_lib.baseboard_fab2(sch_1):vr_pvccin_cpu0_xaddr1"
				( alias ( signalRef "@baseboard_fab2_lib.baseboard_fab2(sch_1):page201_vr_pvccin_cpu0_xaddr1") )
				( attribute "VOLTAGE" "3.3"
					( Units "uVoltage" "V" 1.000000)
					( Status sAliasFlattened )
					( Origin gFrontEnd )
				)
				( attribute "CDS_PHYS_NET_NAME" "VR_PVCCIN_CPU0_XADDR1"
					( Origin gPackager )
				)
				( objectStatus "VR_PVCCIN_CPU0_XADDR1" )
			)
			( signal "@baseboard_fab2_lib.baseboard_fab2(sch_1):page201_vr_pvccin_cpu0_xaddr1"
				( attribute "VOLTAGE" "3.3"
					( Units "uVoltage" "V" 1.000000)
					( Origin gFrontEnd )
				)
				( objectFlag fObjectAlias )
				( objectStatus "page201_vr_pvccin_cpu0_xaddr1" )
			)
			( signal "@baseboard_fab2_lib.baseboard_fab2(sch_1):vr_pvccin_cpu0_xaddr2"
				( alias ( signalRef "@baseboard_fab2_lib.baseboard_fab2(sch_1):page201_vr_pvccin_cpu0_xaddr2") )
				( attribute "VOLTAGE" "3.3"
					( Units "uVoltage" "V" 1.000000)
					( Status sAliasFlattened )
					( Origin gFrontEnd )
				)
				( attribute "CDS_PHYS_NET_NAME" "VR_PVCCIN_CPU0_XADDR2"
					( Origin gPackager )
				)
				( objectStatus "VR_PVCCIN_CPU0_XADDR2" )
			)
			( signal "@baseboard_fab2_lib.baseboard_fab2(sch_1):page201_vr_pvccin_cpu0_xaddr2"
				( attribute "VOLTAGE" "3.3"
					( Units "uVoltage" "V" 1.000000)
					( Origin gFrontEnd )
				)
				( objectFlag fObjectAlias )
				( objectStatus "page201_vr_pvccin_cpu0_xaddr2" )
			)
			( signal "@baseboard_fab2_lib.baseboard_fab2(sch_1):vr_pvsa_cpu0_biref1"
				( attribute "CDS_PHYS_NET_NAME" "VR_PVSA_CPU0_BIREF1"
					( Origin gPackager )
				)
				( objectStatus "VR_PVSA_CPU0_BIREF1" )
			)
			( signal "@baseboard_fab2_lib.baseboard_fab2(sch_1):vr_pvsa_cpu0_pwm"
				( attribute "CDS_PHYS_NET_NAME" "VR_PVSA_CPU0_PWM"
					( Origin gPackager )
				)
				( objectStatus "VR_PVSA_CPU0_PWM" )
			)
			( signal "@baseboard_fab2_lib.baseboard_fab2(sch_1):vr_vrrdy_pvccin_cpu0"
				( alias ( signalRef "@baseboard_fab2_lib.baseboard_fab2(sch_1):page201_vr_vrrdy_pvccin_cpu0") )
				( attribute "VOLTAGE" "3.3"
					( Units "uVoltage" "V" 1.000000)
					( Status sAliasFlattened )
					( Origin gFrontEnd )
				)
				( attribute "CDS_PHYS_NET_NAME" "VR_VRRDY_PVCCIN_CPU0"
					( Origin gPackager )
				)
				( objectStatus "VR_VRRDY_PVCCIN_CPU0" )
			)
			( signal "@baseboard_fab2_lib.baseboard_fab2(sch_1):page201_vr_vrrdy_pvccin_cpu0"
				( attribute "VOLTAGE" "3.3"
					( Units "uVoltage" "V" 1.000000)
					( Origin gFrontEnd )
				)
				( objectFlag fObjectAlias )
				( objectStatus "page201_vr_vrrdy_pvccin_cpu0" )
			)
			( signal "@baseboard_fab2_lib.baseboard_fab2(sch_1):vsense_pvccin_cpu0_avsp"
				( attribute "CDS_PHYS_NET_NAME" "VSENSE_PVCCIN_CPU0_AVSP"
					( Origin gPackager )
				)
				( objectStatus "VSENSE_PVCCIN_CPU0_AVSP" )
			)
			( signal "@baseboard_fab2_lib.baseboard_fab2(sch_1):vsense_pvccin_cpu0_n"
				( attribute "CDS_PHYS_NET_NAME" "VSENSE_PVCCIN_CPU0_N"
					( Origin gPackager )
				)
				( objectStatus "VSENSE_PVCCIN_CPU0_N" )
			)
			( signal "@baseboard_fab2_lib.baseboard_fab2(sch_1):vsense_pvccin_cpu0_p"
				( attribute "CDS_PHYS_NET_NAME" "VSENSE_PVCCIN_CPU0_P"
					( Origin gPackager )
				)
				( objectStatus "VSENSE_PVCCIN_CPU0_P" )
			)
			( signal "@baseboard_fab2_lib.baseboard_fab2(sch_1):vsense_pvsa_cpu0_bvsp"
				( attribute "CDS_PHYS_NET_NAME" "VSENSE_PVSA_CPU0_BVSP"
					( Origin gPackager )
				)
				( objectStatus "VSENSE_PVSA_CPU0_BVSP" )
			)
			( signal "@baseboard_fab2_lib.baseboard_fab2(sch_1):vsense_pvsa_cpu0_n"
				( attribute "CDS_PHYS_NET_NAME" "VSENSE_PVSA_CPU0_N"
					( Origin gPackager )
				)
				( objectStatus "VSENSE_PVSA_CPU0_N" )
			)
			( signal "@baseboard_fab2_lib.baseboard_fab2(sch_1):vsense_pvsa_cpu0_p"
				( attribute "CDS_PHYS_NET_NAME" "VSENSE_PVSA_CPU0_P"
					( Origin gPackager )
				)
				( objectStatus "VSENSE_PVSA_CPU0_P" )
			)
			( signal "@baseboard_fab2_lib.baseboard_fab2(sch_1):tp_pvccin_cpu0_ph1_gl_0"
				( attribute "CDS_PHYS_NET_NAME" "TP_PVCCIN_CPU0_PH1_GL_0"
					( Origin gPackager )
				)
				( objectStatus "TP_PVCCIN_CPU0_PH1_GL_0" )
			)
			( signal "@baseboard_fab2_lib.baseboard_fab2(sch_1):tp_pvccin_cpu0_ph1_gl_1"
				( attribute "CDS_PHYS_NET_NAME" "TP_PVCCIN_CPU0_PH1_GL_1"
					( Origin gPackager )
				)
				( objectStatus "TP_PVCCIN_CPU0_PH1_GL_1" )
			)
			( signal "@baseboard_fab2_lib.baseboard_fab2(sch_1):tp_pvccin_cpu0_ph2_gl_0"
				( attribute "CDS_PHYS_NET_NAME" "TP_PVCCIN_CPU0_PH2_GL_0"
					( Origin gPackager )
				)
				( objectStatus "TP_PVCCIN_CPU0_PH2_GL_0" )
			)
			( signal "@baseboard_fab2_lib.baseboard_fab2(sch_1):tp_pvccin_cpu0_ph2_gl_1"
				( attribute "CDS_PHYS_NET_NAME" "TP_PVCCIN_CPU0_PH2_GL_1"
					( Origin gPackager )
				)
				( objectStatus "TP_PVCCIN_CPU0_PH2_GL_1" )
			)
			( signal "@baseboard_fab2_lib.baseboard_fab2(sch_1):vr_pvccin_cpu0_ph1_boot"
				( attribute "CDS_PHYS_NET_NAME" "VR_PVCCIN_CPU0_PH1_BOOT"
					( Origin gPackager )
				)
				( objectStatus "VR_PVCCIN_CPU0_PH1_BOOT" )
			)
			( signal "@baseboard_fab2_lib.baseboard_fab2(sch_1):vr_pvddq_def_ph1_sw_rc"
				( attribute "CDS_PHYS_NET_NAME" "VR_PVDDQ_DEF_PH1_SW_RC"
					( Origin gPackager )
				)
				( objectStatus "VR_PVDDQ_DEF_PH1_SW_RC" )
			)
			( signal "@baseboard_fab2_lib.baseboard_fab2(sch_1):vr_pvccin_cpu0_ph1_ocset"
				( attribute "CDS_PHYS_NET_NAME" "VR_PVCCIN_CPU0_PH1_OCSET"
					( Origin gPackager )
				)
				( objectStatus "VR_PVCCIN_CPU0_PH1_OCSET" )
			)
			( signal "@baseboard_fab2_lib.baseboard_fab2(sch_1):vr_pvccin_cpu0_ph1_phase"
				( alias ( signalRef "@baseboard_fab2_lib.baseboard_fab2(sch_1):page202_vr_pvccin_cpu0_ph1_phase") )
				( attribute "VOLTAGE" "5"
					( Units "uVoltage" "V" 1.000000)
					( Status sAliasFlattened )
					( Origin gFrontEnd )
				)
				( attribute "CDS_PHYS_NET_NAME" "VR_PVCCIN_CPU0_PH1_PHASE"
					( Origin gPackager )
				)
				( objectStatus "VR_PVCCIN_CPU0_PH1_PHASE" )
			)
			( signal "@baseboard_fab2_lib.baseboard_fab2(sch_1):page202_vr_pvccin_cpu0_ph1_phase"
				( attribute "VOLTAGE" "5"
					( Units "uVoltage" "V" 1.000000)
					( Origin gFrontEnd )
				)
				( objectFlag fObjectAlias )
				( objectStatus "page202_vr_pvccin_cpu0_ph1_phase" )
			)
			( signal "@baseboard_fab2_lib.baseboard_fab2(sch_1):vr_pvccin_cpu0_ph1_vcin"
				( alias ( signalRef "@baseboard_fab2_lib.baseboard_fab2(sch_1):page202_vr_pvccin_cpu0_ph1_vcin") )
				( attribute "VOLTAGE" "5"
					( Units "uVoltage" "V" 1.000000)
					( Status sAliasFlattened )
					( Origin gFrontEnd )
				)
				( attribute "CDS_PHYS_NET_NAME" "VR_PVCCIN_CPU0_PH1_VCIN"
					( Origin gPackager )
				)
				( objectStatus "VR_PVCCIN_CPU0_PH1_VCIN" )
			)
			( signal "@baseboard_fab2_lib.baseboard_fab2(sch_1):page202_vr_pvccin_cpu0_ph1_vcin"
				( attribute "VOLTAGE" "5"
					( Units "uVoltage" "V" 1.000000)
					( Origin gFrontEnd )
				)
				( objectFlag fObjectAlias )
				( objectStatus "page202_vr_pvccin_cpu0_ph1_vcin" )
			)
			( signal "@baseboard_fab2_lib.baseboard_fab2(sch_1):vr_pvccin_cpu0_ph2_boot"
				( attribute "CDS_PHYS_NET_NAME" "VR_PVCCIN_CPU0_PH2_BOOT"
					( Origin gPackager )
				)
				( attribute "VOLTAGE" "5"
					( Units "uVoltage" "V" 1.000000)
					( Origin gFrontEnd )
				)
				( objectStatus "VR_PVCCIN_CPU0_PH2_BOOT" )
			)
			( signal "@baseboard_fab2_lib.baseboard_fab2(sch_1):vr_pvsa_cpu0_phase_sw_rc"
				( attribute "CDS_PHYS_NET_NAME" "VR_PVSA_CPU0_PHASE_SW_RC"
					( Origin gPackager )
				)
				( objectStatus "VR_PVSA_CPU0_PHASE_SW_RC" )
			)
			( signal "@baseboard_fab2_lib.baseboard_fab2(sch_1):vr_pvccin_cpu0_ph2_ocset"
				( alias ( signalRef "@baseboard_fab2_lib.baseboard_fab2(sch_1):page202_vr_pvccin_cpu0_ph2_ocset") )
				( attribute "VOLTAGE" "3.6"
					( Units "uVoltage" "V" 1.000000)
					( Status sAliasFlattened )
					( Origin gFrontEnd )
				)
				( attribute "CDS_PHYS_NET_NAME" "VR_PVCCIN_CPU0_PH2_OCSET"
					( Origin gPackager )
				)
				( objectStatus "VR_PVCCIN_CPU0_PH2_OCSET" )
			)
			( signal "@baseboard_fab2_lib.baseboard_fab2(sch_1):page202_vr_pvccin_cpu0_ph2_ocset"
				( attribute "VOLTAGE" "3.6"
					( Units "uVoltage" "V" 1.000000)
					( Origin gFrontEnd )
				)
				( objectFlag fObjectAlias )
				( objectStatus "page202_vr_pvccin_cpu0_ph2_ocset" )
			)
			( signal "@baseboard_fab2_lib.baseboard_fab2(sch_1):vr_pvccin_cpu0_ph2_phase"
				( alias ( signalRef "@baseboard_fab2_lib.baseboard_fab2(sch_1):page202_vr_pvccin_cpu0_ph2_phase") )
				( attribute "VOLTAGE" "5"
					( Units "uVoltage" "V" 1.000000)
					( Status sAliasFlattened )
					( Origin gFrontEnd )
				)
				( attribute "CDS_PHYS_NET_NAME" "VR_PVCCIN_CPU0_PH2_PHASE"
					( Origin gPackager )
				)
				( objectStatus "VR_PVCCIN_CPU0_PH2_PHASE" )
			)
			( signal "@baseboard_fab2_lib.baseboard_fab2(sch_1):page202_vr_pvccin_cpu0_ph2_phase"
				( attribute "VOLTAGE" "5"
					( Units "uVoltage" "V" 1.000000)
					( Origin gFrontEnd )
				)
				( objectFlag fObjectAlias )
				( objectStatus "page202_vr_pvccin_cpu0_ph2_phase" )
			)
			( signal "@baseboard_fab2_lib.baseboard_fab2(sch_1):vr_pvccin_cpu0_ph2_vcin"
				( alias ( signalRef "@baseboard_fab2_lib.baseboard_fab2(sch_1):page202_vr_pvccin_cpu0_ph2_vcin") )
				( attribute "VOLTAGE" "5"
					( Units "uVoltage" "V" 1.000000)
					( Status sAliasFlattened )
					( Origin gFrontEnd )
				)
				( attribute "CDS_PHYS_NET_NAME" "VR_PVCCIN_CPU0_PH2_VCIN"
					( Origin gPackager )
				)
				( objectStatus "VR_PVCCIN_CPU0_PH2_VCIN" )
			)
			( signal "@baseboard_fab2_lib.baseboard_fab2(sch_1):page202_vr_pvccin_cpu0_ph2_vcin"
				( attribute "VOLTAGE" "5"
					( Units "uVoltage" "V" 1.000000)
					( Origin gFrontEnd )
				)
				( objectFlag fObjectAlias )
				( objectStatus "page202_vr_pvccin_cpu0_ph2_vcin" )
			)
			( signal "@baseboard_fab2_lib.baseboard_fab2(sch_1):vr_pvccin_cpu0_phase1"
				( alias ( signalRef "@baseboard_fab2_lib.baseboard_fab2(sch_1):page202_vr_pvccin_cpu0_phase1") )
				( attribute "VOLTAGE" "5"
					( Units "uVoltage" "V" 1.000000)
					( Status sAliasFlattened )
					( Origin gFrontEnd )
				)
				( attribute "CDS_PHYS_NET_NAME" "VR_PVCCIN_CPU0_PHASE1"
					( Origin gPackager )
				)
				( objectStatus "VR_PVCCIN_CPU0_PHASE1" )
			)
			( signal "@baseboard_fab2_lib.baseboard_fab2(sch_1):page202_vr_pvccin_cpu0_phase1"
				( attribute "VOLTAGE" "5"
					( Units "uVoltage" "V" 1.000000)
					( Origin gFrontEnd )
				)
				( objectFlag fObjectAlias )
				( objectStatus "page202_vr_pvccin_cpu0_phase1" )
			)
			( signal "@baseboard_fab2_lib.baseboard_fab2(sch_1):vr_pvccin_cpu0_phase2"
				( alias ( signalRef "@baseboard_fab2_lib.baseboard_fab2(sch_1):page202_vr_pvccin_cpu0_phase2") )
				( attribute "VOLTAGE" "5"
					( Units "uVoltage" "V" 1.000000)
					( Status sAliasFlattened )
					( Origin gFrontEnd )
				)
				( attribute "CDS_PHYS_NET_NAME" "VR_PVCCIN_CPU0_PHASE2"
					( Origin gPackager )
				)
				( objectStatus "VR_PVCCIN_CPU0_PHASE2" )
			)
			( signal "@baseboard_fab2_lib.baseboard_fab2(sch_1):page202_vr_pvccin_cpu0_phase2"
				( attribute "VOLTAGE" "5"
					( Units "uVoltage" "V" 1.000000)
					( Origin gFrontEnd )
				)
				( objectFlag fObjectAlias )
				( objectStatus "page202_vr_pvccin_cpu0_phase2" )
			)
			( signal "@baseboard_fab2_lib.baseboard_fab2(sch_1):tp_pvccin_cpu0_ph3_gl_0"
				( attribute "CDS_PHYS_NET_NAME" "TP_PVCCIN_CPU0_PH3_GL_0"
					( Origin gPackager )
				)
				( objectStatus "TP_PVCCIN_CPU0_PH3_GL_0" )
			)
			( signal "@baseboard_fab2_lib.baseboard_fab2(sch_1):tp_pvccin_cpu0_ph3_gl_1"
				( attribute "CDS_PHYS_NET_NAME" "TP_PVCCIN_CPU0_PH3_GL_1"
					( Origin gPackager )
				)
				( objectStatus "TP_PVCCIN_CPU0_PH3_GL_1" )
			)
			( signal "@baseboard_fab2_lib.baseboard_fab2(sch_1):tp_pvccin_cpu0_ph4_gl_0"
				( attribute "CDS_PHYS_NET_NAME" "TP_PVCCIN_CPU0_PH4_GL_0"
					( Origin gPackager )
				)
				( objectStatus "TP_PVCCIN_CPU0_PH4_GL_0" )
			)
			( signal "@baseboard_fab2_lib.baseboard_fab2(sch_1):tp_pvccin_cpu0_ph4_gl_1"
				( attribute "CDS_PHYS_NET_NAME" "TP_PVCCIN_CPU0_PH4_GL_1"
					( Origin gPackager )
				)
				( objectStatus "TP_PVCCIN_CPU0_PH4_GL_1" )
			)
			( signal "@baseboard_fab2_lib.baseboard_fab2(sch_1):vr_pvccin_cpu0_ph3_boot"
				( attribute "CDS_PHYS_NET_NAME" "VR_PVCCIN_CPU0_PH3_BOOT"
					( Origin gPackager )
				)
				( objectStatus "VR_PVCCIN_CPU0_PH3_BOOT" )
			)
			( signal "@baseboard_fab2_lib.baseboard_fab2(sch_1):vr_pvsa_cpu1_phase_sw_rc"
				( attribute "CDS_PHYS_NET_NAME" "VR_PVSA_CPU1_PHASE_SW_RC"
					( Origin gPackager )
				)
				( objectStatus "VR_PVSA_CPU1_PHASE_SW_RC" )
			)
			( signal "@baseboard_fab2_lib.baseboard_fab2(sch_1):vr_pvccin_cpu0_ph3_ocset"
				( alias ( signalRef "@baseboard_fab2_lib.baseboard_fab2(sch_1):page203_vr_pvccin_cpu0_ph3_ocset") )
				( attribute "VOLTAGE" "3.6"
					( Units "uVoltage" "V" 1.000000)
					( Status sAliasFlattened )
					( Origin gFrontEnd )
				)
				( attribute "CDS_PHYS_NET_NAME" "VR_PVCCIN_CPU0_PH3_OCSET"
					( Origin gPackager )
				)
				( objectStatus "VR_PVCCIN_CPU0_PH3_OCSET" )
			)
			( signal "@baseboard_fab2_lib.baseboard_fab2(sch_1):page203_vr_pvccin_cpu0_ph3_ocset"
				( attribute "VOLTAGE" "3.6"
					( Units "uVoltage" "V" 1.000000)
					( Origin gFrontEnd )
				)
				( objectFlag fObjectAlias )
				( objectStatus "page203_vr_pvccin_cpu0_ph3_ocset" )
			)
			( signal "@baseboard_fab2_lib.baseboard_fab2(sch_1):vr_pvccin_cpu0_ph3_phase"
				( alias ( signalRef "@baseboard_fab2_lib.baseboard_fab2(sch_1):page203_vr_pvccin_cpu0_ph3_phase") )
				( attribute "VOLTAGE" "5"
					( Units "uVoltage" "V" 1.000000)
					( Status sAliasFlattened )
					( Origin gFrontEnd )
				)
				( attribute "CDS_PHYS_NET_NAME" "VR_PVCCIN_CPU0_PH3_PHASE"
					( Origin gPackager )
				)
				( objectStatus "VR_PVCCIN_CPU0_PH3_PHASE" )
			)
			( signal "@baseboard_fab2_lib.baseboard_fab2(sch_1):page203_vr_pvccin_cpu0_ph3_phase"
				( attribute "VOLTAGE" "5"
					( Units "uVoltage" "V" 1.000000)
					( Origin gFrontEnd )
				)
				( objectFlag fObjectAlias )
				( objectStatus "page203_vr_pvccin_cpu0_ph3_phase" )
			)
			( signal "@baseboard_fab2_lib.baseboard_fab2(sch_1):vr_pvccin_cpu0_ph3_vcin"
				( attribute "CDS_PHYS_NET_NAME" "VR_PVCCIN_CPU0_PH3_VCIN"
					( Origin gPackager )
				)
				( objectStatus "VR_PVCCIN_CPU0_PH3_VCIN" )
			)
			( signal "@baseboard_fab2_lib.baseboard_fab2(sch_1):vr_pvccin_cpu0_ph4_boot"
				( attribute "CDS_PHYS_NET_NAME" "VR_PVCCIN_CPU0_PH4_BOOT"
					( Origin gPackager )
				)
				( objectStatus "VR_PVCCIN_CPU0_PH4_BOOT" )
			)
			( signal "@baseboard_fab2_lib.baseboard_fab2(sch_1):vr_pvccin_cpu0_ph4_ocset"
				( alias ( signalRef "@baseboard_fab2_lib.baseboard_fab2(sch_1):page203_vr_pvccin_cpu0_ph4_ocset") )
				( attribute "VOLTAGE" "3.6"
					( Units "uVoltage" "V" 1.000000)
					( Status sAliasFlattened )
					( Origin gFrontEnd )
				)
				( attribute "CDS_PHYS_NET_NAME" "VR_PVCCIN_CPU0_PH4_OCSET"
					( Origin gPackager )
				)
				( objectStatus "VR_PVCCIN_CPU0_PH4_OCSET" )
			)
			( signal "@baseboard_fab2_lib.baseboard_fab2(sch_1):page203_vr_pvccin_cpu0_ph4_ocset"
				( attribute "VOLTAGE" "3.6"
					( Units "uVoltage" "V" 1.000000)
					( Origin gFrontEnd )
				)
				( objectFlag fObjectAlias )
				( objectStatus "page203_vr_pvccin_cpu0_ph4_ocset" )
			)
			( signal "@baseboard_fab2_lib.baseboard_fab2(sch_1):vr_pvccin_cpu0_ph4_phase"
				( alias ( signalRef "@baseboard_fab2_lib.baseboard_fab2(sch_1):page203_vr_pvccin_cpu0_ph4_phase") )
				( attribute "VOLTAGE" "5"
					( Units "uVoltage" "V" 1.000000)
					( Status sAliasFlattened )
					( Origin gFrontEnd )
				)
				( attribute "CDS_PHYS_NET_NAME" "VR_PVCCIN_CPU0_PH4_PHASE"
					( Origin gPackager )
				)
				( objectStatus "VR_PVCCIN_CPU0_PH4_PHASE" )
			)
			( signal "@baseboard_fab2_lib.baseboard_fab2(sch_1):page203_vr_pvccin_cpu0_ph4_phase"
				( attribute "VOLTAGE" "5"
					( Units "uVoltage" "V" 1.000000)
					( Origin gFrontEnd )
				)
				( objectFlag fObjectAlias )
				( objectStatus "page203_vr_pvccin_cpu0_ph4_phase" )
			)
			( signal "@baseboard_fab2_lib.baseboard_fab2(sch_1):vr_pvccin_cpu0_ph4_vcin"
				( alias ( signalRef "@baseboard_fab2_lib.baseboard_fab2(sch_1):page203_vr_pvccin_cpu0_ph4_vcin") )
				( attribute "VOLTAGE" "5"
					( Units "uVoltage" "V" 1.000000)
					( Status sAliasFlattened )
					( Origin gFrontEnd )
				)
				( attribute "CDS_PHYS_NET_NAME" "VR_PVCCIN_CPU0_PH4_VCIN"
					( Origin gPackager )
				)
				( objectStatus "VR_PVCCIN_CPU0_PH4_VCIN" )
			)
			( signal "@baseboard_fab2_lib.baseboard_fab2(sch_1):page203_vr_pvccin_cpu0_ph4_vcin"
				( attribute "VOLTAGE" "5"
					( Units "uVoltage" "V" 1.000000)
					( Origin gFrontEnd )
				)
				( objectFlag fObjectAlias )
				( objectStatus "page203_vr_pvccin_cpu0_ph4_vcin" )
			)
			( signal "@baseboard_fab2_lib.baseboard_fab2(sch_1):vr_pvccin_cpu0_phase3"
				( alias ( signalRef "@baseboard_fab2_lib.baseboard_fab2(sch_1):page203_vr_pvccin_cpu0_phase3") )
				( attribute "VOLTAGE" "5"
					( Units "uVoltage" "V" 1.000000)
					( Status sAliasFlattened )
					( Origin gFrontEnd )
				)
				( attribute "CDS_PHYS_NET_NAME" "VR_PVCCIN_CPU0_PHASE3"
					( Origin gPackager )
				)
				( objectStatus "VR_PVCCIN_CPU0_PHASE3" )
			)
			( signal "@baseboard_fab2_lib.baseboard_fab2(sch_1):page203_vr_pvccin_cpu0_phase3"
				( attribute "VOLTAGE" "5"
					( Units "uVoltage" "V" 1.000000)
					( Origin gFrontEnd )
				)
				( objectFlag fObjectAlias )
				( objectStatus "page203_vr_pvccin_cpu0_phase3" )
			)
			( signal "@baseboard_fab2_lib.baseboard_fab2(sch_1):vr_pvccin_cpu0_phase4"
				( alias ( signalRef "@baseboard_fab2_lib.baseboard_fab2(sch_1):page203_vr_pvccin_cpu0_phase4") )
				( attribute "VOLTAGE" "5"
					( Units "uVoltage" "V" 1.000000)
					( Status sAliasFlattened )
					( Origin gFrontEnd )
				)
				( attribute "CDS_PHYS_NET_NAME" "VR_PVCCIN_CPU0_PHASE4"
					( Origin gPackager )
				)
				( objectStatus "VR_PVCCIN_CPU0_PHASE4" )
			)
			( signal "@baseboard_fab2_lib.baseboard_fab2(sch_1):page203_vr_pvccin_cpu0_phase4"
				( attribute "VOLTAGE" "5"
					( Units "uVoltage" "V" 1.000000)
					( Origin gFrontEnd )
				)
				( objectFlag fObjectAlias )
				( objectStatus "page203_vr_pvccin_cpu0_phase4" )
			)
			( signal "@baseboard_fab2_lib.baseboard_fab2(sch_1):tp_pvccin_cpu0_ph5_gl_0"
				( attribute "CDS_PHYS_NET_NAME" "TP_PVCCIN_CPU0_PH5_GL_0"
					( Origin gPackager )
				)
				( objectStatus "TP_PVCCIN_CPU0_PH5_GL_0" )
			)
			( signal "@baseboard_fab2_lib.baseboard_fab2(sch_1):tp_pvccin_cpu0_ph5_gl_1"
				( attribute "CDS_PHYS_NET_NAME" "TP_PVCCIN_CPU0_PH5_GL_1"
					( Origin gPackager )
				)
				( objectStatus "TP_PVCCIN_CPU0_PH5_GL_1" )
			)
			( signal "@baseboard_fab2_lib.baseboard_fab2(sch_1):vr_pvccin_cpu0_ph5_boot"
				( attribute "CDS_PHYS_NET_NAME" "VR_PVCCIN_CPU0_PH5_BOOT"
					( Origin gPackager )
				)
				( objectStatus "VR_PVCCIN_CPU0_PH5_BOOT" )
			)
			( signal "@baseboard_fab2_lib.baseboard_fab2(sch_1):vr_pvccin_cpu0_ph5_ocset"
				( alias ( signalRef "@baseboard_fab2_lib.baseboard_fab2(sch_1):page204_vr_pvccin_cpu0_ph5_ocset") )
				( attribute "VOLTAGE" "3.6"
					( Units "uVoltage" "V" 1.000000)
					( Status sAliasFlattened )
					( Origin gFrontEnd )
				)
				( attribute "CDS_PHYS_NET_NAME" "VR_PVCCIN_CPU0_PH5_OCSET"
					( Origin gPackager )
				)
				( objectStatus "VR_PVCCIN_CPU0_PH5_OCSET" )
			)
			( signal "@baseboard_fab2_lib.baseboard_fab2(sch_1):page204_vr_pvccin_cpu0_ph5_ocset"
				( attribute "VOLTAGE" "3.6"
					( Units "uVoltage" "V" 1.000000)
					( Origin gFrontEnd )
				)
				( objectFlag fObjectAlias )
				( objectStatus "page204_vr_pvccin_cpu0_ph5_ocset" )
			)
			( signal "@baseboard_fab2_lib.baseboard_fab2(sch_1):vr_pvccin_cpu0_ph5_phase"
				( alias ( signalRef "@baseboard_fab2_lib.baseboard_fab2(sch_1):page204_vr_pvccin_cpu0_ph5_phase") )
				( attribute "VOLTAGE" "5"
					( Units "uVoltage" "V" 1.000000)
					( Status sAliasFlattened )
					( Origin gFrontEnd )
				)
				( attribute "CDS_PHYS_NET_NAME" "VR_PVCCIN_CPU0_PH5_PHASE"
					( Origin gPackager )
				)
				( objectStatus "VR_PVCCIN_CPU0_PH5_PHASE" )
			)
			( signal "@baseboard_fab2_lib.baseboard_fab2(sch_1):page204_vr_pvccin_cpu0_ph5_phase"
				( attribute "VOLTAGE" "5"
					( Units "uVoltage" "V" 1.000000)
					( Origin gFrontEnd )
				)
				( objectFlag fObjectAlias )
				( objectStatus "page204_vr_pvccin_cpu0_ph5_phase" )
			)
			( signal "@baseboard_fab2_lib.baseboard_fab2(sch_1):vr_pvccin_cpu0_ph5_vcin"
				( alias ( signalRef "@baseboard_fab2_lib.baseboard_fab2(sch_1):page204_vr_pvccin_cpu0_ph5_vcin") )
				( attribute "VOLTAGE" "5"
					( Units "uVoltage" "V" 1.000000)
					( Status sAliasFlattened )
					( Origin gFrontEnd )
				)
				( attribute "CDS_PHYS_NET_NAME" "VR_PVCCIN_CPU0_PH5_VCIN"
					( Origin gPackager )
				)
				( objectStatus "VR_PVCCIN_CPU0_PH5_VCIN" )
			)
			( signal "@baseboard_fab2_lib.baseboard_fab2(sch_1):page204_vr_pvccin_cpu0_ph5_vcin"
				( attribute "VOLTAGE" "5"
					( Units "uVoltage" "V" 1.000000)
					( Origin gFrontEnd )
				)
				( objectFlag fObjectAlias )
				( objectStatus "page204_vr_pvccin_cpu0_ph5_vcin" )
			)
			( signal "@baseboard_fab2_lib.baseboard_fab2(sch_1):vr_pvccin_cpu0_phase5"
				( alias ( signalRef "@baseboard_fab2_lib.baseboard_fab2(sch_1):page204_vr_pvccin_cpu0_phase5") )
				( attribute "VOLTAGE" "5"
					( Units "uVoltage" "V" 1.000000)
					( Status sAliasFlattened )
					( Origin gFrontEnd )
				)
				( attribute "CDS_PHYS_NET_NAME" "VR_PVCCIN_CPU0_PHASE5"
					( Origin gPackager )
				)
				( objectStatus "VR_PVCCIN_CPU0_PHASE5" )
			)
			( signal "@baseboard_fab2_lib.baseboard_fab2(sch_1):page204_vr_pvccin_cpu0_phase5"
				( attribute "VOLTAGE" "5"
					( Units "uVoltage" "V" 1.000000)
					( Origin gFrontEnd )
				)
				( objectFlag fObjectAlias )
				( objectStatus "page204_vr_pvccin_cpu0_phase5" )
			)
			( signal "@baseboard_fab2_lib.baseboard_fab2(sch_1):tp_pvsa_cpu0_gl_0"
				( attribute "CDS_PHYS_NET_NAME" "TP_PVSA_CPU0_GL_0"
					( Origin gPackager )
				)
				( objectStatus "TP_PVSA_CPU0_GL_0" )
			)
			( signal "@baseboard_fab2_lib.baseboard_fab2(sch_1):tp_pvsa_cpu0_gl_1"
				( attribute "CDS_PHYS_NET_NAME" "TP_PVSA_CPU0_GL_1"
					( Origin gPackager )
				)
				( objectStatus "TP_PVSA_CPU0_GL_1" )
			)
			( signal "@baseboard_fab2_lib.baseboard_fab2(sch_1):vr_pvsa_cpu0_boot"
				( attribute "CDS_PHYS_NET_NAME" "VR_PVSA_CPU0_BOOT"
					( Origin gPackager )
				)
				( objectStatus "VR_PVSA_CPU0_BOOT" )
			)
			( signal "@baseboard_fab2_lib.baseboard_fab2(sch_1):vr_pvsa_cpu0_ocset"
				( attribute "CDS_PHYS_NET_NAME" "VR_PVSA_CPU0_OCSET"
					( Origin gPackager )
				)
				( objectStatus "VR_PVSA_CPU0_OCSET" )
			)
			( signal "@baseboard_fab2_lib.baseboard_fab2(sch_1):vr_pvsa_cpu0_phase"
				( alias ( signalRef "@baseboard_fab2_lib.baseboard_fab2(sch_1):page205_vr_pvsa_cpu0_phase") )
				( attribute "VOLTAGE" "5"
					( Units "uVoltage" "V" 1.000000)
					( Status sAliasFlattened )
					( Origin gFrontEnd )
				)
				( attribute "CDS_PHYS_NET_NAME" "VR_PVSA_CPU0_PHASE"
					( Origin gPackager )
				)
				( objectStatus "VR_PVSA_CPU0_PHASE" )
			)
			( signal "@baseboard_fab2_lib.baseboard_fab2(sch_1):page205_vr_pvsa_cpu0_phase"
				( attribute "VOLTAGE" "5"
					( Units "uVoltage" "V" 1.000000)
					( Origin gFrontEnd )
				)
				( objectFlag fObjectAlias )
				( objectStatus "page205_vr_pvsa_cpu0_phase" )
			)
			( signal "@baseboard_fab2_lib.baseboard_fab2(sch_1):vr_pvsa_cpu0_phase_sw"
				( alias ( signalRef "@baseboard_fab2_lib.baseboard_fab2(sch_1):page205_vr_pvsa_cpu0_phase_sw") )
				( attribute "VOLTAGE" "5"
					( Units "uVoltage" "V" 1.000000)
					( Status sAliasFlattened )
					( Origin gFrontEnd )
				)
				( attribute "CDS_PHYS_NET_NAME" "VR_PVSA_CPU0_PHASE_SW"
					( Origin gPackager )
				)
				( objectStatus "VR_PVSA_CPU0_PHASE_SW" )
			)
			( signal "@baseboard_fab2_lib.baseboard_fab2(sch_1):page205_vr_pvsa_cpu0_phase_sw"
				( attribute "VOLTAGE" "5"
					( Units "uVoltage" "V" 1.000000)
					( Origin gFrontEnd )
				)
				( objectFlag fObjectAlias )
				( objectStatus "page205_vr_pvsa_cpu0_phase_sw" )
			)
			( signal "@baseboard_fab2_lib.baseboard_fab2(sch_1):vr_pvsa_cpu0_vcin"
				( alias ( signalRef "@baseboard_fab2_lib.baseboard_fab2(sch_1):page205_vr_pvsa_cpu0_vcin") )
				( attribute "VOLTAGE" "5"
					( Units "uVoltage" "V" 1.000000)
					( Status sAliasFlattened )
					( Origin gFrontEnd )
				)
				( attribute "CDS_PHYS_NET_NAME" "VR_PVSA_CPU0_VCIN"
					( Origin gPackager )
				)
				( objectStatus "VR_PVSA_CPU0_VCIN" )
			)
			( signal "@baseboard_fab2_lib.baseboard_fab2(sch_1):page205_vr_pvsa_cpu0_vcin"
				( attribute "VOLTAGE" "5"
					( Units "uVoltage" "V" 1.000000)
					( Origin gFrontEnd )
				)
				( objectFlag fObjectAlias )
				( objectStatus "page205_vr_pvsa_cpu0_vcin" )
			)
			( signal "@baseboard_fab2_lib.baseboard_fab2(sch_1):a_tsense_pvccin_cpu1"
				( alias ( signalRef "@baseboard_fab2_lib.baseboard_fab2(sch_1):page206_a_tsense_pvccin_cpu1") )
				( attribute "VOLTAGE" "3.6"
					( Units "uVoltage" "V" 1.000000)
					( Status sAliasFlattened )
					( Origin gFrontEnd )
				)
				( attribute "CDS_PHYS_NET_NAME" "A_TSENSE_PVCCIN_CPU1"
					( Origin gPackager )
				)
				( objectStatus "A_TSENSE_PVCCIN_CPU1" )
			)
			( signal "@baseboard_fab2_lib.baseboard_fab2(sch_1):page206_a_tsense_pvccin_cpu1"
				( attribute "VOLTAGE" "3.6"
					( Units "uVoltage" "V" 1.000000)
					( Origin gFrontEnd )
				)
				( objectFlag fObjectAlias )
				( objectStatus "page206_a_tsense_pvccin_cpu1" )
			)
			( signal "@baseboard_fab2_lib.baseboard_fab2(sch_1):a_tsense_pvsa_cpu1"
				( attribute "CDS_PHYS_NET_NAME" "A_TSENSE_PVSA_CPU1"
					( Origin gPackager )
				)
				( objectStatus "A_TSENSE_PVSA_CPU1" )
			)
			( signal "@baseboard_fab2_lib.baseboard_fab2(sch_1):irq_pvccin_cpu1_vrhot_lvc3_r_n"
				( attribute "CDS_PHYS_NET_NAME" "IRQ_PVCCIN_CPU1_VRHOT_LVC3_R_N"
					( Origin gPackager )
				)
				( objectStatus "IRQ_PVCCIN_CPU1_VRHOT_LVC3_R_N" )
			)
			( signal "@baseboard_fab2_lib.baseboard_fab2(sch_1):isense_pvccin_cpu1_ph1_imon"
				( attribute "CDS_PHYS_NET_NAME" "ISENSE_PVCCIN_CPU1_PH1_IMON"
					( Origin gPackager )
				)
				( objectStatus "ISENSE_PVCCIN_CPU1_PH1_IMON" )
			)
			( signal "@baseboard_fab2_lib.baseboard_fab2(sch_1):isense_pvccin_cpu1_ph2_imon"
				( attribute "CDS_PHYS_NET_NAME" "ISENSE_PVCCIN_CPU1_PH2_IMON"
					( Origin gPackager )
				)
				( objectStatus "ISENSE_PVCCIN_CPU1_PH2_IMON" )
			)
			( signal "@baseboard_fab2_lib.baseboard_fab2(sch_1):isense_pvccin_cpu1_ph3_imon"
				( attribute "CDS_PHYS_NET_NAME" "ISENSE_PVCCIN_CPU1_PH3_IMON"
					( Origin gPackager )
				)
				( objectStatus "ISENSE_PVCCIN_CPU1_PH3_IMON" )
			)
			( signal "@baseboard_fab2_lib.baseboard_fab2(sch_1):isense_pvccin_cpu1_ph4_imon"
				( attribute "CDS_PHYS_NET_NAME" "ISENSE_PVCCIN_CPU1_PH4_IMON"
					( Origin gPackager )
				)
				( objectStatus "ISENSE_PVCCIN_CPU1_PH4_IMON" )
			)
			( signal "@baseboard_fab2_lib.baseboard_fab2(sch_1):isense_pvccin_cpu1_ph5_imon"
				( attribute "CDS_PHYS_NET_NAME" "ISENSE_PVCCIN_CPU1_PH5_IMON"
					( Origin gPackager )
				)
				( objectStatus "ISENSE_PVCCIN_CPU1_PH5_IMON" )
			)
			( signal "@baseboard_fab2_lib.baseboard_fab2(sch_1):isense_pvsa_cpu1_imon"
				( attribute "CDS_PHYS_NET_NAME" "ISENSE_PVSA_CPU1_IMON"
					( Origin gPackager )
				)
				( objectStatus "ISENSE_PVSA_CPU1_IMON" )
			)
			( signal "@baseboard_fab2_lib.baseboard_fab2(sch_1):pu_vr_pvccin_cpu1_flt1_smbalt_n_imon"
				( attribute "CDS_PHYS_NET_NAME" "PU_VR_PVCCIN_CPU1_FLT1_SMBALT_N"
					( Origin gPackager )
				)
				( attribute "PNN" "PU_VR_PVCCIN_CPU1_FLT1_SMBALT_N"
					( Origin gPackager )
				)
				( objectStatus "PU_VR_PVCCIN_CPU1_FLT1_SMBALT_N" )
			)
			( signal "@baseboard_fab2_lib.baseboard_fab2(sch_1):pu_vr_pvccin_cpu1_imon"
				( attribute "CDS_PHYS_NET_NAME" "PU_VR_PVCCIN_CPU1_IMON"
					( Origin gPackager )
				)
				( objectStatus "PU_VR_PVCCIN_CPU1_IMON" )
			)
			( signal "@baseboard_fab2_lib.baseboard_fab2(sch_1):pwrgd_pvsa_cpu1_r"
				( attribute "CDS_PHYS_NET_NAME" "PWRGD_PVSA_CPU1_R"
					( Origin gPackager )
				)
				( objectStatus "PWRGD_PVSA_CPU1_R" )
			)
			( signal "@baseboard_fab2_lib.baseboard_fab2(sch_1):svid_valert_vccin_cpu1"
				( attribute "CDS_PHYS_NET_NAME" "SVID_VALERT_VCCIN_CPU1"
					( Origin gPackager )
				)
				( objectStatus "SVID_VALERT_VCCIN_CPU1" )
			)
			( signal "@baseboard_fab2_lib.baseboard_fab2(sch_1):svid_vclk_pvccin_cpu1"
				( attribute "CDS_PHYS_NET_NAME" "SVID_VCLK_PVCCIN_CPU1"
					( Origin gPackager )
				)
				( objectStatus "SVID_VCLK_PVCCIN_CPU1" )
			)
			( signal "@baseboard_fab2_lib.baseboard_fab2(sch_1):svid_vdio_pvccin_cpu1"
				( attribute "CDS_PHYS_NET_NAME" "SVID_VDIO_PVCCIN_CPU1"
					( Origin gPackager )
				)
				( objectStatus "SVID_VDIO_PVCCIN_CPU1" )
			)
			( signal "@baseboard_fab2_lib.baseboard_fab2(sch_1):vr_fet_sw_p12v_stby_pvccin_cpu1"
				( alias ( signalRef "@baseboard_fab2_lib.baseboard_fab2(sch_1):page206_vr_fet_sw_p12v_stby_pvccin_cpu1") )
				( alias ( signalRef "@baseboard_fab2_lib.baseboard_fab2(sch_1):page207_vr_fet_sw_p12v_stby_pvccin_cpu1") )
				( alias ( signalRef "@baseboard_fab2_lib.baseboard_fab2(sch_1):page208_vr_fet_sw_p12v_stby_pvccin_cpu1") )
				( alias ( signalRef "@baseboard_fab2_lib.baseboard_fab2(sch_1):page209_vr_fet_sw_p12v_stby_pvccin_cpu1") )
				( alias ( signalRef "@baseboard_fab2_lib.baseboard_fab2(sch_1):page210_vr_fet_sw_p12v_stby_pvccin_cpu1") )
				( attribute "VOLTAGE" "12"
					( Units "uVoltage" "V" 1.000000)
					( Status sAliasFlattened )
					( Origin gFrontEnd )
				)
				( attribute "CDS_PHYS_NET_NAME" "VR_FET_SW_P12V_STBY_PVCCIN_CPU1"
					( Origin gPackager )
				)
				( objectStatus "VR_FET_SW_P12V_STBY_PVCCIN_CPU1" )
			)
			( signal "@baseboard_fab2_lib.baseboard_fab2(sch_1):page206_vr_fet_sw_p12v_stby_pvccin_cpu1"
				( attribute "VOLTAGE" "12"
					( Units "uVoltage" "V" 1.000000)
					( Origin gFrontEnd )
				)
				( objectFlag fObjectAlias )
				( objectStatus "page206_vr_fet_sw_p12v_stby_pvccin_cpu1" )
			)
			( signal "@baseboard_fab2_lib.baseboard_fab2(sch_1):page207_vr_fet_sw_p12v_stby_pvccin_cpu1"
				( objectFlag fObjectAlias )
				( objectStatus "page207_vr_fet_sw_p12v_stby_pvccin_cpu1" )
			)
			( signal "@baseboard_fab2_lib.baseboard_fab2(sch_1):page208_vr_fet_sw_p12v_stby_pvccin_cpu1"
				( objectFlag fObjectAlias )
				( objectStatus "page208_vr_fet_sw_p12v_stby_pvccin_cpu1" )
			)
			( signal "@baseboard_fab2_lib.baseboard_fab2(sch_1):page209_vr_fet_sw_p12v_stby_pvccin_cpu1"
				( objectFlag fObjectAlias )
				( objectStatus "page209_vr_fet_sw_p12v_stby_pvccin_cpu1" )
			)
			( signal "@baseboard_fab2_lib.baseboard_fab2(sch_1):page210_vr_fet_sw_p12v_stby_pvccin_cpu1"
				( objectFlag fObjectAlias )
				( objectStatus "page210_vr_fet_sw_p12v_stby_pvccin_cpu1" )
			)
			( signal "@baseboard_fab2_lib.baseboard_fab2(sch_1):vr_pvccin_cpu1_airef1"
				( attribute "CDS_PHYS_NET_NAME" "VR_PVCCIN_CPU1_AIREF1"
					( Origin gPackager )
				)
				( objectStatus "VR_PVCCIN_CPU1_AIREF1" )
			)
			( signal "@baseboard_fab2_lib.baseboard_fab2(sch_1):vr_pvccin_cpu1_airef2"
				( attribute "CDS_PHYS_NET_NAME" "VR_PVCCIN_CPU1_AIREF2"
					( Origin gPackager )
				)
				( objectStatus "VR_PVCCIN_CPU1_AIREF2" )
			)
			( signal "@baseboard_fab2_lib.baseboard_fab2(sch_1):vr_pvccin_cpu1_airef3"
				( attribute "CDS_PHYS_NET_NAME" "VR_PVCCIN_CPU1_AIREF3"
					( Origin gPackager )
				)
				( objectStatus "VR_PVCCIN_CPU1_AIREF3" )
			)
			( signal "@baseboard_fab2_lib.baseboard_fab2(sch_1):vr_pvccin_cpu1_airef4"
				( attribute "CDS_PHYS_NET_NAME" "VR_PVCCIN_CPU1_AIREF4"
					( Origin gPackager )
				)
				( objectStatus "VR_PVCCIN_CPU1_AIREF4" )
			)
			( signal "@baseboard_fab2_lib.baseboard_fab2(sch_1):vr_pvccin_cpu1_airef5"
				( attribute "CDS_PHYS_NET_NAME" "VR_PVCCIN_CPU1_AIREF5"
					( Origin gPackager )
				)
				( objectStatus "VR_PVCCIN_CPU1_AIREF5" )
			)
			( signal "@baseboard_fab2_lib.baseboard_fab2(sch_1):vr_pvccin_cpu1_avinsen"
				( alias ( signalRef "@baseboard_fab2_lib.baseboard_fab2(sch_1):page206_vr_pvccin_cpu1_avinsen") )
				( attribute "VOLTAGE" "0.8"
					( Units "uVoltage" "V" 1.000000)
					( Status sAliasFlattened )
					( Origin gFrontEnd )
				)
				( attribute "CDS_PHYS_NET_NAME" "VR_PVCCIN_CPU1_AVINSEN"
					( Origin gPackager )
				)
				( objectStatus "VR_PVCCIN_CPU1_AVINSEN" )
			)
			( signal "@baseboard_fab2_lib.baseboard_fab2(sch_1):page206_vr_pvccin_cpu1_avinsen"
				( attribute "VOLTAGE" "0.8"
					( Units "uVoltage" "V" 1.000000)
					( Origin gFrontEnd )
				)
				( objectFlag fObjectAlias )
				( objectStatus "page206_vr_pvccin_cpu1_avinsen" )
			)
			( signal "@baseboard_fab2_lib.baseboard_fab2(sch_1):vr_pvccin_cpu1_pwm1"
				( alias ( signalRef "@baseboard_fab2_lib.baseboard_fab2(sch_1):page206_vr_pvccin_cpu1_pwm1") )
				( attribute "VOLTAGE" "3.6"
					( Units "uVoltage" "V" 1.000000)
					( Status sAliasFlattened )
					( Origin gFrontEnd )
				)
				( attribute "CDS_PHYS_NET_NAME" "VR_PVCCIN_CPU1_PWM1"
					( Origin gPackager )
				)
				( objectStatus "VR_PVCCIN_CPU1_PWM1" )
			)
			( signal "@baseboard_fab2_lib.baseboard_fab2(sch_1):page206_vr_pvccin_cpu1_pwm1"
				( attribute "VOLTAGE" "3.6"
					( Units "uVoltage" "V" 1.000000)
					( Origin gFrontEnd )
				)
				( objectFlag fObjectAlias )
				( objectStatus "page206_vr_pvccin_cpu1_pwm1" )
			)
			( signal "@baseboard_fab2_lib.baseboard_fab2(sch_1):vr_pvccin_cpu1_pwm2"
				( alias ( signalRef "@baseboard_fab2_lib.baseboard_fab2(sch_1):page206_vr_pvccin_cpu1_pwm2") )
				( attribute "VOLTAGE" "3.6"
					( Units "uVoltage" "V" 1.000000)
					( Status sAliasFlattened )
					( Origin gFrontEnd )
				)
				( attribute "CDS_PHYS_NET_NAME" "VR_PVCCIN_CPU1_PWM2"
					( Origin gPackager )
				)
				( objectStatus "VR_PVCCIN_CPU1_PWM2" )
			)
			( signal "@baseboard_fab2_lib.baseboard_fab2(sch_1):page206_vr_pvccin_cpu1_pwm2"
				( attribute "VOLTAGE" "3.6"
					( Units "uVoltage" "V" 1.000000)
					( Origin gFrontEnd )
				)
				( objectFlag fObjectAlias )
				( objectStatus "page206_vr_pvccin_cpu1_pwm2" )
			)
			( signal "@baseboard_fab2_lib.baseboard_fab2(sch_1):vr_pvccin_cpu1_pwm3"
				( alias ( signalRef "@baseboard_fab2_lib.baseboard_fab2(sch_1):page206_vr_pvccin_cpu1_pwm3") )
				( attribute "VOLTAGE" "3.6"
					( Units "uVoltage" "V" 1.000000)
					( Status sAliasFlattened )
					( Origin gFrontEnd )
				)
				( attribute "CDS_PHYS_NET_NAME" "VR_PVCCIN_CPU1_PWM3"
					( Origin gPackager )
				)
				( objectStatus "VR_PVCCIN_CPU1_PWM3" )
			)
			( signal "@baseboard_fab2_lib.baseboard_fab2(sch_1):page206_vr_pvccin_cpu1_pwm3"
				( attribute "VOLTAGE" "3.6"
					( Units "uVoltage" "V" 1.000000)
					( Origin gFrontEnd )
				)
				( objectFlag fObjectAlias )
				( objectStatus "page206_vr_pvccin_cpu1_pwm3" )
			)
			( signal "@baseboard_fab2_lib.baseboard_fab2(sch_1):vr_pvccin_cpu1_pwm4"
				( alias ( signalRef "@baseboard_fab2_lib.baseboard_fab2(sch_1):page206_vr_pvccin_cpu1_pwm4") )
				( attribute "VOLTAGE" "3.6"
					( Units "uVoltage" "V" 1.000000)
					( Status sAliasFlattened )
					( Origin gFrontEnd )
				)
				( attribute "CDS_PHYS_NET_NAME" "VR_PVCCIN_CPU1_PWM4"
					( Origin gPackager )
				)
				( objectStatus "VR_PVCCIN_CPU1_PWM4" )
			)
			( signal "@baseboard_fab2_lib.baseboard_fab2(sch_1):page206_vr_pvccin_cpu1_pwm4"
				( attribute "VOLTAGE" "3.6"
					( Units "uVoltage" "V" 1.000000)
					( Origin gFrontEnd )
				)
				( objectFlag fObjectAlias )
				( objectStatus "page206_vr_pvccin_cpu1_pwm4" )
			)
			( signal "@baseboard_fab2_lib.baseboard_fab2(sch_1):vr_pvccin_cpu1_pwm5"
				( alias ( signalRef "@baseboard_fab2_lib.baseboard_fab2(sch_1):page209_vr_pvccin_cpu1_pwm5") )
				( attribute "VOLTAGE" "3.6"
					( Units "uVoltage" "V" 1.000000)
					( Status sAliasFlattened )
					( Origin gFrontEnd )
				)
				( attribute "CDS_PHYS_NET_NAME" "VR_PVCCIN_CPU1_PWM5"
					( Origin gPackager )
				)
				( objectStatus "VR_PVCCIN_CPU1_PWM5" )
			)
			( signal "@baseboard_fab2_lib.baseboard_fab2(sch_1):page209_vr_pvccin_cpu1_pwm5"
				( attribute "VOLTAGE" "3.6"
					( Units "uVoltage" "V" 1.000000)
					( Origin gFrontEnd )
				)
				( objectFlag fObjectAlias )
				( objectStatus "page209_vr_pvccin_cpu1_pwm5" )
			)
			( signal "@baseboard_fab2_lib.baseboard_fab2(sch_1):vr_pvccin_cpu1_vd12"
				( attribute "CDS_PHYS_NET_NAME" "VR_PVCCIN_CPU1_VD12"
					( Origin gPackager )
				)
				( objectStatus "VR_PVCCIN_CPU1_VD12" )
			)
			( signal "@baseboard_fab2_lib.baseboard_fab2(sch_1):vr_pvccin_cpu1_vdd"
				( alias ( signalRef "@baseboard_fab2_lib.baseboard_fab2(sch_1):page206_vr_pvccin_cpu1_vdd") )
				( attribute "VOLTAGE" "3.3"
					( Units "uVoltage" "V" 1.000000)
					( Status sAliasFlattened )
					( Origin gFrontEnd )
				)
				( attribute "CDS_PHYS_NET_NAME" "VR_PVCCIN_CPU1_VDD"
					( Origin gPackager )
				)
				( objectStatus "VR_PVCCIN_CPU1_VDD" )
			)
			( signal "@baseboard_fab2_lib.baseboard_fab2(sch_1):page206_vr_pvccin_cpu1_vdd"
				( attribute "VOLTAGE" "3.3"
					( Units "uVoltage" "V" 1.000000)
					( Origin gFrontEnd )
				)
				( objectFlag fObjectAlias )
				( objectStatus "page206_vr_pvccin_cpu1_vdd" )
			)
			( signal "@baseboard_fab2_lib.baseboard_fab2(sch_1):vr_pvccin_cpu1_vren"
				( alias ( signalRef "@baseboard_fab2_lib.baseboard_fab2(sch_1):page206_vr_pvccin_cpu1_vren") )
				( attribute "VOLTAGE" "3.3"
					( Units "uVoltage" "V" 1.000000)
					( Status sAliasFlattened )
					( Origin gFrontEnd )
				)
				( attribute "CDS_PHYS_NET_NAME" "VR_PVCCIN_CPU1_VREN"
					( Origin gPackager )
				)
				( objectStatus "VR_PVCCIN_CPU1_VREN" )
			)
			( signal "@baseboard_fab2_lib.baseboard_fab2(sch_1):page206_vr_pvccin_cpu1_vren"
				( attribute "VOLTAGE" "3.3"
					( Units "uVoltage" "V" 1.000000)
					( Origin gFrontEnd )
				)
				( objectFlag fObjectAlias )
				( objectStatus "page206_vr_pvccin_cpu1_vren" )
			)
			( signal "@baseboard_fab2_lib.baseboard_fab2(sch_1):vr_pvccin_cpu1_xaddr1"
				( alias ( signalRef "@baseboard_fab2_lib.baseboard_fab2(sch_1):page206_vr_pvccin_cpu1_xaddr1") )
				( attribute "VOLTAGE" "3.3"
					( Units "uVoltage" "V" 1.000000)
					( Status sAliasFlattened )
					( Origin gFrontEnd )
				)
				( attribute "CDS_PHYS_NET_NAME" "VR_PVCCIN_CPU1_XADDR1"
					( Origin gPackager )
				)
				( objectStatus "VR_PVCCIN_CPU1_XADDR1" )
			)
			( signal "@baseboard_fab2_lib.baseboard_fab2(sch_1):page206_vr_pvccin_cpu1_xaddr1"
				( attribute "VOLTAGE" "3.3"
					( Units "uVoltage" "V" 1.000000)
					( Origin gFrontEnd )
				)
				( objectFlag fObjectAlias )
				( objectStatus "page206_vr_pvccin_cpu1_xaddr1" )
			)
			( signal "@baseboard_fab2_lib.baseboard_fab2(sch_1):vr_pvccin_cpu1_xaddr2"
				( alias ( signalRef "@baseboard_fab2_lib.baseboard_fab2(sch_1):page206_vr_pvccin_cpu1_xaddr2") )
				( attribute "VOLTAGE" "3.3"
					( Units "uVoltage" "V" 1.000000)
					( Status sAliasFlattened )
					( Origin gFrontEnd )
				)
				( attribute "CDS_PHYS_NET_NAME" "VR_PVCCIN_CPU1_XADDR2"
					( Origin gPackager )
				)
				( objectStatus "VR_PVCCIN_CPU1_XADDR2" )
			)
			( signal "@baseboard_fab2_lib.baseboard_fab2(sch_1):page206_vr_pvccin_cpu1_xaddr2"
				( attribute "VOLTAGE" "3.3"
					( Units "uVoltage" "V" 1.000000)
					( Origin gFrontEnd )
				)
				( objectFlag fObjectAlias )
				( objectStatus "page206_vr_pvccin_cpu1_xaddr2" )
			)
			( signal "@baseboard_fab2_lib.baseboard_fab2(sch_1):vr_pvsa_cpu1_biref1"
				( attribute "CDS_PHYS_NET_NAME" "VR_PVSA_CPU1_BIREF1"
					( Origin gPackager )
				)
				( objectStatus "VR_PVSA_CPU1_BIREF1" )
			)
			( signal "@baseboard_fab2_lib.baseboard_fab2(sch_1):vr_pvsa_cpu1_pwm"
				( alias ( signalRef "@baseboard_fab2_lib.baseboard_fab2(sch_1):page206_vr_pvsa_cpu1_pwm") )
				( attribute "VOLTAGE" "3.6"
					( Units "uVoltage" "V" 1.000000)
					( Status sAliasFlattened )
					( Origin gFrontEnd )
				)
				( attribute "CDS_PHYS_NET_NAME" "VR_PVSA_CPU1_PWM"
					( Origin gPackager )
				)
				( objectStatus "VR_PVSA_CPU1_PWM" )
			)
			( signal "@baseboard_fab2_lib.baseboard_fab2(sch_1):page206_vr_pvsa_cpu1_pwm"
				( attribute "VOLTAGE" "3.6"
					( Units "uVoltage" "V" 1.000000)
					( Origin gFrontEnd )
				)
				( objectFlag fObjectAlias )
				( objectStatus "page206_vr_pvsa_cpu1_pwm" )
			)
			( signal "@baseboard_fab2_lib.baseboard_fab2(sch_1):vr_vrrdy_pvccin_cpu1"
				( attribute "CDS_PHYS_NET_NAME" "VR_VRRDY_PVCCIN_CPU1"
					( Origin gPackager )
				)
				( objectStatus "VR_VRRDY_PVCCIN_CPU1" )
			)
			( signal "@baseboard_fab2_lib.baseboard_fab2(sch_1):vsense_pvccin_cpu1_avsp"
				( attribute "CDS_PHYS_NET_NAME" "VSENSE_PVCCIN_CPU1_AVSP"
					( Origin gPackager )
				)
				( objectStatus "VSENSE_PVCCIN_CPU1_AVSP" )
			)
			( signal "@baseboard_fab2_lib.baseboard_fab2(sch_1):vsense_pvccin_cpu1_n"
				( attribute "CDS_PHYS_NET_NAME" "VSENSE_PVCCIN_CPU1_N"
					( Origin gPackager )
				)
				( objectStatus "VSENSE_PVCCIN_CPU1_N" )
			)
			( signal "@baseboard_fab2_lib.baseboard_fab2(sch_1):vsense_pvccin_cpu1_p"
				( attribute "CDS_PHYS_NET_NAME" "VSENSE_PVCCIN_CPU1_P"
					( Origin gPackager )
				)
				( objectStatus "VSENSE_PVCCIN_CPU1_P" )
			)
			( signal "@baseboard_fab2_lib.baseboard_fab2(sch_1):vsense_pvsa_cpu1_bvsp"
				( attribute "CDS_PHYS_NET_NAME" "VSENSE_PVSA_CPU1_BVSP"
					( Origin gPackager )
				)
				( objectStatus "VSENSE_PVSA_CPU1_BVSP" )
			)
			( signal "@baseboard_fab2_lib.baseboard_fab2(sch_1):vsense_pvsa_cpu1_n"
				( attribute "CDS_PHYS_NET_NAME" "VSENSE_PVSA_CPU1_N"
					( Origin gPackager )
				)
				( objectStatus "VSENSE_PVSA_CPU1_N" )
			)
			( signal "@baseboard_fab2_lib.baseboard_fab2(sch_1):vsense_pvsa_cpu1_p"
				( attribute "CDS_PHYS_NET_NAME" "VSENSE_PVSA_CPU1_P"
					( Origin gPackager )
				)
				( objectStatus "VSENSE_PVSA_CPU1_P" )
			)
			( signal "@baseboard_fab2_lib.baseboard_fab2(sch_1):tp_pvccinc_cpu1_ph1_gl_0"
				( attribute "CDS_PHYS_NET_NAME" "TP_PVCCINC_CPU1_PH1_GL_0"
					( Origin gPackager )
				)
				( objectStatus "TP_PVCCINC_CPU1_PH1_GL_0" )
			)
			( signal "@baseboard_fab2_lib.baseboard_fab2(sch_1):tp_pvccinc_cpu1_ph1_gl_1"
				( attribute "CDS_PHYS_NET_NAME" "TP_PVCCINC_CPU1_PH1_GL_1"
					( Origin gPackager )
				)
				( objectStatus "TP_PVCCINC_CPU1_PH1_GL_1" )
			)
			( signal "@baseboard_fab2_lib.baseboard_fab2(sch_1):tp_pvccinc_cpu1_ph2_gl_0"
				( attribute "CDS_PHYS_NET_NAME" "TP_PVCCINC_CPU1_PH2_GL_0"
					( Origin gPackager )
				)
				( objectStatus "TP_PVCCINC_CPU1_PH2_GL_0" )
			)
			( signal "@baseboard_fab2_lib.baseboard_fab2(sch_1):tp_pvccinc_cpu1_ph2_gl_1"
				( attribute "CDS_PHYS_NET_NAME" "TP_PVCCINC_CPU1_PH2_GL_1"
					( Origin gPackager )
				)
				( objectStatus "TP_PVCCINC_CPU1_PH2_GL_1" )
			)
			( signal "@baseboard_fab2_lib.baseboard_fab2(sch_1):vr_pvccin_cpu1_ph1_boot"
				( attribute "CDS_PHYS_NET_NAME" "VR_PVCCIN_CPU1_PH1_BOOT"
					( Origin gPackager )
				)
				( objectStatus "VR_PVCCIN_CPU1_PH1_BOOT" )
			)
			( signal "@baseboard_fab2_lib.baseboard_fab2(sch_1):vr_pvccin_cpu1_ph1_ocset"
				( attribute "CDS_PHYS_NET_NAME" "VR_PVCCIN_CPU1_PH1_OCSET"
					( Origin gPackager )
				)
				( objectStatus "VR_PVCCIN_CPU1_PH1_OCSET" )
			)
			( signal "@baseboard_fab2_lib.baseboard_fab2(sch_1):vr_pvccin_cpu1_ph1_phase"
				( alias ( signalRef "@baseboard_fab2_lib.baseboard_fab2(sch_1):page207_vr_pvccin_cpu1_ph1_phase") )
				( attribute "VOLTAGE" "5"
					( Units "uVoltage" "V" 1.000000)
					( Status sAliasFlattened )
					( Origin gFrontEnd )
				)
				( attribute "CDS_PHYS_NET_NAME" "VR_PVCCIN_CPU1_PH1_PHASE"
					( Origin gPackager )
				)
				( objectStatus "VR_PVCCIN_CPU1_PH1_PHASE" )
			)
			( signal "@baseboard_fab2_lib.baseboard_fab2(sch_1):page207_vr_pvccin_cpu1_ph1_phase"
				( attribute "VOLTAGE" "5"
					( Units "uVoltage" "V" 1.000000)
					( Origin gFrontEnd )
				)
				( objectFlag fObjectAlias )
				( objectStatus "page207_vr_pvccin_cpu1_ph1_phase" )
			)
			( signal "@baseboard_fab2_lib.baseboard_fab2(sch_1):vr_pvccin_cpu1_ph1_vcin"
				( alias ( signalRef "@baseboard_fab2_lib.baseboard_fab2(sch_1):page207_vr_pvccin_cpu1_ph1_vcin") )
				( attribute "VOLTAGE" "5"
					( Units "uVoltage" "V" 1.000000)
					( Status sAliasFlattened )
					( Origin gFrontEnd )
				)
				( attribute "CDS_PHYS_NET_NAME" "VR_PVCCIN_CPU1_PH1_VCIN"
					( Origin gPackager )
				)
				( objectStatus "VR_PVCCIN_CPU1_PH1_VCIN" )
			)
			( signal "@baseboard_fab2_lib.baseboard_fab2(sch_1):page207_vr_pvccin_cpu1_ph1_vcin"
				( attribute "VOLTAGE" "5"
					( Units "uVoltage" "V" 1.000000)
					( Origin gFrontEnd )
				)
				( objectFlag fObjectAlias )
				( objectStatus "page207_vr_pvccin_cpu1_ph1_vcin" )
			)
			( signal "@baseboard_fab2_lib.baseboard_fab2(sch_1):vr_pvccin_cpu1_ph2_boot"
				( attribute "CDS_PHYS_NET_NAME" "VR_PVCCIN_CPU1_PH2_BOOT"
					( Origin gPackager )
				)
				( objectStatus "VR_PVCCIN_CPU1_PH2_BOOT" )
			)
			( signal "@baseboard_fab2_lib.baseboard_fab2(sch_1):vr_pvccin_cpu1_ph2_ocset"
				( attribute "CDS_PHYS_NET_NAME" "VR_PVCCIN_CPU1_PH2_OCSET"
					( Origin gPackager )
				)
				( objectStatus "VR_PVCCIN_CPU1_PH2_OCSET" )
			)
			( signal "@baseboard_fab2_lib.baseboard_fab2(sch_1):vr_pvccin_cpu1_ph2_phase"
				( alias ( signalRef "@baseboard_fab2_lib.baseboard_fab2(sch_1):page207_vr_pvccin_cpu1_ph2_phase") )
				( attribute "VOLTAGE" "5"
					( Units "uVoltage" "V" 1.000000)
					( Status sAliasFlattened )
					( Origin gFrontEnd )
				)
				( attribute "CDS_PHYS_NET_NAME" "VR_PVCCIN_CPU1_PH2_PHASE"
					( Origin gPackager )
				)
				( objectStatus "VR_PVCCIN_CPU1_PH2_PHASE" )
			)
			( signal "@baseboard_fab2_lib.baseboard_fab2(sch_1):page207_vr_pvccin_cpu1_ph2_phase"
				( attribute "VOLTAGE" "5"
					( Units "uVoltage" "V" 1.000000)
					( Origin gFrontEnd )
				)
				( objectFlag fObjectAlias )
				( objectStatus "page207_vr_pvccin_cpu1_ph2_phase" )
			)
			( signal "@baseboard_fab2_lib.baseboard_fab2(sch_1):vr_pvccin_cpu1_ph2_vcin"
				( attribute "CDS_PHYS_NET_NAME" "VR_PVCCIN_CPU1_PH2_VCIN"
					( Origin gPackager )
				)
				( objectStatus "VR_PVCCIN_CPU1_PH2_VCIN" )
			)
			( signal "@baseboard_fab2_lib.baseboard_fab2(sch_1):vr_pvccin_cpu1_phase1"
				( alias ( signalRef "@baseboard_fab2_lib.baseboard_fab2(sch_1):page207_vr_pvccin_cpu1_phase1") )
				( attribute "VOLTAGE" "5"
					( Units "uVoltage" "V" 1.000000)
					( Status sAliasFlattened )
					( Origin gFrontEnd )
				)
				( attribute "CDS_PHYS_NET_NAME" "VR_PVCCIN_CPU1_PHASE1"
					( Origin gPackager )
				)
				( objectStatus "VR_PVCCIN_CPU1_PHASE1" )
			)
			( signal "@baseboard_fab2_lib.baseboard_fab2(sch_1):page207_vr_pvccin_cpu1_phase1"
				( attribute "VOLTAGE" "5"
					( Units "uVoltage" "V" 1.000000)
					( Origin gFrontEnd )
				)
				( objectFlag fObjectAlias )
				( objectStatus "page207_vr_pvccin_cpu1_phase1" )
			)
			( signal "@baseboard_fab2_lib.baseboard_fab2(sch_1):vr_pvccin_cpu1_phase2"
				( alias ( signalRef "@baseboard_fab2_lib.baseboard_fab2(sch_1):page207_vr_pvccin_cpu1_phase2") )
				( attribute "VOLTAGE" "5"
					( Units "uVoltage" "V" 1.000000)
					( Status sAliasFlattened )
					( Origin gFrontEnd )
				)
				( attribute "CDS_PHYS_NET_NAME" "VR_PVCCIN_CPU1_PHASE2"
					( Origin gPackager )
				)
				( objectStatus "VR_PVCCIN_CPU1_PHASE2" )
			)
			( signal "@baseboard_fab2_lib.baseboard_fab2(sch_1):page207_vr_pvccin_cpu1_phase2"
				( attribute "VOLTAGE" "5"
					( Units "uVoltage" "V" 1.000000)
					( Origin gFrontEnd )
				)
				( objectFlag fObjectAlias )
				( objectStatus "page207_vr_pvccin_cpu1_phase2" )
			)
			( signal "@baseboard_fab2_lib.baseboard_fab2(sch_1):tp_pvccin_cpu1_ph3_gl_0"
				( attribute "CDS_PHYS_NET_NAME" "TP_PVCCIN_CPU1_PH3_GL_0"
					( Origin gPackager )
				)
				( objectStatus "TP_PVCCIN_CPU1_PH3_GL_0" )
			)
			( signal "@baseboard_fab2_lib.baseboard_fab2(sch_1):tp_pvccin_cpu1_ph3_gl_1"
				( attribute "CDS_PHYS_NET_NAME" "TP_PVCCIN_CPU1_PH3_GL_1"
					( Origin gPackager )
				)
				( objectStatus "TP_PVCCIN_CPU1_PH3_GL_1" )
			)
			( signal "@baseboard_fab2_lib.baseboard_fab2(sch_1):tp_pvccin_cpu1_ph4_gl_0"
				( attribute "CDS_PHYS_NET_NAME" "TP_PVCCIN_CPU1_PH4_GL_0"
					( Origin gPackager )
				)
				( objectStatus "TP_PVCCIN_CPU1_PH4_GL_0" )
			)
			( signal "@baseboard_fab2_lib.baseboard_fab2(sch_1):tp_pvccin_cpu1_ph4_gl_1"
				( attribute "CDS_PHYS_NET_NAME" "TP_PVCCIN_CPU1_PH4_GL_1"
					( Origin gPackager )
				)
				( objectStatus "TP_PVCCIN_CPU1_PH4_GL_1" )
			)
			( signal "@baseboard_fab2_lib.baseboard_fab2(sch_1):vr_pvccin_cpu1_ph3_boot"
				( attribute "CDS_PHYS_NET_NAME" "VR_PVCCIN_CPU1_PH3_BOOT"
					( Origin gPackager )
				)
				( objectStatus "VR_PVCCIN_CPU1_PH3_BOOT" )
			)
			( signal "@baseboard_fab2_lib.baseboard_fab2(sch_1):vr_pvccin_cpu1_ph3_ocset"
				( attribute "CDS_PHYS_NET_NAME" "VR_PVCCIN_CPU1_PH3_OCSET"
					( Origin gPackager )
				)
				( objectStatus "VR_PVCCIN_CPU1_PH3_OCSET" )
			)
			( signal "@baseboard_fab2_lib.baseboard_fab2(sch_1):vr_pvccin_cpu1_ph3_phase"
				( attribute "CDS_PHYS_NET_NAME" "VR_PVCCIN_CPU1_PH3_PHASE"
					( Origin gPackager )
				)
				( objectStatus "VR_PVCCIN_CPU1_PH3_PHASE" )
			)
			( signal "@baseboard_fab2_lib.baseboard_fab2(sch_1):vr_pvccin_cpu1_ph3_vcin"
				( alias ( signalRef "@baseboard_fab2_lib.baseboard_fab2(sch_1):page208_vr_pvccin_cpu1_ph3_vcin") )
				( attribute "VOLTAGE" "5"
					( Units "uVoltage" "V" 1.000000)
					( Status sAliasFlattened )
					( Origin gFrontEnd )
				)
				( attribute "CDS_PHYS_NET_NAME" "VR_PVCCIN_CPU1_PH3_VCIN"
					( Origin gPackager )
				)
				( objectStatus "VR_PVCCIN_CPU1_PH3_VCIN" )
			)
			( signal "@baseboard_fab2_lib.baseboard_fab2(sch_1):page208_vr_pvccin_cpu1_ph3_vcin"
				( attribute "VOLTAGE" "5"
					( Units "uVoltage" "V" 1.000000)
					( Origin gFrontEnd )
				)
				( objectFlag fObjectAlias )
				( objectStatus "page208_vr_pvccin_cpu1_ph3_vcin" )
			)
			( signal "@baseboard_fab2_lib.baseboard_fab2(sch_1):vr_pvccin_cpu1_ph4_boot"
				( attribute "CDS_PHYS_NET_NAME" "VR_PVCCIN_CPU1_PH4_BOOT"
					( Origin gPackager )
				)
				( objectStatus "VR_PVCCIN_CPU1_PH4_BOOT" )
			)
			( signal "@baseboard_fab2_lib.baseboard_fab2(sch_1):vr_pvccin_cpu1_ph4_ocset"
				( attribute "CDS_PHYS_NET_NAME" "VR_PVCCIN_CPU1_PH4_OCSET"
					( Origin gPackager )
				)
				( objectStatus "VR_PVCCIN_CPU1_PH4_OCSET" )
			)
			( signal "@baseboard_fab2_lib.baseboard_fab2(sch_1):vr_pvccin_cpu1_ph4_phase"
				( alias ( signalRef "@baseboard_fab2_lib.baseboard_fab2(sch_1):page208_vr_pvccin_cpu1_ph4_phase") )
				( attribute "VOLTAGE" "5"
					( Units "uVoltage" "V" 1.000000)
					( Status sAliasFlattened )
					( Origin gFrontEnd )
				)
				( attribute "CDS_PHYS_NET_NAME" "VR_PVCCIN_CPU1_PH4_PHASE"
					( Origin gPackager )
				)
				( objectStatus "VR_PVCCIN_CPU1_PH4_PHASE" )
			)
			( signal "@baseboard_fab2_lib.baseboard_fab2(sch_1):page208_vr_pvccin_cpu1_ph4_phase"
				( attribute "VOLTAGE" "5"
					( Units "uVoltage" "V" 1.000000)
					( Origin gFrontEnd )
				)
				( objectFlag fObjectAlias )
				( objectStatus "page208_vr_pvccin_cpu1_ph4_phase" )
			)
			( signal "@baseboard_fab2_lib.baseboard_fab2(sch_1):vr_pvccin_cpu1_ph4_vcin"
				( alias ( signalRef "@baseboard_fab2_lib.baseboard_fab2(sch_1):page208_vr_pvccin_cpu1_ph4_vcin") )
				( attribute "VOLTAGE" "5"
					( Units "uVoltage" "V" 1.000000)
					( Status sAliasFlattened )
					( Origin gFrontEnd )
				)
				( attribute "CDS_PHYS_NET_NAME" "VR_PVCCIN_CPU1_PH4_VCIN"
					( Origin gPackager )
				)
				( objectStatus "VR_PVCCIN_CPU1_PH4_VCIN" )
			)
			( signal "@baseboard_fab2_lib.baseboard_fab2(sch_1):page208_vr_pvccin_cpu1_ph4_vcin"
				( attribute "VOLTAGE" "5"
					( Units "uVoltage" "V" 1.000000)
					( Origin gFrontEnd )
				)
				( objectFlag fObjectAlias )
				( objectStatus "page208_vr_pvccin_cpu1_ph4_vcin" )
			)
			( signal "@baseboard_fab2_lib.baseboard_fab2(sch_1):vr_pvccin_cpu1_phase3"
				( alias ( signalRef "@baseboard_fab2_lib.baseboard_fab2(sch_1):page208_vr_pvccin_cpu1_phase3") )
				( attribute "VOLTAGE" "5"
					( Units "uVoltage" "V" 1.000000)
					( Status sAliasFlattened )
					( Origin gFrontEnd )
				)
				( attribute "CDS_PHYS_NET_NAME" "VR_PVCCIN_CPU1_PHASE3"
					( Origin gPackager )
				)
				( objectStatus "VR_PVCCIN_CPU1_PHASE3" )
			)
			( signal "@baseboard_fab2_lib.baseboard_fab2(sch_1):page208_vr_pvccin_cpu1_phase3"
				( attribute "VOLTAGE" "5"
					( Units "uVoltage" "V" 1.000000)
					( Origin gFrontEnd )
				)
				( objectFlag fObjectAlias )
				( objectStatus "page208_vr_pvccin_cpu1_phase3" )
			)
			( signal "@baseboard_fab2_lib.baseboard_fab2(sch_1):vr_pvccin_cpu1_phase4"
				( alias ( signalRef "@baseboard_fab2_lib.baseboard_fab2(sch_1):page208_vr_pvccin_cpu1_phase4") )
				( attribute "VOLTAGE" "5"
					( Units "uVoltage" "V" 1.000000)
					( Status sAliasFlattened )
					( Origin gFrontEnd )
				)
				( attribute "CDS_PHYS_NET_NAME" "VR_PVCCIN_CPU1_PHASE4"
					( Origin gPackager )
				)
				( objectStatus "VR_PVCCIN_CPU1_PHASE4" )
			)
			( signal "@baseboard_fab2_lib.baseboard_fab2(sch_1):page208_vr_pvccin_cpu1_phase4"
				( attribute "VOLTAGE" "5"
					( Units "uVoltage" "V" 1.000000)
					( Origin gFrontEnd )
				)
				( objectFlag fObjectAlias )
				( objectStatus "page208_vr_pvccin_cpu1_phase4" )
			)
			( signal "@baseboard_fab2_lib.baseboard_fab2(sch_1):tp_pvccin_cpu1_ph5_gl_0"
				( attribute "CDS_PHYS_NET_NAME" "TP_PVCCIN_CPU1_PH5_GL_0"
					( Origin gPackager )
				)
				( objectStatus "TP_PVCCIN_CPU1_PH5_GL_0" )
			)
			( signal "@baseboard_fab2_lib.baseboard_fab2(sch_1):tp_pvccin_cpu1_ph5_gl_1"
				( attribute "CDS_PHYS_NET_NAME" "TP_PVCCIN_CPU1_PH5_GL_1"
					( Origin gPackager )
				)
				( objectStatus "TP_PVCCIN_CPU1_PH5_GL_1" )
			)
			( signal "@baseboard_fab2_lib.baseboard_fab2(sch_1):vr_pvccin_cpu1_ph5_boot"
				( attribute "CDS_PHYS_NET_NAME" "VR_PVCCIN_CPU1_PH5_BOOT"
					( Origin gPackager )
				)
				( objectStatus "VR_PVCCIN_CPU1_PH5_BOOT" )
			)
			( signal "@baseboard_fab2_lib.baseboard_fab2(sch_1):vr_pvccin_cpu1_ph5_ocset"
				( attribute "CDS_PHYS_NET_NAME" "VR_PVCCIN_CPU1_PH5_OCSET"
					( Origin gPackager )
				)
				( objectStatus "VR_PVCCIN_CPU1_PH5_OCSET" )
			)
			( signal "@baseboard_fab2_lib.baseboard_fab2(sch_1):vr_pvccin_cpu1_ph5_phase"
				( alias ( signalRef "@baseboard_fab2_lib.baseboard_fab2(sch_1):page209_vr_pvccin_cpu1_ph5_phase") )
				( attribute "VOLTAGE" "5"
					( Units "uVoltage" "V" 1.000000)
					( Status sAliasFlattened )
					( Origin gFrontEnd )
				)
				( attribute "CDS_PHYS_NET_NAME" "VR_PVCCIN_CPU1_PH5_PHASE"
					( Origin gPackager )
				)
				( objectStatus "VR_PVCCIN_CPU1_PH5_PHASE" )
			)
			( signal "@baseboard_fab2_lib.baseboard_fab2(sch_1):page209_vr_pvccin_cpu1_ph5_phase"
				( attribute "VOLTAGE" "5"
					( Units "uVoltage" "V" 1.000000)
					( Origin gFrontEnd )
				)
				( objectFlag fObjectAlias )
				( objectStatus "page209_vr_pvccin_cpu1_ph5_phase" )
			)
			( signal "@baseboard_fab2_lib.baseboard_fab2(sch_1):vr_pvccin_cpu1_ph5_vcin"
				( alias ( signalRef "@baseboard_fab2_lib.baseboard_fab2(sch_1):page209_vr_pvccin_cpu1_ph5_vcin") )
				( attribute "VOLTAGE" "5"
					( Units "uVoltage" "V" 1.000000)
					( Status sAliasFlattened )
					( Origin gFrontEnd )
				)
				( attribute "CDS_PHYS_NET_NAME" "VR_PVCCIN_CPU1_PH5_VCIN"
					( Origin gPackager )
				)
				( objectStatus "VR_PVCCIN_CPU1_PH5_VCIN" )
			)
			( signal "@baseboard_fab2_lib.baseboard_fab2(sch_1):page209_vr_pvccin_cpu1_ph5_vcin"
				( attribute "VOLTAGE" "5"
					( Units "uVoltage" "V" 1.000000)
					( Origin gFrontEnd )
				)
				( objectFlag fObjectAlias )
				( objectStatus "page209_vr_pvccin_cpu1_ph5_vcin" )
			)
			( signal "@baseboard_fab2_lib.baseboard_fab2(sch_1):vr_pvccin_cpu1_phase5"
				( alias ( signalRef "@baseboard_fab2_lib.baseboard_fab2(sch_1):page209_vr_pvccin_cpu1_phase5") )
				( attribute "VOLTAGE" "5"
					( Units "uVoltage" "V" 1.000000)
					( Status sAliasFlattened )
					( Origin gFrontEnd )
				)
				( attribute "CDS_PHYS_NET_NAME" "VR_PVCCIN_CPU1_PHASE5"
					( Origin gPackager )
				)
				( objectStatus "VR_PVCCIN_CPU1_PHASE5" )
			)
			( signal "@baseboard_fab2_lib.baseboard_fab2(sch_1):page209_vr_pvccin_cpu1_phase5"
				( attribute "VOLTAGE" "5"
					( Units "uVoltage" "V" 1.000000)
					( Origin gFrontEnd )
				)
				( objectFlag fObjectAlias )
				( objectStatus "page209_vr_pvccin_cpu1_phase5" )
			)
			( signal "@baseboard_fab2_lib.baseboard_fab2(sch_1):tp_pvsa_cpu1_gl_0"
				( attribute "CDS_PHYS_NET_NAME" "TP_PVSA_CPU1_GL_0"
					( Origin gPackager )
				)
				( objectStatus "TP_PVSA_CPU1_GL_0" )
			)
			( signal "@baseboard_fab2_lib.baseboard_fab2(sch_1):tp_pvsa_cpu1_gl_1"
				( attribute "CDS_PHYS_NET_NAME" "TP_PVSA_CPU1_GL_1"
					( Origin gPackager )
				)
				( objectStatus "TP_PVSA_CPU1_GL_1" )
			)
			( signal "@baseboard_fab2_lib.baseboard_fab2(sch_1):vr_pvsa_cpu1_boot"
				( attribute "CDS_PHYS_NET_NAME" "VR_PVSA_CPU1_BOOT"
					( Origin gPackager )
				)
				( objectStatus "VR_PVSA_CPU1_BOOT" )
			)
			( signal "@baseboard_fab2_lib.baseboard_fab2(sch_1):vr_pvsa_cpu1_ocset"
				( attribute "CDS_PHYS_NET_NAME" "VR_PVSA_CPU1_OCSET"
					( Origin gPackager )
				)
				( objectStatus "VR_PVSA_CPU1_OCSET" )
			)
			( signal "@baseboard_fab2_lib.baseboard_fab2(sch_1):vr_pvsa_cpu1_phase"
				( alias ( signalRef "@baseboard_fab2_lib.baseboard_fab2(sch_1):page210_vr_pvsa_cpu1_phase") )
				( attribute "VOLTAGE" "5"
					( Units "uVoltage" "V" 1.000000)
					( Status sAliasFlattened )
					( Origin gFrontEnd )
				)
				( attribute "CDS_PHYS_NET_NAME" "VR_PVSA_CPU1_PHASE"
					( Origin gPackager )
				)
				( objectStatus "VR_PVSA_CPU1_PHASE" )
			)
			( signal "@baseboard_fab2_lib.baseboard_fab2(sch_1):page210_vr_pvsa_cpu1_phase"
				( attribute "VOLTAGE" "5"
					( Units "uVoltage" "V" 1.000000)
					( Origin gFrontEnd )
				)
				( objectFlag fObjectAlias )
				( objectStatus "page210_vr_pvsa_cpu1_phase" )
			)
			( signal "@baseboard_fab2_lib.baseboard_fab2(sch_1):vr_pvsa_cpu1_phase_sw"
				( alias ( signalRef "@baseboard_fab2_lib.baseboard_fab2(sch_1):page210_vr_pvsa_cpu1_phase_sw") )
				( attribute "VOLTAGE" "5"
					( Units "uVoltage" "V" 1.000000)
					( Status sAliasFlattened )
					( Origin gFrontEnd )
				)
				( attribute "CDS_PHYS_NET_NAME" "VR_PVSA_CPU1_PHASE_SW"
					( Origin gPackager )
				)
				( objectStatus "VR_PVSA_CPU1_PHASE_SW" )
			)
			( signal "@baseboard_fab2_lib.baseboard_fab2(sch_1):page210_vr_pvsa_cpu1_phase_sw"
				( attribute "VOLTAGE" "5"
					( Units "uVoltage" "V" 1.000000)
					( Origin gFrontEnd )
				)
				( objectFlag fObjectAlias )
				( objectStatus "page210_vr_pvsa_cpu1_phase_sw" )
			)
			( signal "@baseboard_fab2_lib.baseboard_fab2(sch_1):vr_pvsa_cpu1_vcin"
				( alias ( signalRef "@baseboard_fab2_lib.baseboard_fab2(sch_1):page210_vr_pvsa_cpu1_vcin") )
				( attribute "VOLTAGE" "5"
					( Units "uVoltage" "V" 1.000000)
					( Status sAliasFlattened )
					( Origin gFrontEnd )
				)
				( attribute "CDS_PHYS_NET_NAME" "VR_PVSA_CPU1_VCIN"
					( Origin gPackager )
				)
				( objectStatus "VR_PVSA_CPU1_VCIN" )
			)
			( signal "@baseboard_fab2_lib.baseboard_fab2(sch_1):page210_vr_pvsa_cpu1_vcin"
				( attribute "VOLTAGE" "5"
					( Units "uVoltage" "V" 1.000000)
					( Origin gFrontEnd )
				)
				( objectFlag fObjectAlias )
				( objectStatus "page210_vr_pvsa_cpu1_vcin" )
			)
			( signal "@baseboard_fab2_lib.baseboard_fab2(sch_1):a_tsense_pvccio_cpu0"
				( alias ( signalRef "@baseboard_fab2_lib.baseboard_fab2(sch_1):page211_a_tsense_pvccio_cpu0") )
				( attribute "VOLTAGE" "3.6"
					( Units "uVoltage" "V" 1.000000)
					( Status sAliasFlattened )
					( Origin gFrontEnd )
				)
				( attribute "CDS_PHYS_NET_NAME" "A_TSENSE_PVCCIO_CPU0"
					( Origin gPackager )
				)
				( objectStatus "A_TSENSE_PVCCIO_CPU0" )
			)
			( signal "@baseboard_fab2_lib.baseboard_fab2(sch_1):page211_a_tsense_pvccio_cpu0"
				( attribute "VOLTAGE" "3.6"
					( Units "uVoltage" "V" 1.000000)
					( Origin gFrontEnd )
				)
				( objectFlag fObjectAlias )
				( objectStatus "page211_a_tsense_pvccio_cpu0" )
			)
			( signal "@baseboard_fab2_lib.baseboard_fab2(sch_1):irq_pvccio_cpu0_vrhot_n"
				( attribute "CDS_PHYS_NET_NAME" "IRQ_PVCCIO_CPU0_VRHOT_N"
					( Origin gPackager )
				)
				( objectStatus "IRQ_PVCCIO_CPU0_VRHOT_N" )
			)
			( signal "@baseboard_fab2_lib.baseboard_fab2(sch_1):isense_pvccio_cpu0_ph1_imon"
				( attribute "CDS_PHYS_NET_NAME" "ISENSE_PVCCIO_CPU0_PH1_IMON"
					( Origin gPackager )
				)
				( objectStatus "ISENSE_PVCCIO_CPU0_PH1_IMON" )
			)
			( signal "@baseboard_fab2_lib.baseboard_fab2(sch_1):pu_vr_pvccio_cpu0_fault1"
				( attribute "CDS_PHYS_NET_NAME" "PU_VR_PVCCIO_CPU0_FAULT1"
					( Origin gPackager )
				)
				( objectStatus "PU_VR_PVCCIO_CPU0_FAULT1" )
			)
			( signal "@baseboard_fab2_lib.baseboard_fab2(sch_1):pwrgd_pvccio_cpu0_r"
				( attribute "CDS_PHYS_NET_NAME" "PWRGD_PVCCIO_CPU0_R"
					( Origin gPackager )
				)
				( objectStatus "PWRGD_PVCCIO_CPU0_R" )
			)
			( signal "@baseboard_fab2_lib.baseboard_fab2(sch_1):svid_alert_pvccio_cpu0"
				( attribute "CDS_PHYS_NET_NAME" "SVID_ALERT_PVCCIO_CPU0"
					( Origin gPackager )
				)
				( objectStatus "SVID_ALERT_PVCCIO_CPU0" )
			)
			( signal "@baseboard_fab2_lib.baseboard_fab2(sch_1):svid_clk_pvccio_cpu0"
				( attribute "CDS_PHYS_NET_NAME" "SVID_CLK_PVCCIO_CPU0"
					( Origin gPackager )
				)
				( objectStatus "SVID_CLK_PVCCIO_CPU0" )
			)
			( signal "@baseboard_fab2_lib.baseboard_fab2(sch_1):svid_vdio_pvccio_cpu0"
				( attribute "CDS_PHYS_NET_NAME" "SVID_VDIO_PVCCIO_CPU0"
					( Origin gPackager )
				)
				( objectStatus "SVID_VDIO_PVCCIO_CPU0" )
			)
			( signal "@baseboard_fab2_lib.baseboard_fab2(sch_1):vr_fet_sw_p12v_stby_pvccio_cpu0"
				( alias ( signalRef "@baseboard_fab2_lib.baseboard_fab2(sch_1):page211_vr_fet_sw_p12v_stby_pvccio_cpu0") )
				( alias ( signalRef "@baseboard_fab2_lib.baseboard_fab2(sch_1):page212_vr_fet_sw_p12v_stby_pvccio_cpu0") )
				( attribute "VOLTAGE" "12"
					( Units "uVoltage" "V" 1.000000)
					( Status sAliasFlattened )
					( Origin gFrontEnd )
				)
				( attribute "CDS_PHYS_NET_NAME" "VR_FET_SW_P12V_STBY_PVCCIO_CPU0"
					( Origin gPackager )
				)
				( objectStatus "VR_FET_SW_P12V_STBY_PVCCIO_CPU0" )
			)
			( signal "@baseboard_fab2_lib.baseboard_fab2(sch_1):page211_vr_fet_sw_p12v_stby_pvccio_cpu0"
				( objectFlag fObjectAlias )
				( objectStatus "page211_vr_fet_sw_p12v_stby_pvccio_cpu0" )
			)
			( signal "@baseboard_fab2_lib.baseboard_fab2(sch_1):page212_vr_fet_sw_p12v_stby_pvccio_cpu0"
				( attribute "VOLTAGE" "12"
					( Units "uVoltage" "V" 1.000000)
					( Origin gFrontEnd )
				)
				( objectFlag fObjectAlias )
				( objectStatus "page212_vr_fet_sw_p12v_stby_pvccio_cpu0" )
			)
			( signal "@baseboard_fab2_lib.baseboard_fab2(sch_1):vr_pvccio_cpu0_airef1"
				( attribute "CDS_PHYS_NET_NAME" "VR_PVCCIO_CPU0_AIREF1"
					( Origin gPackager )
				)
				( objectStatus "VR_PVCCIO_CPU0_AIREF1" )
			)
			( signal "@baseboard_fab2_lib.baseboard_fab2(sch_1):vr_pvccio_cpu0_avsp"
				( alias ( signalRef "@baseboard_fab2_lib.baseboard_fab2(sch_1):page211_vr_pvccio_cpu0_avsp") )
				( attribute "VOLTAGE" "2"
					( Units "uVoltage" "V" 1.000000)
					( Status sAliasFlattened )
					( Origin gFrontEnd )
				)
				( attribute "CDS_PHYS_NET_NAME" "VR_PVCCIO_CPU0_AVSP"
					( Origin gPackager )
				)
				( objectStatus "VR_PVCCIO_CPU0_AVSP" )
			)
			( signal "@baseboard_fab2_lib.baseboard_fab2(sch_1):page211_vr_pvccio_cpu0_avsp"
				( attribute "VOLTAGE" "2"
					( Units "uVoltage" "V" 1.000000)
					( Origin gFrontEnd )
				)
				( objectFlag fObjectAlias )
				( objectStatus "page211_vr_pvccio_cpu0_avsp" )
			)
			( signal "@baseboard_fab2_lib.baseboard_fab2(sch_1):vr_pvccio_cpu0_en"
				( attribute "CDS_PHYS_NET_NAME" "VR_PVCCIO_CPU0_EN"
					( Origin gPackager )
				)
				( objectStatus "VR_PVCCIO_CPU0_EN" )
			)
			( signal "@baseboard_fab2_lib.baseboard_fab2(sch_1):vr_pvccio_cpu0_pwm1"
				( alias ( signalRef "@baseboard_fab2_lib.baseboard_fab2(sch_1):page211_vr_pvccio_cpu0_pwm1") )
				( attribute "VOLTAGE" "3.3"
					( Units "uVoltage" "V" 1.000000)
					( Status sAliasFlattened )
					( Origin gFrontEnd )
				)
				( attribute "CDS_PHYS_NET_NAME" "VR_PVCCIO_CPU0_PWM1"
					( Origin gPackager )
				)
				( objectStatus "VR_PVCCIO_CPU0_PWM1" )
			)
			( signal "@baseboard_fab2_lib.baseboard_fab2(sch_1):page211_vr_pvccio_cpu0_pwm1"
				( attribute "VOLTAGE" "3.3"
					( Units "uVoltage" "V" 1.000000)
					( Origin gFrontEnd )
				)
				( objectFlag fObjectAlias )
				( objectStatus "page211_vr_pvccio_cpu0_pwm1" )
			)
			( signal "@baseboard_fab2_lib.baseboard_fab2(sch_1):vr_pvccio_cpu0_vd12"
				( attribute "CDS_PHYS_NET_NAME" "VR_PVCCIO_CPU0_VD12"
					( Origin gPackager )
				)
				( objectStatus "VR_PVCCIO_CPU0_VD12" )
			)
			( signal "@baseboard_fab2_lib.baseboard_fab2(sch_1):vr_pvccio_cpu0_vdd"
				( attribute "CDS_PHYS_NET_NAME" "VR_PVCCIO_CPU0_VDD"
					( Origin gPackager )
				)
				( objectStatus "VR_PVCCIO_CPU0_VDD" )
			)
			( signal "@baseboard_fab2_lib.baseboard_fab2(sch_1):vr_pvccio_cpu0_vinsen"
				( alias ( signalRef "@baseboard_fab2_lib.baseboard_fab2(sch_1):page211_vr_pvccio_cpu0_vinsen") )
				( attribute "VOLTAGE" "0.8"
					( Units "uVoltage" "V" 1.000000)
					( Status sAliasFlattened )
					( Origin gFrontEnd )
				)
				( attribute "CDS_PHYS_NET_NAME" "VR_PVCCIO_CPU0_VINSEN"
					( Origin gPackager )
				)
				( objectStatus "VR_PVCCIO_CPU0_VINSEN" )
			)
			( signal "@baseboard_fab2_lib.baseboard_fab2(sch_1):page211_vr_pvccio_cpu0_vinsen"
				( attribute "VOLTAGE" "0.8"
					( Units "uVoltage" "V" 1.000000)
					( Origin gFrontEnd )
				)
				( objectFlag fObjectAlias )
				( objectStatus "page211_vr_pvccio_cpu0_vinsen" )
			)
			( signal "@baseboard_fab2_lib.baseboard_fab2(sch_1):vr_pvccio_cpu0_xaddr1"
				( alias ( signalRef "@baseboard_fab2_lib.baseboard_fab2(sch_1):page211_vr_pvccio_cpu0_xaddr1") )
				( attribute "VOLTAGE" "3.3"
					( Units "uVoltage" "V" 1.000000)
					( Status sAliasFlattened )
					( Origin gFrontEnd )
				)
				( attribute "CDS_PHYS_NET_NAME" "VR_PVCCIO_CPU0_XADDR1"
					( Origin gPackager )
				)
				( objectStatus "VR_PVCCIO_CPU0_XADDR1" )
			)
			( signal "@baseboard_fab2_lib.baseboard_fab2(sch_1):page211_vr_pvccio_cpu0_xaddr1"
				( attribute "VOLTAGE" "3.3"
					( Units "uVoltage" "V" 1.000000)
					( Origin gFrontEnd )
				)
				( objectFlag fObjectAlias )
				( objectStatus "page211_vr_pvccio_cpu0_xaddr1" )
			)
			( signal "@baseboard_fab2_lib.baseboard_fab2(sch_1):vr_pvccio_cpu0_xaddr2"
				( alias ( signalRef "@baseboard_fab2_lib.baseboard_fab2(sch_1):page211_vr_pvccio_cpu0_xaddr2") )
				( attribute "VOLTAGE" "3.3V"
					( Units "uVoltage" "V" 1.000000)
					( Status sAliasFlattened )
					( Origin gFrontEnd )
				)
				( attribute "CDS_PHYS_NET_NAME" "VR_PVCCIO_CPU0_XADDR2"
					( Origin gPackager )
				)
				( objectStatus "VR_PVCCIO_CPU0_XADDR2" )
			)
			( signal "@baseboard_fab2_lib.baseboard_fab2(sch_1):page211_vr_pvccio_cpu0_xaddr2"
				( attribute "VOLTAGE" "3.3V"
					( Units "uVoltage" "V" 1.000000)
					( Origin gFrontEnd )
				)
				( objectFlag fObjectAlias )
				( objectStatus "page211_vr_pvccio_cpu0_xaddr2" )
			)
			( signal "@baseboard_fab2_lib.baseboard_fab2(sch_1):vsense_pvccio_cpu0_avsn"
				( attribute "CDS_PHYS_NET_NAME" "VSENSE_PVCCIO_CPU0_AVSN"
					( Origin gPackager )
				)
				( objectStatus "VSENSE_PVCCIO_CPU0_AVSN" )
			)
			( signal "@baseboard_fab2_lib.baseboard_fab2(sch_1):vsense_pvccio_cpu0_avsp"
				( attribute "CDS_PHYS_NET_NAME" "VSENSE_PVCCIO_CPU0_AVSP"
					( Origin gPackager )
				)
				( objectStatus "VSENSE_PVCCIO_CPU0_AVSP" )
			)
			( signal "@baseboard_fab2_lib.baseboard_fab2(sch_1):tp_pvccio_cpu0_gl_0"
				( attribute "CDS_PHYS_NET_NAME" "TP_PVCCIO_CPU0_GL_0"
					( Origin gPackager )
				)
				( objectStatus "TP_PVCCIO_CPU0_GL_0" )
			)
			( signal "@baseboard_fab2_lib.baseboard_fab2(sch_1):tp_pvccio_cpu0_gl_1"
				( attribute "CDS_PHYS_NET_NAME" "TP_PVCCIO_CPU0_GL_1"
					( Origin gPackager )
				)
				( objectStatus "TP_PVCCIO_CPU0_GL_1" )
			)
			( signal "@baseboard_fab2_lib.baseboard_fab2(sch_1):vr_pvccio_cpu0_ocset"
				( attribute "CDS_PHYS_NET_NAME" "VR_PVCCIO_CPU0_OCSET"
					( Origin gPackager )
				)
				( objectStatus "VR_PVCCIO_CPU0_OCSET" )
			)
			( signal "@baseboard_fab2_lib.baseboard_fab2(sch_1):vr_pvccio_cpu0_ph1_boot"
				( attribute "CDS_PHYS_NET_NAME" "VR_PVCCIO_CPU0_PH1_BOOT"
					( Origin gPackager )
				)
				( objectStatus "VR_PVCCIO_CPU0_PH1_BOOT" )
			)
			( signal "@baseboard_fab2_lib.baseboard_fab2(sch_1):vr_pvccio_cpu0_ph1_phase"
				( alias ( signalRef "@baseboard_fab2_lib.baseboard_fab2(sch_1):page212_vr_pvccio_cpu0_ph1_phase") )
				( attribute "VOLTAGE" "5"
					( Units "uVoltage" "V" 1.000000)
					( Status sAliasFlattened )
					( Origin gFrontEnd )
				)
				( attribute "CDS_PHYS_NET_NAME" "VR_PVCCIO_CPU0_PH1_PHASE"
					( Origin gPackager )
				)
				( objectStatus "VR_PVCCIO_CPU0_PH1_PHASE" )
			)
			( signal "@baseboard_fab2_lib.baseboard_fab2(sch_1):page212_vr_pvccio_cpu0_ph1_phase"
				( attribute "VOLTAGE" "5"
					( Units "uVoltage" "V" 1.000000)
					( Origin gFrontEnd )
				)
				( objectFlag fObjectAlias )
				( objectStatus "page212_vr_pvccio_cpu0_ph1_phase" )
			)
			( signal "@baseboard_fab2_lib.baseboard_fab2(sch_1):vr_pvccio_cpu0_ph1_sw"
				( alias ( signalRef "@baseboard_fab2_lib.baseboard_fab2(sch_1):page212_vr_pvccio_cpu0_ph1_sw") )
				( attribute "VOLTAGE" "5"
					( Units "uVoltage" "V" 1.000000)
					( Status sAliasFlattened )
					( Origin gFrontEnd )
				)
				( attribute "CDS_PHYS_NET_NAME" "VR_PVCCIO_CPU0_PH1_SW"
					( Origin gPackager )
				)
				( objectStatus "VR_PVCCIO_CPU0_PH1_SW" )
			)
			( signal "@baseboard_fab2_lib.baseboard_fab2(sch_1):page212_vr_pvccio_cpu0_ph1_sw"
				( attribute "VOLTAGE" "5"
					( Units "uVoltage" "V" 1.000000)
					( Origin gFrontEnd )
				)
				( objectFlag fObjectAlias )
				( objectStatus "page212_vr_pvccio_cpu0_ph1_sw" )
			)
			( signal "@baseboard_fab2_lib.baseboard_fab2(sch_1):vr_pvccio_cpu0_ph1_vcin"
				( alias ( signalRef "@baseboard_fab2_lib.baseboard_fab2(sch_1):page212_vr_pvccio_cpu0_ph1_vcin") )
				( attribute "VOLTAGE" "5"
					( Units "uVoltage" "V" 1.000000)
					( Status sAliasFlattened )
					( Origin gFrontEnd )
				)
				( attribute "CDS_PHYS_NET_NAME" "VR_PVCCIO_CPU0_PH1_VCIN"
					( Origin gPackager )
				)
				( objectStatus "VR_PVCCIO_CPU0_PH1_VCIN" )
			)
			( signal "@baseboard_fab2_lib.baseboard_fab2(sch_1):page212_vr_pvccio_cpu0_ph1_vcin"
				( attribute "VOLTAGE" "5"
					( Units "uVoltage" "V" 1.000000)
					( Origin gFrontEnd )
				)
				( objectFlag fObjectAlias )
				( objectStatus "page212_vr_pvccio_cpu0_ph1_vcin" )
			)
			( signal "@baseboard_fab2_lib.baseboard_fab2(sch_1):a_tsense_pvccio_cpu1"
				( attribute "CDS_PHYS_NET_NAME" "A_TSENSE_PVCCIO_CPU1"
					( Origin gPackager )
				)
				( objectStatus "A_TSENSE_PVCCIO_CPU1" )
			)
			( signal "@baseboard_fab2_lib.baseboard_fab2(sch_1):irq_pvccio_cpu1_vrhot_n"
				( attribute "CDS_PHYS_NET_NAME" "IRQ_PVCCIO_CPU1_VRHOT_N"
					( Origin gPackager )
				)
				( objectStatus "IRQ_PVCCIO_CPU1_VRHOT_N" )
			)
			( signal "@baseboard_fab2_lib.baseboard_fab2(sch_1):isense_pvccio_cpu1_ph1_imon"
				( attribute "CDS_PHYS_NET_NAME" "ISENSE_PVCCIO_CPU1_PH1_IMON"
					( Origin gPackager )
				)
				( objectStatus "ISENSE_PVCCIO_CPU1_PH1_IMON" )
			)
			( signal "@baseboard_fab2_lib.baseboard_fab2(sch_1):pu_vr_pvccio_cpu1_fault1"
				( attribute "CDS_PHYS_NET_NAME" "PU_VR_PVCCIO_CPU1_FAULT1"
					( Origin gPackager )
				)
				( objectStatus "PU_VR_PVCCIO_CPU1_FAULT1" )
			)
			( signal "@baseboard_fab2_lib.baseboard_fab2(sch_1):pwrgd_pvccio_cpu1_r"
				( attribute "CDS_PHYS_NET_NAME" "PWRGD_PVCCIO_CPU1_R"
					( Origin gPackager )
				)
				( objectStatus "PWRGD_PVCCIO_CPU1_R" )
			)
			( signal "@baseboard_fab2_lib.baseboard_fab2(sch_1):svid_alert_pvccio_cpu1"
				( attribute "CDS_PHYS_NET_NAME" "SVID_ALERT_PVCCIO_CPU1"
					( Origin gPackager )
				)
				( objectStatus "SVID_ALERT_PVCCIO_CPU1" )
			)
			( signal "@baseboard_fab2_lib.baseboard_fab2(sch_1):svid_clk_pvccio_cpu1"
				( attribute "CDS_PHYS_NET_NAME" "SVID_CLK_PVCCIO_CPU1"
					( Origin gPackager )
				)
				( objectStatus "SVID_CLK_PVCCIO_CPU1" )
			)
			( signal "@baseboard_fab2_lib.baseboard_fab2(sch_1):svid_vdio_pvccio_cpu1"
				( attribute "CDS_PHYS_NET_NAME" "SVID_VDIO_PVCCIO_CPU1"
					( Origin gPackager )
				)
				( objectStatus "SVID_VDIO_PVCCIO_CPU1" )
			)
			( signal "@baseboard_fab2_lib.baseboard_fab2(sch_1):vr_pvccio_cpu1_airef1"
				( attribute "CDS_PHYS_NET_NAME" "VR_PVCCIO_CPU1_AIREF1"
					( Origin gPackager )
				)
				( objectStatus "VR_PVCCIO_CPU1_AIREF1" )
			)
			( signal "@baseboard_fab2_lib.baseboard_fab2(sch_1):vr_pvccio_cpu1_avsp"
				( alias ( signalRef "@baseboard_fab2_lib.baseboard_fab2(sch_1):page213_vr_pvccio_cpu1_avsp") )
				( attribute "VOLTAGE" "1.05"
					( Units "uVoltage" "V" 1.000000)
					( Status sAliasFlattened )
					( Origin gFrontEnd )
				)
				( attribute "CDS_PHYS_NET_NAME" "VR_PVCCIO_CPU1_AVSP"
					( Origin gPackager )
				)
				( objectStatus "VR_PVCCIO_CPU1_AVSP" )
			)
			( signal "@baseboard_fab2_lib.baseboard_fab2(sch_1):page213_vr_pvccio_cpu1_avsp"
				( attribute "VOLTAGE" "1.05"
					( Units "uVoltage" "V" 1.000000)
					( Origin gFrontEnd )
				)
				( objectFlag fObjectAlias )
				( objectStatus "page213_vr_pvccio_cpu1_avsp" )
			)
			( signal "@baseboard_fab2_lib.baseboard_fab2(sch_1):vr_pvccio_cpu1_en"
				( alias ( signalRef "@baseboard_fab2_lib.baseboard_fab2(sch_1):page213_vr_pvccio_cpu1_en") )
				( attribute "VOLTAGE" "3.3"
					( Units "uVoltage" "V" 1.000000)
					( Status sAliasFlattened )
					( Origin gFrontEnd )
				)
				( attribute "CDS_PHYS_NET_NAME" "VR_PVCCIO_CPU1_EN"
					( Origin gPackager )
				)
				( objectStatus "VR_PVCCIO_CPU1_EN" )
			)
			( signal "@baseboard_fab2_lib.baseboard_fab2(sch_1):page213_vr_pvccio_cpu1_en"
				( attribute "VOLTAGE" "3.3"
					( Units "uVoltage" "V" 1.000000)
					( Origin gFrontEnd )
				)
				( objectFlag fObjectAlias )
				( objectStatus "page213_vr_pvccio_cpu1_en" )
			)
			( signal "@baseboard_fab2_lib.baseboard_fab2(sch_1):vr_pvccio_cpu1_pwm1"
				( alias ( signalRef "@baseboard_fab2_lib.baseboard_fab2(sch_1):page213_vr_pvccio_cpu1_pwm1") )
				( attribute "VOLTAGE" "3.6"
					( Units "uVoltage" "V" 1.000000)
					( Status sAliasFlattened )
					( Origin gFrontEnd )
				)
				( attribute "CDS_PHYS_NET_NAME" "VR_PVCCIO_CPU1_PWM1"
					( Origin gPackager )
				)
				( objectStatus "VR_PVCCIO_CPU1_PWM1" )
			)
			( signal "@baseboard_fab2_lib.baseboard_fab2(sch_1):page213_vr_pvccio_cpu1_pwm1"
				( attribute "VOLTAGE" "3.6"
					( Units "uVoltage" "V" 1.000000)
					( Origin gFrontEnd )
				)
				( objectFlag fObjectAlias )
				( objectStatus "page213_vr_pvccio_cpu1_pwm1" )
			)
			( signal "@baseboard_fab2_lib.baseboard_fab2(sch_1):vr_pvccio_cpu1_vd12"
				( attribute "CDS_PHYS_NET_NAME" "VR_PVCCIO_CPU1_VD12"
					( Origin gPackager )
				)
				( objectStatus "VR_PVCCIO_CPU1_VD12" )
			)
			( signal "@baseboard_fab2_lib.baseboard_fab2(sch_1):vr_pvccio_cpu1_vdd"
				( alias ( signalRef "@baseboard_fab2_lib.baseboard_fab2(sch_1):page213_vr_pvccio_cpu1_vdd") )
				( attribute "VOLTAGE" "3.3"
					( Units "uVoltage" "V" 1.000000)
					( Status sAliasFlattened )
					( Origin gFrontEnd )
				)
				( attribute "CDS_PHYS_NET_NAME" "VR_PVCCIO_CPU1_VDD"
					( Origin gPackager )
				)
				( objectStatus "VR_PVCCIO_CPU1_VDD" )
			)
			( signal "@baseboard_fab2_lib.baseboard_fab2(sch_1):page213_vr_pvccio_cpu1_vdd"
				( attribute "VOLTAGE" "3.3"
					( Units "uVoltage" "V" 1.000000)
					( Origin gFrontEnd )
				)
				( objectFlag fObjectAlias )
				( objectStatus "page213_vr_pvccio_cpu1_vdd" )
			)
			( signal "@baseboard_fab2_lib.baseboard_fab2(sch_1):vr_pvccio_cpu1_vinsen"
				( attribute "CDS_PHYS_NET_NAME" "VR_PVCCIO_CPU1_VINSEN"
					( Origin gPackager )
				)
				( objectStatus "VR_PVCCIO_CPU1_VINSEN" )
			)
			( signal "@baseboard_fab2_lib.baseboard_fab2(sch_1):vr_pvccio_cpu1_xaddr1"
				( alias ( signalRef "@baseboard_fab2_lib.baseboard_fab2(sch_1):page213_vr_pvccio_cpu1_xaddr1") )
				( attribute "VOLTAGE" "3.3"
					( Units "uVoltage" "V" 1.000000)
					( Status sAliasFlattened )
					( Origin gFrontEnd )
				)
				( attribute "CDS_PHYS_NET_NAME" "VR_PVCCIO_CPU1_XADDR1"
					( Origin gPackager )
				)
				( objectStatus "VR_PVCCIO_CPU1_XADDR1" )
			)
			( signal "@baseboard_fab2_lib.baseboard_fab2(sch_1):page213_vr_pvccio_cpu1_xaddr1"
				( attribute "VOLTAGE" "3.3"
					( Units "uVoltage" "V" 1.000000)
					( Origin gFrontEnd )
				)
				( objectFlag fObjectAlias )
				( objectStatus "page213_vr_pvccio_cpu1_xaddr1" )
			)
			( signal "@baseboard_fab2_lib.baseboard_fab2(sch_1):vr_pvccio_cpu1_xaddr2"
				( alias ( signalRef "@baseboard_fab2_lib.baseboard_fab2(sch_1):page213_vr_pvccio_cpu1_xaddr2") )
				( attribute "VOLTAGE" "3.3"
					( Units "uVoltage" "V" 1.000000)
					( Status sAliasFlattened )
					( Origin gFrontEnd )
				)
				( attribute "CDS_PHYS_NET_NAME" "VR_PVCCIO_CPU1_XADDR2"
					( Origin gPackager )
				)
				( objectStatus "VR_PVCCIO_CPU1_XADDR2" )
			)
			( signal "@baseboard_fab2_lib.baseboard_fab2(sch_1):page213_vr_pvccio_cpu1_xaddr2"
				( attribute "VOLTAGE" "3.3"
					( Units "uVoltage" "V" 1.000000)
					( Origin gFrontEnd )
				)
				( objectFlag fObjectAlias )
				( objectStatus "page213_vr_pvccio_cpu1_xaddr2" )
			)
			( signal "@baseboard_fab2_lib.baseboard_fab2(sch_1):vsense_pvccio_cpu1_avsn"
				( attribute "CDS_PHYS_NET_NAME" "VSENSE_PVCCIO_CPU1_AVSN"
					( Origin gPackager )
				)
				( objectStatus "VSENSE_PVCCIO_CPU1_AVSN" )
			)
			( signal "@baseboard_fab2_lib.baseboard_fab2(sch_1):vsense_pvccio_cpu1_avsp"
				( attribute "CDS_PHYS_NET_NAME" "VSENSE_PVCCIO_CPU1_AVSP"
					( Origin gPackager )
				)
				( objectStatus "VSENSE_PVCCIO_CPU1_AVSP" )
			)
			( signal "@baseboard_fab2_lib.baseboard_fab2(sch_1):tp_pvccio_cpu1_gl_0"
				( attribute "CDS_PHYS_NET_NAME" "TP_PVCCIO_CPU1_GL_0"
					( Origin gPackager )
				)
				( objectStatus "TP_PVCCIO_CPU1_GL_0" )
			)
			( signal "@baseboard_fab2_lib.baseboard_fab2(sch_1):tp_pvccio_cpu1_gl_1"
				( attribute "CDS_PHYS_NET_NAME" "TP_PVCCIO_CPU1_GL_1"
					( Origin gPackager )
				)
				( objectStatus "TP_PVCCIO_CPU1_GL_1" )
			)
			( signal "@baseboard_fab2_lib.baseboard_fab2(sch_1):vr_pvccio_cpu1_ocset"
				( attribute "CDS_PHYS_NET_NAME" "VR_PVCCIO_CPU1_OCSET"
					( Origin gPackager )
				)
				( objectStatus "VR_PVCCIO_CPU1_OCSET" )
			)
			( signal "@baseboard_fab2_lib.baseboard_fab2(sch_1):vr_pvccio_cpu1_ph1_boot"
				( attribute "CDS_PHYS_NET_NAME" "VR_PVCCIO_CPU1_PH1_BOOT"
					( Origin gPackager )
				)
				( objectStatus "VR_PVCCIO_CPU1_PH1_BOOT" )
			)
			( signal "@baseboard_fab2_lib.baseboard_fab2(sch_1):vr_pvccio_cpu1_ph1_phase"
				( attribute "CDS_PHYS_NET_NAME" "VR_PVCCIO_CPU1_PH1_PHASE"
					( Origin gPackager )
				)
				( objectStatus "VR_PVCCIO_CPU1_PH1_PHASE" )
			)
			( signal "@baseboard_fab2_lib.baseboard_fab2(sch_1):vr_pvccio_cpu1_ph1_sw"
				( attribute "CDS_PHYS_NET_NAME" "VR_PVCCIO_CPU1_PH1_SW"
					( Origin gPackager )
				)
				( objectStatus "VR_PVCCIO_CPU1_PH1_SW" )
			)
			( signal "@baseboard_fab2_lib.baseboard_fab2(sch_1):vr_pvccio_cpu1_ph1_vcin"
				( attribute "CDS_PHYS_NET_NAME" "VR_PVCCIO_CPU1_PH1_VCIN"
					( Origin gPackager )
				)
				( objectStatus "VR_PVCCIO_CPU1_PH1_VCIN" )
			)
			( signal "@baseboard_fab2_lib.baseboard_fab2(sch_1):a_tsense_pvddq_abc"
				( attribute "CDS_PHYS_NET_NAME" "A_TSENSE_PVDDQ_ABC"
					( Origin gPackager )
				)
				( objectStatus "A_TSENSE_PVDDQ_ABC" )
			)
			( signal "@baseboard_fab2_lib.baseboard_fab2(sch_1):irq_pvddq_abc_vrhot_lvt3_r_n"
				( attribute "CDS_PHYS_NET_NAME" "IRQ_PVDDQ_ABC_VRHOT_LVT3_R_N"
					( Origin gPackager )
				)
				( objectStatus "IRQ_PVDDQ_ABC_VRHOT_LVT3_R_N" )
			)
			( signal "@baseboard_fab2_lib.baseboard_fab2(sch_1):isense_pvddq_abc_ph1_imon"
				( attribute "CDS_PHYS_NET_NAME" "ISENSE_PVDDQ_ABC_PH1_IMON"
					( Origin gPackager )
				)
				( objectStatus "ISENSE_PVDDQ_ABC_PH1_IMON" )
			)
			( signal "@baseboard_fab2_lib.baseboard_fab2(sch_1):isense_pvddq_abc_ph2_imon"
				( attribute "CDS_PHYS_NET_NAME" "ISENSE_PVDDQ_ABC_PH2_IMON"
					( Origin gPackager )
				)
				( objectStatus "ISENSE_PVDDQ_ABC_PH2_IMON" )
			)
			( signal "@baseboard_fab2_lib.baseboard_fab2(sch_1):pu_vr_pvddq_abc_fault1"
				( attribute "CDS_PHYS_NET_NAME" "PU_VR_PVDDQ_ABC_FAULT1"
					( Origin gPackager )
				)
				( objectStatus "PU_VR_PVDDQ_ABC_FAULT1" )
			)
			( signal "@baseboard_fab2_lib.baseboard_fab2(sch_1):pwrgd_pvddq_abc"
				( attribute "CDS_PHYS_NET_NAME" "PWRGD_PVDDQ_ABC"
					( Origin gPackager )
				)
				( objectStatus "PWRGD_PVDDQ_ABC" )
			)
			( signal "@baseboard_fab2_lib.baseboard_fab2(sch_1):pwrgd_pvddq_abc_r"
				( attribute "CDS_PHYS_NET_NAME" "PWRGD_PVDDQ_ABC_R"
					( Origin gPackager )
				)
				( objectStatus "PWRGD_PVDDQ_ABC_R" )
			)
			( signal "@baseboard_fab2_lib.baseboard_fab2(sch_1):svid_alert_pvddq_abc"
				( attribute "CDS_PHYS_NET_NAME" "SVID_ALERT_PVDDQ_ABC"
					( Origin gPackager )
				)
				( objectStatus "SVID_ALERT_PVDDQ_ABC" )
			)
			( signal "@baseboard_fab2_lib.baseboard_fab2(sch_1):svid_clk_pvddq_abc"
				( attribute "CDS_PHYS_NET_NAME" "SVID_CLK_PVDDQ_ABC"
					( Origin gPackager )
				)
				( objectStatus "SVID_CLK_PVDDQ_ABC" )
			)
			( signal "@baseboard_fab2_lib.baseboard_fab2(sch_1):svid_vdio_pvddq_abc"
				( attribute "CDS_PHYS_NET_NAME" "SVID_VDIO_PVDDQ_ABC"
					( Origin gPackager )
				)
				( objectStatus "SVID_VDIO_PVDDQ_ABC" )
			)
			( signal "@baseboard_fab2_lib.baseboard_fab2(sch_1):tp_pvddq_abc_mp1"
				( attribute "CDS_PHYS_NET_NAME" "TP_PVDDQ_ABC_MP1"
					( Origin gPackager )
				)
				( objectStatus "TP_PVDDQ_ABC_MP1" )
			)
			( signal "@baseboard_fab2_lib.baseboard_fab2(sch_1):tp_pvddq_abc_mp2"
				( attribute "CDS_PHYS_NET_NAME" "TP_PVDDQ_ABC_MP2"
					( Origin gPackager )
				)
				( objectStatus "TP_PVDDQ_ABC_MP2" )
			)
			( signal "@baseboard_fab2_lib.baseboard_fab2(sch_1):vr_fet_sw_p12v_stby_pvddq_abc"
				( alias ( signalRef "@baseboard_fab2_lib.baseboard_fab2(sch_1):page216_vr_fet_sw_p12v_stby_pvddq_abc") )
				( alias ( signalRef "@baseboard_fab2_lib.baseboard_fab2(sch_1):page217_vr_fet_sw_p12v_stby_pvddq_abc") )
				( attribute "CDS_PHYS_NET_NAME" "VR_FET_SW_P12V_STBY_PVDDQ_ABC"
					( Origin gPackager )
				)
				( objectStatus "VR_FET_SW_P12V_STBY_PVDDQ_ABC" )
			)
			( signal "@baseboard_fab2_lib.baseboard_fab2(sch_1):page216_vr_fet_sw_p12v_stby_pvddq_abc"
				( objectFlag fObjectAlias )
				( objectStatus "page216_vr_fet_sw_p12v_stby_pvddq_abc" )
			)
			( signal "@baseboard_fab2_lib.baseboard_fab2(sch_1):page217_vr_fet_sw_p12v_stby_pvddq_abc"
				( objectFlag fObjectAlias )
				( objectStatus "page217_vr_fet_sw_p12v_stby_pvddq_abc" )
			)
			( signal "@baseboard_fab2_lib.baseboard_fab2(sch_1):vr_pvddq_abc_airef1"
				( attribute "CDS_PHYS_NET_NAME" "VR_PVDDQ_ABC_AIREF1"
					( Origin gPackager )
				)
				( objectStatus "VR_PVDDQ_ABC_AIREF1" )
			)
			( signal "@baseboard_fab2_lib.baseboard_fab2(sch_1):vr_pvddq_abc_airef2"
				( attribute "CDS_PHYS_NET_NAME" "VR_PVDDQ_ABC_AIREF2"
					( Origin gPackager )
				)
				( objectStatus "VR_PVDDQ_ABC_AIREF2" )
			)
			( signal "@baseboard_fab2_lib.baseboard_fab2(sch_1):vr_pvddq_abc_avsp"
				( attribute "CDS_PHYS_NET_NAME" "VR_PVDDQ_ABC_AVSP"
					( Origin gPackager )
				)
				( objectStatus "VR_PVDDQ_ABC_AVSP" )
			)
			( signal "@baseboard_fab2_lib.baseboard_fab2(sch_1):vr_pvddq_abc_pwm1"
				( attribute "CDS_PHYS_NET_NAME" "VR_PVDDQ_ABC_PWM1"
					( Origin gPackager )
				)
				( objectStatus "VR_PVDDQ_ABC_PWM1" )
			)
			( signal "@baseboard_fab2_lib.baseboard_fab2(sch_1):vr_pvddq_abc_pwm2"
				( attribute "CDS_PHYS_NET_NAME" "VR_PVDDQ_ABC_PWM2"
					( Origin gPackager )
				)
				( objectStatus "VR_PVDDQ_ABC_PWM2" )
			)
			( signal "@baseboard_fab2_lib.baseboard_fab2(sch_1):vr_pvddq_abc_vd12"
				( attribute "CDS_PHYS_NET_NAME" "VR_PVDDQ_ABC_VD12"
					( Origin gPackager )
				)
				( objectStatus "VR_PVDDQ_ABC_VD12" )
			)
			( signal "@baseboard_fab2_lib.baseboard_fab2(sch_1):vr_pvddq_abc_vdd"
				( attribute "CDS_PHYS_NET_NAME" "VR_PVDDQ_ABC_VDD"
					( Origin gPackager )
				)
				( objectStatus "VR_PVDDQ_ABC_VDD" )
			)
			( signal "@baseboard_fab2_lib.baseboard_fab2(sch_1):vr_pvddq_abc_vinsen"
				( attribute "CDS_PHYS_NET_NAME" "VR_PVDDQ_ABC_VINSEN"
					( Origin gPackager )
				)
				( objectStatus "VR_PVDDQ_ABC_VINSEN" )
			)
			( signal "@baseboard_fab2_lib.baseboard_fab2(sch_1):vr_pvddq_abc_vren"
				( attribute "CDS_PHYS_NET_NAME" "VR_PVDDQ_ABC_VREN"
					( Origin gPackager )
				)
				( objectStatus "VR_PVDDQ_ABC_VREN" )
			)
			( signal "@baseboard_fab2_lib.baseboard_fab2(sch_1):vr_pvddq_abc_xaddr1"
				( attribute "CDS_PHYS_NET_NAME" "VR_PVDDQ_ABC_XADDR1"
					( Origin gPackager )
				)
				( objectStatus "VR_PVDDQ_ABC_XADDR1" )
			)
			( signal "@baseboard_fab2_lib.baseboard_fab2(sch_1):vr_pvddq_abc_xaddr2"
				( attribute "CDS_PHYS_NET_NAME" "VR_PVDDQ_ABC_XADDR2"
					( Origin gPackager )
				)
				( objectStatus "VR_PVDDQ_ABC_XADDR2" )
			)
			( signal "@baseboard_fab2_lib.baseboard_fab2(sch_1):vsense_pvddq_abc_n"
				( attribute "CDS_PHYS_NET_NAME" "VSENSE_PVDDQ_ABC_N"
					( Origin gPackager )
				)
				( objectStatus "VSENSE_PVDDQ_ABC_N" )
			)
			( signal "@baseboard_fab2_lib.baseboard_fab2(sch_1):vsense_pvddq_abc_p"
				( attribute "CDS_PHYS_NET_NAME" "VSENSE_PVDDQ_ABC_P"
					( Origin gPackager )
				)
				( objectStatus "VSENSE_PVDDQ_ABC_P" )
			)
			( signal "@baseboard_fab2_lib.baseboard_fab2(sch_1):tp_pvddq_abc_ph1_gl_0"
				( attribute "CDS_PHYS_NET_NAME" "TP_PVDDQ_ABC_PH1_GL_0"
					( Origin gPackager )
				)
				( objectStatus "TP_PVDDQ_ABC_PH1_GL_0" )
			)
			( signal "@baseboard_fab2_lib.baseboard_fab2(sch_1):tp_pvddq_abc_ph1_gl_1"
				( attribute "CDS_PHYS_NET_NAME" "TP_PVDDQ_ABC_PH1_GL_1"
					( Origin gPackager )
				)
				( objectStatus "TP_PVDDQ_ABC_PH1_GL_1" )
			)
			( signal "@baseboard_fab2_lib.baseboard_fab2(sch_1):tp_pvddq_abc_ph2_gl_0"
				( attribute "CDS_PHYS_NET_NAME" "TP_PVDDQ_ABC_PH2_GL_0"
					( Origin gPackager )
				)
				( objectStatus "TP_PVDDQ_ABC_PH2_GL_0" )
			)
			( signal "@baseboard_fab2_lib.baseboard_fab2(sch_1):tp_pvddq_abc_ph2_gl_1"
				( attribute "CDS_PHYS_NET_NAME" "TP_PVDDQ_ABC_PH2_GL_1"
					( Origin gPackager )
				)
				( objectStatus "TP_PVDDQ_ABC_PH2_GL_1" )
			)
			( signal "@baseboard_fab2_lib.baseboard_fab2(sch_1):vr_pvddq_abc_ph1_boot"
				( attribute "CDS_PHYS_NET_NAME" "VR_PVDDQ_ABC_PH1_BOOT"
					( Origin gPackager )
				)
				( objectStatus "VR_PVDDQ_ABC_PH1_BOOT" )
			)
			( signal "@baseboard_fab2_lib.baseboard_fab2(sch_1):vr_pvddq_abc_ph1_ocset"
				( alias ( signalRef "@baseboard_fab2_lib.baseboard_fab2(sch_1):page216_vr_pvddq_abc_ph1_ocset") )
				( attribute "VOLTAGE" "3.6"
					( Units "uVoltage" "V" 1.000000)
					( Status sAliasFlattened )
					( Origin gFrontEnd )
				)
				( attribute "CDS_PHYS_NET_NAME" "VR_PVDDQ_ABC_PH1_OCSET"
					( Origin gPackager )
				)
				( objectStatus "VR_PVDDQ_ABC_PH1_OCSET" )
			)
			( signal "@baseboard_fab2_lib.baseboard_fab2(sch_1):page216_vr_pvddq_abc_ph1_ocset"
				( attribute "VOLTAGE" "3.6"
					( Units "uVoltage" "V" 1.000000)
					( Origin gFrontEnd )
				)
				( objectFlag fObjectAlias )
				( objectStatus "page216_vr_pvddq_abc_ph1_ocset" )
			)
			( signal "@baseboard_fab2_lib.baseboard_fab2(sch_1):vr_pvddq_abc_ph1_phase"
				( attribute "CDS_PHYS_NET_NAME" "VR_PVDDQ_ABC_PH1_PHASE"
					( Origin gPackager )
				)
				( objectStatus "VR_PVDDQ_ABC_PH1_PHASE" )
			)
			( signal "@baseboard_fab2_lib.baseboard_fab2(sch_1):vr_pvddq_abc_ph1_sw"
				( attribute "CDS_PHYS_NET_NAME" "VR_PVDDQ_ABC_PH1_SW"
					( Origin gPackager )
				)
				( objectStatus "VR_PVDDQ_ABC_PH1_SW" )
			)
			( signal "@baseboard_fab2_lib.baseboard_fab2(sch_1):vr_pvddq_abc_ph1_vcin"
				( attribute "CDS_PHYS_NET_NAME" "VR_PVDDQ_ABC_PH1_VCIN"
					( Origin gPackager )
				)
				( objectStatus "VR_PVDDQ_ABC_PH1_VCIN" )
			)
			( signal "@baseboard_fab2_lib.baseboard_fab2(sch_1):vr_pvddq_abc_ph2_boot"
				( attribute "CDS_PHYS_NET_NAME" "VR_PVDDQ_ABC_PH2_BOOT"
					( Origin gPackager )
				)
				( objectStatus "VR_PVDDQ_ABC_PH2_BOOT" )
			)
			( signal "@baseboard_fab2_lib.baseboard_fab2(sch_1):vr_pvddq_abc_ph2_ocset"
				( alias ( signalRef "@baseboard_fab2_lib.baseboard_fab2(sch_1):page216_vr_pvddq_abc_ph2_ocset") )
				( attribute "VOLTAGE" "3.6"
					( Units "uVoltage" "V" 1.000000)
					( Status sAliasFlattened )
					( Origin gFrontEnd )
				)
				( attribute "CDS_PHYS_NET_NAME" "VR_PVDDQ_ABC_PH2_OCSET"
					( Origin gPackager )
				)
				( objectStatus "VR_PVDDQ_ABC_PH2_OCSET" )
			)
			( signal "@baseboard_fab2_lib.baseboard_fab2(sch_1):page216_vr_pvddq_abc_ph2_ocset"
				( attribute "VOLTAGE" "3.6"
					( Units "uVoltage" "V" 1.000000)
					( Origin gFrontEnd )
				)
				( objectFlag fObjectAlias )
				( objectStatus "page216_vr_pvddq_abc_ph2_ocset" )
			)
			( signal "@baseboard_fab2_lib.baseboard_fab2(sch_1):vr_pvddq_abc_ph2_phase"
				( attribute "CDS_PHYS_NET_NAME" "VR_PVDDQ_ABC_PH2_PHASE"
					( Origin gPackager )
				)
				( objectStatus "VR_PVDDQ_ABC_PH2_PHASE" )
			)
			( signal "@baseboard_fab2_lib.baseboard_fab2(sch_1):vr_pvddq_abc_ph2_sw"
				( attribute "CDS_PHYS_NET_NAME" "VR_PVDDQ_ABC_PH2_SW"
					( Origin gPackager )
				)
				( objectStatus "VR_PVDDQ_ABC_PH2_SW" )
			)
			( signal "@baseboard_fab2_lib.baseboard_fab2(sch_1):vr_pvddq_abc_ph2_vcin"
				( attribute "CDS_PHYS_NET_NAME" "VR_PVDDQ_ABC_PH2_VCIN"
					( Origin gPackager )
				)
				( objectStatus "VR_PVDDQ_ABC_PH2_VCIN" )
			)
			( signal "@baseboard_fab2_lib.baseboard_fab2(sch_1):a_tsense_pvddq_def"
				( attribute "CDS_PHYS_NET_NAME" "A_TSENSE_PVDDQ_DEF"
					( Origin gPackager )
				)
				( objectStatus "A_TSENSE_PVDDQ_DEF" )
			)
			( signal "@baseboard_fab2_lib.baseboard_fab2(sch_1):irq_pvddq_def_vrhot_lvt3_r_n"
				( attribute "CDS_PHYS_NET_NAME" "IRQ_PVDDQ_DEF_VRHOT_LVT3_R_N"
					( Origin gPackager )
				)
				( objectStatus "IRQ_PVDDQ_DEF_VRHOT_LVT3_R_N" )
			)
			( signal "@baseboard_fab2_lib.baseboard_fab2(sch_1):isense_pvddq_def_ph1_imon"
				( attribute "CDS_PHYS_NET_NAME" "ISENSE_PVDDQ_DEF_PH1_IMON"
					( Origin gPackager )
				)
				( objectStatus "ISENSE_PVDDQ_DEF_PH1_IMON" )
			)
			( signal "@baseboard_fab2_lib.baseboard_fab2(sch_1):isense_pvddq_def_ph2_imon"
				( attribute "CDS_PHYS_NET_NAME" "ISENSE_PVDDQ_DEF_PH2_IMON"
					( Origin gPackager )
				)
				( objectStatus "ISENSE_PVDDQ_DEF_PH2_IMON" )
			)
			( signal "@baseboard_fab2_lib.baseboard_fab2(sch_1):pu_vr_pvddq_def_fault1"
				( attribute "CDS_PHYS_NET_NAME" "PU_VR_PVDDQ_DEF_FAULT1"
					( Origin gPackager )
				)
				( objectStatus "PU_VR_PVDDQ_DEF_FAULT1" )
			)
			( signal "@baseboard_fab2_lib.baseboard_fab2(sch_1):pwrgd_pvddq_def"
				( attribute "CDS_PHYS_NET_NAME" "PWRGD_PVDDQ_DEF"
					( Origin gPackager )
				)
				( objectStatus "PWRGD_PVDDQ_DEF" )
			)
			( signal "@baseboard_fab2_lib.baseboard_fab2(sch_1):pwrgd_pvddq_def_r"
				( attribute "CDS_PHYS_NET_NAME" "PWRGD_PVDDQ_DEF_R"
					( Origin gPackager )
				)
				( objectStatus "PWRGD_PVDDQ_DEF_R" )
			)
			( signal "@baseboard_fab2_lib.baseboard_fab2(sch_1):svid_alert_pvddq_def"
				( attribute "CDS_PHYS_NET_NAME" "SVID_ALERT_PVDDQ_DEF"
					( Origin gPackager )
				)
				( objectStatus "SVID_ALERT_PVDDQ_DEF" )
			)
			( signal "@baseboard_fab2_lib.baseboard_fab2(sch_1):svid_clk_pvddq_def"
				( attribute "CDS_PHYS_NET_NAME" "SVID_CLK_PVDDQ_DEF"
					( Origin gPackager )
				)
				( objectStatus "SVID_CLK_PVDDQ_DEF" )
			)
			( signal "@baseboard_fab2_lib.baseboard_fab2(sch_1):svid_vdio_pvddq_def"
				( attribute "CDS_PHYS_NET_NAME" "SVID_VDIO_PVDDQ_DEF"
					( Origin gPackager )
				)
				( objectStatus "SVID_VDIO_PVDDQ_DEF" )
			)
			( signal "@baseboard_fab2_lib.baseboard_fab2(sch_1):tp_pvddq_def_mp1"
				( attribute "CDS_PHYS_NET_NAME" "TP_PVDDQ_DEF_MP1"
					( Origin gPackager )
				)
				( objectStatus "TP_PVDDQ_DEF_MP1" )
			)
			( signal "@baseboard_fab2_lib.baseboard_fab2(sch_1):tp_pvddq_def_mp2"
				( attribute "CDS_PHYS_NET_NAME" "TP_PVDDQ_DEF_MP2"
					( Origin gPackager )
				)
				( objectStatus "TP_PVDDQ_DEF_MP2" )
			)
			( signal "@baseboard_fab2_lib.baseboard_fab2(sch_1):vr_fet_sw_p12v_stby_pvddq_def"
				( alias ( signalRef "@baseboard_fab2_lib.baseboard_fab2(sch_1):page219_vr_fet_sw_p12v_stby_pvddq_def") )
				( alias ( signalRef "@baseboard_fab2_lib.baseboard_fab2(sch_1):page220_vr_fet_sw_p12v_stby_pvddq_def") )
				( alias ( signalRef "@baseboard_fab2_lib.baseboard_fab2(sch_1):page235_vr_fet_sw_p12v_stby_pvddq_def") )
				( alias ( signalRef "@baseboard_fab2_lib.baseboard_fab2(sch_1):page236_vr_fet_sw_p12v_stby_pvddq_def") )
				( attribute "CDS_PHYS_NET_NAME" "VR_FET_SW_P12V_STBY_PVDDQ_DEF"
					( Origin gPackager )
				)
				( objectStatus "VR_FET_SW_P12V_STBY_PVDDQ_DEF" )
			)
			( signal "@baseboard_fab2_lib.baseboard_fab2(sch_1):page219_vr_fet_sw_p12v_stby_pvddq_def"
				( objectFlag fObjectAlias )
				( objectStatus "page219_vr_fet_sw_p12v_stby_pvddq_def" )
			)
			( signal "@baseboard_fab2_lib.baseboard_fab2(sch_1):page220_vr_fet_sw_p12v_stby_pvddq_def"
				( objectFlag fObjectAlias )
				( objectStatus "page220_vr_fet_sw_p12v_stby_pvddq_def" )
			)
			( signal "@baseboard_fab2_lib.baseboard_fab2(sch_1):page235_vr_fet_sw_p12v_stby_pvddq_def"
				( objectFlag fObjectAlias )
				( objectStatus "page235_vr_fet_sw_p12v_stby_pvddq_def" )
			)
			( signal "@baseboard_fab2_lib.baseboard_fab2(sch_1):page236_vr_fet_sw_p12v_stby_pvddq_def"
				( objectFlag fObjectAlias )
				( objectStatus "page236_vr_fet_sw_p12v_stby_pvddq_def" )
			)
			( signal "@baseboard_fab2_lib.baseboard_fab2(sch_1):vr_pvddq_def_airef1"
				( attribute "CDS_PHYS_NET_NAME" "VR_PVDDQ_DEF_AIREF1"
					( Origin gPackager )
				)
				( objectStatus "VR_PVDDQ_DEF_AIREF1" )
			)
			( signal "@baseboard_fab2_lib.baseboard_fab2(sch_1):vr_pvddq_def_airef2"
				( attribute "CDS_PHYS_NET_NAME" "VR_PVDDQ_DEF_AIREF2"
					( Origin gPackager )
				)
				( objectStatus "VR_PVDDQ_DEF_AIREF2" )
			)
			( signal "@baseboard_fab2_lib.baseboard_fab2(sch_1):vr_pvddq_def_avsp"
				( attribute "CDS_PHYS_NET_NAME" "VR_PVDDQ_DEF_AVSP"
					( Origin gPackager )
				)
				( objectStatus "VR_PVDDQ_DEF_AVSP" )
			)
			( signal "@baseboard_fab2_lib.baseboard_fab2(sch_1):vr_pvddq_def_pwm1"
				( attribute "CDS_PHYS_NET_NAME" "VR_PVDDQ_DEF_PWM1"
					( Origin gPackager )
				)
				( objectStatus "VR_PVDDQ_DEF_PWM1" )
			)
			( signal "@baseboard_fab2_lib.baseboard_fab2(sch_1):vr_pvddq_def_pwm2"
				( attribute "CDS_PHYS_NET_NAME" "VR_PVDDQ_DEF_PWM2"
					( Origin gPackager )
				)
				( objectStatus "VR_PVDDQ_DEF_PWM2" )
			)
			( signal "@baseboard_fab2_lib.baseboard_fab2(sch_1):vr_pvddq_def_vd12"
				( attribute "CDS_PHYS_NET_NAME" "VR_PVDDQ_DEF_VD12"
					( Origin gPackager )
				)
				( objectStatus "VR_PVDDQ_DEF_VD12" )
			)
			( signal "@baseboard_fab2_lib.baseboard_fab2(sch_1):vr_pvddq_def_vdd"
				( attribute "CDS_PHYS_NET_NAME" "VR_PVDDQ_DEF_VDD"
					( Origin gPackager )
				)
				( objectStatus "VR_PVDDQ_DEF_VDD" )
			)
			( signal "@baseboard_fab2_lib.baseboard_fab2(sch_1):vr_pvddq_def_vinsen"
				( attribute "CDS_PHYS_NET_NAME" "VR_PVDDQ_DEF_VINSEN"
					( Origin gPackager )
				)
				( objectStatus "VR_PVDDQ_DEF_VINSEN" )
			)
			( signal "@baseboard_fab2_lib.baseboard_fab2(sch_1):vr_pvddq_def_vren"
				( attribute "CDS_PHYS_NET_NAME" "VR_PVDDQ_DEF_VREN"
					( Origin gPackager )
				)
				( objectStatus "VR_PVDDQ_DEF_VREN" )
			)
			( signal "@baseboard_fab2_lib.baseboard_fab2(sch_1):vr_pvddq_def_xaddr1"
				( attribute "CDS_PHYS_NET_NAME" "VR_PVDDQ_DEF_XADDR1"
					( Origin gPackager )
				)
				( objectStatus "VR_PVDDQ_DEF_XADDR1" )
			)
			( signal "@baseboard_fab2_lib.baseboard_fab2(sch_1):vr_pvddq_def_xaddr2"
				( attribute "CDS_PHYS_NET_NAME" "VR_PVDDQ_DEF_XADDR2"
					( Origin gPackager )
				)
				( objectStatus "VR_PVDDQ_DEF_XADDR2" )
			)
			( signal "@baseboard_fab2_lib.baseboard_fab2(sch_1):vsense_pvddq_def_n"
				( attribute "CDS_PHYS_NET_NAME" "VSENSE_PVDDQ_DEF_N"
					( Origin gPackager )
				)
				( objectStatus "VSENSE_PVDDQ_DEF_N" )
			)
			( signal "@baseboard_fab2_lib.baseboard_fab2(sch_1):vsense_pvddq_def_p"
				( attribute "CDS_PHYS_NET_NAME" "VSENSE_PVDDQ_DEF_P"
					( Origin gPackager )
				)
				( objectStatus "VSENSE_PVDDQ_DEF_P" )
			)
			( signal "@baseboard_fab2_lib.baseboard_fab2(sch_1):tp_pvddq_def_ph1_gl_0"
				( attribute "CDS_PHYS_NET_NAME" "TP_PVDDQ_DEF_PH1_GL_0"
					( Origin gPackager )
				)
				( objectStatus "TP_PVDDQ_DEF_PH1_GL_0" )
			)
			( signal "@baseboard_fab2_lib.baseboard_fab2(sch_1):tp_pvddq_def_ph1_gl_1"
				( attribute "CDS_PHYS_NET_NAME" "TP_PVDDQ_DEF_PH1_GL_1"
					( Origin gPackager )
				)
				( objectStatus "TP_PVDDQ_DEF_PH1_GL_1" )
			)
			( signal "@baseboard_fab2_lib.baseboard_fab2(sch_1):tp_pvddq_def_ph2_gl_0"
				( attribute "CDS_PHYS_NET_NAME" "TP_PVDDQ_DEF_PH2_GL_0"
					( Origin gPackager )
				)
				( objectStatus "TP_PVDDQ_DEF_PH2_GL_0" )
			)
			( signal "@baseboard_fab2_lib.baseboard_fab2(sch_1):tp_pvddq_def_ph2_gl_1"
				( attribute "CDS_PHYS_NET_NAME" "TP_PVDDQ_DEF_PH2_GL_1"
					( Origin gPackager )
				)
				( objectStatus "TP_PVDDQ_DEF_PH2_GL_1" )
			)
			( signal "@baseboard_fab2_lib.baseboard_fab2(sch_1):vr_pvddq_def_ph1_boot"
				( attribute "CDS_PHYS_NET_NAME" "VR_PVDDQ_DEF_PH1_BOOT"
					( Origin gPackager )
				)
				( objectStatus "VR_PVDDQ_DEF_PH1_BOOT" )
			)
			( signal "@baseboard_fab2_lib.baseboard_fab2(sch_1):vr_pvddq_def_ph1_ocset"
				( alias ( signalRef "@baseboard_fab2_lib.baseboard_fab2(sch_1):page219_vr_pvddq_def_ph1_ocset") )
				( attribute "VOLTAGE" "3.6"
					( Units "uVoltage" "V" 1.000000)
					( Status sAliasFlattened )
					( Origin gFrontEnd )
				)
				( attribute "CDS_PHYS_NET_NAME" "VR_PVDDQ_DEF_PH1_OCSET"
					( Origin gPackager )
				)
				( objectStatus "VR_PVDDQ_DEF_PH1_OCSET" )
			)
			( signal "@baseboard_fab2_lib.baseboard_fab2(sch_1):page219_vr_pvddq_def_ph1_ocset"
				( attribute "VOLTAGE" "3.6"
					( Units "uVoltage" "V" 1.000000)
					( Origin gFrontEnd )
				)
				( objectFlag fObjectAlias )
				( objectStatus "page219_vr_pvddq_def_ph1_ocset" )
			)
			( signal "@baseboard_fab2_lib.baseboard_fab2(sch_1):vr_pvddq_def_ph1_phase"
				( attribute "CDS_PHYS_NET_NAME" "VR_PVDDQ_DEF_PH1_PHASE"
					( Origin gPackager )
				)
				( objectStatus "VR_PVDDQ_DEF_PH1_PHASE" )
			)
			( signal "@baseboard_fab2_lib.baseboard_fab2(sch_1):vr_pvddq_def_ph1_sw"
				( attribute "CDS_PHYS_NET_NAME" "VR_PVDDQ_DEF_PH1_SW"
					( Origin gPackager )
				)
				( objectStatus "VR_PVDDQ_DEF_PH1_SW" )
			)
			( signal "@baseboard_fab2_lib.baseboard_fab2(sch_1):vr_pvddq_def_ph1_vcin"
				( attribute "CDS_PHYS_NET_NAME" "VR_PVDDQ_DEF_PH1_VCIN"
					( Origin gPackager )
				)
				( objectStatus "VR_PVDDQ_DEF_PH1_VCIN" )
			)
			( signal "@baseboard_fab2_lib.baseboard_fab2(sch_1):vr_pvddq_def_ph2_boot"
				( attribute "CDS_PHYS_NET_NAME" "VR_PVDDQ_DEF_PH2_BOOT"
					( Origin gPackager )
				)
				( objectStatus "VR_PVDDQ_DEF_PH2_BOOT" )
			)
			( signal "@baseboard_fab2_lib.baseboard_fab2(sch_1):vr_pvddq_def_ph2_ocset"
				( alias ( signalRef "@baseboard_fab2_lib.baseboard_fab2(sch_1):page219_vr_pvddq_def_ph2_ocset") )
				( attribute "VOLTAGE" "3.6"
					( Units "uVoltage" "V" 1.000000)
					( Status sAliasFlattened )
					( Origin gFrontEnd )
				)
				( attribute "CDS_PHYS_NET_NAME" "VR_PVDDQ_DEF_PH2_OCSET"
					( Origin gPackager )
				)
				( objectStatus "VR_PVDDQ_DEF_PH2_OCSET" )
			)
			( signal "@baseboard_fab2_lib.baseboard_fab2(sch_1):page219_vr_pvddq_def_ph2_ocset"
				( attribute "VOLTAGE" "3.6"
					( Units "uVoltage" "V" 1.000000)
					( Origin gFrontEnd )
				)
				( objectFlag fObjectAlias )
				( objectStatus "page219_vr_pvddq_def_ph2_ocset" )
			)
			( signal "@baseboard_fab2_lib.baseboard_fab2(sch_1):vr_pvddq_def_ph2_phase"
				( attribute "CDS_PHYS_NET_NAME" "VR_PVDDQ_DEF_PH2_PHASE"
					( Origin gPackager )
				)
				( objectStatus "VR_PVDDQ_DEF_PH2_PHASE" )
			)
			( signal "@baseboard_fab2_lib.baseboard_fab2(sch_1):vr_pvddq_def_ph2_sw"
				( attribute "CDS_PHYS_NET_NAME" "VR_PVDDQ_DEF_PH2_SW"
					( Origin gPackager )
				)
				( objectStatus "VR_PVDDQ_DEF_PH2_SW" )
			)
			( signal "@baseboard_fab2_lib.baseboard_fab2(sch_1):vr_pvddq_def_ph2_vcin"
				( attribute "CDS_PHYS_NET_NAME" "VR_PVDDQ_DEF_PH2_VCIN"
					( Origin gPackager )
				)
				( objectStatus "VR_PVDDQ_DEF_PH2_VCIN" )
			)
			( signal "@baseboard_fab2_lib.baseboard_fab2(sch_1):fm_pvtt_abc_en_r"
				( attribute "CDS_PHYS_NET_NAME" "FM_PVTT_ABC_EN_R"
					( Origin gPackager )
				)
				( objectStatus "FM_PVTT_ABC_EN_R" )
			)
			( signal "@baseboard_fab2_lib.baseboard_fab2(sch_1):pwrgd_pvtt_abc_cpu0_r"
				( attribute "CDS_PHYS_NET_NAME" "PWRGD_PVTT_ABC_CPU0_R"
					( Origin gPackager )
				)
				( objectStatus "PWRGD_PVTT_ABC_CPU0_R" )
			)
			( signal "@baseboard_fab2_lib.baseboard_fab2(sch_1):vr_pvtt_abc_bias"
				( attribute "CDS_PHYS_NET_NAME" "VR_PVTT_ABC_BIAS"
					( Origin gPackager )
				)
				( objectStatus "VR_PVTT_ABC_BIAS" )
			)
			( signal "@baseboard_fab2_lib.baseboard_fab2(sch_1):vr_pvtt_abc_sns"
				( attribute "CDS_PHYS_NET_NAME" "VR_PVTT_ABC_SNS"
					( Origin gPackager )
				)
				( objectStatus "VR_PVTT_ABC_SNS" )
			)
			( signal "@baseboard_fab2_lib.baseboard_fab2(sch_1):vr_pvtt_abc_vref"
				( attribute "CDS_PHYS_NET_NAME" "VR_PVTT_ABC_VREF"
					( Origin gPackager )
				)
				( objectStatus "VR_PVTT_ABC_VREF" )
			)
			( signal "@baseboard_fab2_lib.baseboard_fab2(sch_1):vsense_pvddq_abc_vtt"
				( attribute "CDS_PHYS_NET_NAME" "VSENSE_PVDDQ_ABC_VTT"
					( Origin gPackager )
				)
				( objectStatus "VSENSE_PVDDQ_ABC_VTT" )
			)
			( signal "@baseboard_fab2_lib.baseboard_fab2(sch_1):fm_pvtt_def_en_r"
				( attribute "CDS_PHYS_NET_NAME" "FM_PVTT_DEF_EN_R"
					( Origin gPackager )
				)
				( objectStatus "FM_PVTT_DEF_EN_R" )
			)
			( signal "@baseboard_fab2_lib.baseboard_fab2(sch_1):pwrgd_pvtt_def_cpu0_r"
				( attribute "CDS_PHYS_NET_NAME" "PWRGD_PVTT_DEF_CPU0_R"
					( Origin gPackager )
				)
				( objectStatus "PWRGD_PVTT_DEF_CPU0_R" )
			)
			( signal "@baseboard_fab2_lib.baseboard_fab2(sch_1):vr_pvtt_def_bias"
				( attribute "CDS_PHYS_NET_NAME" "VR_PVTT_DEF_BIAS"
					( Origin gPackager )
				)
				( objectStatus "VR_PVTT_DEF_BIAS" )
			)
			( signal "@baseboard_fab2_lib.baseboard_fab2(sch_1):vr_pvtt_def_sns"
				( attribute "CDS_PHYS_NET_NAME" "VR_PVTT_DEF_SNS"
					( Origin gPackager )
				)
				( objectStatus "VR_PVTT_DEF_SNS" )
			)
			( signal "@baseboard_fab2_lib.baseboard_fab2(sch_1):vr_pvtt_def_vref"
				( attribute "CDS_PHYS_NET_NAME" "VR_PVTT_DEF_VREF"
					( Origin gPackager )
				)
				( objectStatus "VR_PVTT_DEF_VREF" )
			)
			( signal "@baseboard_fab2_lib.baseboard_fab2(sch_1):vsense_pvddq_def_vtt"
				( attribute "CDS_PHYS_NET_NAME" "VSENSE_PVDDQ_DEF_VTT"
					( Origin gPackager )
				)
				( objectStatus "VSENSE_PVDDQ_DEF_VTT" )
			)
			( signal "@baseboard_fab2_lib.baseboard_fab2(sch_1):a_tsense_pvddq_ghj"
				( attribute "CDS_PHYS_NET_NAME" "A_TSENSE_PVDDQ_GHJ"
					( Origin gPackager )
				)
				( objectStatus "A_TSENSE_PVDDQ_GHJ" )
			)
			( signal "@baseboard_fab2_lib.baseboard_fab2(sch_1):irq_pvddq_ghj_vrhot_lvt3_r_n"
				( attribute "CDS_PHYS_NET_NAME" "IRQ_PVDDQ_GHJ_VRHOT_LVT3_R_N"
					( Origin gPackager )
				)
				( objectStatus "IRQ_PVDDQ_GHJ_VRHOT_LVT3_R_N" )
			)
			( signal "@baseboard_fab2_lib.baseboard_fab2(sch_1):isense_pvddq_ghj_ph1_imon"
				( attribute "CDS_PHYS_NET_NAME" "ISENSE_PVDDQ_GHJ_PH1_IMON"
					( Origin gPackager )
				)
				( objectStatus "ISENSE_PVDDQ_GHJ_PH1_IMON" )
			)
			( signal "@baseboard_fab2_lib.baseboard_fab2(sch_1):isense_pvddq_ghj_ph2_imon"
				( attribute "CDS_PHYS_NET_NAME" "ISENSE_PVDDQ_GHJ_PH2_IMON"
					( Origin gPackager )
				)
				( objectStatus "ISENSE_PVDDQ_GHJ_PH2_IMON" )
			)
			( signal "@baseboard_fab2_lib.baseboard_fab2(sch_1):pu_vr_pvddq_ghj_fault1"
				( attribute "CDS_PHYS_NET_NAME" "PU_VR_PVDDQ_GHJ_FAULT1"
					( Origin gPackager )
				)
				( objectStatus "PU_VR_PVDDQ_GHJ_FAULT1" )
			)
			( signal "@baseboard_fab2_lib.baseboard_fab2(sch_1):pwrgd_pvddq_ghj"
				( attribute "CDS_PHYS_NET_NAME" "PWRGD_PVDDQ_GHJ"
					( Origin gPackager )
				)
				( objectStatus "PWRGD_PVDDQ_GHJ" )
			)
			( signal "@baseboard_fab2_lib.baseboard_fab2(sch_1):pwrgd_pvddq_ghj_r"
				( attribute "CDS_PHYS_NET_NAME" "PWRGD_PVDDQ_GHJ_R"
					( Origin gPackager )
				)
				( objectStatus "PWRGD_PVDDQ_GHJ_R" )
			)
			( signal "@baseboard_fab2_lib.baseboard_fab2(sch_1):svid_alert_pvddq_ghj"
				( attribute "CDS_PHYS_NET_NAME" "SVID_ALERT_PVDDQ_GHJ"
					( Origin gPackager )
				)
				( objectStatus "SVID_ALERT_PVDDQ_GHJ" )
			)
			( signal "@baseboard_fab2_lib.baseboard_fab2(sch_1):svid_clk_pvddq_ghj"
				( attribute "CDS_PHYS_NET_NAME" "SVID_CLK_PVDDQ_GHJ"
					( Origin gPackager )
				)
				( objectStatus "SVID_CLK_PVDDQ_GHJ" )
			)
			( signal "@baseboard_fab2_lib.baseboard_fab2(sch_1):svid_vdio_pvddq_ghj"
				( attribute "CDS_PHYS_NET_NAME" "SVID_VDIO_PVDDQ_GHJ"
					( Origin gPackager )
				)
				( objectStatus "SVID_VDIO_PVDDQ_GHJ" )
			)
			( signal "@baseboard_fab2_lib.baseboard_fab2(sch_1):tp_pvddq_ghj_mp1"
				( attribute "CDS_PHYS_NET_NAME" "TP_PVDDQ_GHJ_MP1"
					( Origin gPackager )
				)
				( objectStatus "TP_PVDDQ_GHJ_MP1" )
			)
			( signal "@baseboard_fab2_lib.baseboard_fab2(sch_1):tp_pvddq_ghj_mp2"
				( attribute "CDS_PHYS_NET_NAME" "TP_PVDDQ_GHJ_MP2"
					( Origin gPackager )
				)
				( objectStatus "TP_PVDDQ_GHJ_MP2" )
			)
			( signal "@baseboard_fab2_lib.baseboard_fab2(sch_1):vr_fet_sw_p12v_stby_pvddq_ghj"
				( alias ( signalRef "@baseboard_fab2_lib.baseboard_fab2(sch_1):page224_vr_fet_sw_p12v_stby_pvddq_ghj") )
				( alias ( signalRef "@baseboard_fab2_lib.baseboard_fab2(sch_1):page225_vr_fet_sw_p12v_stby_pvddq_ghj") )
				( attribute "CDS_PHYS_NET_NAME" "VR_FET_SW_P12V_STBY_PVDDQ_GHJ"
					( Origin gPackager )
				)
				( objectStatus "VR_FET_SW_P12V_STBY_PVDDQ_GHJ" )
			)
			( signal "@baseboard_fab2_lib.baseboard_fab2(sch_1):page224_vr_fet_sw_p12v_stby_pvddq_ghj"
				( objectFlag fObjectAlias )
				( objectStatus "page224_vr_fet_sw_p12v_stby_pvddq_ghj" )
			)
			( signal "@baseboard_fab2_lib.baseboard_fab2(sch_1):page225_vr_fet_sw_p12v_stby_pvddq_ghj"
				( objectFlag fObjectAlias )
				( objectStatus "page225_vr_fet_sw_p12v_stby_pvddq_ghj" )
			)
			( signal "@baseboard_fab2_lib.baseboard_fab2(sch_1):vr_pvddq_ghj_airef1"
				( attribute "CDS_PHYS_NET_NAME" "VR_PVDDQ_GHJ_AIREF1"
					( Origin gPackager )
				)
				( objectStatus "VR_PVDDQ_GHJ_AIREF1" )
			)
			( signal "@baseboard_fab2_lib.baseboard_fab2(sch_1):vr_pvddq_ghj_airef2"
				( attribute "CDS_PHYS_NET_NAME" "VR_PVDDQ_GHJ_AIREF2"
					( Origin gPackager )
				)
				( objectStatus "VR_PVDDQ_GHJ_AIREF2" )
			)
			( signal "@baseboard_fab2_lib.baseboard_fab2(sch_1):vr_pvddq_ghj_avsp"
				( attribute "CDS_PHYS_NET_NAME" "VR_PVDDQ_GHJ_AVSP"
					( Origin gPackager )
				)
				( objectStatus "VR_PVDDQ_GHJ_AVSP" )
			)
			( signal "@baseboard_fab2_lib.baseboard_fab2(sch_1):vr_pvddq_ghj_pwm1"
				( attribute "CDS_PHYS_NET_NAME" "VR_PVDDQ_GHJ_PWM1"
					( Origin gPackager )
				)
				( objectStatus "VR_PVDDQ_GHJ_PWM1" )
			)
			( signal "@baseboard_fab2_lib.baseboard_fab2(sch_1):vr_pvddq_ghj_pwm2"
				( attribute "CDS_PHYS_NET_NAME" "VR_PVDDQ_GHJ_PWM2"
					( Origin gPackager )
				)
				( objectStatus "VR_PVDDQ_GHJ_PWM2" )
			)
			( signal "@baseboard_fab2_lib.baseboard_fab2(sch_1):vr_pvddq_ghj_vd12"
				( attribute "CDS_PHYS_NET_NAME" "VR_PVDDQ_GHJ_VD12"
					( Origin gPackager )
				)
				( objectStatus "VR_PVDDQ_GHJ_VD12" )
			)
			( signal "@baseboard_fab2_lib.baseboard_fab2(sch_1):vr_pvddq_ghj_vdd"
				( attribute "CDS_PHYS_NET_NAME" "VR_PVDDQ_GHJ_VDD"
					( Origin gPackager )
				)
				( objectStatus "VR_PVDDQ_GHJ_VDD" )
			)
			( signal "@baseboard_fab2_lib.baseboard_fab2(sch_1):vr_pvddq_ghj_vinsen"
				( attribute "CDS_PHYS_NET_NAME" "VR_PVDDQ_GHJ_VINSEN"
					( Origin gPackager )
				)
				( objectStatus "VR_PVDDQ_GHJ_VINSEN" )
			)
			( signal "@baseboard_fab2_lib.baseboard_fab2(sch_1):vr_pvddq_ghj_vren"
				( attribute "CDS_PHYS_NET_NAME" "VR_PVDDQ_GHJ_VREN"
					( Origin gPackager )
				)
				( objectStatus "VR_PVDDQ_GHJ_VREN" )
			)
			( signal "@baseboard_fab2_lib.baseboard_fab2(sch_1):vr_pvddq_ghj_xaddr1"
				( attribute "CDS_PHYS_NET_NAME" "VR_PVDDQ_GHJ_XADDR1"
					( Origin gPackager )
				)
				( objectStatus "VR_PVDDQ_GHJ_XADDR1" )
			)
			( signal "@baseboard_fab2_lib.baseboard_fab2(sch_1):vr_pvddq_ghj_xaddr2"
				( attribute "CDS_PHYS_NET_NAME" "VR_PVDDQ_GHJ_XADDR2"
					( Origin gPackager )
				)
				( objectStatus "VR_PVDDQ_GHJ_XADDR2" )
			)
			( signal "@baseboard_fab2_lib.baseboard_fab2(sch_1):vsense_pvddq_ghj_n"
				( attribute "CDS_PHYS_NET_NAME" "VSENSE_PVDDQ_GHJ_N"
					( Origin gPackager )
				)
				( objectStatus "VSENSE_PVDDQ_GHJ_N" )
			)
			( signal "@baseboard_fab2_lib.baseboard_fab2(sch_1):vsense_pvddq_ghj_p"
				( attribute "CDS_PHYS_NET_NAME" "VSENSE_PVDDQ_GHJ_P"
					( Origin gPackager )
				)
				( objectStatus "VSENSE_PVDDQ_GHJ_P" )
			)
			( signal "@baseboard_fab2_lib.baseboard_fab2(sch_1):tp_pvddq_ghj_ph1_gl_0"
				( attribute "CDS_PHYS_NET_NAME" "TP_PVDDQ_GHJ_PH1_GL_0"
					( Origin gPackager )
				)
				( objectStatus "TP_PVDDQ_GHJ_PH1_GL_0" )
			)
			( signal "@baseboard_fab2_lib.baseboard_fab2(sch_1):tp_pvddq_ghj_ph1_gl_1"
				( attribute "CDS_PHYS_NET_NAME" "TP_PVDDQ_GHJ_PH1_GL_1"
					( Origin gPackager )
				)
				( objectStatus "TP_PVDDQ_GHJ_PH1_GL_1" )
			)
			( signal "@baseboard_fab2_lib.baseboard_fab2(sch_1):tp_pvddq_ghj_ph2_gl_0"
				( attribute "CDS_PHYS_NET_NAME" "TP_PVDDQ_GHJ_PH2_GL_0"
					( Origin gPackager )
				)
				( objectStatus "TP_PVDDQ_GHJ_PH2_GL_0" )
			)
			( signal "@baseboard_fab2_lib.baseboard_fab2(sch_1):tp_pvddq_ghj_ph2_gl_1"
				( attribute "CDS_PHYS_NET_NAME" "TP_PVDDQ_GHJ_PH2_GL_1"
					( Origin gPackager )
				)
				( objectStatus "TP_PVDDQ_GHJ_PH2_GL_1" )
			)
			( signal "@baseboard_fab2_lib.baseboard_fab2(sch_1):vr_pvddq_ghj_ph1_boot"
				( attribute "CDS_PHYS_NET_NAME" "VR_PVDDQ_GHJ_PH1_BOOT"
					( Origin gPackager )
				)
				( objectStatus "VR_PVDDQ_GHJ_PH1_BOOT" )
			)
			( signal "@baseboard_fab2_lib.baseboard_fab2(sch_1):vr_pvddq_ghj_ph1_ocset"
				( alias ( signalRef "@baseboard_fab2_lib.baseboard_fab2(sch_1):page224_vr_pvddq_ghj_ph1_ocset") )
				( attribute "VOLTAGE" "3.6"
					( Units "uVoltage" "V" 1.000000)
					( Status sAliasFlattened )
					( Origin gFrontEnd )
				)
				( attribute "CDS_PHYS_NET_NAME" "VR_PVDDQ_GHJ_PH1_OCSET"
					( Origin gPackager )
				)
				( objectStatus "VR_PVDDQ_GHJ_PH1_OCSET" )
			)
			( signal "@baseboard_fab2_lib.baseboard_fab2(sch_1):page224_vr_pvddq_ghj_ph1_ocset"
				( attribute "VOLTAGE" "3.6"
					( Units "uVoltage" "V" 1.000000)
					( Origin gFrontEnd )
				)
				( objectFlag fObjectAlias )
				( objectStatus "page224_vr_pvddq_ghj_ph1_ocset" )
			)
			( signal "@baseboard_fab2_lib.baseboard_fab2(sch_1):vr_pvddq_ghj_ph1_phase"
				( attribute "CDS_PHYS_NET_NAME" "VR_PVDDQ_GHJ_PH1_PHASE"
					( Origin gPackager )
				)
				( objectStatus "VR_PVDDQ_GHJ_PH1_PHASE" )
			)
			( signal "@baseboard_fab2_lib.baseboard_fab2(sch_1):vr_pvddq_ghj_ph1_sw"
				( attribute "CDS_PHYS_NET_NAME" "VR_PVDDQ_GHJ_PH1_SW"
					( Origin gPackager )
				)
				( objectStatus "VR_PVDDQ_GHJ_PH1_SW" )
			)
			( signal "@baseboard_fab2_lib.baseboard_fab2(sch_1):vr_pvddq_ghj_ph1_vcin"
				( attribute "CDS_PHYS_NET_NAME" "VR_PVDDQ_GHJ_PH1_VCIN"
					( Origin gPackager )
				)
				( objectStatus "VR_PVDDQ_GHJ_PH1_VCIN" )
			)
			( signal "@baseboard_fab2_lib.baseboard_fab2(sch_1):vr_pvddq_ghj_ph2_boot"
				( attribute "CDS_PHYS_NET_NAME" "VR_PVDDQ_GHJ_PH2_BOOT"
					( Origin gPackager )
				)
				( objectStatus "VR_PVDDQ_GHJ_PH2_BOOT" )
			)
			( signal "@baseboard_fab2_lib.baseboard_fab2(sch_1):vr_pvddq_ghj_ph2_ocset"
				( alias ( signalRef "@baseboard_fab2_lib.baseboard_fab2(sch_1):page224_vr_pvddq_ghj_ph2_ocset") )
				( attribute "VOLTAGE" "3.6"
					( Units "uVoltage" "V" 1.000000)
					( Status sAliasFlattened )
					( Origin gFrontEnd )
				)
				( attribute "CDS_PHYS_NET_NAME" "VR_PVDDQ_GHJ_PH2_OCSET"
					( Origin gPackager )
				)
				( objectStatus "VR_PVDDQ_GHJ_PH2_OCSET" )
			)
			( signal "@baseboard_fab2_lib.baseboard_fab2(sch_1):page224_vr_pvddq_ghj_ph2_ocset"
				( attribute "VOLTAGE" "3.6"
					( Units "uVoltage" "V" 1.000000)
					( Origin gFrontEnd )
				)
				( objectFlag fObjectAlias )
				( objectStatus "page224_vr_pvddq_ghj_ph2_ocset" )
			)
			( signal "@baseboard_fab2_lib.baseboard_fab2(sch_1):vr_pvddq_ghj_ph2_phase"
				( attribute "CDS_PHYS_NET_NAME" "VR_PVDDQ_GHJ_PH2_PHASE"
					( Origin gPackager )
				)
				( objectStatus "VR_PVDDQ_GHJ_PH2_PHASE" )
			)
			( signal "@baseboard_fab2_lib.baseboard_fab2(sch_1):vr_pvddq_ghj_ph2_sw"
				( attribute "CDS_PHYS_NET_NAME" "VR_PVDDQ_GHJ_PH2_SW"
					( Origin gPackager )
				)
				( objectStatus "VR_PVDDQ_GHJ_PH2_SW" )
			)
			( signal "@baseboard_fab2_lib.baseboard_fab2(sch_1):vr_pvddq_ghj_ph2_vcin"
				( attribute "CDS_PHYS_NET_NAME" "VR_PVDDQ_GHJ_PH2_VCIN"
					( Origin gPackager )
				)
				( objectStatus "VR_PVDDQ_GHJ_PH2_VCIN" )
			)
			( signal "@baseboard_fab2_lib.baseboard_fab2(sch_1):a_tsense_pvddq_klm"
				( attribute "CDS_PHYS_NET_NAME" "A_TSENSE_PVDDQ_KLM"
					( Origin gPackager )
				)
				( objectStatus "A_TSENSE_PVDDQ_KLM" )
			)
			( signal "@baseboard_fab2_lib.baseboard_fab2(sch_1):irq_pvddq_klm_vrhot_lvt3_r_n"
				( attribute "CDS_PHYS_NET_NAME" "IRQ_PVDDQ_KLM_VRHOT_LVT3_R_N"
					( Origin gPackager )
				)
				( objectStatus "IRQ_PVDDQ_KLM_VRHOT_LVT3_R_N" )
			)
			( signal "@baseboard_fab2_lib.baseboard_fab2(sch_1):isense_pvddq_klm_ph1_imon"
				( attribute "CDS_PHYS_NET_NAME" "ISENSE_PVDDQ_KLM_PH1_IMON"
					( Origin gPackager )
				)
				( objectStatus "ISENSE_PVDDQ_KLM_PH1_IMON" )
			)
			( signal "@baseboard_fab2_lib.baseboard_fab2(sch_1):isense_pvddq_klm_ph2_imon"
				( attribute "CDS_PHYS_NET_NAME" "ISENSE_PVDDQ_KLM_PH2_IMON"
					( Origin gPackager )
				)
				( objectStatus "ISENSE_PVDDQ_KLM_PH2_IMON" )
			)
			( signal "@baseboard_fab2_lib.baseboard_fab2(sch_1):nc_pvddq_klm_gp0"
				( attribute "CDS_PHYS_NET_NAME" "NC_PVDDQ_KLM_GP0"
					( Origin gPackager )
				)
				( objectStatus "NC_PVDDQ_KLM_GP0" )
			)
			( signal "@baseboard_fab2_lib.baseboard_fab2(sch_1):nc_pvddq_klm_gp1"
				( attribute "CDS_PHYS_NET_NAME" "NC_PVDDQ_KLM_GP1"
					( Origin gPackager )
				)
				( objectStatus "NC_PVDDQ_KLM_GP1" )
			)
			( signal "@baseboard_fab2_lib.baseboard_fab2(sch_1):pu_vr_pvddq_klm_fault1"
				( attribute "CDS_PHYS_NET_NAME" "PU_VR_PVDDQ_KLM_FAULT1"
					( Origin gPackager )
				)
				( objectStatus "PU_VR_PVDDQ_KLM_FAULT1" )
			)
			( signal "@baseboard_fab2_lib.baseboard_fab2(sch_1):pwrgd_pvddq_klm"
				( attribute "CDS_PHYS_NET_NAME" "PWRGD_PVDDQ_KLM"
					( Origin gPackager )
				)
				( objectStatus "PWRGD_PVDDQ_KLM" )
			)
			( signal "@baseboard_fab2_lib.baseboard_fab2(sch_1):pwrgd_pvddq_klm_r"
				( attribute "CDS_PHYS_NET_NAME" "PWRGD_PVDDQ_KLM_R"
					( Origin gPackager )
				)
				( objectStatus "PWRGD_PVDDQ_KLM_R" )
			)
			( signal "@baseboard_fab2_lib.baseboard_fab2(sch_1):svid_alert_pvddq_klm"
				( attribute "CDS_PHYS_NET_NAME" "SVID_ALERT_PVDDQ_KLM"
					( Origin gPackager )
				)
				( objectStatus "SVID_ALERT_PVDDQ_KLM" )
			)
			( signal "@baseboard_fab2_lib.baseboard_fab2(sch_1):svid_clk_pvddq_klm"
				( attribute "CDS_PHYS_NET_NAME" "SVID_CLK_PVDDQ_KLM"
					( Origin gPackager )
				)
				( objectStatus "SVID_CLK_PVDDQ_KLM" )
			)
			( signal "@baseboard_fab2_lib.baseboard_fab2(sch_1):svid_vdio_pvddq_klm"
				( attribute "CDS_PHYS_NET_NAME" "SVID_VDIO_PVDDQ_KLM"
					( Origin gPackager )
				)
				( objectStatus "SVID_VDIO_PVDDQ_KLM" )
			)
			( signal "@baseboard_fab2_lib.baseboard_fab2(sch_1):vr_fet_sw_p12v_stby_pvddq_klm"
				( alias ( signalRef "@baseboard_fab2_lib.baseboard_fab2(sch_1):page227_vr_fet_sw_p12v_stby_pvddq_klm") )
				( alias ( signalRef "@baseboard_fab2_lib.baseboard_fab2(sch_1):page228_vr_fet_sw_p12v_stby_pvddq_klm") )
				( attribute "CDS_PHYS_NET_NAME" "VR_FET_SW_P12V_STBY_PVDDQ_KLM"
					( Origin gPackager )
				)
				( objectStatus "VR_FET_SW_P12V_STBY_PVDDQ_KLM" )
			)
			( signal "@baseboard_fab2_lib.baseboard_fab2(sch_1):page227_vr_fet_sw_p12v_stby_pvddq_klm"
				( objectFlag fObjectAlias )
				( objectStatus "page227_vr_fet_sw_p12v_stby_pvddq_klm" )
			)
			( signal "@baseboard_fab2_lib.baseboard_fab2(sch_1):page228_vr_fet_sw_p12v_stby_pvddq_klm"
				( objectFlag fObjectAlias )
				( objectStatus "page228_vr_fet_sw_p12v_stby_pvddq_klm" )
			)
			( signal "@baseboard_fab2_lib.baseboard_fab2(sch_1):vr_pvddq_klm_airef1"
				( attribute "CDS_PHYS_NET_NAME" "VR_PVDDQ_KLM_AIREF1"
					( Origin gPackager )
				)
				( objectStatus "VR_PVDDQ_KLM_AIREF1" )
			)
			( signal "@baseboard_fab2_lib.baseboard_fab2(sch_1):vr_pvddq_klm_airef2"
				( attribute "CDS_PHYS_NET_NAME" "VR_PVDDQ_KLM_AIREF2"
					( Origin gPackager )
				)
				( objectStatus "VR_PVDDQ_KLM_AIREF2" )
			)
			( signal "@baseboard_fab2_lib.baseboard_fab2(sch_1):vr_pvddq_klm_avsp"
				( attribute "CDS_PHYS_NET_NAME" "VR_PVDDQ_KLM_AVSP"
					( Origin gPackager )
				)
				( objectStatus "VR_PVDDQ_KLM_AVSP" )
			)
			( signal "@baseboard_fab2_lib.baseboard_fab2(sch_1):vr_pvddq_klm_pwm1"
				( attribute "CDS_PHYS_NET_NAME" "VR_PVDDQ_KLM_PWM1"
					( Origin gPackager )
				)
				( objectStatus "VR_PVDDQ_KLM_PWM1" )
			)
			( signal "@baseboard_fab2_lib.baseboard_fab2(sch_1):vr_pvddq_klm_pwm2"
				( attribute "CDS_PHYS_NET_NAME" "VR_PVDDQ_KLM_PWM2"
					( Origin gPackager )
				)
				( objectStatus "VR_PVDDQ_KLM_PWM2" )
			)
			( signal "@baseboard_fab2_lib.baseboard_fab2(sch_1):vr_pvddq_klm_vd12"
				( attribute "CDS_PHYS_NET_NAME" "VR_PVDDQ_KLM_VD12"
					( Origin gPackager )
				)
				( objectStatus "VR_PVDDQ_KLM_VD12" )
			)
			( signal "@baseboard_fab2_lib.baseboard_fab2(sch_1):vr_pvddq_klm_vdd"
				( attribute "CDS_PHYS_NET_NAME" "VR_PVDDQ_KLM_VDD"
					( Origin gPackager )
				)
				( objectStatus "VR_PVDDQ_KLM_VDD" )
			)
			( signal "@baseboard_fab2_lib.baseboard_fab2(sch_1):vr_pvddq_klm_vinsen"
				( attribute "CDS_PHYS_NET_NAME" "VR_PVDDQ_KLM_VINSEN"
					( Origin gPackager )
				)
				( objectStatus "VR_PVDDQ_KLM_VINSEN" )
			)
			( signal "@baseboard_fab2_lib.baseboard_fab2(sch_1):vr_pvddq_klm_vren"
				( attribute "CDS_PHYS_NET_NAME" "VR_PVDDQ_KLM_VREN"
					( Origin gPackager )
				)
				( objectStatus "VR_PVDDQ_KLM_VREN" )
			)
			( signal "@baseboard_fab2_lib.baseboard_fab2(sch_1):vr_pvddq_klm_xaddr1"
				( attribute "CDS_PHYS_NET_NAME" "VR_PVDDQ_KLM_XADDR1"
					( Origin gPackager )
				)
				( objectStatus "VR_PVDDQ_KLM_XADDR1" )
			)
			( signal "@baseboard_fab2_lib.baseboard_fab2(sch_1):vr_pvddq_klm_xaddr2"
				( attribute "CDS_PHYS_NET_NAME" "VR_PVDDQ_KLM_XADDR2"
					( Origin gPackager )
				)
				( objectStatus "VR_PVDDQ_KLM_XADDR2" )
			)
			( signal "@baseboard_fab2_lib.baseboard_fab2(sch_1):vsense_pvddq_klm_n"
				( attribute "CDS_PHYS_NET_NAME" "VSENSE_PVDDQ_KLM_N"
					( Origin gPackager )
				)
				( objectStatus "VSENSE_PVDDQ_KLM_N" )
			)
			( signal "@baseboard_fab2_lib.baseboard_fab2(sch_1):vsense_pvddq_klm_p"
				( attribute "CDS_PHYS_NET_NAME" "VSENSE_PVDDQ_KLM_P"
					( Origin gPackager )
				)
				( objectStatus "VSENSE_PVDDQ_KLM_P" )
			)
			( signal "@baseboard_fab2_lib.baseboard_fab2(sch_1):tp_pvddq_klm_ph1_gl_0"
				( attribute "CDS_PHYS_NET_NAME" "TP_PVDDQ_KLM_PH1_GL_0"
					( Origin gPackager )
				)
				( objectStatus "TP_PVDDQ_KLM_PH1_GL_0" )
			)
			( signal "@baseboard_fab2_lib.baseboard_fab2(sch_1):tp_pvddq_klm_ph1_gl_1"
				( attribute "CDS_PHYS_NET_NAME" "TP_PVDDQ_KLM_PH1_GL_1"
					( Origin gPackager )
				)
				( objectStatus "TP_PVDDQ_KLM_PH1_GL_1" )
			)
			( signal "@baseboard_fab2_lib.baseboard_fab2(sch_1):tp_pvddq_klm_ph2_gl_0"
				( attribute "CDS_PHYS_NET_NAME" "TP_PVDDQ_KLM_PH2_GL_0"
					( Origin gPackager )
				)
				( objectStatus "TP_PVDDQ_KLM_PH2_GL_0" )
			)
			( signal "@baseboard_fab2_lib.baseboard_fab2(sch_1):tp_pvddq_klm_ph2_gl_1"
				( attribute "CDS_PHYS_NET_NAME" "TP_PVDDQ_KLM_PH2_GL_1"
					( Origin gPackager )
				)
				( objectStatus "TP_PVDDQ_KLM_PH2_GL_1" )
			)
			( signal "@baseboard_fab2_lib.baseboard_fab2(sch_1):vr_pvddq_klm_ph1_boot"
				( attribute "CDS_PHYS_NET_NAME" "VR_PVDDQ_KLM_PH1_BOOT"
					( Origin gPackager )
				)
				( objectStatus "VR_PVDDQ_KLM_PH1_BOOT" )
			)
			( signal "@baseboard_fab2_lib.baseboard_fab2(sch_1):vr_pvddq_klm_ph1_ocset"
				( alias ( signalRef "@baseboard_fab2_lib.baseboard_fab2(sch_1):page227_vr_pvddq_klm_ph1_ocset") )
				( attribute "VOLTAGE" "3.6"
					( Units "uVoltage" "V" 1.000000)
					( Status sAliasFlattened )
					( Origin gFrontEnd )
				)
				( attribute "CDS_PHYS_NET_NAME" "VR_PVDDQ_KLM_PH1_OCSET"
					( Origin gPackager )
				)
				( objectStatus "VR_PVDDQ_KLM_PH1_OCSET" )
			)
			( signal "@baseboard_fab2_lib.baseboard_fab2(sch_1):page227_vr_pvddq_klm_ph1_ocset"
				( attribute "VOLTAGE" "3.6"
					( Units "uVoltage" "V" 1.000000)
					( Origin gFrontEnd )
				)
				( objectFlag fObjectAlias )
				( objectStatus "page227_vr_pvddq_klm_ph1_ocset" )
			)
			( signal "@baseboard_fab2_lib.baseboard_fab2(sch_1):vr_pvddq_klm_ph1_phase"
				( attribute "CDS_PHYS_NET_NAME" "VR_PVDDQ_KLM_PH1_PHASE"
					( Origin gPackager )
				)
				( objectStatus "VR_PVDDQ_KLM_PH1_PHASE" )
			)
			( signal "@baseboard_fab2_lib.baseboard_fab2(sch_1):vr_pvddq_klm_ph1_sw"
				( attribute "CDS_PHYS_NET_NAME" "VR_PVDDQ_KLM_PH1_SW"
					( Origin gPackager )
				)
				( objectStatus "VR_PVDDQ_KLM_PH1_SW" )
			)
			( signal "@baseboard_fab2_lib.baseboard_fab2(sch_1):vr_pvddq_klm_ph1_vcin"
				( attribute "CDS_PHYS_NET_NAME" "VR_PVDDQ_KLM_PH1_VCIN"
					( Origin gPackager )
				)
				( objectStatus "VR_PVDDQ_KLM_PH1_VCIN" )
			)
			( signal "@baseboard_fab2_lib.baseboard_fab2(sch_1):vr_pvddq_klm_ph2_boot"
				( attribute "CDS_PHYS_NET_NAME" "VR_PVDDQ_KLM_PH2_BOOT"
					( Origin gPackager )
				)
				( objectStatus "VR_PVDDQ_KLM_PH2_BOOT" )
			)
			( signal "@baseboard_fab2_lib.baseboard_fab2(sch_1):vr_pvddq_klm_ph2_ocset"
				( alias ( signalRef "@baseboard_fab2_lib.baseboard_fab2(sch_1):page227_vr_pvddq_klm_ph2_ocset") )
				( attribute "VOLTAGE" "3.6"
					( Units "uVoltage" "V" 1.000000)
					( Status sAliasFlattened )
					( Origin gFrontEnd )
				)
				( attribute "CDS_PHYS_NET_NAME" "VR_PVDDQ_KLM_PH2_OCSET"
					( Origin gPackager )
				)
				( objectStatus "VR_PVDDQ_KLM_PH2_OCSET" )
			)
			( signal "@baseboard_fab2_lib.baseboard_fab2(sch_1):page227_vr_pvddq_klm_ph2_ocset"
				( attribute "VOLTAGE" "3.6"
					( Units "uVoltage" "V" 1.000000)
					( Origin gFrontEnd )
				)
				( objectFlag fObjectAlias )
				( objectStatus "page227_vr_pvddq_klm_ph2_ocset" )
			)
			( signal "@baseboard_fab2_lib.baseboard_fab2(sch_1):vr_pvddq_klm_ph2_phase"
				( attribute "CDS_PHYS_NET_NAME" "VR_PVDDQ_KLM_PH2_PHASE"
					( Origin gPackager )
				)
				( objectStatus "VR_PVDDQ_KLM_PH2_PHASE" )
			)
			( signal "@baseboard_fab2_lib.baseboard_fab2(sch_1):vr_pvddq_klm_ph2_sw"
				( attribute "CDS_PHYS_NET_NAME" "VR_PVDDQ_KLM_PH2_SW"
					( Origin gPackager )
				)
				( objectStatus "VR_PVDDQ_KLM_PH2_SW" )
			)
			( signal "@baseboard_fab2_lib.baseboard_fab2(sch_1):vr_pvddq_klm_ph2_vcin"
				( attribute "CDS_PHYS_NET_NAME" "VR_PVDDQ_KLM_PH2_VCIN"
					( Origin gPackager )
				)
				( objectStatus "VR_PVDDQ_KLM_PH2_VCIN" )
			)
			( signal "@baseboard_fab2_lib.baseboard_fab2(sch_1):fm_pvtt_ghj_en_r"
				( attribute "CDS_PHYS_NET_NAME" "FM_PVTT_GHJ_EN_R"
					( Origin gPackager )
				)
				( objectStatus "FM_PVTT_GHJ_EN_R" )
			)
			( signal "@baseboard_fab2_lib.baseboard_fab2(sch_1):pwrgd_pvtt_ghj_cpu1_r"
				( attribute "CDS_PHYS_NET_NAME" "PWRGD_PVTT_GHJ_CPU1_R"
					( Origin gPackager )
				)
				( objectStatus "PWRGD_PVTT_GHJ_CPU1_R" )
			)
			( signal "@baseboard_fab2_lib.baseboard_fab2(sch_1):vr_pvtt_ghj_bias"
				( attribute "CDS_PHYS_NET_NAME" "VR_PVTT_GHJ_BIAS"
					( Origin gPackager )
				)
				( objectStatus "VR_PVTT_GHJ_BIAS" )
			)
			( signal "@baseboard_fab2_lib.baseboard_fab2(sch_1):vr_pvtt_ghj_sns"
				( attribute "CDS_PHYS_NET_NAME" "VR_PVTT_GHJ_SNS"
					( Origin gPackager )
				)
				( objectStatus "VR_PVTT_GHJ_SNS" )
			)
			( signal "@baseboard_fab2_lib.baseboard_fab2(sch_1):vr_pvtt_ghj_vref"
				( attribute "CDS_PHYS_NET_NAME" "VR_PVTT_GHJ_VREF"
					( Origin gPackager )
				)
				( objectStatus "VR_PVTT_GHJ_VREF" )
			)
			( signal "@baseboard_fab2_lib.baseboard_fab2(sch_1):vsense_pvddq_ghj_vtt"
				( attribute "CDS_PHYS_NET_NAME" "VSENSE_PVDDQ_GHJ_VTT"
					( Origin gPackager )
				)
				( objectStatus "VSENSE_PVDDQ_GHJ_VTT" )
			)
			( signal "@baseboard_fab2_lib.baseboard_fab2(sch_1):fm_pvtt_klm_en_r"
				( attribute "CDS_PHYS_NET_NAME" "FM_PVTT_KLM_EN_R"
					( Origin gPackager )
				)
				( objectStatus "FM_PVTT_KLM_EN_R" )
			)
			( signal "@baseboard_fab2_lib.baseboard_fab2(sch_1):pwrgd_pvtt_klm_cpu1_r"
				( attribute "CDS_PHYS_NET_NAME" "PWRGD_PVTT_KLM_CPU1_R"
					( Origin gPackager )
				)
				( objectStatus "PWRGD_PVTT_KLM_CPU1_R" )
			)
			( signal "@baseboard_fab2_lib.baseboard_fab2(sch_1):vr_pvtt_klm_bias"
				( attribute "CDS_PHYS_NET_NAME" "VR_PVTT_KLM_BIAS"
					( Origin gPackager )
				)
				( objectStatus "VR_PVTT_KLM_BIAS" )
			)
			( signal "@baseboard_fab2_lib.baseboard_fab2(sch_1):vr_pvtt_klm_sns"
				( attribute "CDS_PHYS_NET_NAME" "VR_PVTT_KLM_SNS"
					( Origin gPackager )
				)
				( objectStatus "VR_PVTT_KLM_SNS" )
			)
			( signal "@baseboard_fab2_lib.baseboard_fab2(sch_1):vr_pvtt_klm_vref"
				( attribute "CDS_PHYS_NET_NAME" "VR_PVTT_KLM_VREF"
					( Origin gPackager )
				)
				( objectStatus "VR_PVTT_KLM_VREF" )
			)
			( signal "@baseboard_fab2_lib.baseboard_fab2(sch_1):vsense_pvddq_klm_vtt"
				( attribute "CDS_PHYS_NET_NAME" "VSENSE_PVDDQ_KLM_VTT"
					( Origin gPackager )
				)
				( objectStatus "VSENSE_PVDDQ_KLM_VTT" )
			)
			( signal "@baseboard_fab2_lib.baseboard_fab2(sch_1):agnd_pvpp_abc"
				( alias ( signalRef "@baseboard_fab2_lib.baseboard_fab2(sch_1):page231_agnd_pvpp_abc") )
				( attribute "VOLTAGE" "0.0V"
					( Units "uVoltage" "V" 1.000000)
					( Status sAliasFlattened )
					( Origin gFrontEnd )
				)
				( attribute "CDS_PHYS_NET_NAME" "AGND_PVPP_ABC"
					( Origin gPackager )
				)
				( objectStatus "AGND_PVPP_ABC" )
			)
			( signal "@baseboard_fab2_lib.baseboard_fab2(sch_1):page231_agnd_pvpp_abc"
				( attribute "VOLTAGE" "0.0V"
					( Units "uVoltage" "V" 1.000000)
					( Origin gFrontEnd )
				)
				( objectFlag fObjectAlias )
				( objectStatus "page231_agnd_pvpp_abc" )
			)
			( signal "@baseboard_fab2_lib.baseboard_fab2(sch_1):fm_pvpp_pvddq_cpu0_en_abc"
				( attribute "CDS_PHYS_NET_NAME" "FM_PVPP_PVDDQ_CPU0_EN_ABC"
					( Origin gPackager )
				)
				( objectStatus "FM_PVPP_PVDDQ_CPU0_EN_ABC" )
			)
			( signal "@baseboard_fab2_lib.baseboard_fab2(sch_1):pwrgd_pvpp_abc_r"
				( attribute "CDS_PHYS_NET_NAME" "PWRGD_PVPP_ABC_R"
					( Origin gPackager )
				)
				( objectStatus "PWRGD_PVPP_ABC_R" )
			)
			( signal "@baseboard_fab2_lib.baseboard_fab2(sch_1):vr_comp_pvpp_abc"
				( attribute "CDS_PHYS_NET_NAME" "VR_COMP_PVPP_ABC"
					( Origin gPackager )
				)
				( objectStatus "VR_COMP_PVPP_ABC" )
			)
			( signal "@baseboard_fab2_lib.baseboard_fab2(sch_1):vr_comp_pvpp_abc_3"
				( attribute "CDS_PHYS_NET_NAME" "VR_COMP_PVPP_ABC_3"
					( Origin gPackager )
				)
				( objectStatus "VR_COMP_PVPP_ABC_3" )
			)
			( signal "@baseboard_fab2_lib.baseboard_fab2(sch_1):vr_comp_rc_pvpp_abc"
				( attribute "CDS_PHYS_NET_NAME" "VR_COMP_RC_PVPP_ABC"
					( Origin gPackager )
				)
				( objectStatus "VR_COMP_RC_PVPP_ABC" )
			)
			( signal "@baseboard_fab2_lib.baseboard_fab2(sch_1):vr_fb_pvpp_abc"
				( attribute "CDS_PHYS_NET_NAME" "VR_FB_PVPP_ABC"
					( Origin gPackager )
				)
				( objectStatus "VR_FB_PVPP_ABC" )
			)
			( signal "@baseboard_fab2_lib.baseboard_fab2(sch_1):vr_fet_sw_p12v_stby_pvpp_abc"
				( attribute "CDS_PHYS_NET_NAME" "VR_FET_SW_P12V_STBY_PVPP_ABC"
					( Origin gPackager )
				)
				( objectStatus "VR_FET_SW_P12V_STBY_PVPP_ABC" )
			)
			( signal "@baseboard_fab2_lib.baseboard_fab2(sch_1):vr_pvpp_abc_boot"
				( attribute "CDS_PHYS_NET_NAME" "VR_PVPP_ABC_BOOT"
					( Origin gPackager )
				)
				( objectStatus "VR_PVPP_ABC_BOOT" )
			)
			( signal "@baseboard_fab2_lib.baseboard_fab2(sch_1):vr_pvpp_abc_boot_r"
				( attribute "CDS_PHYS_NET_NAME" "VR_PVPP_ABC_BOOT_R"
					( Origin gPackager )
				)
				( objectStatus "VR_PVPP_ABC_BOOT_R" )
			)
			( signal "@baseboard_fab2_lib.baseboard_fab2(sch_1):vr_pvpp_abc_iset"
				( attribute "CDS_PHYS_NET_NAME" "VR_PVPP_ABC_ISET"
					( Origin gPackager )
				)
				( objectStatus "VR_PVPP_ABC_ISET" )
			)
			( signal "@baseboard_fab2_lib.baseboard_fab2(sch_1):vr_pvpp_abc_phase"
				( attribute "CDS_PHYS_NET_NAME" "VR_PVPP_ABC_PHASE"
					( Origin gPackager )
				)
				( objectStatus "VR_PVPP_ABC_PHASE" )
			)
			( signal "@baseboard_fab2_lib.baseboard_fab2(sch_1):vr_pvpp_abc_snub"
				( attribute "CDS_PHYS_NET_NAME" "VR_PVPP_ABC_SNUB"
					( Origin gPackager )
				)
				( objectStatus "VR_PVPP_ABC_SNUB" )
			)
			( signal "@baseboard_fab2_lib.baseboard_fab2(sch_1):vr_pvpp_abc_ss"
				( attribute "CDS_PHYS_NET_NAME" "VR_PVPP_ABC_SS"
					( Origin gPackager )
				)
				( objectStatus "VR_PVPP_ABC_SS" )
			)
			( signal "@baseboard_fab2_lib.baseboard_fab2(sch_1):vr_vb_pvpp_abc"
				( attribute "CDS_PHYS_NET_NAME" "VR_VB_PVPP_ABC"
					( Origin gPackager )
				)
				( objectStatus "VR_VB_PVPP_ABC" )
			)
			( signal "@baseboard_fab2_lib.baseboard_fab2(sch_1):vsense_pvpp_abc"
				( attribute "CDS_PHYS_NET_NAME" "VSENSE_PVPP_ABC"
					( Origin gPackager )
				)
				( objectStatus "VSENSE_PVPP_ABC" )
			)
			( signal "@baseboard_fab2_lib.baseboard_fab2(sch_1):agnd_pvpp_def"
				( alias ( signalRef "@baseboard_fab2_lib.baseboard_fab2(sch_1):page232_agnd_pvpp_def") )
				( attribute "VOLTAGE" "0.0V"
					( Units "uVoltage" "V" 1.000000)
					( Status sAliasFlattened )
					( Origin gFrontEnd )
				)
				( attribute "CDS_PHYS_NET_NAME" "AGND_PVPP_DEF"
					( Origin gPackager )
				)
				( objectStatus "AGND_PVPP_DEF" )
			)
			( signal "@baseboard_fab2_lib.baseboard_fab2(sch_1):page232_agnd_pvpp_def"
				( attribute "VOLTAGE" "0.0V"
					( Units "uVoltage" "V" 1.000000)
					( Origin gFrontEnd )
				)
				( objectFlag fObjectAlias )
				( objectStatus "page232_agnd_pvpp_def" )
			)
			( signal "@baseboard_fab2_lib.baseboard_fab2(sch_1):fm_pvpp_pvddq_cpu0_en_def"
				( attribute "CDS_PHYS_NET_NAME" "FM_PVPP_PVDDQ_CPU0_EN_DEF"
					( Origin gPackager )
				)
				( objectStatus "FM_PVPP_PVDDQ_CPU0_EN_DEF" )
			)
			( signal "@baseboard_fab2_lib.baseboard_fab2(sch_1):pwrgd_pvpp_def_r"
				( attribute "CDS_PHYS_NET_NAME" "PWRGD_PVPP_DEF_R"
					( Origin gPackager )
				)
				( objectStatus "PWRGD_PVPP_DEF_R" )
			)
			( signal "@baseboard_fab2_lib.baseboard_fab2(sch_1):vr_comp_pvpp_def"
				( attribute "CDS_PHYS_NET_NAME" "VR_COMP_PVPP_DEF"
					( Origin gPackager )
				)
				( objectStatus "VR_COMP_PVPP_DEF" )
			)
			( signal "@baseboard_fab2_lib.baseboard_fab2(sch_1):vr_comp_pvpp_def_3"
				( attribute "CDS_PHYS_NET_NAME" "VR_COMP_PVPP_DEF_3"
					( Origin gPackager )
				)
				( objectStatus "VR_COMP_PVPP_DEF_3" )
			)
			( signal "@baseboard_fab2_lib.baseboard_fab2(sch_1):vr_comp_rc_pvpp_def"
				( attribute "CDS_PHYS_NET_NAME" "VR_COMP_RC_PVPP_DEF"
					( Origin gPackager )
				)
				( objectStatus "VR_COMP_RC_PVPP_DEF" )
			)
			( signal "@baseboard_fab2_lib.baseboard_fab2(sch_1):vr_fb_pvpp_def"
				( attribute "CDS_PHYS_NET_NAME" "VR_FB_PVPP_DEF"
					( Origin gPackager )
				)
				( objectStatus "VR_FB_PVPP_DEF" )
			)
			( signal "@baseboard_fab2_lib.baseboard_fab2(sch_1):vr_fet_sw_p12v_stby_pvpp_def"
				( attribute "CDS_PHYS_NET_NAME" "VR_FET_SW_P12V_STBY_PVPP_DEF"
					( Origin gPackager )
				)
				( objectStatus "VR_FET_SW_P12V_STBY_PVPP_DEF" )
			)
			( signal "@baseboard_fab2_lib.baseboard_fab2(sch_1):vr_pvpp_def_boot"
				( attribute "CDS_PHYS_NET_NAME" "VR_PVPP_DEF_BOOT"
					( Origin gPackager )
				)
				( objectStatus "VR_PVPP_DEF_BOOT" )
			)
			( signal "@baseboard_fab2_lib.baseboard_fab2(sch_1):vr_pvpp_def_boot_r"
				( attribute "CDS_PHYS_NET_NAME" "VR_PVPP_DEF_BOOT_R"
					( Origin gPackager )
				)
				( objectStatus "VR_PVPP_DEF_BOOT_R" )
			)
			( signal "@baseboard_fab2_lib.baseboard_fab2(sch_1):vr_pvpp_def_iset"
				( attribute "CDS_PHYS_NET_NAME" "VR_PVPP_DEF_ISET"
					( Origin gPackager )
				)
				( objectStatus "VR_PVPP_DEF_ISET" )
			)
			( signal "@baseboard_fab2_lib.baseboard_fab2(sch_1):vr_pvpp_def_phase"
				( attribute "CDS_PHYS_NET_NAME" "VR_PVPP_DEF_PHASE"
					( Origin gPackager )
				)
				( objectStatus "VR_PVPP_DEF_PHASE" )
			)
			( signal "@baseboard_fab2_lib.baseboard_fab2(sch_1):vr_pvpp_def_snub"
				( attribute "CDS_PHYS_NET_NAME" "VR_PVPP_DEF_SNUB"
					( Origin gPackager )
				)
				( objectStatus "VR_PVPP_DEF_SNUB" )
			)
			( signal "@baseboard_fab2_lib.baseboard_fab2(sch_1):vr_pvpp_def_ss"
				( attribute "CDS_PHYS_NET_NAME" "VR_PVPP_DEF_SS"
					( Origin gPackager )
				)
				( objectStatus "VR_PVPP_DEF_SS" )
			)
			( signal "@baseboard_fab2_lib.baseboard_fab2(sch_1):vr_vb_pvpp_def"
				( attribute "CDS_PHYS_NET_NAME" "VR_VB_PVPP_DEF"
					( Origin gPackager )
				)
				( objectStatus "VR_VB_PVPP_DEF" )
			)
			( signal "@baseboard_fab2_lib.baseboard_fab2(sch_1):vsense_pvpp_def"
				( attribute "CDS_PHYS_NET_NAME" "VSENSE_PVPP_DEF"
					( Origin gPackager )
				)
				( objectStatus "VSENSE_PVPP_DEF" )
			)
			( signal "@baseboard_fab2_lib.baseboard_fab2(sch_1):agnd_pvpp_ghj"
				( alias ( signalRef "@baseboard_fab2_lib.baseboard_fab2(sch_1):page233_agnd_pvpp_ghj") )
				( attribute "VOLTAGE" "0.0V"
					( Units "uVoltage" "V" 1.000000)
					( Status sAliasFlattened )
					( Origin gFrontEnd )
				)
				( attribute "CDS_PHYS_NET_NAME" "AGND_PVPP_GHJ"
					( Origin gPackager )
				)
				( objectStatus "AGND_PVPP_GHJ" )
			)
			( signal "@baseboard_fab2_lib.baseboard_fab2(sch_1):page233_agnd_pvpp_ghj"
				( attribute "VOLTAGE" "0.0V"
					( Units "uVoltage" "V" 1.000000)
					( Origin gFrontEnd )
				)
				( objectFlag fObjectAlias )
				( objectStatus "page233_agnd_pvpp_ghj" )
			)
			( signal "@baseboard_fab2_lib.baseboard_fab2(sch_1):fm_pvpp_pvddq_cpu1_en_ghj"
				( attribute "CDS_PHYS_NET_NAME" "FM_PVPP_PVDDQ_CPU1_EN_GHJ"
					( Origin gPackager )
				)
				( objectStatus "FM_PVPP_PVDDQ_CPU1_EN_GHJ" )
			)
			( signal "@baseboard_fab2_lib.baseboard_fab2(sch_1):pwrgd_pvpp_ghj_r"
				( attribute "CDS_PHYS_NET_NAME" "PWRGD_PVPP_GHJ_R"
					( Origin gPackager )
				)
				( objectStatus "PWRGD_PVPP_GHJ_R" )
			)
			( signal "@baseboard_fab2_lib.baseboard_fab2(sch_1):vr_comp_pvpp_ghj"
				( attribute "CDS_PHYS_NET_NAME" "VR_COMP_PVPP_GHJ"
					( Origin gPackager )
				)
				( objectStatus "VR_COMP_PVPP_GHJ" )
			)
			( signal "@baseboard_fab2_lib.baseboard_fab2(sch_1):vr_comp_pvpp_ghj_3"
				( attribute "CDS_PHYS_NET_NAME" "VR_COMP_PVPP_GHJ_3"
					( Origin gPackager )
				)
				( objectStatus "VR_COMP_PVPP_GHJ_3" )
			)
			( signal "@baseboard_fab2_lib.baseboard_fab2(sch_1):vr_comp_rc_pvpp_ghj"
				( attribute "CDS_PHYS_NET_NAME" "VR_COMP_RC_PVPP_GHJ"
					( Origin gPackager )
				)
				( objectStatus "VR_COMP_RC_PVPP_GHJ" )
			)
			( signal "@baseboard_fab2_lib.baseboard_fab2(sch_1):vr_fb_pvpp_ghj"
				( attribute "CDS_PHYS_NET_NAME" "VR_FB_PVPP_GHJ"
					( Origin gPackager )
				)
				( objectStatus "VR_FB_PVPP_GHJ" )
			)
			( signal "@baseboard_fab2_lib.baseboard_fab2(sch_1):vr_fet_sw_p12v_stby_pvpp_ghj"
				( attribute "CDS_PHYS_NET_NAME" "VR_FET_SW_P12V_STBY_PVPP_GHJ"
					( Origin gPackager )
				)
				( objectStatus "VR_FET_SW_P12V_STBY_PVPP_GHJ" )
			)
			( signal "@baseboard_fab2_lib.baseboard_fab2(sch_1):vr_pvpp_ghj_boot"
				( attribute "CDS_PHYS_NET_NAME" "VR_PVPP_GHJ_BOOT"
					( Origin gPackager )
				)
				( objectStatus "VR_PVPP_GHJ_BOOT" )
			)
			( signal "@baseboard_fab2_lib.baseboard_fab2(sch_1):vr_pvpp_ghj_boot_r"
				( attribute "CDS_PHYS_NET_NAME" "VR_PVPP_GHJ_BOOT_R"
					( Origin gPackager )
				)
				( objectStatus "VR_PVPP_GHJ_BOOT_R" )
			)
			( signal "@baseboard_fab2_lib.baseboard_fab2(sch_1):vr_pvpp_ghj_iset"
				( attribute "CDS_PHYS_NET_NAME" "VR_PVPP_GHJ_ISET"
					( Origin gPackager )
				)
				( objectStatus "VR_PVPP_GHJ_ISET" )
			)
			( signal "@baseboard_fab2_lib.baseboard_fab2(sch_1):vr_pvpp_ghj_phase"
				( attribute "CDS_PHYS_NET_NAME" "VR_PVPP_GHJ_PHASE"
					( Origin gPackager )
				)
				( objectStatus "VR_PVPP_GHJ_PHASE" )
			)
			( signal "@baseboard_fab2_lib.baseboard_fab2(sch_1):vr_pvpp_ghj_snub"
				( attribute "CDS_PHYS_NET_NAME" "VR_PVPP_GHJ_SNUB"
					( Origin gPackager )
				)
				( objectStatus "VR_PVPP_GHJ_SNUB" )
			)
			( signal "@baseboard_fab2_lib.baseboard_fab2(sch_1):vr_pvpp_ghj_ss"
				( attribute "CDS_PHYS_NET_NAME" "VR_PVPP_GHJ_SS"
					( Origin gPackager )
				)
				( objectStatus "VR_PVPP_GHJ_SS" )
			)
			( signal "@baseboard_fab2_lib.baseboard_fab2(sch_1):vr_vb_pvpp_ghj"
				( attribute "CDS_PHYS_NET_NAME" "VR_VB_PVPP_GHJ"
					( Origin gPackager )
				)
				( objectStatus "VR_VB_PVPP_GHJ" )
			)
			( signal "@baseboard_fab2_lib.baseboard_fab2(sch_1):vsense_pvpp_ghj"
				( attribute "CDS_PHYS_NET_NAME" "VSENSE_PVPP_GHJ"
					( Origin gPackager )
				)
				( objectStatus "VSENSE_PVPP_GHJ" )
			)
			( signal "@baseboard_fab2_lib.baseboard_fab2(sch_1):agnd_pvpp_klm"
				( alias ( signalRef "@baseboard_fab2_lib.baseboard_fab2(sch_1):page234_agnd_pvpp_klm") )
				( attribute "VOLTAGE" "0.0V"
					( Units "uVoltage" "V" 1.000000)
					( Status sAliasFlattened )
					( Origin gFrontEnd )
				)
				( attribute "CDS_PHYS_NET_NAME" "AGND_PVPP_KLM"
					( Origin gPackager )
				)
				( objectStatus "AGND_PVPP_KLM" )
			)
			( signal "@baseboard_fab2_lib.baseboard_fab2(sch_1):page234_agnd_pvpp_klm"
				( attribute "VOLTAGE" "0.0V"
					( Units "uVoltage" "V" 1.000000)
					( Origin gFrontEnd )
				)
				( objectFlag fObjectAlias )
				( objectStatus "page234_agnd_pvpp_klm" )
			)
			( signal "@baseboard_fab2_lib.baseboard_fab2(sch_1):fm_pvpp_pvddq_cpu1_en_klm"
				( attribute "CDS_PHYS_NET_NAME" "FM_PVPP_PVDDQ_CPU1_EN_KLM"
					( Origin gPackager )
				)
				( objectStatus "FM_PVPP_PVDDQ_CPU1_EN_KLM" )
			)
			( signal "@baseboard_fab2_lib.baseboard_fab2(sch_1):pwrgd_pvpp_klm_r"
				( attribute "CDS_PHYS_NET_NAME" "PWRGD_PVPP_KLM_R"
					( Origin gPackager )
				)
				( objectStatus "PWRGD_PVPP_KLM_R" )
			)
			( signal "@baseboard_fab2_lib.baseboard_fab2(sch_1):vr_comp_pvpp_klm"
				( attribute "CDS_PHYS_NET_NAME" "VR_COMP_PVPP_KLM"
					( Origin gPackager )
				)
				( objectStatus "VR_COMP_PVPP_KLM" )
			)
			( signal "@baseboard_fab2_lib.baseboard_fab2(sch_1):vr_comp_pvpp_klm_3"
				( attribute "CDS_PHYS_NET_NAME" "VR_COMP_PVPP_KLM_3"
					( Origin gPackager )
				)
				( objectStatus "VR_COMP_PVPP_KLM_3" )
			)
			( signal "@baseboard_fab2_lib.baseboard_fab2(sch_1):vr_comp_rc_pvpp_klm"
				( attribute "CDS_PHYS_NET_NAME" "VR_COMP_RC_PVPP_KLM"
					( Origin gPackager )
				)
				( objectStatus "VR_COMP_RC_PVPP_KLM" )
			)
			( signal "@baseboard_fab2_lib.baseboard_fab2(sch_1):vr_fb_pvpp_klm"
				( attribute "CDS_PHYS_NET_NAME" "VR_FB_PVPP_KLM"
					( Origin gPackager )
				)
				( objectStatus "VR_FB_PVPP_KLM" )
			)
			( signal "@baseboard_fab2_lib.baseboard_fab2(sch_1):vr_fet_sw_p12v_stby_pvpp_klm"
				( attribute "CDS_PHYS_NET_NAME" "VR_FET_SW_P12V_STBY_PVPP_KLM"
					( Origin gPackager )
				)
				( objectStatus "VR_FET_SW_P12V_STBY_PVPP_KLM" )
			)
			( signal "@baseboard_fab2_lib.baseboard_fab2(sch_1):vr_pvpp_klm_boot"
				( attribute "CDS_PHYS_NET_NAME" "VR_PVPP_KLM_BOOT"
					( Origin gPackager )
				)
				( objectStatus "VR_PVPP_KLM_BOOT" )
			)
			( signal "@baseboard_fab2_lib.baseboard_fab2(sch_1):vr_pvpp_klm_boot_r"
				( attribute "CDS_PHYS_NET_NAME" "VR_PVPP_KLM_BOOT_R"
					( Origin gPackager )
				)
				( objectStatus "VR_PVPP_KLM_BOOT_R" )
			)
			( signal "@baseboard_fab2_lib.baseboard_fab2(sch_1):vr_pvpp_klm_iset"
				( attribute "CDS_PHYS_NET_NAME" "VR_PVPP_KLM_ISET"
					( Origin gPackager )
				)
				( objectStatus "VR_PVPP_KLM_ISET" )
			)
			( signal "@baseboard_fab2_lib.baseboard_fab2(sch_1):vr_pvpp_klm_phase"
				( attribute "CDS_PHYS_NET_NAME" "VR_PVPP_KLM_PHASE"
					( Origin gPackager )
				)
				( objectStatus "VR_PVPP_KLM_PHASE" )
			)
			( signal "@baseboard_fab2_lib.baseboard_fab2(sch_1):vr_pvpp_klm_snub"
				( attribute "CDS_PHYS_NET_NAME" "VR_PVPP_KLM_SNUB"
					( Origin gPackager )
				)
				( objectStatus "VR_PVPP_KLM_SNUB" )
			)
			( signal "@baseboard_fab2_lib.baseboard_fab2(sch_1):vr_pvpp_klm_ss"
				( attribute "CDS_PHYS_NET_NAME" "VR_PVPP_KLM_SS"
					( Origin gPackager )
				)
				( objectStatus "VR_PVPP_KLM_SS" )
			)
			( signal "@baseboard_fab2_lib.baseboard_fab2(sch_1):vr_vb_pvpp_klm"
				( attribute "CDS_PHYS_NET_NAME" "VR_VB_PVPP_KLM"
					( Origin gPackager )
				)
				( objectStatus "VR_VB_PVPP_KLM" )
			)
			( signal "@baseboard_fab2_lib.baseboard_fab2(sch_1):vsense_pvpp_klm"
				( attribute "CDS_PHYS_NET_NAME" "VSENSE_PVPP_KLM"
					( Origin gPackager )
				)
				( objectStatus "VSENSE_PVPP_KLM" )
			)
			( signal "@baseboard_fab2_lib.baseboard_fab2(sch_1):a_tsense_p1v05_pch_stby_tmon"
				( attribute "CDS_PHYS_NET_NAME" "A_TSENSE_P1V05_PCH_STBY_TMON"
					( Origin gPackager )
				)
				( objectStatus "A_TSENSE_P1V05_PCH_STBY_TMON" )
			)
			( signal "@baseboard_fab2_lib.baseboard_fab2(sch_1):a_tsense_pvnn_pch_tmon"
				( attribute "CDS_PHYS_NET_NAME" "A_TSENSE_PVNN_PCH_TMON"
					( Origin gPackager )
				)
				( objectStatus "A_TSENSE_PVNN_PCH_TMON" )
			)
			( signal "@baseboard_fab2_lib.baseboard_fab2(sch_1):irq_pvnn_pch_vrhot_n"
				( attribute "CDS_PHYS_NET_NAME" "IRQ_PVNN_PCH_VRHOT_N"
					( Origin gPackager )
				)
				( objectStatus "IRQ_PVNN_PCH_VRHOT_N" )
			)
			( signal "@baseboard_fab2_lib.baseboard_fab2(sch_1):isense_p1v05_pch_stby_ph1_imon"
				( attribute "CDS_PHYS_NET_NAME" "ISENSE_P1V05_PCH_STBY_PH1_IMON"
					( Origin gPackager )
				)
				( objectStatus "ISENSE_P1V05_PCH_STBY_PH1_IMON" )
			)
			( signal "@baseboard_fab2_lib.baseboard_fab2(sch_1):isense_pvnn_pch_ph1_imon"
				( attribute "CDS_PHYS_NET_NAME" "ISENSE_PVNN_PCH_PH1_IMON"
					( Origin gPackager )
				)
				( objectStatus "ISENSE_PVNN_PCH_PH1_IMON" )
			)
			( signal "@baseboard_fab2_lib.baseboard_fab2(sch_1):pu_vr_pvnn_pch_fault1"
				( attribute "CDS_PHYS_NET_NAME" "PU_VR_PVNN_PCH_FAULT1"
					( Origin gPackager )
				)
				( objectStatus "PU_VR_PVNN_PCH_FAULT1" )
			)
			( signal "@baseboard_fab2_lib.baseboard_fab2(sch_1):pwrgd_p1v8_pch_stby"
				( attribute "CDS_PHYS_NET_NAME" "PWRGD_P1V8_PCH_STBY"
					( Origin gPackager )
				)
				( objectStatus "PWRGD_P1V8_PCH_STBY" )
			)
			( signal "@baseboard_fab2_lib.baseboard_fab2(sch_1):pwrgd_pvnn_pch_r"
				( attribute "CDS_PHYS_NET_NAME" "PWRGD_PVNN_PCH_R"
					( Origin gPackager )
				)
				( objectStatus "PWRGD_PVNN_PCH_R" )
			)
			( signal "@baseboard_fab2_lib.baseboard_fab2(sch_1):pu_pvnn_pch_vdio"
				( attribute "CDS_PHYS_NET_NAME" "PU_PVNN_PCH_VDIO"
					( Origin gPackager )
				)
				( objectStatus "PU_PVNN_PCH_VDIO" )
			)
			( signal "@baseboard_fab2_lib.baseboard_fab2(sch_1):vr_p1v05_pch_biref1"
				( attribute "CDS_PHYS_NET_NAME" "VR_P1V05_PCH_BIREF1"
					( Origin gPackager )
				)
				( objectStatus "VR_P1V05_PCH_BIREF1" )
			)
			( signal "@baseboard_fab2_lib.baseboard_fab2(sch_1):vr_p1v05_pch_stby_avsp"
				( attribute "CDS_PHYS_NET_NAME" "VR_P1V05_PCH_STBY_AVSP"
					( Origin gPackager )
				)
				( objectStatus "VR_P1V05_PCH_STBY_AVSP" )
			)
			( signal "@baseboard_fab2_lib.baseboard_fab2(sch_1):vr_p1v05_pch_stby_pwm1"
				( attribute "CDS_PHYS_NET_NAME" "VR_P1V05_PCH_STBY_PWM1"
					( Origin gPackager )
				)
				( objectStatus "VR_P1V05_PCH_STBY_PWM1" )
			)
			( signal "@baseboard_fab2_lib.baseboard_fab2(sch_1):vr_pvnn_p1v05_pch_vd12"
				( attribute "CDS_PHYS_NET_NAME" "VR_PVNN_P1V05_PCH_VD12"
					( Origin gPackager )
				)
				( objectStatus "VR_PVNN_P1V05_PCH_VD12" )
			)
			( signal "@baseboard_fab2_lib.baseboard_fab2(sch_1):vr_pvnn_pch_airef1"
				( attribute "CDS_PHYS_NET_NAME" "VR_PVNN_PCH_AIREF1"
					( Origin gPackager )
				)
				( objectStatus "VR_PVNN_PCH_AIREF1" )
			)
			( signal "@baseboard_fab2_lib.baseboard_fab2(sch_1):vr_pvnn_pch_avsp"
				( attribute "CDS_PHYS_NET_NAME" "VR_PVNN_PCH_AVSP"
					( Origin gPackager )
				)
				( objectStatus "VR_PVNN_PCH_AVSP" )
			)
			( signal "@baseboard_fab2_lib.baseboard_fab2(sch_1):vr_pvnn_pch_pwm1"
				( attribute "CDS_PHYS_NET_NAME" "VR_PVNN_PCH_PWM1"
					( Origin gPackager )
				)
				( objectStatus "VR_PVNN_PCH_PWM1" )
			)
			( signal "@baseboard_fab2_lib.baseboard_fab2(sch_1):vr_pvnn_pch_vdd"
				( attribute "CDS_PHYS_NET_NAME" "VR_PVNN_PCH_VDD"
					( Origin gPackager )
				)
				( objectStatus "VR_PVNN_PCH_VDD" )
			)
			( signal "@baseboard_fab2_lib.baseboard_fab2(sch_1):vr_pvnn_pch_vinsen"
				( attribute "CDS_PHYS_NET_NAME" "VR_PVNN_PCH_VINSEN"
					( Origin gPackager )
				)
				( objectStatus "VR_PVNN_PCH_VINSEN" )
			)
			( signal "@baseboard_fab2_lib.baseboard_fab2(sch_1):vr_pvnn_pch_vren"
				( attribute "CDS_PHYS_NET_NAME" "VR_PVNN_PCH_VREN"
					( Origin gPackager )
				)
				( objectStatus "VR_PVNN_PCH_VREN" )
			)
			( signal "@baseboard_fab2_lib.baseboard_fab2(sch_1):vr_pvnn_pch_xaddr1"
				( attribute "CDS_PHYS_NET_NAME" "VR_PVNN_PCH_XADDR1"
					( Origin gPackager )
				)
				( objectStatus "VR_PVNN_PCH_XADDR1" )
			)
			( signal "@baseboard_fab2_lib.baseboard_fab2(sch_1):vr_pvnn_pch_xaddr2"
				( attribute "CDS_PHYS_NET_NAME" "VR_PVNN_PCH_XADDR2"
					( Origin gPackager )
				)
				( objectStatus "VR_PVNN_PCH_XADDR2" )
			)
			( signal "@baseboard_fab2_lib.baseboard_fab2(sch_1):vsense_p1v05_pch_stby_avsn"
				( attribute "CDS_PHYS_NET_NAME" "VSENSE_P1V05_PCH_STBY_AVSN"
					( Origin gPackager )
				)
				( objectStatus "VSENSE_P1V05_PCH_STBY_AVSN" )
			)
			( signal "@baseboard_fab2_lib.baseboard_fab2(sch_1):vsense_p1v05_pch_stby_avsp"
				( attribute "CDS_PHYS_NET_NAME" "VSENSE_P1V05_PCH_STBY_AVSP"
					( Origin gPackager )
				)
				( objectStatus "VSENSE_P1V05_PCH_STBY_AVSP" )
			)
			( signal "@baseboard_fab2_lib.baseboard_fab2(sch_1):vsense_pvnn_pch_stby_avsn"
				( attribute "CDS_PHYS_NET_NAME" "VSENSE_PVNN_PCH_STBY_AVSN"
					( Origin gPackager )
				)
				( objectStatus "VSENSE_PVNN_PCH_STBY_AVSN" )
			)
			( signal "@baseboard_fab2_lib.baseboard_fab2(sch_1):vsense_pvnn_pch_stby_avsp"
				( attribute "CDS_PHYS_NET_NAME" "VSENSE_PVNN_PCH_STBY_AVSP"
					( Origin gPackager )
				)
				( objectStatus "VSENSE_PVNN_PCH_STBY_AVSP" )
			)
			( signal "@baseboard_fab2_lib.baseboard_fab2(sch_1):nc_clk_156m_cpu1_osc"
				( attribute "CDS_PHYS_NET_NAME" "NC_CLK_156M_CPU1_OSC"
					( Origin gPackager )
				)
				( objectStatus "NC_CLK_156M_CPU1_OSC" )
			)
			( signal "@baseboard_fab2_lib.baseboard_fab2(sch_1):nc_clk_156m_cpu0_osc"
				( attribute "CDS_PHYS_NET_NAME" "NC_CLK_156M_CPU0_OSC"
					( Origin gPackager )
				)
				( objectStatus "NC_CLK_156M_CPU0_OSC" )
			)
			( signal "@baseboard_fab2_lib.baseboard_fab2(sch_1):tp_p1v05_pch_gl_0"
				( attribute "CDS_PHYS_NET_NAME" "TP_P1V05_PCH_GL_0"
					( Origin gPackager )
				)
				( objectStatus "TP_P1V05_PCH_GL_0" )
			)
			( signal "@baseboard_fab2_lib.baseboard_fab2(sch_1):tp_p1v05_pch_gl_1"
				( attribute "CDS_PHYS_NET_NAME" "TP_P1V05_PCH_GL_1"
					( Origin gPackager )
				)
				( objectStatus "TP_P1V05_PCH_GL_1" )
			)
			( signal "@baseboard_fab2_lib.baseboard_fab2(sch_1):tp_pvnn_pch_gl_0"
				( attribute "CDS_PHYS_NET_NAME" "TP_PVNN_PCH_GL_0"
					( Origin gPackager )
				)
				( objectStatus "TP_PVNN_PCH_GL_0" )
			)
			( signal "@baseboard_fab2_lib.baseboard_fab2(sch_1):tp_pvnn_pch_gl_1"
				( attribute "CDS_PHYS_NET_NAME" "TP_PVNN_PCH_GL_1"
					( Origin gPackager )
				)
				( objectStatus "TP_PVNN_PCH_GL_1" )
			)
			( signal "@baseboard_fab2_lib.baseboard_fab2(sch_1):vr_p1v05_pch_stby_ocset"
				( attribute "CDS_PHYS_NET_NAME" "VR_P1V05_PCH_STBY_OCSET"
					( Origin gPackager )
				)
				( objectStatus "VR_P1V05_PCH_STBY_OCSET" )
			)
			( signal "@baseboard_fab2_lib.baseboard_fab2(sch_1):vr_p1v05_pch_stby_ph1_boot"
				( attribute "CDS_PHYS_NET_NAME" "VR_P1V05_PCH_STBY_PH1_BOOT"
					( Origin gPackager )
				)
				( objectStatus "VR_P1V05_PCH_STBY_PH1_BOOT" )
			)
			( signal "@baseboard_fab2_lib.baseboard_fab2(sch_1):vr_p1v05_pch_stby_ph1_phase"
				( attribute "CDS_PHYS_NET_NAME" "VR_P1V05_PCH_STBY_PH1_PHASE"
					( Origin gPackager )
				)
				( objectStatus "VR_P1V05_PCH_STBY_PH1_PHASE" )
			)
			( signal "@baseboard_fab2_lib.baseboard_fab2(sch_1):vr_p1v05_pch_stby_ph1_phase_sw"
				( attribute "CDS_PHYS_NET_NAME" "VR_P1V05_PCH_STBY_PH1_PHASE_SW"
					( Origin gPackager )
				)
				( objectStatus "VR_P1V05_PCH_STBY_PH1_PHASE_SW" )
			)
			( signal "@baseboard_fab2_lib.baseboard_fab2(sch_1):vr_p1v05_pch_stby_ph1_vcin"
				( attribute "CDS_PHYS_NET_NAME" "VR_P1V05_PCH_STBY_PH1_VCIN"
					( Origin gPackager )
				)
				( objectStatus "VR_P1V05_PCH_STBY_PH1_VCIN" )
			)
			( signal "@baseboard_fab2_lib.baseboard_fab2(sch_1):vr_pvnn_pch_ph1_boot"
				( attribute "CDS_PHYS_NET_NAME" "VR_PVNN_PCH_PH1_BOOT"
					( Origin gPackager )
				)
				( objectStatus "VR_PVNN_PCH_PH1_BOOT" )
			)
			( signal "@baseboard_fab2_lib.baseboard_fab2(sch_1):vr_pvnn_pch_ph1_phase"
				( attribute "CDS_PHYS_NET_NAME" "VR_PVNN_PCH_PH1_PHASE"
					( Origin gPackager )
				)
				( objectStatus "VR_PVNN_PCH_PH1_PHASE" )
			)
			( signal "@baseboard_fab2_lib.baseboard_fab2(sch_1):vr_pvnn_pch_ph1_phase_sw"
				( attribute "CDS_PHYS_NET_NAME" "VR_PVNN_PCH_PH1_PHASE_SW"
					( Origin gPackager )
				)
				( objectStatus "VR_PVNN_PCH_PH1_PHASE_SW" )
			)
			( signal "@baseboard_fab2_lib.baseboard_fab2(sch_1):vr_pvnn_pch_ph1_vcin"
				( attribute "CDS_PHYS_NET_NAME" "VR_PVNN_PCH_PH1_VCIN"
					( Origin gPackager )
				)
				( objectStatus "VR_PVNN_PCH_PH1_VCIN" )
			)
			( signal "@baseboard_fab2_lib.baseboard_fab2(sch_1):vr_pvnn_pch_stby_ocset"
				( attribute "CDS_PHYS_NET_NAME" "VR_PVNN_PCH_STBY_OCSET"
					( Origin gPackager )
				)
				( objectStatus "VR_PVNN_PCH_STBY_OCSET" )
			)
			( signal "@baseboard_fab2_lib.baseboard_fab2(sch_1):pwrgd_p1v8_pch_stby_r"
				( attribute "CDS_PHYS_NET_NAME" "PWRGD_P1V8_PCH_STBY_R"
					( Origin gPackager )
				)
				( objectStatus "PWRGD_P1V8_PCH_STBY_R" )
			)
			( signal "@baseboard_fab2_lib.baseboard_fab2(sch_1):vr_p1v8_pch_stby_fb"
				( attribute "CDS_PHYS_NET_NAME" "VR_P1V8_PCH_STBY_FB"
					( Origin gPackager )
				)
				( objectStatus "VR_P1V8_PCH_STBY_FB" )
			)
			( signal "@baseboard_fab2_lib.baseboard_fab2(sch_1):pwrgd_p1v15_bmc_stby_r"
				( attribute "CDS_PHYS_NET_NAME" "PWRGD_P1V15_BMC_STBY_R"
					( Origin gPackager )
				)
				( objectStatus "PWRGD_P1V15_BMC_STBY_R" )
			)
			( signal "@baseboard_fab2_lib.baseboard_fab2(sch_1):agnd_p3v3_stby"
				( alias ( signalRef "@baseboard_fab2_lib.baseboard_fab2(sch_1):page240_agnd_p3v3_stby") )
				( attribute "VOLTAGE" "0V"
					( Units "uVoltage" "V" 1.000000)
					( Status sAliasFlattened )
					( Origin gFrontEnd )
				)
				( attribute "CDS_PHYS_NET_NAME" "AGND_P3V3_STBY"
					( Origin gPackager )
				)
				( objectStatus "AGND_P3V3_STBY" )
			)
			( signal "@baseboard_fab2_lib.baseboard_fab2(sch_1):page240_agnd_p3v3_stby"
				( attribute "VOLTAGE" "0V"
					( Units "uVoltage" "V" 1.000000)
					( Origin gFrontEnd )
				)
				( objectFlag fObjectAlias )
				( objectStatus "page240_agnd_p3v3_stby" )
			)
			( signal "@baseboard_fab2_lib.baseboard_fab2(sch_1):pwrgd_p3v3_stby_r"
				( attribute "CDS_PHYS_NET_NAME" "PWRGD_P3V3_STBY_R"
					( Origin gPackager )
				)
				( objectStatus "PWRGD_P3V3_STBY_R" )
			)
			( signal "@baseboard_fab2_lib.baseboard_fab2(sch_1):pwrgd_p5v_stby"
				( attribute "CDS_PHYS_NET_NAME" "PWRGD_P5V_STBY"
					( Origin gPackager )
				)
				( objectStatus "PWRGD_P5V_STBY" )
			)
			( signal "@baseboard_fab2_lib.baseboard_fab2(sch_1):vr_fet_sw_p12v_stby_p3v3_stby"
				( attribute "CDS_PHYS_NET_NAME" "VR_FET_SW_P12V_STBY_P3V3_STBY"
					( Origin gPackager )
				)
				( objectStatus "VR_FET_SW_P12V_STBY_P3V3_STBY" )
			)
			( signal "@baseboard_fab2_lib.baseboard_fab2(sch_1):vr_p3v3_stby_boot"
				( attribute "CDS_PHYS_NET_NAME" "VR_P3V3_STBY_BOOT"
					( Origin gPackager )
				)
				( objectStatus "VR_P3V3_STBY_BOOT" )
			)
			( signal "@baseboard_fab2_lib.baseboard_fab2(sch_1):vr_p3v3_stby_boot_r"
				( attribute "CDS_PHYS_NET_NAME" "VR_P3V3_STBY_BOOT_R"
					( Origin gPackager )
				)
				( objectStatus "VR_P3V3_STBY_BOOT_R" )
			)
			( signal "@baseboard_fab2_lib.baseboard_fab2(sch_1):vr_p3v3_stby_en"
				( attribute "CDS_PHYS_NET_NAME" "VR_P3V3_STBY_EN"
					( Origin gPackager )
				)
				( objectStatus "VR_P3V3_STBY_EN" )
			)
			( signal "@baseboard_fab2_lib.baseboard_fab2(sch_1):vr_p3v3_stby_lgate"
				( attribute "CDS_PHYS_NET_NAME" "VR_P3V3_STBY_LGATE"
					( Origin gPackager )
				)
				( objectStatus "VR_P3V3_STBY_LGATE" )
			)
			( signal "@baseboard_fab2_lib.baseboard_fab2(sch_1):vr_p3v3_stby_ocselect"
				( attribute "CDS_PHYS_NET_NAME" "VR_P3V3_STBY_OCSELECT"
					( Origin gPackager )
				)
				( objectStatus "VR_P3V3_STBY_OCSELECT" )
			)
			( signal "@baseboard_fab2_lib.baseboard_fab2(sch_1):vr_p3v3_stby_phase"
				( attribute "CDS_PHYS_NET_NAME" "VR_P3V3_STBY_PHASE"
					( Origin gPackager )
				)
				( objectStatus "VR_P3V3_STBY_PHASE" )
			)
			( signal "@baseboard_fab2_lib.baseboard_fab2(sch_1):vr_p3v3_stby_snub"
				( attribute "CDS_PHYS_NET_NAME" "VR_P3V3_STBY_SNUB"
					( Origin gPackager )
				)
				( objectStatus "VR_P3V3_STBY_SNUB" )
			)
			( signal "@baseboard_fab2_lib.baseboard_fab2(sch_1):vr_p3v3_stby_ugate"
				( attribute "CDS_PHYS_NET_NAME" "VR_P3V3_STBY_UGATE"
					( Origin gPackager )
				)
				( objectStatus "VR_P3V3_STBY_UGATE" )
			)
			( signal "@baseboard_fab2_lib.baseboard_fab2(sch_1):vsense_p3v3_stby"
				( attribute "CDS_PHYS_NET_NAME" "VSENSE_P3V3_STBY"
					( Origin gPackager )
				)
				( objectStatus "VSENSE_P3V3_STBY" )
			)
			( signal "@baseboard_fab2_lib.baseboard_fab2(sch_1):vsense_rgnd_p3v3_stby"
				( attribute "CDS_PHYS_NET_NAME" "VSENSE_RGND_P3V3_STBY"
					( Origin gPackager )
				)
				( objectStatus "VSENSE_RGND_P3V3_STBY" )
			)
			( signal "@baseboard_fab2_lib.baseboard_fab2(sch_1):vsense_vout_p3v3_stby"
				( attribute "CDS_PHYS_NET_NAME" "VSENSE_VOUT_P3V3_STBY"
					( Origin gPackager )
				)
				( objectStatus "VSENSE_VOUT_P3V3_STBY" )
			)
			( signal "@baseboard_fab2_lib.baseboard_fab2(sch_1):agnd_p5v_stby"
				( alias ( signalRef "@baseboard_fab2_lib.baseboard_fab2(sch_1):page241_agnd_p5v_stby") )
				( attribute "VOLTAGE" "0"
					( Units "uVoltage" "V" 1.000000)
					( Status sAliasFlattened )
					( Origin gFrontEnd )
				)
				( attribute "CDS_PHYS_NET_NAME" "AGND_P5V_STBY"
					( Origin gPackager )
				)
				( objectStatus "AGND_P5V_STBY" )
			)
			( signal "@baseboard_fab2_lib.baseboard_fab2(sch_1):page241_agnd_p5v_stby"
				( attribute "VOLTAGE" "0"
					( Units "uVoltage" "V" 1.000000)
					( Origin gFrontEnd )
				)
				( objectFlag fObjectAlias )
				( objectStatus "page241_agnd_p5v_stby" )
			)
			( signal "@baseboard_fab2_lib.baseboard_fab2(sch_1):pwrgd_p5v_stby_r"
				( attribute "CDS_PHYS_NET_NAME" "PWRGD_P5V_STBY_R"
					( Origin gPackager )
				)
				( objectStatus "PWRGD_P5V_STBY_R" )
			)
			( signal "@baseboard_fab2_lib.baseboard_fab2(sch_1):vr_fet_sw_p5v_stby_pvin"
				( attribute "CDS_PHYS_NET_NAME" "VR_FET_SW_P5V_STBY_PVIN"
					( Origin gPackager )
				)
				( objectStatus "VR_FET_SW_P5V_STBY_PVIN" )
			)
			( signal "@baseboard_fab2_lib.baseboard_fab2(sch_1):vr_p5v_stby_boot"
				( attribute "CDS_PHYS_NET_NAME" "VR_P5V_STBY_BOOT"
					( Origin gPackager )
				)
				( objectStatus "VR_P5V_STBY_BOOT" )
			)
			( signal "@baseboard_fab2_lib.baseboard_fab2(sch_1):vr_p5v_stby_comp"
				( attribute "CDS_PHYS_NET_NAME" "VR_P5V_STBY_COMP"
					( Origin gPackager )
				)
				( objectStatus "VR_P5V_STBY_COMP" )
			)
			( signal "@baseboard_fab2_lib.baseboard_fab2(sch_1):vr_p5v_stby_en"
				( attribute "CDS_PHYS_NET_NAME" "VR_P5V_STBY_EN"
					( Origin gPackager )
				)
				( objectStatus "VR_P5V_STBY_EN" )
			)
			( signal "@baseboard_fab2_lib.baseboard_fab2(sch_1):vr_p5v_stby_phase"
				( attribute "CDS_PHYS_NET_NAME" "VR_P5V_STBY_PHASE"
					( Origin gPackager )
				)
				( objectStatus "VR_P5V_STBY_PHASE" )
			)
			( signal "@baseboard_fab2_lib.baseboard_fab2(sch_1):vr_p5v_stby_rc_comp"
				( attribute "CDS_PHYS_NET_NAME" "VR_P5V_STBY_RC_COMP"
					( Origin gPackager )
				)
				( objectStatus "VR_P5V_STBY_RC_COMP" )
			)
			( signal "@baseboard_fab2_lib.baseboard_fab2(sch_1):vr_p5v_stby_rt"
				( attribute "CDS_PHYS_NET_NAME" "VR_P5V_STBY_RT"
					( Origin gPackager )
				)
				( objectStatus "VR_P5V_STBY_RT" )
			)
			( signal "@baseboard_fab2_lib.baseboard_fab2(sch_1):vr_p5v_stby_ss"
				( attribute "CDS_PHYS_NET_NAME" "VR_P5V_STBY_SS"
					( Origin gPackager )
				)
				( objectStatus "VR_P5V_STBY_SS" )
			)
			( signal "@baseboard_fab2_lib.baseboard_fab2(sch_1):vr_p5v_stby_vin"
				( attribute "CDS_PHYS_NET_NAME" "VR_P5V_STBY_VIN"
					( Origin gPackager )
				)
				( objectStatus "VR_P5V_STBY_VIN" )
			)
			( signal "@baseboard_fab2_lib.baseboard_fab2(sch_1):vr_p5v_stby_vsense"
				( attribute "CDS_PHYS_NET_NAME" "VR_P5V_STBY_VSENSE"
					( Origin gPackager )
				)
				( objectStatus "VR_P5V_STBY_VSENSE" )
			)
			( signal "@baseboard_fab2_lib.baseboard_fab2(sch_1):vr_p5v_stby_vsense_r"
				( attribute "CDS_PHYS_NET_NAME" "VR_P5V_STBY_VSENSE_R"
					( Origin gPackager )
				)
				( objectStatus "VR_P5V_STBY_VSENSE_R" )
			)
			( signal "@baseboard_fab2_lib.baseboard_fab2(sch_1):vr_pvccin_cpu0_ph1_boot_r"
				( attribute "CDS_PHYS_NET_NAME" "VR_PVCCIN_CPU0_PH1_BOOT_R"
					( Origin gPackager )
				)
				( objectStatus "VR_PVCCIN_CPU0_PH1_BOOT_R" )
			)
			( signal "@baseboard_fab2_lib.baseboard_fab2(sch_1):vr_pvccin_cpu0_ph2_boot_r"
				( attribute "CDS_PHYS_NET_NAME" "VR_PVCCIN_CPU0_PH2_BOOT_R"
					( Origin gPackager )
				)
				( objectStatus "VR_PVCCIN_CPU0_PH2_BOOT_R" )
			)
			( signal "@baseboard_fab2_lib.baseboard_fab2(sch_1):vr_pvccin_cpu1_phase3_rc"
				( attribute "CDS_PHYS_NET_NAME" "VR_PVCCIN_CPU1_PHASE3_RC"
					( Origin gPackager )
				)
				( objectStatus "VR_PVCCIN_CPU1_PHASE3_RC" )
			)
			( signal "@baseboard_fab2_lib.baseboard_fab2(sch_1):vr_pvddq_klm_ph1_boot_r"
				( attribute "CDS_PHYS_NET_NAME" "VR_PVDDQ_KLM_PH1_BOOT_R"
					( Origin gPackager )
				)
				( objectStatus "VR_PVDDQ_KLM_PH1_BOOT_R" )
			)
			( signal "@baseboard_fab2_lib.baseboard_fab2(sch_1):vr_pvddq_klm_ph2_boot_r"
				( attribute "CDS_PHYS_NET_NAME" "VR_PVDDQ_KLM_PH2_BOOT_R"
					( Origin gPackager )
				)
				( objectStatus "VR_PVDDQ_KLM_PH2_BOOT_R" )
			)
			( signal "@baseboard_fab2_lib.baseboard_fab2(sch_1):vr_pvccin_cpu1_ph5_boot_r"
				( attribute "CDS_PHYS_NET_NAME" "VR_PVCCIN_CPU1_PH5_BOOT_R"
					( Origin gPackager )
				)
				( objectStatus "VR_PVCCIN_CPU1_PH5_BOOT_R" )
			)
			( signal "@baseboard_fab2_lib.baseboard_fab2(sch_1):vr_pvccin_cpu1_ph3_boot_r"
				( attribute "CDS_PHYS_NET_NAME" "VR_PVCCIN_CPU1_PH3_BOOT_R"
					( Origin gPackager )
				)
				( objectStatus "VR_PVCCIN_CPU1_PH3_BOOT_R" )
			)
			( signal "@baseboard_fab2_lib.baseboard_fab2(sch_1):vr_pvccin_cpu1_ph4_boot_r"
				( attribute "CDS_PHYS_NET_NAME" "VR_PVCCIN_CPU1_PH4_BOOT_R"
					( Origin gPackager )
				)
				( objectStatus "VR_PVCCIN_CPU1_PH4_BOOT_R" )
			)
			( signal "@baseboard_fab2_lib.baseboard_fab2(sch_1):vr_pvccin_cpu1_ph1_boot_r"
				( attribute "CDS_PHYS_NET_NAME" "VR_PVCCIN_CPU1_PH1_BOOT_R"
					( Origin gPackager )
				)
				( objectStatus "VR_PVCCIN_CPU1_PH1_BOOT_R" )
			)
			( signal "@baseboard_fab2_lib.baseboard_fab2(sch_1):vr_pvddq_ghj_ph1_boot_r"
				( attribute "CDS_PHYS_NET_NAME" "VR_PVDDQ_GHJ_PH1_BOOT_R"
					( Origin gPackager )
				)
				( objectStatus "VR_PVDDQ_GHJ_PH1_BOOT_R" )
			)
			( signal "@baseboard_fab2_lib.baseboard_fab2(sch_1):vr_pvddq_ghj_ph2_boot_r"
				( attribute "CDS_PHYS_NET_NAME" "VR_PVDDQ_GHJ_PH2_BOOT_R"
					( Origin gPackager )
				)
				( objectStatus "VR_PVDDQ_GHJ_PH2_BOOT_R" )
			)
			( signal "@baseboard_fab2_lib.baseboard_fab2(sch_1):vr_pvddq_ghj_ph1_sw_rc"
				( attribute "CDS_PHYS_NET_NAME" "VR_PVDDQ_GHJ_PH1_SW_RC"
					( Origin gPackager )
				)
				( objectStatus "VR_PVDDQ_GHJ_PH1_SW_RC" )
			)
			( signal "@baseboard_fab2_lib.baseboard_fab2(sch_1):vr_pvccin_cpu0_ph3_boot_r"
				( attribute "CDS_PHYS_NET_NAME" "VR_PVCCIN_CPU0_PH3_BOOT_R"
					( Origin gPackager )
				)
				( objectStatus "VR_PVCCIN_CPU0_PH3_BOOT_R" )
			)
			( signal "@baseboard_fab2_lib.baseboard_fab2(sch_1):vr_pvddq_def_ph1_boot_r"
				( attribute "CDS_PHYS_NET_NAME" "VR_PVDDQ_DEF_PH1_BOOT_R"
					( Origin gPackager )
				)
				( objectStatus "VR_PVDDQ_DEF_PH1_BOOT_R" )
			)
			( signal "@baseboard_fab2_lib.baseboard_fab2(sch_1):vr_pvddq_def_ph2_boot_r"
				( attribute "CDS_PHYS_NET_NAME" "VR_PVDDQ_DEF_PH2_BOOT_R"
					( Origin gPackager )
				)
				( objectStatus "VR_PVDDQ_DEF_PH2_BOOT_R" )
			)
			( signal "@baseboard_fab2_lib.baseboard_fab2(sch_1):vr_pvddq_abc_ph1_boot_r"
				( attribute "CDS_PHYS_NET_NAME" "VR_PVDDQ_ABC_PH1_BOOT_R"
					( Origin gPackager )
				)
				( objectStatus "VR_PVDDQ_ABC_PH1_BOOT_R" )
			)
			( signal "@baseboard_fab2_lib.baseboard_fab2(sch_1):vr_pvddq_abc_ph2_boot_r"
				( attribute "CDS_PHYS_NET_NAME" "VR_PVDDQ_ABC_PH2_BOOT_R"
					( Origin gPackager )
				)
				( objectStatus "VR_PVDDQ_ABC_PH2_BOOT_R" )
			)
			( signal "@baseboard_fab2_lib.baseboard_fab2(sch_1):vr_pvsa_cpu1_boot_r"
				( attribute "CDS_PHYS_NET_NAME" "VR_PVSA_CPU1_BOOT_R"
					( Origin gPackager )
				)
				( objectStatus "VR_PVSA_CPU1_BOOT_R" )
			)
			( signal "@baseboard_fab2_lib.baseboard_fab2(sch_1):vr_pvsa_cpu0_boot_r"
				( attribute "CDS_PHYS_NET_NAME" "VR_PVSA_CPU0_BOOT_R"
					( Origin gPackager )
				)
				( objectStatus "VR_PVSA_CPU0_BOOT_R" )
			)
			( signal "@baseboard_fab2_lib.baseboard_fab2(sch_1):vr_pvccio_cpu1_ph1_boot_r"
				( attribute "CDS_PHYS_NET_NAME" "VR_PVCCIO_CPU1_PH1_BOOT_R"
					( Origin gPackager )
				)
				( objectStatus "VR_PVCCIO_CPU1_PH1_BOOT_R" )
			)
			( signal "@baseboard_fab2_lib.baseboard_fab2(sch_1):vr_p1v05_pch_stby_ph1_boot_r"
				( attribute "CDS_PHYS_NET_NAME" "VR_P1V05_PCH_STBY_PH1_BOOT_R"
					( Origin gPackager )
				)
				( objectStatus "VR_P1V05_PCH_STBY_PH1_BOOT_R" )
			)
			( signal "@baseboard_fab2_lib.baseboard_fab2(sch_1):vr_pvnn_pch_ph1_boot_r"
				( attribute "CDS_PHYS_NET_NAME" "VR_PVNN_PCH_PH1_BOOT_R"
					( Origin gPackager )
				)
				( objectStatus "VR_PVNN_PCH_PH1_BOOT_R" )
			)
			( signal "@baseboard_fab2_lib.baseboard_fab2(sch_1):vr_pvccio_cpu0_ph1_boot_r"
				( attribute "CDS_PHYS_NET_NAME" "VR_PVCCIO_CPU0_PH1_BOOT_R"
					( Origin gPackager )
				)
				( objectStatus "VR_PVCCIO_CPU0_PH1_BOOT_R" )
			)
			( signal "@baseboard_fab2_lib.baseboard_fab2(sch_1):vr_pvccin_cpu1_ph2_boot_r"
				( attribute "CDS_PHYS_NET_NAME" "VR_PVCCIN_CPU1_PH2_BOOT_R"
					( Origin gPackager )
				)
				( objectStatus "VR_PVCCIN_CPU1_PH2_BOOT_R" )
			)
			( signal "@baseboard_fab2_lib.baseboard_fab2(sch_1):vr_pvccin_cpu0_ph4_boot_r"
				( attribute "CDS_PHYS_NET_NAME" "VR_PVCCIN_CPU0_PH4_BOOT_R"
					( Origin gPackager )
				)
				( objectStatus "VR_PVCCIN_CPU0_PH4_BOOT_R" )
			)
			( signal "@baseboard_fab2_lib.baseboard_fab2(sch_1):p3e_cpu0_pe1_pch_con_rxn(8)"
				( attribute "CDS_PHYS_NET_NAME" "P3E_CPU0_PE1_PCH_CON_RXN<8>"
					( Origin gPackager )
				)
				( attribute "PNN" "P3E_CPU0_PE1_PCH_CON_RXN<8>"
					( Origin gPackager )
				)
				( objectStatus "P3E_CPU0_PE1_PCH_CON_RXN<8>" )
			)
			( signal "@baseboard_fab2_lib.baseboard_fab2(sch_1):p3e_cpu0_pe1_pch_con_rxn(9)"
				( attribute "CDS_PHYS_NET_NAME" "P3E_CPU0_PE1_PCH_CON_RXN<9>"
					( Origin gPackager )
				)
				( attribute "PNN" "P3E_CPU0_PE1_PCH_CON_RXN<9>"
					( Origin gPackager )
				)
				( objectStatus "P3E_CPU0_PE1_PCH_CON_RXN<9>" )
			)
			( signal "@baseboard_fab2_lib.baseboard_fab2(sch_1):p3e_cpu0_pe1_pch_con_rxn(10)"
				( attribute "CDS_PHYS_NET_NAME" "P3E_CPU0_PE1_PCH_CON_RXN<10>"
					( Origin gPackager )
				)
				( attribute "PNN" "P3E_CPU0_PE1_PCH_CON_RXN<10>"
					( Origin gPackager )
				)
				( objectStatus "P3E_CPU0_PE1_PCH_CON_RXN<10>" )
			)
			( signal "@baseboard_fab2_lib.baseboard_fab2(sch_1):p3e_cpu0_pe1_pch_con_rxn(11)"
				( attribute "CDS_PHYS_NET_NAME" "P3E_CPU0_PE1_PCH_CON_RXN<11>"
					( Origin gPackager )
				)
				( attribute "PNN" "P3E_CPU0_PE1_PCH_CON_RXN<11>"
					( Origin gPackager )
				)
				( objectStatus "P3E_CPU0_PE1_PCH_CON_RXN<11>" )
			)
			( signal "@baseboard_fab2_lib.baseboard_fab2(sch_1):p3e_cpu0_pe1_pch_con_rxn(12)"
				( attribute "CDS_PHYS_NET_NAME" "P3E_CPU0_PE1_PCH_CON_RXN<12>"
					( Origin gPackager )
				)
				( attribute "PNN" "P3E_CPU0_PE1_PCH_CON_RXN<12>"
					( Origin gPackager )
				)
				( objectStatus "P3E_CPU0_PE1_PCH_CON_RXN<12>" )
			)
			( signal "@baseboard_fab2_lib.baseboard_fab2(sch_1):p3e_cpu0_pe1_pch_con_rxn(13)"
				( attribute "CDS_PHYS_NET_NAME" "P3E_CPU0_PE1_PCH_CON_RXN<13>"
					( Origin gPackager )
				)
				( attribute "PNN" "P3E_CPU0_PE1_PCH_CON_RXN<13>"
					( Origin gPackager )
				)
				( objectStatus "P3E_CPU0_PE1_PCH_CON_RXN<13>" )
			)
			( signal "@baseboard_fab2_lib.baseboard_fab2(sch_1):p3e_cpu0_pe1_pch_con_rxn(14)"
				( attribute "CDS_PHYS_NET_NAME" "P3E_CPU0_PE1_PCH_CON_RXN<14>"
					( Origin gPackager )
				)
				( attribute "PNN" "P3E_CPU0_PE1_PCH_CON_RXN<14>"
					( Origin gPackager )
				)
				( objectStatus "P3E_CPU0_PE1_PCH_CON_RXN<14>" )
			)
			( signal "@baseboard_fab2_lib.baseboard_fab2(sch_1):p3e_cpu0_pe1_pch_con_rxn(15)"
				( attribute "CDS_PHYS_NET_NAME" "P3E_CPU0_PE1_PCH_CON_RXN<15>"
					( Origin gPackager )
				)
				( attribute "PNN" "P3E_CPU0_PE1_PCH_CON_RXN<15>"
					( Origin gPackager )
				)
				( objectStatus "P3E_CPU0_PE1_PCH_CON_RXN<15>" )
			)
			( signal "@baseboard_fab2_lib.baseboard_fab2(sch_1):p3e_cpu0_pe1_pch_con_rxp(8)"
				( attribute "CDS_PHYS_NET_NAME" "P3E_CPU0_PE1_PCH_CON_RXP<8>"
					( Origin gPackager )
				)
				( attribute "PNN" "P3E_CPU0_PE1_PCH_CON_RXP<8>"
					( Origin gPackager )
				)
				( objectStatus "P3E_CPU0_PE1_PCH_CON_RXP<8>" )
			)
			( signal "@baseboard_fab2_lib.baseboard_fab2(sch_1):p3e_cpu0_pe1_pch_con_rxp(9)"
				( attribute "CDS_PHYS_NET_NAME" "P3E_CPU0_PE1_PCH_CON_RXP<9>"
					( Origin gPackager )
				)
				( attribute "PNN" "P3E_CPU0_PE1_PCH_CON_RXP<9>"
					( Origin gPackager )
				)
				( objectStatus "P3E_CPU0_PE1_PCH_CON_RXP<9>" )
			)
			( signal "@baseboard_fab2_lib.baseboard_fab2(sch_1):p3e_cpu0_pe1_pch_con_rxp(10)"
				( attribute "CDS_PHYS_NET_NAME" "P3E_CPU0_PE1_PCH_CON_RXP<10>"
					( Origin gPackager )
				)
				( attribute "PNN" "P3E_CPU0_PE1_PCH_CON_RXP<10>"
					( Origin gPackager )
				)
				( objectStatus "P3E_CPU0_PE1_PCH_CON_RXP<10>" )
			)
			( signal "@baseboard_fab2_lib.baseboard_fab2(sch_1):p3e_cpu0_pe1_pch_con_rxp(11)"
				( attribute "CDS_PHYS_NET_NAME" "P3E_CPU0_PE1_PCH_CON_RXP<11>"
					( Origin gPackager )
				)
				( attribute "PNN" "P3E_CPU0_PE1_PCH_CON_RXP<11>"
					( Origin gPackager )
				)
				( objectStatus "P3E_CPU0_PE1_PCH_CON_RXP<11>" )
			)
			( signal "@baseboard_fab2_lib.baseboard_fab2(sch_1):p3e_cpu0_pe1_pch_con_rxp(12)"
				( attribute "CDS_PHYS_NET_NAME" "P3E_CPU0_PE1_PCH_CON_RXP<12>"
					( Origin gPackager )
				)
				( attribute "PNN" "P3E_CPU0_PE1_PCH_CON_RXP<12>"
					( Origin gPackager )
				)
				( objectStatus "P3E_CPU0_PE1_PCH_CON_RXP<12>" )
			)
			( signal "@baseboard_fab2_lib.baseboard_fab2(sch_1):p3e_cpu0_pe1_pch_con_rxp(13)"
				( attribute "CDS_PHYS_NET_NAME" "P3E_CPU0_PE1_PCH_CON_RXP<13>"
					( Origin gPackager )
				)
				( attribute "PNN" "P3E_CPU0_PE1_PCH_CON_RXP<13>"
					( Origin gPackager )
				)
				( objectStatus "P3E_CPU0_PE1_PCH_CON_RXP<13>" )
			)
			( signal "@baseboard_fab2_lib.baseboard_fab2(sch_1):p3e_cpu0_pe1_pch_con_rxp(14)"
				( attribute "CDS_PHYS_NET_NAME" "P3E_CPU0_PE1_PCH_CON_RXP<14>"
					( Origin gPackager )
				)
				( attribute "PNN" "P3E_CPU0_PE1_PCH_CON_RXP<14>"
					( Origin gPackager )
				)
				( objectStatus "P3E_CPU0_PE1_PCH_CON_RXP<14>" )
			)
			( signal "@baseboard_fab2_lib.baseboard_fab2(sch_1):p3e_cpu0_pe1_pch_con_rxp(15)"
				( attribute "CDS_PHYS_NET_NAME" "P3E_CPU0_PE1_PCH_CON_RXP<15>"
					( Origin gPackager )
				)
				( attribute "PNN" "P3E_CPU0_PE1_PCH_CON_RXP<15>"
					( Origin gPackager )
				)
				( objectStatus "P3E_CPU0_PE1_PCH_CON_RXP<15>" )
			)
			( signal "@baseboard_fab2_lib.baseboard_fab2(sch_1):p3e_cpu0_pe1_pch_con_txn(8)"
				( attribute "CDS_PHYS_NET_NAME" "P3E_CPU0_PE1_PCH_CON_TXN<8>"
					( Origin gPackager )
				)
				( attribute "PNN" "P3E_CPU0_PE1_PCH_CON_TXN<8>"
					( Origin gPackager )
				)
				( objectStatus "P3E_CPU0_PE1_PCH_CON_TXN<8>" )
			)
			( signal "@baseboard_fab2_lib.baseboard_fab2(sch_1):p3e_cpu0_pe1_pch_con_txn(9)"
				( attribute "CDS_PHYS_NET_NAME" "P3E_CPU0_PE1_PCH_CON_TXN<9>"
					( Origin gPackager )
				)
				( attribute "PNN" "P3E_CPU0_PE1_PCH_CON_TXN<9>"
					( Origin gPackager )
				)
				( objectStatus "P3E_CPU0_PE1_PCH_CON_TXN<9>" )
			)
			( signal "@baseboard_fab2_lib.baseboard_fab2(sch_1):p3e_cpu0_pe1_pch_con_txn(10)"
				( attribute "CDS_PHYS_NET_NAME" "P3E_CPU0_PE1_PCH_CON_TXN<10>"
					( Origin gPackager )
				)
				( attribute "PNN" "P3E_CPU0_PE1_PCH_CON_TXN<10>"
					( Origin gPackager )
				)
				( objectStatus "P3E_CPU0_PE1_PCH_CON_TXN<10>" )
			)
			( signal "@baseboard_fab2_lib.baseboard_fab2(sch_1):p3e_cpu0_pe1_pch_con_txn(11)"
				( attribute "CDS_PHYS_NET_NAME" "P3E_CPU0_PE1_PCH_CON_TXN<11>"
					( Origin gPackager )
				)
				( attribute "PNN" "P3E_CPU0_PE1_PCH_CON_TXN<11>"
					( Origin gPackager )
				)
				( objectStatus "P3E_CPU0_PE1_PCH_CON_TXN<11>" )
			)
			( signal "@baseboard_fab2_lib.baseboard_fab2(sch_1):p3e_cpu0_pe1_pch_con_txn(12)"
				( attribute "CDS_PHYS_NET_NAME" "P3E_CPU0_PE1_PCH_CON_TXN<12>"
					( Origin gPackager )
				)
				( attribute "PNN" "P3E_CPU0_PE1_PCH_CON_TXN<12>"
					( Origin gPackager )
				)
				( objectStatus "P3E_CPU0_PE1_PCH_CON_TXN<12>" )
			)
			( signal "@baseboard_fab2_lib.baseboard_fab2(sch_1):p3e_cpu0_pe1_pch_con_txn(13)"
				( attribute "CDS_PHYS_NET_NAME" "P3E_CPU0_PE1_PCH_CON_TXN<13>"
					( Origin gPackager )
				)
				( attribute "PNN" "P3E_CPU0_PE1_PCH_CON_TXN<13>"
					( Origin gPackager )
				)
				( objectStatus "P3E_CPU0_PE1_PCH_CON_TXN<13>" )
			)
			( signal "@baseboard_fab2_lib.baseboard_fab2(sch_1):p3e_cpu0_pe1_pch_con_txn(14)"
				( attribute "CDS_PHYS_NET_NAME" "P3E_CPU0_PE1_PCH_CON_TXN<14>"
					( Origin gPackager )
				)
				( attribute "PNN" "P3E_CPU0_PE1_PCH_CON_TXN<14>"
					( Origin gPackager )
				)
				( objectStatus "P3E_CPU0_PE1_PCH_CON_TXN<14>" )
			)
			( signal "@baseboard_fab2_lib.baseboard_fab2(sch_1):p3e_cpu0_pe1_pch_con_txn(15)"
				( attribute "CDS_PHYS_NET_NAME" "P3E_CPU0_PE1_PCH_CON_TXN<15>"
					( Origin gPackager )
				)
				( attribute "PNN" "P3E_CPU0_PE1_PCH_CON_TXN<15>"
					( Origin gPackager )
				)
				( objectStatus "P3E_CPU0_PE1_PCH_CON_TXN<15>" )
			)
			( signal "@baseboard_fab2_lib.baseboard_fab2(sch_1):p3e_cpu0_pe1_pch_con_txp(8)"
				( attribute "CDS_PHYS_NET_NAME" "P3E_CPU0_PE1_PCH_CON_TXP<8>"
					( Origin gPackager )
				)
				( attribute "PNN" "P3E_CPU0_PE1_PCH_CON_TXP<8>"
					( Origin gPackager )
				)
				( objectStatus "P3E_CPU0_PE1_PCH_CON_TXP<8>" )
			)
			( signal "@baseboard_fab2_lib.baseboard_fab2(sch_1):p3e_cpu0_pe1_pch_con_txp(9)"
				( attribute "CDS_PHYS_NET_NAME" "P3E_CPU0_PE1_PCH_CON_TXP<9>"
					( Origin gPackager )
				)
				( attribute "PNN" "P3E_CPU0_PE1_PCH_CON_TXP<9>"
					( Origin gPackager )
				)
				( objectStatus "P3E_CPU0_PE1_PCH_CON_TXP<9>" )
			)
			( signal "@baseboard_fab2_lib.baseboard_fab2(sch_1):p3e_cpu0_pe1_pch_con_txp(10)"
				( attribute "CDS_PHYS_NET_NAME" "P3E_CPU0_PE1_PCH_CON_TXP<10>"
					( Origin gPackager )
				)
				( attribute "PNN" "P3E_CPU0_PE1_PCH_CON_TXP<10>"
					( Origin gPackager )
				)
				( objectStatus "P3E_CPU0_PE1_PCH_CON_TXP<10>" )
			)
			( signal "@baseboard_fab2_lib.baseboard_fab2(sch_1):p3e_cpu0_pe1_pch_con_txp(11)"
				( attribute "CDS_PHYS_NET_NAME" "P3E_CPU0_PE1_PCH_CON_TXP<11>"
					( Origin gPackager )
				)
				( attribute "PNN" "P3E_CPU0_PE1_PCH_CON_TXP<11>"
					( Origin gPackager )
				)
				( objectStatus "P3E_CPU0_PE1_PCH_CON_TXP<11>" )
			)
			( signal "@baseboard_fab2_lib.baseboard_fab2(sch_1):p3e_cpu0_pe1_pch_con_txp(12)"
				( attribute "CDS_PHYS_NET_NAME" "P3E_CPU0_PE1_PCH_CON_TXP<12>"
					( Origin gPackager )
				)
				( attribute "PNN" "P3E_CPU0_PE1_PCH_CON_TXP<12>"
					( Origin gPackager )
				)
				( objectStatus "P3E_CPU0_PE1_PCH_CON_TXP<12>" )
			)
			( signal "@baseboard_fab2_lib.baseboard_fab2(sch_1):p3e_cpu0_pe1_pch_con_txp(13)"
				( attribute "CDS_PHYS_NET_NAME" "P3E_CPU0_PE1_PCH_CON_TXP<13>"
					( Origin gPackager )
				)
				( attribute "PNN" "P3E_CPU0_PE1_PCH_CON_TXP<13>"
					( Origin gPackager )
				)
				( objectStatus "P3E_CPU0_PE1_PCH_CON_TXP<13>" )
			)
			( signal "@baseboard_fab2_lib.baseboard_fab2(sch_1):p3e_cpu0_pe1_pch_con_txp(14)"
				( attribute "CDS_PHYS_NET_NAME" "P3E_CPU0_PE1_PCH_CON_TXP<14>"
					( Origin gPackager )
				)
				( attribute "PNN" "P3E_CPU0_PE1_PCH_CON_TXP<14>"
					( Origin gPackager )
				)
				( objectStatus "P3E_CPU0_PE1_PCH_CON_TXP<14>" )
			)
			( signal "@baseboard_fab2_lib.baseboard_fab2(sch_1):p3e_cpu0_pe1_pch_con_txp(15)"
				( attribute "CDS_PHYS_NET_NAME" "P3E_CPU0_PE1_PCH_CON_TXP<15>"
					( Origin gPackager )
				)
				( attribute "PNN" "P3E_CPU0_PE1_PCH_CON_TXP<15>"
					( Origin gPackager )
				)
				( objectStatus "P3E_CPU0_PE1_PCH_CON_TXP<15>" )
			)
			( signal "@baseboard_fab2_lib.baseboard_fab2(sch_1):uv_high_set_n"
				( attribute "CDS_PHYS_NET_NAME" "UV_HIGH_SET_N"
					( Origin gPackager )
				)
				( objectStatus "UV_HIGH_SET_N" )
			)
			( signal "@baseboard_fab2_lib.baseboard_fab2(sch_1):bmc_strap_bit5"
				( attribute "CDS_PHYS_NET_NAME" "BMC_STRAP_BIT5"
					( Origin gPackager )
				)
				( objectStatus "BMC_STRAP_BIT5" )
			)
			( signal "@baseboard_fab2_lib.baseboard_fab2(sch_1):pca9555_a0"
				( attribute "CDS_PHYS_NET_NAME" "PCA9555_A0"
					( Origin gPackager )
				)
				( objectStatus "PCA9555_A0" )
			)
			( signal "@baseboard_fab2_lib.baseboard_fab2(sch_1):pca9555_int_n"
				( attribute "CDS_PHYS_NET_NAME" "PCA9555_INT_N"
					( Origin gPackager )
				)
				( objectStatus "PCA9555_INT_N" )
			)
			( signal "@baseboard_fab2_lib.baseboard_fab2(sch_1):fm_tpm_pres_rst"
				( attribute "CDS_PHYS_NET_NAME" "FM_TPM_PRES_RST"
					( Origin gPackager )
				)
				( objectStatus "FM_TPM_PRES_RST" )
			)
			( signal "@baseboard_fab2_lib.baseboard_fab2(sch_1):fm_tpm_pres_rst_n"
				( attribute "CDS_PHYS_NET_NAME" "FM_TPM_PRES_RST_N"
					( Origin gPackager )
				)
				( objectStatus "FM_TPM_PRES_RST_N" )
			)
			( signal "@baseboard_fab2_lib.baseboard_fab2(sch_1):vref_2v2"
				( attribute "CDS_PHYS_NET_NAME" "VREF_2V2"
					( Origin gPackager )
				)
				( objectStatus "VREF_2V2" )
			)
			( signal "@baseboard_fab2_lib.baseboard_fab2(sch_1):bmc_m_a0"
				( attribute "CDS_PHYS_NET_NAME" "BMC_M_A0"
					( Origin gPackager )
				)
				( objectStatus "BMC_M_A0" )
			)
			( signal "@baseboard_fab2_lib.baseboard_fab2(sch_1):bmc_m_a1"
				( attribute "CDS_PHYS_NET_NAME" "BMC_M_A1"
					( Origin gPackager )
				)
				( objectStatus "BMC_M_A1" )
			)
			( signal "@baseboard_fab2_lib.baseboard_fab2(sch_1):bmc_m_a10"
				( attribute "CDS_PHYS_NET_NAME" "BMC_M_A10"
					( Origin gPackager )
				)
				( objectStatus "BMC_M_A10" )
			)
			( signal "@baseboard_fab2_lib.baseboard_fab2(sch_1):bmc_m_a11"
				( attribute "CDS_PHYS_NET_NAME" "BMC_M_A11"
					( Origin gPackager )
				)
				( objectStatus "BMC_M_A11" )
			)
			( signal "@baseboard_fab2_lib.baseboard_fab2(sch_1):bmc_m_a12"
				( attribute "CDS_PHYS_NET_NAME" "BMC_M_A12"
					( Origin gPackager )
				)
				( objectStatus "BMC_M_A12" )
			)
			( signal "@baseboard_fab2_lib.baseboard_fab2(sch_1):bmc_m_a13"
				( attribute "CDS_PHYS_NET_NAME" "BMC_M_A13"
					( Origin gPackager )
				)
				( objectStatus "BMC_M_A13" )
			)
			( signal "@baseboard_fab2_lib.baseboard_fab2(sch_1):bmc_m_a2"
				( attribute "CDS_PHYS_NET_NAME" "BMC_M_A2"
					( Origin gPackager )
				)
				( objectStatus "BMC_M_A2" )
			)
			( signal "@baseboard_fab2_lib.baseboard_fab2(sch_1):bmc_m_a3"
				( attribute "CDS_PHYS_NET_NAME" "BMC_M_A3"
					( Origin gPackager )
				)
				( objectStatus "BMC_M_A3" )
			)
			( signal "@baseboard_fab2_lib.baseboard_fab2(sch_1):bmc_m_a4"
				( attribute "CDS_PHYS_NET_NAME" "BMC_M_A4"
					( Origin gPackager )
				)
				( objectStatus "BMC_M_A4" )
			)
			( signal "@baseboard_fab2_lib.baseboard_fab2(sch_1):bmc_m_a5"
				( attribute "CDS_PHYS_NET_NAME" "BMC_M_A5"
					( Origin gPackager )
				)
				( objectStatus "BMC_M_A5" )
			)
			( signal "@baseboard_fab2_lib.baseboard_fab2(sch_1):bmc_m_a6"
				( attribute "CDS_PHYS_NET_NAME" "BMC_M_A6"
					( Origin gPackager )
				)
				( objectStatus "BMC_M_A6" )
			)
			( signal "@baseboard_fab2_lib.baseboard_fab2(sch_1):bmc_m_a7"
				( attribute "CDS_PHYS_NET_NAME" "BMC_M_A7"
					( Origin gPackager )
				)
				( objectStatus "BMC_M_A7" )
			)
			( signal "@baseboard_fab2_lib.baseboard_fab2(sch_1):bmc_m_a8"
				( attribute "CDS_PHYS_NET_NAME" "BMC_M_A8"
					( Origin gPackager )
				)
				( objectStatus "BMC_M_A8" )
			)
			( signal "@baseboard_fab2_lib.baseboard_fab2(sch_1):bmc_m_a9"
				( attribute "CDS_PHYS_NET_NAME" "BMC_M_A9"
					( Origin gPackager )
				)
				( objectStatus "BMC_M_A9" )
			)
			( signal "@baseboard_fab2_lib.baseboard_fab2(sch_1):bmc_m_ba0"
				( attribute "CDS_PHYS_NET_NAME" "BMC_M_BA0"
					( Origin gPackager )
				)
				( objectStatus "BMC_M_BA0" )
			)
			( signal "@baseboard_fab2_lib.baseboard_fab2(sch_1):bmc_m_ba1"
				( attribute "CDS_PHYS_NET_NAME" "BMC_M_BA1"
					( Origin gPackager )
				)
				( objectStatus "BMC_M_BA1" )
			)
			( signal "@baseboard_fab2_lib.baseboard_fab2(sch_1):bmc_m_bg0"
				( attribute "CDS_PHYS_NET_NAME" "BMC_M_BG0"
					( Origin gPackager )
				)
				( objectStatus "BMC_M_BG0" )
			)
			( signal "@baseboard_fab2_lib.baseboard_fab2(sch_1):bmc_m_cas_n"
				( attribute "CDS_PHYS_NET_NAME" "BMC_M_CAS_N"
					( Origin gPackager )
				)
				( objectStatus "BMC_M_CAS_N" )
			)
			( signal "@baseboard_fab2_lib.baseboard_fab2(sch_1):bmc_m_cke"
				( attribute "CDS_PHYS_NET_NAME" "BMC_M_CKE"
					( Origin gPackager )
				)
				( objectStatus "BMC_M_CKE" )
			)
			( signal "@baseboard_fab2_lib.baseboard_fab2(sch_1):bmc_m_clk_dn"
				( attribute "CDS_PHYS_NET_NAME" "BMC_M_CLK_DN"
					( Origin gPackager )
				)
				( objectStatus "BMC_M_CLK_DN" )
			)
			( signal "@baseboard_fab2_lib.baseboard_fab2(sch_1):bmc_m_clk_dp"
				( attribute "CDS_PHYS_NET_NAME" "BMC_M_CLK_DP"
					( Origin gPackager )
				)
				( objectStatus "BMC_M_CLK_DP" )
			)
			( signal "@baseboard_fab2_lib.baseboard_fab2(sch_1):bmc_m_cs_n"
				( attribute "CDS_PHYS_NET_NAME" "BMC_M_CS_N"
					( Origin gPackager )
				)
				( objectStatus "BMC_M_CS_N" )
			)
			( signal "@baseboard_fab2_lib.baseboard_fab2(sch_1):bmc_m_dm0"
				( attribute "CDS_PHYS_NET_NAME" "BMC_M_DM0"
					( Origin gPackager )
				)
				( objectStatus "BMC_M_DM0" )
			)
			( signal "@baseboard_fab2_lib.baseboard_fab2(sch_1):bmc_m_dm1"
				( attribute "CDS_PHYS_NET_NAME" "BMC_M_DM1"
					( Origin gPackager )
				)
				( objectStatus "BMC_M_DM1" )
			)
			( signal "@baseboard_fab2_lib.baseboard_fab2(sch_1):bmc_m_dq0"
				( attribute "CDS_PHYS_NET_NAME" "BMC_M_DQ0"
					( Origin gPackager )
				)
				( objectStatus "BMC_M_DQ0" )
			)
			( signal "@baseboard_fab2_lib.baseboard_fab2(sch_1):bmc_m_dq1"
				( attribute "CDS_PHYS_NET_NAME" "BMC_M_DQ1"
					( Origin gPackager )
				)
				( objectStatus "BMC_M_DQ1" )
			)
			( signal "@baseboard_fab2_lib.baseboard_fab2(sch_1):bmc_m_dq10"
				( attribute "CDS_PHYS_NET_NAME" "BMC_M_DQ10"
					( Origin gPackager )
				)
				( objectStatus "BMC_M_DQ10" )
			)
			( signal "@baseboard_fab2_lib.baseboard_fab2(sch_1):bmc_m_dq11"
				( attribute "CDS_PHYS_NET_NAME" "BMC_M_DQ11"
					( Origin gPackager )
				)
				( objectStatus "BMC_M_DQ11" )
			)
			( signal "@baseboard_fab2_lib.baseboard_fab2(sch_1):bmc_m_dq12"
				( attribute "CDS_PHYS_NET_NAME" "BMC_M_DQ12"
					( Origin gPackager )
				)
				( objectStatus "BMC_M_DQ12" )
			)
			( signal "@baseboard_fab2_lib.baseboard_fab2(sch_1):bmc_m_dq13"
				( attribute "CDS_PHYS_NET_NAME" "BMC_M_DQ13"
					( Origin gPackager )
				)
				( objectStatus "BMC_M_DQ13" )
			)
			( signal "@baseboard_fab2_lib.baseboard_fab2(sch_1):bmc_m_dq14"
				( attribute "CDS_PHYS_NET_NAME" "BMC_M_DQ14"
					( Origin gPackager )
				)
				( objectStatus "BMC_M_DQ14" )
			)
			( signal "@baseboard_fab2_lib.baseboard_fab2(sch_1):bmc_m_dq15"
				( attribute "CDS_PHYS_NET_NAME" "BMC_M_DQ15"
					( Origin gPackager )
				)
				( objectStatus "BMC_M_DQ15" )
			)
			( signal "@baseboard_fab2_lib.baseboard_fab2(sch_1):bmc_m_dq2"
				( attribute "CDS_PHYS_NET_NAME" "BMC_M_DQ2"
					( Origin gPackager )
				)
				( objectStatus "BMC_M_DQ2" )
			)
			( signal "@baseboard_fab2_lib.baseboard_fab2(sch_1):bmc_m_dq3"
				( attribute "CDS_PHYS_NET_NAME" "BMC_M_DQ3"
					( Origin gPackager )
				)
				( objectStatus "BMC_M_DQ3" )
			)
			( signal "@baseboard_fab2_lib.baseboard_fab2(sch_1):bmc_m_dq4"
				( attribute "CDS_PHYS_NET_NAME" "BMC_M_DQ4"
					( Origin gPackager )
				)
				( objectStatus "BMC_M_DQ4" )
			)
			( signal "@baseboard_fab2_lib.baseboard_fab2(sch_1):bmc_m_dq5"
				( attribute "CDS_PHYS_NET_NAME" "BMC_M_DQ5"
					( Origin gPackager )
				)
				( objectStatus "BMC_M_DQ5" )
			)
			( signal "@baseboard_fab2_lib.baseboard_fab2(sch_1):bmc_m_dq6"
				( attribute "CDS_PHYS_NET_NAME" "BMC_M_DQ6"
					( Origin gPackager )
				)
				( objectStatus "BMC_M_DQ6" )
			)
			( signal "@baseboard_fab2_lib.baseboard_fab2(sch_1):bmc_m_dq7"
				( attribute "CDS_PHYS_NET_NAME" "BMC_M_DQ7"
					( Origin gPackager )
				)
				( objectStatus "BMC_M_DQ7" )
			)
			( signal "@baseboard_fab2_lib.baseboard_fab2(sch_1):bmc_m_dq8"
				( attribute "CDS_PHYS_NET_NAME" "BMC_M_DQ8"
					( Origin gPackager )
				)
				( objectStatus "BMC_M_DQ8" )
			)
			( signal "@baseboard_fab2_lib.baseboard_fab2(sch_1):bmc_m_dq9"
				( attribute "CDS_PHYS_NET_NAME" "BMC_M_DQ9"
					( Origin gPackager )
				)
				( objectStatus "BMC_M_DQ9" )
			)
			( signal "@baseboard_fab2_lib.baseboard_fab2(sch_1):bmc_m_dqs0_dn"
				( attribute "CDS_PHYS_NET_NAME" "BMC_M_DQS0_DN"
					( Origin gPackager )
				)
				( objectStatus "BMC_M_DQS0_DN" )
			)
			( signal "@baseboard_fab2_lib.baseboard_fab2(sch_1):bmc_m_dqs0_dp"
				( attribute "CDS_PHYS_NET_NAME" "BMC_M_DQS0_DP"
					( Origin gPackager )
				)
				( objectStatus "BMC_M_DQS0_DP" )
			)
			( signal "@baseboard_fab2_lib.baseboard_fab2(sch_1):bmc_m_dqs1_dp"
				( attribute "CDS_PHYS_NET_NAME" "BMC_M_DQS1_DP"
					( Origin gPackager )
				)
				( objectStatus "BMC_M_DQS1_DP" )
			)
			( signal "@baseboard_fab2_lib.baseboard_fab2(sch_1):a_dacrset"
				( attribute "CDS_PHYS_NET_NAME" "A_DACRSET"
					( Origin gPackager )
				)
				( objectStatus "A_DACRSET" )
			)
			( signal "@baseboard_fab2_lib.baseboard_fab2(sch_1):irq_lpc_serirq_r"
				( attribute "CDS_PHYS_NET_NAME" "IRQ_LPC_SERIRQ_R"
					( Origin gPackager )
				)
				( objectStatus "IRQ_LPC_SERIRQ_R" )
			)
			( signal "@baseboard_fab2_lib.baseboard_fab2(sch_1):lpc_lad0_io0_r"
				( attribute "CDS_PHYS_NET_NAME" "LPC_LAD0_IO0_R"
					( Origin gPackager )
				)
				( objectStatus "LPC_LAD0_IO0_R" )
			)
			( signal "@baseboard_fab2_lib.baseboard_fab2(sch_1):lpc_lad1_io1_r"
				( attribute "CDS_PHYS_NET_NAME" "LPC_LAD1_IO1_R"
					( Origin gPackager )
				)
				( objectStatus "LPC_LAD1_IO1_R" )
			)
			( signal "@baseboard_fab2_lib.baseboard_fab2(sch_1):lpc_lad3_io3_r"
				( attribute "CDS_PHYS_NET_NAME" "LPC_LAD3_IO3_R"
					( Origin gPackager )
				)
				( objectStatus "LPC_LAD3_IO3_R" )
			)
			( signal "@baseboard_fab2_lib.baseboard_fab2(sch_1):rst_bmc_lvc3_n"
				( attribute "CDS_PHYS_NET_NAME" "RST_BMC_LVC3_N"
					( Origin gPackager )
				)
				( objectStatus "RST_BMC_LVC3_N" )
			)
			( signal "@baseboard_fab2_lib.baseboard_fab2(sch_1):sgpio_bmc_clk_r"
				( attribute "CDS_PHYS_NET_NAME" "SGPIO_BMC_CLK_R"
					( Origin gPackager )
				)
				( objectStatus "SGPIO_BMC_CLK_R" )
			)
			( signal "@baseboard_fab2_lib.baseboard_fab2(sch_1):sgpio_bmc_ld_r_n"
				( attribute "CDS_PHYS_NET_NAME" "SGPIO_BMC_LD_R_N"
					( Origin gPackager )
				)
				( objectStatus "SGPIO_BMC_LD_R_N" )
			)
			( signal "@baseboard_fab2_lib.baseboard_fab2(sch_1):bmc_vga_hsync"
				( attribute "CDS_PHYS_NET_NAME" "BMC_VGA_HSYNC"
					( Origin gPackager )
				)
				( objectStatus "BMC_VGA_HSYNC" )
			)
			( signal "@baseboard_fab2_lib.baseboard_fab2(sch_1):pu_24m_osc_oe"
				( attribute "CDS_PHYS_NET_NAME" "PU_24M_OSC_OE"
					( Origin gPackager )
				)
				( objectStatus "PU_24M_OSC_OE" )
			)
			( signal "@baseboard_fab2_lib.baseboard_fab2(sch_1):a_usb2bvres"
				( attribute "CDS_PHYS_NET_NAME" "A_USB2BVRES"
					( Origin gPackager )
				)
				( objectStatus "A_USB2BVRES" )
			)
			( signal "@baseboard_fab2_lib.baseboard_fab2(sch_1):vccbat_tw12"
				( attribute "CDS_PHYS_NET_NAME" "VCCBAT_TW12"
					( Origin gPackager )
				)
				( objectStatus "VCCBAT_TW12" )
			)
			( signal "@baseboard_fab2_lib.baseboard_fab2(sch_1):a_usb2avres"
				( attribute "CDS_PHYS_NET_NAME" "A_USB2AVRES"
					( Origin gPackager )
				)
				( objectStatus "A_USB2AVRES" )
			)
			( signal "@baseboard_fab2_lib.baseboard_fab2(sch_1):gpios7"
				( attribute "CDS_PHYS_NET_NAME" "GPIOS7"
					( Origin gPackager )
				)
				( objectStatus "GPIOS7" )
			)
			( signal "@baseboard_fab2_lib.baseboard_fab2(sch_1):bmc_self_hw_rst"
				( alias ( signalRef "@baseboard_fab2_lib.baseboard_fab2(sch_1):page146_bmc_self_hw_rst") )
				( attribute "CDS_PHYS_NET_NAME" "BMC_SELF_HW_RST"
					( Origin gPackager )
				)
				( objectStatus "BMC_SELF_HW_RST" )
			)
			( signal "@baseboard_fab2_lib.baseboard_fab2(sch_1):page146_bmc_self_hw_rst"
				( attribute "CDS_PHYS_NET_NAME" "BMC_SELF_HW_RST"
					( Origin gPackager )
				)
				( objectFlag fObjectAlias )
				( objectStatus "page146_bmc_self_hw_rst" )
			)
			( signal "@baseboard_fab2_lib.baseboard_fab2(sch_1):pwrgd_p2v5_bmc_stby"
				( attribute "CDS_PHYS_NET_NAME" "PWRGD_P2V5_BMC_STBY"
					( Origin gPackager )
				)
				( objectStatus "PWRGD_P2V5_BMC_STBY" )
			)
			( signal "@baseboard_fab2_lib.baseboard_fab2(sch_1):vr_pvccin_cpu0_phase1_rc"
				( attribute "CDS_PHYS_NET_NAME" "VR_PVCCIN_CPU0_PHASE1_RC"
					( Origin gPackager )
				)
				( objectStatus "VR_PVCCIN_CPU0_PHASE1_RC" )
			)
			( signal "@baseboard_fab2_lib.baseboard_fab2(sch_1):fm_tpm_pres_rst_n_r"
				( attribute "CDS_PHYS_NET_NAME" "FM_TPM_PRES_RST_N_R"
					( Origin gPackager )
				)
				( objectStatus "FM_TPM_PRES_RST_N_R" )
			)
			( signal "@baseboard_fab2_lib.baseboard_fab2(sch_1):usb2_p02_dn"
				( attribute "CDS_PHYS_NET_NAME" "USB2_P02_DN"
					( Origin gPackager )
				)
				( objectStatus "USB2_P02_DN" )
			)
			( signal "@baseboard_fab2_lib.baseboard_fab2(sch_1):usb2_p02_dp"
				( attribute "CDS_PHYS_NET_NAME" "USB2_P02_DP"
					( Origin gPackager )
				)
				( objectStatus "USB2_P02_DP" )
			)
			( signal "@baseboard_fab2_lib.baseboard_fab2(sch_1):jtag_riser_tms"
				( attribute "CDS_PHYS_NET_NAME" "JTAG_RISER_TMS"
					( Origin gPackager )
				)
				( objectStatus "JTAG_RISER_TMS" )
			)
			( signal "@baseboard_fab2_lib.baseboard_fab2(sch_1):jtag_riser_tck"
				( attribute "CDS_PHYS_NET_NAME" "JTAG_RISER_TCK"
					( Origin gPackager )
				)
				( objectStatus "JTAG_RISER_TCK" )
			)
			( signal "@baseboard_fab2_lib.baseboard_fab2(sch_1):smb_debug_stby_lvc3_scl_r"
				( attribute "CDS_PHYS_NET_NAME" "SMB_DEBUG_STBY_LVC3_SCL_R"
					( Origin gPackager )
				)
				( objectStatus "SMB_DEBUG_STBY_LVC3_SCL_R" )
			)
			( signal "@baseboard_fab2_lib.baseboard_fab2(sch_1):smb_debug_stby_lvc3_scl"
				( attribute "CDS_PHYS_NET_NAME" "SMB_DEBUG_STBY_LVC3_SCL"
					( Origin gPackager )
				)
				( objectStatus "SMB_DEBUG_STBY_LVC3_SCL" )
			)
			( signal "@baseboard_fab2_lib.baseboard_fab2(sch_1):hsc_smbus_switch_en"
				( attribute "CDS_PHYS_NET_NAME" "HSC_SMBUS_SWITCH_EN"
					( Origin gPackager )
				)
				( attribute "PHYS_NET_NAME" "HSC_SMBUS_SWITCH_EN"
					( Origin gPackager )
				)
				( objectStatus "HSC_SMBUS_SWITCH_EN" )
			)
			( signal "@baseboard_fab2_lib.baseboard_fab2(sch_1):smb_host_stby_lvc3_scl_r3"
				( attribute "CDS_PHYS_NET_NAME" "SMB_HOST_STBY_LVC3_SCL_R3"
					( Origin gPackager )
				)
				( objectStatus "SMB_HOST_STBY_LVC3_SCL_R3" )
			)
			( signal "@baseboard_fab2_lib.baseboard_fab2(sch_1):smb_host_stby_lvc3_sda_r3"
				( attribute "CDS_PHYS_NET_NAME" "SMB_HOST_STBY_LVC3_SDA_R3"
					( Origin gPackager )
				)
				( objectStatus "SMB_HOST_STBY_LVC3_SDA_R3" )
			)
			( signal "@baseboard_fab2_lib.baseboard_fab2(sch_1):pd_id_eeprom_wp"
				( attribute "CDS_PHYS_NET_NAME" "PD_ID_EEPROM_WP"
					( Origin gPackager )
				)
				( objectStatus "PD_ID_EEPROM_WP" )
			)
			( signal "@baseboard_fab2_lib.baseboard_fab2(sch_1):tp_bmc_m_a15"
				( attribute "CDS_PHYS_NET_NAME" "TP_BMC_M_A15"
					( Origin gPackager )
				)
				( objectStatus "TP_BMC_M_A15" )
			)
			( signal "@baseboard_fab2_lib.baseboard_fab2(sch_1):rst_pcie_m2_dev_and"
				( attribute "CDS_PHYS_NET_NAME" "RST_PCIE_M2_DEV_AND"
					( Origin gPackager )
				)
				( objectStatus "RST_PCIE_M2_DEV_AND" )
			)
			( signal "@baseboard_fab2_lib.baseboard_fab2(sch_1):vr_pvccin_cpu0_phase2_rc"
				( attribute "CDS_PHYS_NET_NAME" "VR_PVCCIN_CPU0_PHASE2_RC"
					( Origin gPackager )
				)
				( objectStatus "VR_PVCCIN_CPU0_PHASE2_RC" )
			)
			( signal "@baseboard_fab2_lib.baseboard_fab2(sch_1):vr_p2v5_bmc_stby_fb"
				( attribute "CDS_PHYS_NET_NAME" "VR_P2V5_BMC_STBY_FB"
					( Origin gPackager )
				)
				( objectStatus "VR_P2V5_BMC_STBY_FB" )
			)
			( signal "@baseboard_fab2_lib.baseboard_fab2(sch_1):vr_pvddq_klm_ph2_rc"
				( attribute "CDS_PHYS_NET_NAME" "VR_PVDDQ_KLM_PH2_RC"
					( Origin gPackager )
				)
				( objectStatus "VR_PVDDQ_KLM_PH2_RC" )
			)
			( signal "@baseboard_fab2_lib.baseboard_fab2(sch_1):vr_pvccin_cpu1_phase5_rc"
				( attribute "CDS_PHYS_NET_NAME" "VR_PVCCIN_CPU1_PHASE5_RC"
					( Origin gPackager )
				)
				( objectStatus "VR_PVCCIN_CPU1_PHASE5_RC" )
			)
			( signal "@baseboard_fab2_lib.baseboard_fab2(sch_1):vr_pvccin_cpu1_phase4_rc"
				( attribute "CDS_PHYS_NET_NAME" "VR_PVCCIN_CPU1_PHASE4_RC"
					( Origin gPackager )
				)
				( objectStatus "VR_PVCCIN_CPU1_PHASE4_RC" )
			)
			( signal "@baseboard_fab2_lib.baseboard_fab2(sch_1):vr_pvccin_cpu1_phase1_rc"
				( attribute "CDS_PHYS_NET_NAME" "VR_PVCCIN_CPU1_PHASE1_RC"
					( Origin gPackager )
				)
				( objectStatus "VR_PVCCIN_CPU1_PHASE1_RC" )
			)
			( signal "@baseboard_fab2_lib.baseboard_fab2(sch_1):vr_pvccin_cpu1_phase2_rc"
				( attribute "CDS_PHYS_NET_NAME" "VR_PVCCIN_CPU1_PHASE2_RC"
					( Origin gPackager )
				)
				( objectStatus "VR_PVCCIN_CPU1_PHASE2_RC" )
			)
			( signal "@baseboard_fab2_lib.baseboard_fab2(sch_1):vr_pvddq_ghj_ph2_sw_rc"
				( attribute "CDS_PHYS_NET_NAME" "VR_PVDDQ_GHJ_PH2_SW_RC"
					( Origin gPackager )
				)
				( objectStatus "VR_PVDDQ_GHJ_PH2_SW_RC" )
			)
			( signal "@baseboard_fab2_lib.baseboard_fab2(sch_1):vr_pvccin_cpu0_phase5_rc"
				( attribute "CDS_PHYS_NET_NAME" "VR_PVCCIN_CPU0_PHASE5_RC"
					( Origin gPackager )
				)
				( objectStatus "VR_PVCCIN_CPU0_PHASE5_RC" )
			)
			( signal "@baseboard_fab2_lib.baseboard_fab2(sch_1):vr_pvccin_cpu0_phase3_rc"
				( attribute "CDS_PHYS_NET_NAME" "VR_PVCCIN_CPU0_PHASE3_RC"
					( Origin gPackager )
				)
				( objectStatus "VR_PVCCIN_CPU0_PHASE3_RC" )
			)
			( signal "@baseboard_fab2_lib.baseboard_fab2(sch_1):vr_pvccin_cpu0_phase4_rc"
				( attribute "CDS_PHYS_NET_NAME" "VR_PVCCIN_CPU0_PHASE4_RC"
					( Origin gPackager )
				)
				( objectStatus "VR_PVCCIN_CPU0_PHASE4_RC" )
			)
			( signal "@baseboard_fab2_lib.baseboard_fab2(sch_1):vr_pvddq_def_ph2_sw_rc"
				( attribute "CDS_PHYS_NET_NAME" "VR_PVDDQ_DEF_PH2_SW_RC"
					( Origin gPackager )
				)
				( objectStatus "VR_PVDDQ_DEF_PH2_SW_RC" )
			)
			( signal "@baseboard_fab2_lib.baseboard_fab2(sch_1):vr_pvddq_abc_ph1_sw_rc"
				( attribute "CDS_PHYS_NET_NAME" "VR_PVDDQ_ABC_PH1_SW_RC"
					( Origin gPackager )
				)
				( objectStatus "VR_PVDDQ_ABC_PH1_SW_RC" )
			)
			( signal "@baseboard_fab2_lib.baseboard_fab2(sch_1):vr_pvddq_abc_ph2_sw_rc"
				( attribute "CDS_PHYS_NET_NAME" "VR_PVDDQ_ABC_PH2_SW_RC"
					( Origin gPackager )
				)
				( objectStatus "VR_PVDDQ_ABC_PH2_SW_RC" )
			)
			( signal "@baseboard_fab2_lib.baseboard_fab2(sch_1):vr_pvccio_cpu1_ph1_sw_rc"
				( attribute "CDS_PHYS_NET_NAME" "VR_PVCCIO_CPU1_PH1_SW_RC"
					( Origin gPackager )
				)
				( objectStatus "VR_PVCCIO_CPU1_PH1_SW_RC" )
			)
			( signal "@baseboard_fab2_lib.baseboard_fab2(sch_1):vr_pvccin_cpu0_ph5_boot_r"
				( attribute "CDS_PHYS_NET_NAME" "VR_PVCCIN_CPU0_PH5_BOOT_R"
					( Origin gPackager )
				)
				( objectStatus "VR_PVCCIN_CPU0_PH5_BOOT_R" )
			)
			( signal "@baseboard_fab2_lib.baseboard_fab2(sch_1):vr_pvnn_pch_ph1_phase_sw_rc"
				( attribute "CDS_PHYS_NET_NAME" "VR_PVNN_PCH_PH1_PHASE_SW_RC"
					( Origin gPackager )
				)
				( objectStatus "VR_PVNN_PCH_PH1_PHASE_SW_RC" )
			)
			( signal "@baseboard_fab2_lib.baseboard_fab2(sch_1):vr_pvccio_cpu0_ph1_sw_rc"
				( attribute "CDS_PHYS_NET_NAME" "VR_PVCCIO_CPU0_PH1_SW_RC"
					( Origin gPackager )
				)
				( objectStatus "VR_PVCCIO_CPU0_PH1_SW_RC" )
			)
			( signal "@baseboard_fab2_lib.baseboard_fab2(sch_1):spi_tpm_bmc_di_r"
				( attribute "CDS_PHYS_NET_NAME" "SPI_TPM_BMC_DI_R"
					( Origin gPackager )
				)
				( objectStatus "SPI_TPM_BMC_DI_R" )
			)
			( signal "@baseboard_fab2_lib.baseboard_fab2(sch_1):rst_bmc_ddr3_r_n"
				( attribute "CDS_PHYS_NET_NAME" "RST_BMC_DDR3_R_N"
					( Origin gPackager )
				)
				( objectStatus "RST_BMC_DDR3_R_N" )
			)
			( signal "@baseboard_fab2_lib.baseboard_fab2(sch_1):smb_cpu0_pe_hp_gtl_r_scl"
				( attribute "CDS_PHYS_NET_NAME" "SMB_CPU0_PE_HP_GTL_R_SCL"
					( Origin gPackager )
				)
				( objectStatus "SMB_CPU0_PE_HP_GTL_R_SCL" )
			)
			( signal "@baseboard_fab2_lib.baseboard_fab2(sch_1):smb_cpu0_pe_hp_gtl_r_sda"
				( attribute "CDS_PHYS_NET_NAME" "SMB_CPU0_PE_HP_GTL_R_SDA"
					( Origin gPackager )
				)
				( objectStatus "SMB_CPU0_PE_HP_GTL_R_SDA" )
			)
			( signal "@baseboard_fab2_lib.baseboard_fab2(sch_1):smb_cpu0_pe_hp_gtl_scl"
				( attribute "CDS_PHYS_NET_NAME" "SMB_CPU0_PE_HP_GTL_SCL"
					( Origin gPackager )
				)
				( objectStatus "SMB_CPU0_PE_HP_GTL_SCL" )
			)
			( signal "@baseboard_fab2_lib.baseboard_fab2(sch_1):smb_cpu0_pe_hp_gtl_sda"
				( attribute "CDS_PHYS_NET_NAME" "SMB_CPU0_PE_HP_GTL_SDA"
					( Origin gPackager )
				)
				( objectStatus "SMB_CPU0_PE_HP_GTL_SDA" )
			)
			( signal "@baseboard_fab2_lib.baseboard_fab2(sch_1):tp_smb_pehpcpu0_en"
				( attribute "CDS_PHYS_NET_NAME" "TP_SMB_PEHPCPU0_EN"
					( Origin gPackager )
				)
				( objectStatus "TP_SMB_PEHPCPU0_EN" )
			)
			( signal "@baseboard_fab2_lib.baseboard_fab2(sch_1):smb_pehpcpu0_stby_lvc3_r_scl"
				( attribute "CDS_PHYS_NET_NAME" "SMB_PEHPCPU0_STBY_LVC3_R_SCL"
					( Origin gPackager )
				)
				( objectStatus "SMB_PEHPCPU0_STBY_LVC3_R_SCL" )
			)
			( signal "@baseboard_fab2_lib.baseboard_fab2(sch_1):smb_pehpcpu0_stby_lvc3_r_sda"
				( attribute "CDS_PHYS_NET_NAME" "SMB_PEHPCPU0_STBY_LVC3_R_SDA"
					( Origin gPackager )
				)
				( objectStatus "SMB_PEHPCPU0_STBY_LVC3_R_SDA" )
			)
			( signal "@baseboard_fab2_lib.baseboard_fab2(sch_1):smb_pehpcpu0_stby_lvc3_scl"
				( attribute "CDS_PHYS_NET_NAME" "SMB_PEHPCPU0_STBY_LVC3_SCL"
					( Origin gPackager )
				)
				( objectStatus "SMB_PEHPCPU0_STBY_LVC3_SCL" )
			)
			( signal "@baseboard_fab2_lib.baseboard_fab2(sch_1):smb_pehpcpu0_stby_lvc3_sda"
				( attribute "CDS_PHYS_NET_NAME" "SMB_PEHPCPU0_STBY_LVC3_SDA"
					( Origin gPackager )
				)
				( objectStatus "SMB_PEHPCPU0_STBY_LVC3_SDA" )
			)
			( signal "@baseboard_fab2_lib.baseboard_fab2(sch_1):fm_ocp_mezzb_pres_1v05_pch_n"
				( attribute "CDS_PHYS_NET_NAME" "FM_OCP_MEZZB_PRES_1V05_PCH_N"
					( Origin gPackager )
				)
				( objectStatus "FM_OCP_MEZZB_PRES_1V05_PCH_N" )
			)
			( signal "@baseboard_fab2_lib.baseboard_fab2(sch_1):fm_ocp_mezzc_pres_1v05_pch_n"
				( attribute "CDS_PHYS_NET_NAME" "FM_OCP_MEZZC_PRES_1V05_PCH_N"
					( Origin gPackager )
				)
				( objectStatus "FM_OCP_MEZZC_PRES_1V05_PCH_N" )
			)
			( signal "@baseboard_fab2_lib.baseboard_fab2(sch_1):bmc_strap_bit3"
				( alias ( signalRef "@baseboard_fab2_lib.baseboard_fab2(sch_1):page146_bmc_strap_bit3") )
				( attribute "CDS_PHYS_NET_NAME" "BMC_STRAP_BIT3"
					( Origin gPackager )
				)
				( objectStatus "BMC_STRAP_BIT3" )
			)
			( signal "@baseboard_fab2_lib.baseboard_fab2(sch_1):page146_bmc_strap_bit3"
				( objectFlag fObjectAlias )
				( objectStatus "page146_bmc_strap_bit3" )
			)
			( signal "@baseboard_fab2_lib.baseboard_fab2(sch_1):smb_debug_stby_lvc3_sda"
				( attribute "CDS_PHYS_NET_NAME" "SMB_DEBUG_STBY_LVC3_SDA"
					( Origin gPackager )
				)
				( objectStatus "SMB_DEBUG_STBY_LVC3_SDA" )
			)
			( signal "@baseboard_fab2_lib.baseboard_fab2(sch_1):smb_debug_stby_lvc3_sda_r"
				( attribute "CDS_PHYS_NET_NAME" "SMB_DEBUG_STBY_LVC3_SDA_R"
					( Origin gPackager )
				)
				( objectStatus "SMB_DEBUG_STBY_LVC3_SDA_R" )
			)
			( signal "@baseboard_fab2_lib.baseboard_fab2(sch_1):bmc_strap_bit27"
				( attribute "CDS_PHYS_NET_NAME" "BMC_STRAP_BIT27"
					( Origin gPackager )
				)
				( objectStatus "BMC_STRAP_BIT27" )
			)
			( signal "@baseboard_fab2_lib.baseboard_fab2(sch_1):bmc_strap_bit17"
				( attribute "CDS_PHYS_NET_NAME" "BMC_STRAP_BIT17"
					( Origin gPackager )
				)
				( objectStatus "BMC_STRAP_BIT17" )
			)
			( signal "@baseboard_fab2_lib.baseboard_fab2(sch_1):bmc_strap_bit18"
				( attribute "CDS_PHYS_NET_NAME" "BMC_STRAP_BIT18"
					( Origin gPackager )
				)
				( objectStatus "BMC_STRAP_BIT18" )
			)
			( signal "@baseboard_fab2_lib.baseboard_fab2(sch_1):bmc_strap_bit20"
				( attribute "CDS_PHYS_NET_NAME" "BMC_STRAP_BIT20"
					( Origin gPackager )
				)
				( objectStatus "BMC_STRAP_BIT20" )
			)
			( signal "@baseboard_fab2_lib.baseboard_fab2(sch_1):rst_pcie_m2_dev_ic_n"
				( attribute "CDS_PHYS_NET_NAME" "RST_PCIE_M2_DEV_IC_N"
					( Origin gPackager )
				)
				( objectStatus "RST_PCIE_M2_DEV_IC_N" )
			)
			( signal "@baseboard_fab2_lib.baseboard_fab2(sch_1):fm_tpm_pres_n"
				( alias ( signalRef "@baseboard_fab2_lib.baseboard_fab2(sch_1):page146_fm_tpm_pres_n") )
				( attribute "CDS_PHYS_NET_NAME" "FM_TPM_PRES_N"
					( Origin gPackager )
				)
				( objectStatus "FM_TPM_PRES_N" )
			)
			( signal "@baseboard_fab2_lib.baseboard_fab2(sch_1):page146_fm_tpm_pres_n"
				( attribute "CDS_PHYS_NET_NAME" "FM_TPM_PRES_N"
					( Origin gPackager )
				)
				( objectFlag fObjectAlias )
				( objectStatus "page146_fm_tpm_pres_n" )
			)
			( signal "@baseboard_fab2_lib.baseboard_fab2(sch_1):pwrgd_p1v2_bmc_stby"
				( attribute "CDS_PHYS_NET_NAME" "PWRGD_P1V2_BMC_STBY"
					( Origin gPackager )
				)
				( objectStatus "PWRGD_P1V2_BMC_STBY" )
			)
			( signal "@baseboard_fab2_lib.baseboard_fab2(sch_1):pwrgd_p1v2_bmc_stby_r"
				( attribute "CDS_PHYS_NET_NAME" "PWRGD_P1V2_BMC_STBY_R"
					( Origin gPackager )
				)
				( objectStatus "PWRGD_P1V2_BMC_STBY_R" )
			)
			( signal "@baseboard_fab2_lib.baseboard_fab2(sch_1):tpm_spi_bmc_wp_n"
				( alias ( signalRef "@baseboard_fab2_lib.baseboard_fab2(sch_1):page137_tpm_spi_bmc_wp_n") )
				( attribute "CDS_PHYS_NET_NAME" "TPM_SPI_BMC_WP_N"
					( Origin gPackager )
				)
				( objectStatus "TPM_SPI_BMC_WP_N" )
			)
			( signal "@baseboard_fab2_lib.baseboard_fab2(sch_1):page137_tpm_spi_bmc_wp_n"
				( attribute "CDS_PHYS_NET_NAME" "TPM_SPI_BMC_WP_N"
					( Origin gPackager )
				)
				( objectFlag fObjectAlias )
				( objectStatus "page137_tpm_spi_bmc_wp_n" )
			)
			( signal "@baseboard_fab2_lib.baseboard_fab2(sch_1):vr_p1v05_pch_stby_ph1_sw_rc"
				( attribute "CDS_PHYS_NET_NAME" "VR_P1V05_PCH_STBY_PH1_SW_RC"
					( Origin gPackager )
				)
				( objectStatus "VR_P1V05_PCH_STBY_PH1_SW_RC" )
			)
			( signal "@baseboard_fab2_lib.baseboard_fab2(sch_1):fm_ocp_mezzc_pres_lvt3_bmc"
				( attribute "CDS_PHYS_NET_NAME" "FM_OCP_MEZZC_PRES_LVT3_BMC"
					( Origin gPackager )
				)
				( objectStatus "FM_OCP_MEZZC_PRES_LVT3_BMC" )
			)
			( signal "@baseboard_fab2_lib.baseboard_fab2(sch_1):vr_p1v15_bmc_stby_fb"
				( attribute "CDS_PHYS_NET_NAME" "VR_P1V15_BMC_STBY_FB"
					( Origin gPackager )
				)
				( objectStatus "VR_P1V15_BMC_STBY_FB" )
			)
			( signal "@baseboard_fab2_lib.baseboard_fab2(sch_1):vr_p1v2_bmc_stby_fb"
				( attribute "CDS_PHYS_NET_NAME" "VR_P1V2_BMC_STBY_FB"
					( Origin gPackager )
				)
				( objectStatus "VR_P1V2_BMC_STBY_FB" )
			)
			( signal "@baseboard_fab2_lib.baseboard_fab2(sch_1):fm_ocp_mezzb_pres_lvt3_bmc"
				( attribute "CDS_PHYS_NET_NAME" "FM_OCP_MEZZB_PRES_LVT3_BMC"
					( Origin gPackager )
				)
				( objectStatus "FM_OCP_MEZZB_PRES_LVT3_BMC" )
			)
			( signal "@baseboard_fab2_lib.baseboard_fab2(sch_1):p5v_tps2061"
				( attribute "CDS_PHYS_NET_NAME" "P5V_TPS2061"
					( Origin gPackager )
				)
				( objectStatus "P5V_TPS2061" )
			)
			( signal "@baseboard_fab2_lib.baseboard_fab2(sch_1):fm_usb_p0_en_r_n"
				( attribute "CDS_PHYS_NET_NAME" "FM_USB_P0_EN_R_N"
					( Origin gPackager )
				)
				( objectStatus "FM_USB_P0_EN_R_N" )
			)
			( signal "@baseboard_fab2_lib.baseboard_fab2(sch_1):fm_mezzb_prsnt1_n"
				( attribute "CDS_PHYS_NET_NAME" "FM_MEZZB_PRSNT1_N"
					( Origin gPackager )
				)
				( objectStatus "FM_MEZZB_PRSNT1_N" )
			)
			( signal "@baseboard_fab2_lib.baseboard_fab2(sch_1):pump_pwm_out"
				( attribute "CDS_PHYS_NET_NAME" "PUMP_PWM_OUT"
					( Origin gPackager )
				)
				( objectStatus "PUMP_PWM_OUT" )
			)
			( signal "@baseboard_fab2_lib.baseboard_fab2(sch_1):p12v_pump"
				( attribute "CDS_PHYS_NET_NAME" "P12V_PUMP"
					( Origin gPackager )
				)
				( objectStatus "P12V_PUMP" )
			)
			( signal "@baseboard_fab2_lib.baseboard_fab2(sch_1):p1v8_m2"
				( attribute "CDS_PHYS_NET_NAME" "P1V8_M2"
					( Origin gPackager )
				)
				( objectStatus "P1V8_M2" )
			)
			( signal "@baseboard_fab2_lib.baseboard_fab2(sch_1):smb_pehpcpu0_stby_lvc3_r2_scl"
				( attribute "CDS_PHYS_NET_NAME" "SMB_PEHPCPU0_STBY_LVC3_R2_SCL"
					( Origin gPackager )
				)
				( objectStatus "SMB_PEHPCPU0_STBY_LVC3_R2_SCL" )
			)
			( signal "@baseboard_fab2_lib.baseboard_fab2(sch_1):smb_pehpcpu0_stby_lvc3_r2_sda"
				( attribute "CDS_PHYS_NET_NAME" "SMB_PEHPCPU0_STBY_LVC3_R2_SDA"
					( Origin gPackager )
				)
				( objectStatus "SMB_PEHPCPU0_STBY_LVC3_R2_SDA" )
			)
			( signal "@baseboard_fab2_lib.baseboard_fab2(sch_1):pump_tach_d"
				( attribute "CDS_PHYS_NET_NAME" "PUMP_TACH_D"
					( Origin gPackager )
				)
				( objectStatus "PUMP_TACH_D" )
			)
			( signal "@baseboard_fab2_lib.baseboard_fab2(sch_1):pump_tach_r"
				( attribute "CDS_PHYS_NET_NAME" "PUMP_TACH_R"
					( Origin gPackager )
				)
				( objectStatus "PUMP_TACH_R" )
			)
			( signal "@baseboard_fab2_lib.baseboard_fab2(sch_1):usb2_p02_dn_r"
				( attribute "CDS_PHYS_NET_NAME" "USB2_P02_DN_R"
					( Origin gPackager )
				)
				( objectStatus "USB2_P02_DN_R" )
			)
			( signal "@baseboard_fab2_lib.baseboard_fab2(sch_1):usb2_p02_dp_r"
				( attribute "CDS_PHYS_NET_NAME" "USB2_P02_DP_R"
					( Origin gPackager )
				)
				( objectStatus "USB2_P02_DP_R" )
			)
			( signal "@baseboard_fab2_lib.baseboard_fab2(sch_1):usb2_pch_bmc_p5_dn_r"
				( attribute "CDS_PHYS_NET_NAME" "USB2_PCH_BMC_P5_DN_R"
					( Origin gPackager )
				)
				( objectStatus "USB2_PCH_BMC_P5_DN_R" )
			)
			( signal "@baseboard_fab2_lib.baseboard_fab2(sch_1):usb2_pch_bmc_p5_dp_r"
				( attribute "CDS_PHYS_NET_NAME" "USB2_PCH_BMC_P5_DP_R"
					( Origin gPackager )
				)
				( objectStatus "USB2_PCH_BMC_P5_DP_R" )
			)
			( signal "@baseboard_fab2_lib.baseboard_fab2(sch_1):usb_pch_bmc_p4_dn_r"
				( attribute "CDS_PHYS_NET_NAME" "USB_PCH_BMC_P4_DN_R"
					( Origin gPackager )
				)
				( objectStatus "USB_PCH_BMC_P4_DN_R" )
			)
			( signal "@baseboard_fab2_lib.baseboard_fab2(sch_1):usb_pch_bmc_p4_dp_r"
				( attribute "CDS_PHYS_NET_NAME" "USB_PCH_BMC_P4_DP_R"
					( Origin gPackager )
				)
				( objectStatus "USB_PCH_BMC_P4_DP_R" )
			)
			( signal "@baseboard_fab2_lib.baseboard_fab2(sch_1):i2c_bmc_vga_ddc_scl"
				( attribute "CDS_PHYS_NET_NAME" "I2C_BMC_VGA_DDC_SCL"
					( Origin gPackager )
				)
				( objectStatus "I2C_BMC_VGA_DDC_SCL" )
			)
			( signal "@baseboard_fab2_lib.baseboard_fab2(sch_1):i2c_bmc_vga_ddc_sda"
				( attribute "CDS_PHYS_NET_NAME" "I2C_BMC_VGA_DDC_SDA"
					( Origin gPackager )
				)
				( objectStatus "I2C_BMC_VGA_DDC_SDA" )
			)
			( signal "@baseboard_fab2_lib.baseboard_fab2(sch_1):i2c_bmc_vga_ddc_scl_g"
				( attribute "CDS_PHYS_NET_NAME" "I2C_BMC_VGA_DDC_SCL_G"
					( Origin gPackager )
				)
				( objectStatus "I2C_BMC_VGA_DDC_SCL_G" )
			)
			( signal "@baseboard_fab2_lib.baseboard_fab2(sch_1):i2c_bmc_vga_ddc_sda_g"
				( attribute "CDS_PHYS_NET_NAME" "I2C_BMC_VGA_DDC_SDA_G"
					( Origin gPackager )
				)
				( objectStatus "I2C_BMC_VGA_DDC_SDA_G" )
			)
			( signal "@baseboard_fab2_lib.baseboard_fab2(sch_1):p5v_vga_d"
				( alias ( signalRef "@baseboard_fab2_lib.baseboard_fab2(sch_1):page255_p5v_vga_d") )
				( attribute "CDS_PHYS_NET_NAME" "P5V_VGA_D"
					( Origin gPackager )
				)
				( objectStatus "P5V_VGA_D" )
			)
			( signal "@baseboard_fab2_lib.baseboard_fab2(sch_1):page255_p5v_vga_d"
				( objectFlag fObjectAlias )
				( objectStatus "page255_p5v_vga_d" )
			)
			( signal "@baseboard_fab2_lib.baseboard_fab2(sch_1):q25w1_gate"
				( attribute "CDS_PHYS_NET_NAME" "Q25W1_GATE"
					( Origin gPackager )
				)
				( objectStatus "Q25W1_GATE" )
			)
			( signal "@baseboard_fab2_lib.baseboard_fab2(sch_1):q25w2_gate"
				( attribute "CDS_PHYS_NET_NAME" "Q25W2_GATE"
					( Origin gPackager )
				)
				( objectStatus "Q25W2_GATE" )
			)
			( signal "@baseboard_fab2_lib.baseboard_fab2(sch_1):v_ibmc_5v_ddc_scl_j"
				( attribute "CDS_PHYS_NET_NAME" "V_IBMC_5V_DDC_SCL_J"
					( Origin gPackager )
				)
				( objectStatus "V_IBMC_5V_DDC_SCL_J" )
			)
			( signal "@baseboard_fab2_lib.baseboard_fab2(sch_1):v_ibmc_5v_ddc_sda_j"
				( attribute "CDS_PHYS_NET_NAME" "V_IBMC_5V_DDC_SDA_J"
					( Origin gPackager )
				)
				( objectStatus "V_IBMC_5V_DDC_SDA_J" )
			)
			( signal "@baseboard_fab2_lib.baseboard_fab2(sch_1):vga_rear_hsync_s"
				( attribute "CDS_PHYS_NET_NAME" "VGA_REAR_HSYNC_S"
					( Origin gPackager )
				)
				( objectStatus "VGA_REAR_HSYNC_S" )
			)
			( signal "@baseboard_fab2_lib.baseboard_fab2(sch_1):vga_rear_vsync_s"
				( attribute "CDS_PHYS_NET_NAME" "VGA_REAR_VSYNC_S"
					( Origin gPackager )
				)
				( objectStatus "VGA_REAR_VSYNC_S" )
			)
			( signal "@baseboard_fab2_lib.baseboard_fab2(sch_1):v_io_hsync_j"
				( attribute "CDS_PHYS_NET_NAME" "V_IO_HSYNC_J"
					( Origin gPackager )
				)
				( objectStatus "V_IO_HSYNC_J" )
			)
			( signal "@baseboard_fab2_lib.baseboard_fab2(sch_1):v_io_vsync_j"
				( attribute "CDS_PHYS_NET_NAME" "V_IO_VSYNC_J"
					( Origin gPackager )
				)
				( objectStatus "V_IO_VSYNC_J" )
			)
			( signal "@baseboard_fab2_lib.baseboard_fab2(sch_1):p5v_vga"
				( attribute "CDS_PHYS_NET_NAME" "P5V_VGA"
					( Origin gPackager )
				)
				( objectStatus "P5V_VGA" )
			)
			( signal "@baseboard_fab2_lib.baseboard_fab2(sch_1):clk_48m_usb_bmc_r"
				( attribute "CDS_PHYS_NET_NAME" "CLK_48M_USB_BMC_R"
					( Origin gPackager )
				)
				( objectStatus "CLK_48M_USB_BMC_R" )
			)
			( signal "@baseboard_fab2_lib.baseboard_fab2(sch_1):rst_pltrst_buf_n_r"
				( attribute "CDS_PHYS_NET_NAME" "RST_PLTRST_BUF_N_R"
					( Origin gPackager )
				)
				( objectStatus "RST_PLTRST_BUF_N_R" )
			)
			( signal "@baseboard_fab2_lib.baseboard_fab2(sch_1):pd_cpu0_ear_n"
				( attribute "CDS_PHYS_NET_NAME" "PD_CPU0_EAR_N"
					( Origin gPackager )
				)
				( objectStatus "PD_CPU0_EAR_N" )
			)
			( signal "@baseboard_fab2_lib.baseboard_fab2(sch_1):pd_cpu1_ear_n"
				( attribute "CDS_PHYS_NET_NAME" "PD_CPU1_EAR_N"
					( Origin gPackager )
				)
				( objectStatus "PD_CPU1_EAR_N" )
			)
			( signal "@baseboard_fab2_lib.baseboard_fab2(sch_1):fm_slps3_r_n"
				( attribute "CDS_PHYS_NET_NAME" "FM_SLPS3_R_N"
					( Origin gPackager )
				)
				( objectStatus "FM_SLPS3_R_N" )
			)
			( signal "@baseboard_fab2_lib.baseboard_fab2(sch_1):usb3_p01_fb_rxn"
				( attribute "CDS_PHYS_NET_NAME" "USB3_P01_FB_RXN"
					( Origin gPackager )
				)
				( objectStatus "USB3_P01_FB_RXN" )
			)
			( signal "@baseboard_fab2_lib.baseboard_fab2(sch_1):usb3_p01_fb_rxp"
				( attribute "CDS_PHYS_NET_NAME" "USB3_P01_FB_RXP"
					( Origin gPackager )
				)
				( objectStatus "USB3_P01_FB_RXP" )
			)
			( signal "@baseboard_fab2_lib.baseboard_fab2(sch_1):usb3_p01_fb_txn"
				( attribute "CDS_PHYS_NET_NAME" "USB3_P01_FB_TXN"
					( Origin gPackager )
				)
				( objectStatus "USB3_P01_FB_TXN" )
			)
			( signal "@baseboard_fab2_lib.baseboard_fab2(sch_1):usb3_p01_fb_txp"
				( attribute "CDS_PHYS_NET_NAME" "USB3_P01_FB_TXP"
					( Origin gPackager )
				)
				( objectStatus "USB3_P01_FB_TXP" )
			)
			( signal "@baseboard_fab2_lib.baseboard_fab2(sch_1):usb3_p01_c_txn"
				( attribute "CDS_PHYS_NET_NAME" "USB3_P01_C_TXN"
					( Origin gPackager )
				)
				( objectStatus "USB3_P01_C_TXN" )
			)
			( signal "@baseboard_fab2_lib.baseboard_fab2(sch_1):usb3_p01_c_txp"
				( attribute "CDS_PHYS_NET_NAME" "USB3_P01_C_TXP"
					( Origin gPackager )
				)
				( objectStatus "USB3_P01_C_TXP" )
			)
			( signal "@baseboard_fab2_lib.baseboard_fab2(sch_1):usb3_p01_rxn"
				( attribute "CDS_PHYS_NET_NAME" "USB3_P01_RXN"
					( Origin gPackager )
				)
				( objectStatus "USB3_P01_RXN" )
			)
			( signal "@baseboard_fab2_lib.baseboard_fab2(sch_1):usb3_p01_rxp"
				( attribute "CDS_PHYS_NET_NAME" "USB3_P01_RXP"
					( Origin gPackager )
				)
				( objectStatus "USB3_P01_RXP" )
			)
			( signal "@baseboard_fab2_lib.baseboard_fab2(sch_1):usb3_p01_txn"
				( attribute "CDS_PHYS_NET_NAME" "USB3_P01_TXN"
					( Origin gPackager )
				)
				( objectStatus "USB3_P01_TXN" )
			)
			( signal "@baseboard_fab2_lib.baseboard_fab2(sch_1):usb3_p01_txp"
				( attribute "CDS_PHYS_NET_NAME" "USB3_P01_TXP"
					( Origin gPackager )
				)
				( objectStatus "USB3_P01_TXP" )
			)
			( signal "@baseboard_fab2_lib.baseboard_fab2(sch_1):temp_sensor_b"
				( attribute "CDS_PHYS_NET_NAME" "TEMP_SENSOR_B"
					( Origin gPackager )
				)
				( objectStatus "TEMP_SENSOR_B" )
			)
			( signal "@baseboard_fab2_lib.baseboard_fab2(sch_1):temp_sensor_e"
				( attribute "CDS_PHYS_NET_NAME" "TEMP_SENSOR_E"
					( Origin gPackager )
				)
				( objectStatus "TEMP_SENSOR_E" )
			)
			( signal "@baseboard_fab2_lib.baseboard_fab2(sch_1):pwrgd_pvddq_klm_n"
				( attribute "CDS_PHYS_NET_NAME" "PWRGD_PVDDQ_KLM_N"
					( Origin gPackager )
				)
				( objectStatus "PWRGD_PVDDQ_KLM_N" )
			)
			( signal "@baseboard_fab2_lib.baseboard_fab2(sch_1):pwrgd_pvddq_abc_n"
				( attribute "CDS_PHYS_NET_NAME" "PWRGD_PVDDQ_ABC_N"
					( Origin gPackager )
				)
				( objectStatus "PWRGD_PVDDQ_ABC_N" )
			)
			( signal "@baseboard_fab2_lib.baseboard_fab2(sch_1):pwrgd_pvddq_ghj_n"
				( attribute "CDS_PHYS_NET_NAME" "PWRGD_PVDDQ_GHJ_N"
					( Origin gPackager )
				)
				( objectStatus "PWRGD_PVDDQ_GHJ_N" )
			)
			( signal "@baseboard_fab2_lib.baseboard_fab2(sch_1):p12v_nvdimm_abc_d"
				( attribute "CDS_PHYS_NET_NAME" "P12V_NVDIMM_ABC_D"
					( Origin gPackager )
				)
				( objectStatus "P12V_NVDIMM_ABC_D" )
			)
			( signal "@baseboard_fab2_lib.baseboard_fab2(sch_1):fm_global_rst_warn_n_r"
				( attribute "CDS_PHYS_NET_NAME" "FM_GLOBAL_RST_WARN_N_R"
					( Origin gPackager )
				)
				( objectStatus "FM_GLOBAL_RST_WARN_N_R" )
			)
			( signal "@baseboard_fab2_lib.baseboard_fab2(sch_1):pu_cpld1_pt20d_programn"
				( attribute "CDS_PHYS_NET_NAME" "PU_CPLD1_PT20D_PROGRAMN"
					( Origin gPackager )
				)
				( objectStatus "PU_CPLD1_PT20D_PROGRAMN" )
			)
			( signal "@baseboard_fab2_lib.baseboard_fab2(sch_1):smb_host_stby_lvc3_sda_r4"
				( attribute "CDS_PHYS_NET_NAME" "SMB_HOST_STBY_LVC3_SDA_R4"
					( Origin gPackager )
				)
				( objectStatus "SMB_HOST_STBY_LVC3_SDA_R4" )
			)
			( signal "@baseboard_fab2_lib.baseboard_fab2(sch_1):xtal_ck_mng_out_r"
				( attribute "CDS_PHYS_NET_NAME" "XTAL_CK_MNG_OUT_R"
					( Origin gPackager )
				)
				( objectStatus "XTAL_CK_MNG_OUT_R" )
			)
			( signal "@baseboard_fab2_lib.baseboard_fab2(sch_1):smb_host_stby_lvc3_scl_r4"
				( attribute "CDS_PHYS_NET_NAME" "SMB_HOST_STBY_LVC3_SCL_R4"
					( Origin gPackager )
				)
				( objectStatus "SMB_HOST_STBY_LVC3_SCL_R4" )
			)
			( signal "@baseboard_fab2_lib.baseboard_fab2(sch_1):pu_33p_33m_smbadr"
				( attribute "CDS_PHYS_NET_NAME" "PU_33P_33M_SMBADR"
					( Origin gPackager )
				)
				( objectStatus "PU_33P_33M_SMBADR" )
			)
			( signal "@baseboard_fab2_lib.baseboard_fab2(sch_1):fm_cpu1_cd_pres_n"
				( attribute "CDS_PHYS_NET_NAME" "FM_CPU1_CD_PRES_N"
					( Origin gPackager )
				)
				( objectStatus "FM_CPU1_CD_PRES_N" )
			)
			( signal "@baseboard_fab2_lib.baseboard_fab2(sch_1):pu_pvnn_pch_vclk"
				( attribute "CDS_PHYS_NET_NAME" "PU_PVNN_PCH_VCLK"
					( Origin gPackager )
				)
				( objectStatus "PU_PVNN_PCH_VCLK" )
			)
			( signal "@baseboard_fab2_lib.baseboard_fab2(sch_1):fm_pwr_btn_r2_n"
				( attribute "CDS_PHYS_NET_NAME" "FM_PWR_BTN_R2_N"
					( Origin gPackager )
				)
				( objectStatus "FM_PWR_BTN_R2_N" )
			)
			( signal "@baseboard_fab2_lib.baseboard_fab2(sch_1):fm_pch_pwrbtn_r1_n"
				( attribute "CDS_PHYS_NET_NAME" "FM_PCH_PWRBTN_R1_N"
					( Origin gPackager )
				)
				( objectStatus "FM_PCH_PWRBTN_R1_N" )
			)
			( signal "@baseboard_fab2_lib.baseboard_fab2(sch_1):fm_pwr_btn_r1_n"
				( attribute "CDS_PHYS_NET_NAME" "FM_PWR_BTN_R1_N"
					( Origin gPackager )
				)
				( objectStatus "FM_PWR_BTN_R1_N" )
			)
			( signal "@baseboard_fab2_lib.baseboard_fab2(sch_1):rst_system_btn_r_n"
				( attribute "CDS_PHYS_NET_NAME" "RST_SYSTEM_BTN_R_N"
					( Origin gPackager )
				)
				( objectStatus "RST_SYSTEM_BTN_R_N" )
			)
			( signal "@baseboard_fab2_lib.baseboard_fab2(sch_1):rst_bmc_sysrst_btn_out_b_r1_n"
				( attribute "CDS_PHYS_NET_NAME" "RST_BMC_SYSRST_BTN_OUT_B_R1_N"
					( Origin gPackager )
				)
				( objectStatus "RST_BMC_SYSRST_BTN_OUT_B_R1_N" )
			)
			( signal "@baseboard_fab2_lib.baseboard_fab2(sch_1):pu_jtag_bmc_rtck"
				( attribute "CDS_PHYS_NET_NAME" "PU_JTAG_BMC_RTCK"
					( Origin gPackager )
				)
				( objectStatus "PU_JTAG_BMC_RTCK" )
			)
			( signal "@baseboard_fab2_lib.baseboard_fab2(sch_1):tp_rgmii2txd2_gpiou2"
				( attribute "CDS_PHYS_NET_NAME" "TP_RGMII2TXD2_GPIOU2"
					( Origin gPackager )
				)
				( objectStatus "TP_RGMII2TXD2_GPIOU2" )
			)
			( signal "@baseboard_fab2_lib.baseboard_fab2(sch_1):tp_rgmii2txd3_gpiou3"
				( attribute "CDS_PHYS_NET_NAME" "TP_RGMII2TXD3_GPIOU3"
					( Origin gPackager )
				)
				( objectStatus "TP_RGMII2TXD3_GPIOU3" )
			)
			( signal "@baseboard_fab2_lib.baseboard_fab2(sch_1):rst_bmc_extrst_n"
				( attribute "CDS_PHYS_NET_NAME" "RST_BMC_EXTRST_N"
					( Origin gPackager )
				)
				( attribute "PHYS_NET_NAME" "RST_BMC_EXTRST_N"
					( Origin gPackager )
				)
				( objectStatus "RST_BMC_EXTRST_N" )
			)
			( signal "@baseboard_fab2_lib.baseboard_fab2(sch_1):tp_slotx24_rsvd63"
				( attribute "CDS_PHYS_NET_NAME" "TP_SLOTX24_RSVD63"
					( Origin gPackager )
				)
				( objectStatus "TP_SLOTX24_RSVD63" )
			)
			( signal "@baseboard_fab2_lib.baseboard_fab2(sch_1):fm_prsnt_2_1_n"
				( attribute "CDS_PHYS_NET_NAME" "FM_PRSNT_2_1_N"
					( Origin gPackager )
				)
				( objectStatus "FM_PRSNT_2_1_N" )
			)
			( signal "@baseboard_fab2_lib.baseboard_fab2(sch_1):tp_slotx24_rsvd66"
				( attribute "CDS_PHYS_NET_NAME" "TP_SLOTX24_RSVD66"
					( Origin gPackager )
				)
				( objectStatus "TP_SLOTX24_RSVD66" )
			)
			( signal "@baseboard_fab2_lib.baseboard_fab2(sch_1):pu_spi_bmc_bt_cs0_n"
				( attribute "CDS_PHYS_NET_NAME" "PU_SPI_BMC_BT_CS0_N"
					( Origin gPackager )
				)
				( objectStatus "PU_SPI_BMC_BT_CS0_N" )
			)
			( signal "@baseboard_fab2_lib.baseboard_fab2(sch_1):pd_uv_high_set"
				( attribute "CDS_PHYS_NET_NAME" "PD_UV_HIGH_SET"
					( Origin gPackager )
				)
				( objectStatus "PD_UV_HIGH_SET" )
			)
			( signal "@baseboard_fab2_lib.baseboard_fab2(sch_1):pu_uv_high_set"
				( attribute "CDS_PHYS_NET_NAME" "PU_UV_HIGH_SET"
					( Origin gPackager )
				)
				( objectStatus "PU_UV_HIGH_SET" )
			)
			( signal "@baseboard_fab2_lib.baseboard_fab2(sch_1):smb_host_stby_lvc3_sda_r5"
				( attribute "CDS_PHYS_NET_NAME" "SMB_HOST_STBY_LVC3_SDA_R5"
					( Origin gPackager )
				)
				( objectStatus "SMB_HOST_STBY_LVC3_SDA_R5" )
			)
			( signal "@baseboard_fab2_lib.baseboard_fab2(sch_1):smb_host_stby_lvc3_scl_r5"
				( attribute "CDS_PHYS_NET_NAME" "SMB_HOST_STBY_LVC3_SCL_R5"
					( Origin gPackager )
				)
				( objectStatus "SMB_HOST_STBY_LVC3_SCL_R5" )
			)
			( signal "@baseboard_fab2_lib.baseboard_fab2(sch_1):smb_slotx24_pch_stby_lvc3_scl"
				( attribute "CDS_PHYS_NET_NAME" "SMB_SLOTX24_PCH_STBY_LVC3_SCL"
					( Origin gPackager )
				)
				( objectStatus "SMB_SLOTX24_PCH_STBY_LVC3_SCL" )
			)
			( signal "@baseboard_fab2_lib.baseboard_fab2(sch_1):smb_slotx24_pch_stby_lvc3_sda"
				( attribute "CDS_PHYS_NET_NAME" "SMB_SLOTX24_PCH_STBY_LVC3_SDA"
					( Origin gPackager )
				)
				( objectStatus "SMB_SLOTX24_PCH_STBY_LVC3_SDA" )
			)
			( signal "@baseboard_fab2_lib.baseboard_fab2(sch_1):tp_bmc_gpioa2"
				( attribute "CDS_PHYS_NET_NAME" "TP_BMC_GPIOA2"
					( Origin gPackager )
				)
				( objectStatus "TP_BMC_GPIOA2" )
			)
			( signal "@baseboard_fab2_lib.baseboard_fab2(sch_1):pu_pvnn_pch_pinalrt_n"
				( attribute "CDS_PHYS_NET_NAME" "PU_PVNN_PCH_PINALRT_N"
					( Origin gPackager )
				)
				( objectStatus "PU_PVNN_PCH_PINALRT_N" )
			)
			( signal "@baseboard_fab2_lib.baseboard_fab2(sch_1):p3v3_db1200_r1"
				( attribute "CDS_PHYS_NET_NAME" "P3V3_DB1200_R1"
					( Origin gPackager )
				)
				( objectStatus "P3V3_DB1200_R1" )
			)
			( signal "@baseboard_fab2_lib.baseboard_fab2(sch_1):fm_db1200_pwrgd_r"
				( attribute "CDS_PHYS_NET_NAME" "FM_DB1200_PWRGD_R"
					( Origin gPackager )
				)
				( objectStatus "FM_DB1200_PWRGD_R" )
			)
			( signal "@baseboard_fab2_lib.baseboard_fab2(sch_1):kr_p1_ocp_rx_c_dn"
				( attribute "CDS_PHYS_NET_NAME" "KR_P1_OCP_RX_C_DN"
					( Origin gPackager )
				)
				( objectStatus "KR_P1_OCP_RX_C_DN" )
			)
			( signal "@baseboard_fab2_lib.baseboard_fab2(sch_1):kr_p1_ocp_rx_c_dp"
				( attribute "CDS_PHYS_NET_NAME" "KR_P1_OCP_RX_C_DP"
					( Origin gPackager )
				)
				( objectStatus "KR_P1_OCP_RX_C_DP" )
			)
			( signal "@baseboard_fab2_lib.baseboard_fab2(sch_1):kr_p1_ocp_rx_dn"
				( attribute "CDS_PHYS_NET_NAME" "KR_P1_OCP_RX_DN"
					( Origin gPackager )
				)
				( objectStatus "KR_P1_OCP_RX_DN" )
			)
			( signal "@baseboard_fab2_lib.baseboard_fab2(sch_1):kr_p1_ocp_rx_dp"
				( attribute "CDS_PHYS_NET_NAME" "KR_P1_OCP_RX_DP"
					( Origin gPackager )
				)
				( objectStatus "KR_P1_OCP_RX_DP" )
			)
			( signal "@baseboard_fab2_lib.baseboard_fab2(sch_1):kr_p1_ocp_tx_dn"
				( attribute "CDS_PHYS_NET_NAME" "KR_P1_OCP_TX_DN"
					( Origin gPackager )
				)
				( objectStatus "KR_P1_OCP_TX_DN" )
			)
			( signal "@baseboard_fab2_lib.baseboard_fab2(sch_1):kr_p1_ocp_tx_dp"
				( attribute "CDS_PHYS_NET_NAME" "KR_P1_OCP_TX_DP"
					( Origin gPackager )
				)
				( objectStatus "KR_P1_OCP_TX_DP" )
			)
			( signal "@baseboard_fab2_lib.baseboard_fab2(sch_1):jtag_mcp_tck_r1"
				( attribute "CDS_PHYS_NET_NAME" "JTAG_MCP_TCK_R1"
					( Origin gPackager )
				)
				( objectStatus "JTAG_MCP_TCK_R1" )
			)
			( signal "@baseboard_fab2_lib.baseboard_fab2(sch_1):p5v_stby_usbc"
				( attribute "CDS_PHYS_NET_NAME" "P5V_STBY_USBC"
					( Origin gPackager )
				)
				( objectStatus "P5V_STBY_USBC" )
			)
			( signal "@baseboard_fab2_lib.baseboard_fab2(sch_1):fm_adr_complete_cpu1_n"
				( attribute "CDS_PHYS_NET_NAME" "FM_ADR_COMPLETE_CPU1_N"
					( Origin gPackager )
				)
				( objectStatus "FM_ADR_COMPLETE_CPU1_N" )
			)
			( signal "@baseboard_fab2_lib.baseboard_fab2(sch_1):irq_dimm_save_cpu1_r_n"
				( attribute "CDS_PHYS_NET_NAME" "IRQ_DIMM_SAVE_CPU1_R_N"
					( Origin gPackager )
				)
				( objectStatus "IRQ_DIMM_SAVE_CPU1_R_N" )
			)
			( signal "@baseboard_fab2_lib.baseboard_fab2(sch_1):irq_dimm_save_lvt3_cpu1"
				( attribute "CDS_PHYS_NET_NAME" "IRQ_DIMM_SAVE_LVT3_CPU1"
					( Origin gPackager )
				)
				( objectStatus "IRQ_DIMM_SAVE_LVT3_CPU1" )
			)
			( signal "@baseboard_fab2_lib.baseboard_fab2(sch_1):fm_adr_complete_cpu0_r"
				( attribute "CDS_PHYS_NET_NAME" "FM_ADR_COMPLETE_CPU0_R"
					( Origin gPackager )
				)
				( objectStatus "FM_ADR_COMPLETE_CPU0_R" )
			)
			( signal "@baseboard_fab2_lib.baseboard_fab2(sch_1):fm_adr_complete_cpu1_r"
				( attribute "CDS_PHYS_NET_NAME" "FM_ADR_COMPLETE_CPU1_R"
					( Origin gPackager )
				)
				( objectStatus "FM_ADR_COMPLETE_CPU1_R" )
			)
			( signal "@baseboard_fab2_lib.baseboard_fab2(sch_1):smb_debug_stby_lvc3_scl_r1"
				( attribute "CDS_PHYS_NET_NAME" "SMB_DEBUG_STBY_LVC3_SCL_R1"
					( Origin gPackager )
				)
				( objectStatus "SMB_DEBUG_STBY_LVC3_SCL_R1" )
			)
			( signal "@baseboard_fab2_lib.baseboard_fab2(sch_1):smb_debug_stby_lvc3_sda_r1"
				( attribute "CDS_PHYS_NET_NAME" "SMB_DEBUG_STBY_LVC3_SDA_R1"
					( Origin gPackager )
				)
				( objectStatus "SMB_DEBUG_STBY_LVC3_SDA_R1" )
			)
			( signal "@baseboard_fab2_lib.baseboard_fab2(sch_1):debug_card2_prsnt"
				( attribute "CDS_PHYS_NET_NAME" "DEBUG_CARD2_PRSNT"
					( Origin gPackager )
				)
				( objectStatus "DEBUG_CARD2_PRSNT" )
			)
			( signal "@baseboard_fab2_lib.baseboard_fab2(sch_1):spa_mid_dbg2_tx"
				( attribute "CDS_PHYS_NET_NAME" "SPA_MID_DBG2_TX"
					( Origin gPackager )
				)
				( objectStatus "SPA_MID_DBG2_TX" )
			)
			( signal "@baseboard_fab2_lib.baseboard_fab2(sch_1):spa_mid_dbg2_rx_buf"
				( attribute "CDS_PHYS_NET_NAME" "SPA_MID_DBG2_RX_BUF"
					( Origin gPackager )
				)
				( objectStatus "SPA_MID_DBG2_RX_BUF" )
			)
			( signal "@baseboard_fab2_lib.baseboard_fab2(sch_1):spa_mid_dbg2_tx_r"
				( attribute "CDS_PHYS_NET_NAME" "SPA_MID_DBG2_TX_R"
					( Origin gPackager )
				)
				( objectStatus "SPA_MID_DBG2_TX_R" )
			)
			( signal "@baseboard_fab2_lib.baseboard_fab2(sch_1):spa_mid_dbg1_tx"
				( attribute "CDS_PHYS_NET_NAME" "SPA_MID_DBG1_TX"
					( Origin gPackager )
				)
				( objectStatus "SPA_MID_DBG1_TX" )
			)
			( signal "@baseboard_fab2_lib.baseboard_fab2(sch_1):spa_mid_dbg1_tx_r"
				( attribute "CDS_PHYS_NET_NAME" "SPA_MID_DBG1_TX_R"
					( Origin gPackager )
				)
				( objectStatus "SPA_MID_DBG1_TX_R" )
			)
			( signal "@baseboard_fab2_lib.baseboard_fab2(sch_1):fm_cpu_caterr_msmi_lvt3_n"
				( attribute "CDS_PHYS_NET_NAME" "FM_CPU_CATERR_MSMI_LVT3_N"
					( Origin gPackager )
				)
				( objectStatus "FM_CPU_CATERR_MSMI_LVT3_N" )
			)
			( signal "@baseboard_fab2_lib.baseboard_fab2(sch_1):spa_mid_dbg1_tx_en"
				( attribute "CDS_PHYS_NET_NAME" "SPA_MID_DBG1_TX_EN"
					( Origin gPackager )
				)
				( objectStatus "SPA_MID_DBG1_TX_EN" )
			)
			( signal "@baseboard_fab2_lib.baseboard_fab2(sch_1):smb_debug_stby_lvc3_scl_conn"
				( attribute "CDS_PHYS_NET_NAME" "SMB_DEBUG_STBY_LVC3_SCL_CONN"
					( Origin gPackager )
				)
				( objectStatus "SMB_DEBUG_STBY_LVC3_SCL_CONN" )
			)
			( signal "@baseboard_fab2_lib.baseboard_fab2(sch_1):smb_debug_stby_lvc3_sda_conn"
				( attribute "CDS_PHYS_NET_NAME" "SMB_DEBUG_STBY_LVC3_SDA_CONN"
					( Origin gPackager )
				)
				( objectStatus "SMB_DEBUG_STBY_LVC3_SDA_CONN" )
			)
			( signal "@baseboard_fab2_lib.baseboard_fab2(sch_1):bmc_m_clk"
				( attribute "CDS_PHYS_NET_NAME" "BMC_M_CLK"
					( Origin gPackager )
				)
				( objectStatus "BMC_M_CLK" )
			)
			( signal "@baseboard_fab2_lib.baseboard_fab2(sch_1):smb_m2_alt_r_n"
				( attribute "CDS_PHYS_NET_NAME" "SMB_M2_ALT_R_N"
					( Origin gPackager )
				)
				( objectStatus "SMB_M2_ALT_R_N" )
			)
			( signal "@baseboard_fab2_lib.baseboard_fab2(sch_1):smb_m2_alt_n"
				( attribute "CDS_PHYS_NET_NAME" "SMB_M2_ALT_N"
					( Origin gPackager )
				)
				( objectStatus "SMB_M2_ALT_N" )
			)
			( signal "@baseboard_fab2_lib.baseboard_fab2(sch_1):tp_pump"
				( attribute "CDS_PHYS_NET_NAME" "TP_PUMP"
					( Origin gPackager )
				)
				( objectStatus "TP_PUMP" )
			)
			( signal "@baseboard_fab2_lib.baseboard_fab2(sch_1):pump_tach1"
				( attribute "CDS_PHYS_NET_NAME" "PUMP_TACH1"
					( Origin gPackager )
				)
				( objectStatus "PUMP_TACH1" )
			)
			( signal "@baseboard_fab2_lib.baseboard_fab2(sch_1):pump_tach1_d"
				( attribute "CDS_PHYS_NET_NAME" "PUMP_TACH1_D"
					( Origin gPackager )
				)
				( objectStatus "PUMP_TACH1_D" )
			)
			( signal "@baseboard_fab2_lib.baseboard_fab2(sch_1):pump_tach1_r"
				( attribute "CDS_PHYS_NET_NAME" "PUMP_TACH1_R"
					( Origin gPackager )
				)
				( objectStatus "PUMP_TACH1_R" )
			)
			( signal "@baseboard_fab2_lib.baseboard_fab2(sch_1):smb_m2_scl"
				( attribute "CDS_PHYS_NET_NAME" "SMB_M2_SCL"
					( Origin gPackager )
				)
				( objectStatus "SMB_M2_SCL" )
			)
			( signal "@baseboard_fab2_lib.baseboard_fab2(sch_1):smb_m2_scl_r"
				( attribute "CDS_PHYS_NET_NAME" "SMB_M2_SCL_R"
					( Origin gPackager )
				)
				( objectStatus "SMB_M2_SCL_R" )
			)
			( signal "@baseboard_fab2_lib.baseboard_fab2(sch_1):smb_m2_sda"
				( attribute "CDS_PHYS_NET_NAME" "SMB_M2_SDA"
					( Origin gPackager )
				)
				( objectStatus "SMB_M2_SDA" )
			)
			( signal "@baseboard_fab2_lib.baseboard_fab2(sch_1):smb_m2_sda_r"
				( attribute "CDS_PHYS_NET_NAME" "SMB_M2_SDA_R"
					( Origin gPackager )
				)
				( objectStatus "SMB_M2_SDA_R" )
			)
			( signal "@baseboard_fab2_lib.baseboard_fab2(sch_1):vref_lmv431_1v42"
				( attribute "CDS_PHYS_NET_NAME" "VREF_LMV431_1V42"
					( Origin gPackager )
				)
				( objectStatus "VREF_LMV431_1V42" )
			)
			( signal "@baseboard_fab2_lib.baseboard_fab2(sch_1):pu_id_eeprom_a0"
				( attribute "CDS_PHYS_NET_NAME" "PU_ID_EEPROM_A0"
					( Origin gPackager )
				)
				( objectStatus "PU_ID_EEPROM_A0" )
			)
			( signal "@baseboard_fab2_lib.baseboard_fab2(sch_1):bmc_self_hw_d_rst"
				( attribute "CDS_PHYS_NET_NAME" "BMC_SELF_HW_D_RST"
					( Origin gPackager )
				)
				( objectStatus "BMC_SELF_HW_D_RST" )
			)
			( signal "@baseboard_fab2_lib.baseboard_fab2(sch_1):pca9554_a0"
				( attribute "CDS_PHYS_NET_NAME" "PCA9554_A0"
					( Origin gPackager )
				)
				( objectStatus "PCA9554_A0" )
			)
			( signal "@baseboard_fab2_lib.baseboard_fab2(sch_1):fm_pmbus_alert_buf_en_r_n"
				( attribute "CDS_PHYS_NET_NAME" "FM_PMBUS_ALERT_BUF_EN_R_N"
					( Origin gPackager )
				)
				( objectStatus "FM_PMBUS_ALERT_BUF_EN_R_N" )
			)
			( signal "@baseboard_fab2_lib.baseboard_fab2(sch_1):fm_pmbus_alert_buf_en_r2_n"
				( attribute "CDS_PHYS_NET_NAME" "FM_PMBUS_ALERT_BUF_EN_R2_N"
					( Origin gPackager )
				)
				( objectStatus "FM_PMBUS_ALERT_BUF_EN_R2_N" )
			)
			( signal "@baseboard_fab2_lib.baseboard_fab2(sch_1):fm_pmbus_alert_buf_en_r3_n"
				( attribute "CDS_PHYS_NET_NAME" "FM_PMBUS_ALERT_BUF_EN_R3_N"
					( Origin gPackager )
				)
				( objectStatus "FM_PMBUS_ALERT_BUF_EN_R3_N" )
			)
			( signal "@baseboard_fab2_lib.baseboard_fab2(sch_1):jtag_bmc_tck0"
				( attribute "CDS_PHYS_NET_NAME" "JTAG_BMC_TCK0"
					( Origin gPackager )
				)
				( objectStatus "JTAG_BMC_TCK0" )
			)
			( signal "@baseboard_fab2_lib.baseboard_fab2(sch_1):jtag_bmc_tck1"
				( attribute "CDS_PHYS_NET_NAME" "JTAG_BMC_TCK1"
					( Origin gPackager )
				)
				( objectStatus "JTAG_BMC_TCK1" )
			)
			( signal "@baseboard_fab2_lib.baseboard_fab2(sch_1):pd_gtl2014_3_vref"
				( attribute "CDS_PHYS_NET_NAME" "PD_GTL2014_3_VREF"
					( Origin gPackager )
				)
				( objectStatus "PD_GTL2014_3_VREF" )
			)
			( signal "@baseboard_fab2_lib.baseboard_fab2(sch_1):pu_gtl2014_3_dir"
				( attribute "CDS_PHYS_NET_NAME" "PU_GTL2014_3_DIR"
					( Origin gPackager )
				)
				( objectStatus "PU_GTL2014_3_DIR" )
			)
			( signal "@baseboard_fab2_lib.baseboard_fab2(sch_1):xdp_cpu_tck0_r"
				( attribute "CDS_PHYS_NET_NAME" "XDP_CPU_TCK0_R"
					( Origin gPackager )
				)
				( objectStatus "XDP_CPU_TCK0_R" )
			)
			( signal "@baseboard_fab2_lib.baseboard_fab2(sch_1):xdp_pch_tck1_r"
				( attribute "CDS_PHYS_NET_NAME" "XDP_PCH_TCK1_R"
					( Origin gPackager )
				)
				( objectStatus "XDP_PCH_TCK1_R" )
			)
			( signal "@baseboard_fab2_lib.baseboard_fab2(sch_1):xdp_tdi_r"
				( attribute "CDS_PHYS_NET_NAME" "XDP_TDI_R"
					( Origin gPackager )
				)
				( objectStatus "XDP_TDI_R" )
			)
			( signal "@baseboard_fab2_lib.baseboard_fab2(sch_1):xdp_tms_r"
				( attribute "CDS_PHYS_NET_NAME" "XDP_TMS_R"
					( Origin gPackager )
				)
				( objectStatus "XDP_TMS_R" )
			)
			( signal "@baseboard_fab2_lib.baseboard_fab2(sch_1):xdp_trst_r_n"
				( attribute "CDS_PHYS_NET_NAME" "XDP_TRST_R_N"
					( Origin gPackager )
				)
				( objectStatus "XDP_TRST_R_N" )
			)
			( signal "@baseboard_fab2_lib.baseboard_fab2(sch_1):cpu_xdp_present_n"
				( attribute "CDS_PHYS_NET_NAME" "CPU_XDP_PRESENT_N"
					( Origin gPackager )
				)
				( objectStatus "CPU_XDP_PRESENT_N" )
			)
			( signal "@baseboard_fab2_lib.baseboard_fab2(sch_1):p0v7_gtl2014_vref_6"
				( alias ( signalRef "@baseboard_fab2_lib.baseboard_fab2(sch_1):page268_p0v7_gtl2014_vref_6") )
				( attribute "VOLTAGE" "+0.7 V"
					( Units "uVoltage" "V" 1.000000)
					( Status sAliasFlattened )
					( Origin gFrontEnd )
				)
				( attribute "CDS_PHYS_NET_NAME" "P0V7_GTL2014_VREF_6"
					( Origin gPackager )
				)
				( objectStatus "P0V7_GTL2014_VREF_6" )
			)
			( signal "@baseboard_fab2_lib.baseboard_fab2(sch_1):page268_p0v7_gtl2014_vref_6"
				( attribute "VOLTAGE" "+0.7 V"
					( Units "uVoltage" "V" 1.000000)
					( Origin gFrontEnd )
				)
				( objectFlag fObjectAlias )
				( objectStatus "page268_p0v7_gtl2014_vref_6" )
			)
			( signal "@baseboard_fab2_lib.baseboard_fab2(sch_1):pd_gtl2014_6_b0"
				( attribute "CDS_PHYS_NET_NAME" "PD_GTL2014_6_B0"
					( Origin gPackager )
				)
				( objectStatus "PD_GTL2014_6_B0" )
			)
			( signal "@baseboard_fab2_lib.baseboard_fab2(sch_1):pd_gtl2014_6_b2"
				( attribute "CDS_PHYS_NET_NAME" "PD_GTL2014_6_B2"
					( Origin gPackager )
				)
				( objectStatus "PD_GTL2014_6_B2" )
			)
			( signal "@baseboard_fab2_lib.baseboard_fab2(sch_1):pd_gtl2014_dir_6"
				( attribute "CDS_PHYS_NET_NAME" "PD_GTL2014_DIR_6"
					( Origin gPackager )
				)
				( objectStatus "PD_GTL2014_DIR_6" )
			)
			( signal "@baseboard_fab2_lib.baseboard_fab2(sch_1):tp_gtl2014_6_a0"
				( attribute "CDS_PHYS_NET_NAME" "TP_GTL2014_6_A0"
					( Origin gPackager )
				)
				( objectStatus "TP_GTL2014_6_A0" )
			)
			( signal "@baseboard_fab2_lib.baseboard_fab2(sch_1):tp_gtl2014_6_a2"
				( attribute "CDS_PHYS_NET_NAME" "TP_GTL2014_6_A2"
					( Origin gPackager )
				)
				( objectStatus "TP_GTL2014_6_A2" )
			)
			( signal "@baseboard_fab2_lib.baseboard_fab2(sch_1):bmc_jtag_sel_n"
				( attribute "CDS_PHYS_NET_NAME" "BMC_JTAG_SEL_N"
					( Origin gPackager )
				)
				( objectStatus "BMC_JTAG_SEL_N" )
			)
			( signal "@baseboard_fab2_lib.baseboard_fab2(sch_1):pca9554_int_n"
				( attribute "CDS_PHYS_NET_NAME" "PCA9554_INT_N"
					( Origin gPackager )
				)
				( objectStatus "PCA9554_INT_N" )
			)
			( signal "@baseboard_fab2_lib.baseboard_fab2(sch_1):bmc_jtag_sel_n_mux"
				( attribute "CDS_PHYS_NET_NAME" "BMC_JTAG_SEL_N_MUX"
					( Origin gPackager )
				)
				( objectStatus "BMC_JTAG_SEL_N_MUX" )
			)
			( signal "@baseboard_fab2_lib.baseboard_fab2(sch_1):jtag_pld_tck_mux"
				( attribute "CDS_PHYS_NET_NAME" "JTAG_PLD_TCK_MUX"
					( Origin gPackager )
				)
				( objectStatus "JTAG_PLD_TCK_MUX" )
			)
			( signal "@baseboard_fab2_lib.baseboard_fab2(sch_1):jtag_pld_tdi_mux"
				( attribute "CDS_PHYS_NET_NAME" "JTAG_PLD_TDI_MUX"
					( Origin gPackager )
				)
				( objectStatus "JTAG_PLD_TDI_MUX" )
			)
			( signal "@baseboard_fab2_lib.baseboard_fab2(sch_1):jtag_pld_tdo_mux"
				( attribute "CDS_PHYS_NET_NAME" "JTAG_PLD_TDO_MUX"
					( Origin gPackager )
				)
				( objectStatus "JTAG_PLD_TDO_MUX" )
			)
			( signal "@baseboard_fab2_lib.baseboard_fab2(sch_1):jtag_pld_tms_mux"
				( attribute "CDS_PHYS_NET_NAME" "JTAG_PLD_TMS_MUX"
					( Origin gPackager )
				)
				( objectStatus "JTAG_PLD_TMS_MUX" )
			)
			( signal "@baseboard_fab2_lib.baseboard_fab2(sch_1):rst_bmc_pltrst_buf_n"
				( attribute "CDS_PHYS_NET_NAME" "RST_BMC_PLTRST_BUF_N"
					( Origin gPackager )
				)
				( objectStatus "RST_BMC_PLTRST_BUF_N" )
			)
			( signal "@baseboard_fab2_lib.baseboard_fab2(sch_1):jtag_bmc_buf_tdi"
				( attribute "CDS_PHYS_NET_NAME" "JTAG_BMC_BUF_TDI"
					( Origin gPackager )
				)
				( objectStatus "JTAG_BMC_BUF_TDI" )
			)
			( signal "@baseboard_fab2_lib.baseboard_fab2(sch_1):jtag_bmc_buf_tdo"
				( attribute "CDS_PHYS_NET_NAME" "JTAG_BMC_BUF_TDO"
					( Origin gPackager )
				)
				( objectStatus "JTAG_BMC_BUF_TDO" )
			)
			( signal "@baseboard_fab2_lib.baseboard_fab2(sch_1):jtag_bmc_buf_tms"
				( attribute "CDS_PHYS_NET_NAME" "JTAG_BMC_BUF_TMS"
					( Origin gPackager )
				)
				( objectStatus "JTAG_BMC_BUF_TMS" )
			)
			( signal "@baseboard_fab2_lib.baseboard_fab2(sch_1):bmc_jtag_sel"
				( attribute "CDS_PHYS_NET_NAME" "BMC_JTAG_SEL"
					( Origin gPackager )
				)
				( objectStatus "BMC_JTAG_SEL" )
			)
			( signal "@baseboard_fab2_lib.baseboard_fab2(sch_1):jtag_bmc_trst_buf_n"
				( attribute "CDS_PHYS_NET_NAME" "JTAG_BMC_TRST_BUF_N"
					( Origin gPackager )
				)
				( objectStatus "JTAG_BMC_TRST_BUF_N" )
			)
			( signal "@baseboard_fab2_lib.baseboard_fab2(sch_1):bmc_jtag_sel_buf"
				( attribute "CDS_PHYS_NET_NAME" "BMC_JTAG_SEL_BUF"
					( Origin gPackager )
				)
				( objectStatus "BMC_JTAG_SEL_BUF" )
			)
			( signal "@baseboard_fab2_lib.baseboard_fab2(sch_1):bmc_preq_buf_n"
				( attribute "CDS_PHYS_NET_NAME" "BMC_PREQ_BUF_N"
					( Origin gPackager )
				)
				( objectStatus "BMC_PREQ_BUF_N" )
			)
			( signal "@baseboard_fab2_lib.baseboard_fab2(sch_1):bmc_pwr_debug_buf_n"
				( attribute "CDS_PHYS_NET_NAME" "BMC_PWR_DEBUG_BUF_N"
					( Origin gPackager )
				)
				( objectStatus "BMC_PWR_DEBUG_BUF_N" )
			)
			( signal "@baseboard_fab2_lib.baseboard_fab2(sch_1):spa_5v_sin_sw_d"
				( attribute "CDS_PHYS_NET_NAME" "SPA_5V_SIN_SW_D"
					( Origin gPackager )
				)
				( objectStatus "SPA_5V_SIN_SW_D" )
			)
			( signal "@baseboard_fab2_lib.baseboard_fab2(sch_1):pu_dev_off_n"
				( attribute "CDS_PHYS_NET_NAME" "PU_DEV_OFF_N"
					( Origin gPackager )
				)
				( objectStatus "PU_DEV_OFF_N" )
			)
			( signal "@baseboard_fab2_lib.baseboard_fab2(sch_1):tp_pch_gdp8_susclk"
				( attribute "CDS_PHYS_NET_NAME" "TP_PCH_GDP8_SUSCLK"
					( Origin gPackager )
				)
				( objectStatus "TP_PCH_GDP8_SUSCLK" )
			)
			( signal "@baseboard_fab2_lib.baseboard_fab2(sch_1):l1_85ohm_6inch_dn"
				( attribute "CDS_PHYS_NET_NAME" "L1_85OHM_6INCH_DN"
					( Origin gPackager )
				)
				( objectStatus "L1_85OHM_6INCH_DN" )
			)
			( signal "@baseboard_fab2_lib.baseboard_fab2(sch_1):l1_85ohm_6inch_dp"
				( attribute "CDS_PHYS_NET_NAME" "L1_85OHM_6INCH_DP"
					( Origin gPackager )
				)
				( objectStatus "L1_85OHM_6INCH_DP" )
			)
			( signal "@baseboard_fab2_lib.baseboard_fab2(sch_1):l1_85ohm_5inch_dn"
				( attribute "CDS_PHYS_NET_NAME" "L1_85OHM_5INCH_DN"
					( Origin gPackager )
				)
				( objectStatus "L1_85OHM_5INCH_DN" )
			)
			( signal "@baseboard_fab2_lib.baseboard_fab2(sch_1):l1_85ohm_5inch_dp"
				( attribute "CDS_PHYS_NET_NAME" "L1_85OHM_5INCH_DP"
					( Origin gPackager )
				)
				( objectStatus "L1_85OHM_5INCH_DP" )
			)
			( signal "@baseboard_fab2_lib.baseboard_fab2(sch_1):l3_85ohm_5inch_dn"
				( attribute "CDS_PHYS_NET_NAME" "L3_85OHM_5INCH_DN"
					( Origin gPackager )
				)
				( objectStatus "L3_85OHM_5INCH_DN" )
			)
			( signal "@baseboard_fab2_lib.baseboard_fab2(sch_1):l3_85ohm_5inch_dp"
				( attribute "CDS_PHYS_NET_NAME" "L3_85OHM_5INCH_DP"
					( Origin gPackager )
				)
				( objectStatus "L3_85OHM_5INCH_DP" )
			)
			( signal "@baseboard_fab2_lib.baseboard_fab2(sch_1):l5_85ohm_5inch_dn"
				( attribute "CDS_PHYS_NET_NAME" "L5_85OHM_5INCH_DN"
					( Origin gPackager )
				)
				( objectStatus "L5_85OHM_5INCH_DN" )
			)
			( signal "@baseboard_fab2_lib.baseboard_fab2(sch_1):l5_85ohm_5inch_dp"
				( attribute "CDS_PHYS_NET_NAME" "L5_85OHM_5INCH_DP"
					( Origin gPackager )
				)
				( objectStatus "L5_85OHM_5INCH_DP" )
			)
			( signal "@baseboard_fab2_lib.baseboard_fab2(sch_1):l10_85ohm_5inch_dn"
				( attribute "CDS_PHYS_NET_NAME" "L10_85OHM_5INCH_DN"
					( Origin gPackager )
				)
				( objectStatus "L10_85OHM_5INCH_DN" )
			)
			( signal "@baseboard_fab2_lib.baseboard_fab2(sch_1):l10_85ohm_5inch_dp"
				( attribute "CDS_PHYS_NET_NAME" "L10_85OHM_5INCH_DP"
					( Origin gPackager )
				)
				( objectStatus "L10_85OHM_5INCH_DP" )
			)
			( signal "@baseboard_fab2_lib.baseboard_fab2(sch_1):l12_85ohm_5inch_dn"
				( attribute "CDS_PHYS_NET_NAME" "L12_85OHM_5INCH_DN"
					( Origin gPackager )
				)
				( objectStatus "L12_85OHM_5INCH_DN" )
			)
			( signal "@baseboard_fab2_lib.baseboard_fab2(sch_1):l12_85ohm_5inch_dp"
				( attribute "CDS_PHYS_NET_NAME" "L12_85OHM_5INCH_DP"
					( Origin gPackager )
				)
				( objectStatus "L12_85OHM_5INCH_DP" )
			)
			( signal "@baseboard_fab2_lib.baseboard_fab2(sch_1):l14_85ohm_5inch_dn"
				( attribute "CDS_PHYS_NET_NAME" "L14_85OHM_5INCH_DN"
					( Origin gPackager )
				)
				( objectStatus "L14_85OHM_5INCH_DN" )
			)
			( signal "@baseboard_fab2_lib.baseboard_fab2(sch_1):l14_85ohm_5inch_dp"
				( attribute "CDS_PHYS_NET_NAME" "L14_85OHM_5INCH_DP"
					( Origin gPackager )
				)
				( objectStatus "L14_85OHM_5INCH_DP" )
			)
			( signal "@baseboard_fab2_lib.baseboard_fab2(sch_1):l10_85ohm_10inch_dn"
				( attribute "CDS_PHYS_NET_NAME" "L10_85OHM_10INCH_DN"
					( Origin gPackager )
				)
				( objectStatus "L10_85OHM_10INCH_DN" )
			)
			( signal "@baseboard_fab2_lib.baseboard_fab2(sch_1):l10_85ohm_10inch_dp"
				( attribute "CDS_PHYS_NET_NAME" "L10_85OHM_10INCH_DP"
					( Origin gPackager )
				)
				( objectStatus "L10_85OHM_10INCH_DP" )
			)
			( signal "@baseboard_fab2_lib.baseboard_fab2(sch_1):l12_85ohm_10inch_dn"
				( attribute "CDS_PHYS_NET_NAME" "L12_85OHM_10INCH_DN"
					( Origin gPackager )
				)
				( objectStatus "L12_85OHM_10INCH_DN" )
			)
			( signal "@baseboard_fab2_lib.baseboard_fab2(sch_1):l12_85ohm_10inch_dp"
				( attribute "CDS_PHYS_NET_NAME" "L12_85OHM_10INCH_DP"
					( Origin gPackager )
				)
				( objectStatus "L12_85OHM_10INCH_DP" )
			)
			( signal "@baseboard_fab2_lib.baseboard_fab2(sch_1):l14_85ohm_10inch_dn"
				( attribute "CDS_PHYS_NET_NAME" "L14_85OHM_10INCH_DN"
					( Origin gPackager )
				)
				( objectStatus "L14_85OHM_10INCH_DN" )
			)
			( signal "@baseboard_fab2_lib.baseboard_fab2(sch_1):l14_85ohm_10inch_dp"
				( attribute "CDS_PHYS_NET_NAME" "L14_85OHM_10INCH_DP"
					( Origin gPackager )
				)
				( objectStatus "L14_85OHM_10INCH_DP" )
			)
			( signal "@baseboard_fab2_lib.baseboard_fab2(sch_1):l1_85ohm_10inch_dn"
				( attribute "CDS_PHYS_NET_NAME" "L1_85OHM_10INCH_DN"
					( Origin gPackager )
				)
				( objectStatus "L1_85OHM_10INCH_DN" )
			)
			( signal "@baseboard_fab2_lib.baseboard_fab2(sch_1):l1_85ohm_10inch_dp"
				( attribute "CDS_PHYS_NET_NAME" "L1_85OHM_10INCH_DP"
					( Origin gPackager )
				)
				( objectStatus "L1_85OHM_10INCH_DP" )
			)
			( signal "@baseboard_fab2_lib.baseboard_fab2(sch_1):l3_85ohm_10inch_dn"
				( attribute "CDS_PHYS_NET_NAME" "L3_85OHM_10INCH_DN"
					( Origin gPackager )
				)
				( objectStatus "L3_85OHM_10INCH_DN" )
			)
			( signal "@baseboard_fab2_lib.baseboard_fab2(sch_1):l3_85ohm_10inch_dp"
				( attribute "CDS_PHYS_NET_NAME" "L3_85OHM_10INCH_DP"
					( Origin gPackager )
				)
				( objectStatus "L3_85OHM_10INCH_DP" )
			)
			( signal "@baseboard_fab2_lib.baseboard_fab2(sch_1):l5_85ohm_10inch_dn"
				( attribute "CDS_PHYS_NET_NAME" "L5_85OHM_10INCH_DN"
					( Origin gPackager )
				)
				( objectStatus "L5_85OHM_10INCH_DN" )
			)
			( signal "@baseboard_fab2_lib.baseboard_fab2(sch_1):l5_85ohm_10inch_dp"
				( attribute "CDS_PHYS_NET_NAME" "L5_85OHM_10INCH_DP"
					( Origin gPackager )
				)
				( objectStatus "L5_85OHM_10INCH_DP" )
			)
			( signal "@baseboard_fab2_lib.baseboard_fab2(sch_1):l10_73ohm_6inch_dn"
				( attribute "CDS_PHYS_NET_NAME" "L10_73OHM_6INCH_DN"
					( Origin gPackager )
				)
				( objectStatus "L10_73OHM_6INCH_DN" )
			)
			( signal "@baseboard_fab2_lib.baseboard_fab2(sch_1):l10_73ohm_6inch_dp"
				( attribute "CDS_PHYS_NET_NAME" "L10_73OHM_6INCH_DP"
					( Origin gPackager )
				)
				( objectStatus "L10_73OHM_6INCH_DP" )
			)
			( signal "@baseboard_fab2_lib.baseboard_fab2(sch_1):l10_85ohm_6inch_dn"
				( attribute "CDS_PHYS_NET_NAME" "L10_85OHM_6INCH_DN"
					( Origin gPackager )
				)
				( objectStatus "L10_85OHM_6INCH_DN" )
			)
			( signal "@baseboard_fab2_lib.baseboard_fab2(sch_1):l10_85ohm_6inch_dp"
				( attribute "CDS_PHYS_NET_NAME" "L10_85OHM_6INCH_DP"
					( Origin gPackager )
				)
				( objectStatus "L10_85OHM_6INCH_DP" )
			)
			( signal "@baseboard_fab2_lib.baseboard_fab2(sch_1):l12_73ohm_6inch_dn"
				( attribute "CDS_PHYS_NET_NAME" "L12_73OHM_6INCH_DN"
					( Origin gPackager )
				)
				( objectStatus "L12_73OHM_6INCH_DN" )
			)
			( signal "@baseboard_fab2_lib.baseboard_fab2(sch_1):l12_73ohm_6inch_dp"
				( attribute "CDS_PHYS_NET_NAME" "L12_73OHM_6INCH_DP"
					( Origin gPackager )
				)
				( objectStatus "L12_73OHM_6INCH_DP" )
			)
			( signal "@baseboard_fab2_lib.baseboard_fab2(sch_1):l12_85ohm_6inch_dn"
				( attribute "CDS_PHYS_NET_NAME" "L12_85OHM_6INCH_DN"
					( Origin gPackager )
				)
				( objectStatus "L12_85OHM_6INCH_DN" )
			)
			( signal "@baseboard_fab2_lib.baseboard_fab2(sch_1):l12_85ohm_6inch_dp"
				( attribute "CDS_PHYS_NET_NAME" "L12_85OHM_6INCH_DP"
					( Origin gPackager )
				)
				( objectStatus "L12_85OHM_6INCH_DP" )
			)
			( signal "@baseboard_fab2_lib.baseboard_fab2(sch_1):l14_73ohm_6inch_dn"
				( attribute "CDS_PHYS_NET_NAME" "L14_73OHM_6INCH_DN"
					( Origin gPackager )
				)
				( objectStatus "L14_73OHM_6INCH_DN" )
			)
			( signal "@baseboard_fab2_lib.baseboard_fab2(sch_1):l14_73ohm_6inch_dp"
				( attribute "CDS_PHYS_NET_NAME" "L14_73OHM_6INCH_DP"
					( Origin gPackager )
				)
				( objectStatus "L14_73OHM_6INCH_DP" )
			)
			( signal "@baseboard_fab2_lib.baseboard_fab2(sch_1):l14_85ohm_6inch_dn"
				( attribute "CDS_PHYS_NET_NAME" "L14_85OHM_6INCH_DN"
					( Origin gPackager )
				)
				( objectStatus "L14_85OHM_6INCH_DN" )
			)
			( signal "@baseboard_fab2_lib.baseboard_fab2(sch_1):l14_85ohm_6inch_dp"
				( attribute "CDS_PHYS_NET_NAME" "L14_85OHM_6INCH_DP"
					( Origin gPackager )
				)
				( objectStatus "L14_85OHM_6INCH_DP" )
			)
			( signal "@baseboard_fab2_lib.baseboard_fab2(sch_1):l1_73ohm_6inch_dn"
				( attribute "CDS_PHYS_NET_NAME" "L1_73OHM_6INCH_DN"
					( Origin gPackager )
				)
				( objectStatus "L1_73OHM_6INCH_DN" )
			)
			( signal "@baseboard_fab2_lib.baseboard_fab2(sch_1):l1_73ohm_6inch_dp"
				( attribute "CDS_PHYS_NET_NAME" "L1_73OHM_6INCH_DP"
					( Origin gPackager )
				)
				( objectStatus "L1_73OHM_6INCH_DP" )
			)
			( signal "@baseboard_fab2_lib.baseboard_fab2(sch_1):l3_73ohm_6inch_dn"
				( attribute "CDS_PHYS_NET_NAME" "L3_73OHM_6INCH_DN"
					( Origin gPackager )
				)
				( objectStatus "L3_73OHM_6INCH_DN" )
			)
			( signal "@baseboard_fab2_lib.baseboard_fab2(sch_1):l3_73ohm_6inch_dp"
				( attribute "CDS_PHYS_NET_NAME" "L3_73OHM_6INCH_DP"
					( Origin gPackager )
				)
				( objectStatus "L3_73OHM_6INCH_DP" )
			)
			( signal "@baseboard_fab2_lib.baseboard_fab2(sch_1):l3_85ohm_6inch_dn"
				( attribute "CDS_PHYS_NET_NAME" "L3_85OHM_6INCH_DN"
					( Origin gPackager )
				)
				( objectStatus "L3_85OHM_6INCH_DN" )
			)
			( signal "@baseboard_fab2_lib.baseboard_fab2(sch_1):l3_85ohm_6inch_dp"
				( attribute "CDS_PHYS_NET_NAME" "L3_85OHM_6INCH_DP"
					( Origin gPackager )
				)
				( objectStatus "L3_85OHM_6INCH_DP" )
			)
			( signal "@baseboard_fab2_lib.baseboard_fab2(sch_1):l5_73ohm_6inch_dn"
				( attribute "CDS_PHYS_NET_NAME" "L5_73OHM_6INCH_DN"
					( Origin gPackager )
				)
				( objectStatus "L5_73OHM_6INCH_DN" )
			)
			( signal "@baseboard_fab2_lib.baseboard_fab2(sch_1):l5_73ohm_6inch_dp"
				( attribute "CDS_PHYS_NET_NAME" "L5_73OHM_6INCH_DP"
					( Origin gPackager )
				)
				( objectStatus "L5_73OHM_6INCH_DP" )
			)
			( signal "@baseboard_fab2_lib.baseboard_fab2(sch_1):l5_85ohm_6inch_dn"
				( attribute "CDS_PHYS_NET_NAME" "L5_85OHM_6INCH_DN"
					( Origin gPackager )
				)
				( objectStatus "L5_85OHM_6INCH_DN" )
			)
			( signal "@baseboard_fab2_lib.baseboard_fab2(sch_1):l5_85ohm_6inch_dp"
				( attribute "CDS_PHYS_NET_NAME" "L5_85OHM_6INCH_DP"
					( Origin gPackager )
				)
				( objectStatus "L5_85OHM_6INCH_DP" )
			)
			( signal "@baseboard_fab2_lib.baseboard_fab2(sch_1):l12_95ohm_6inch_dp"
				( attribute "CDS_PHYS_NET_NAME" "L12_95OHM_6INCH_DP"
					( Origin gPackager )
				)
				( objectStatus "L12_95OHM_6INCH_DP" )
			)
			( signal "@baseboard_fab2_lib.baseboard_fab2(sch_1):l10_100ohm_6inch_dn"
				( attribute "CDS_PHYS_NET_NAME" "L10_100OHM_6INCH_DN"
					( Origin gPackager )
				)
				( objectStatus "L10_100OHM_6INCH_DN" )
			)
			( signal "@baseboard_fab2_lib.baseboard_fab2(sch_1):l10_100ohm_6inch_dp"
				( attribute "CDS_PHYS_NET_NAME" "L10_100OHM_6INCH_DP"
					( Origin gPackager )
				)
				( objectStatus "L10_100OHM_6INCH_DP" )
			)
			( signal "@baseboard_fab2_lib.baseboard_fab2(sch_1):l12_100ohm_6inch_dn"
				( attribute "CDS_PHYS_NET_NAME" "L12_100OHM_6INCH_DN"
					( Origin gPackager )
				)
				( objectStatus "L12_100OHM_6INCH_DN" )
			)
			( signal "@baseboard_fab2_lib.baseboard_fab2(sch_1):l12_100ohm_6inch_dp"
				( attribute "CDS_PHYS_NET_NAME" "L12_100OHM_6INCH_DP"
					( Origin gPackager )
				)
				( objectStatus "L12_100OHM_6INCH_DP" )
			)
			( signal "@baseboard_fab2_lib.baseboard_fab2(sch_1):l14_100ohm_6inch_dn"
				( attribute "CDS_PHYS_NET_NAME" "L14_100OHM_6INCH_DN"
					( Origin gPackager )
				)
				( objectStatus "L14_100OHM_6INCH_DN" )
			)
			( signal "@baseboard_fab2_lib.baseboard_fab2(sch_1):l14_100ohm_6inch_dp"
				( attribute "CDS_PHYS_NET_NAME" "L14_100OHM_6INCH_DP"
					( Origin gPackager )
				)
				( objectStatus "L14_100OHM_6INCH_DP" )
			)
			( signal "@baseboard_fab2_lib.baseboard_fab2(sch_1):l1_100ohm_6inch_dn"
				( attribute "CDS_PHYS_NET_NAME" "L1_100OHM_6INCH_DN"
					( Origin gPackager )
				)
				( objectStatus "L1_100OHM_6INCH_DN" )
			)
			( signal "@baseboard_fab2_lib.baseboard_fab2(sch_1):l1_100ohm_6inch_dp"
				( attribute "CDS_PHYS_NET_NAME" "L1_100OHM_6INCH_DP"
					( Origin gPackager )
				)
				( objectStatus "L1_100OHM_6INCH_DP" )
			)
			( signal "@baseboard_fab2_lib.baseboard_fab2(sch_1):l10_40ohm_6inch"
				( attribute "CDS_PHYS_NET_NAME" "L10_40OHM_6INCH"
					( Origin gPackager )
				)
				( objectStatus "L10_40OHM_6INCH" )
			)
			( signal "@baseboard_fab2_lib.baseboard_fab2(sch_1):l10_50ohm_6inch"
				( attribute "CDS_PHYS_NET_NAME" "L10_50OHM_6INCH"
					( Origin gPackager )
				)
				( objectStatus "L10_50OHM_6INCH" )
			)
			( signal "@baseboard_fab2_lib.baseboard_fab2(sch_1):l12_40ohm_6inch"
				( attribute "CDS_PHYS_NET_NAME" "L12_40OHM_6INCH"
					( Origin gPackager )
				)
				( objectStatus "L12_40OHM_6INCH" )
			)
			( signal "@baseboard_fab2_lib.baseboard_fab2(sch_1):l12_50ohm_6inch"
				( attribute "CDS_PHYS_NET_NAME" "L12_50OHM_6INCH"
					( Origin gPackager )
				)
				( objectStatus "L12_50OHM_6INCH" )
			)
			( signal "@baseboard_fab2_lib.baseboard_fab2(sch_1):l14_40ohm_6inch"
				( attribute "CDS_PHYS_NET_NAME" "L14_40OHM_6INCH"
					( Origin gPackager )
				)
				( objectStatus "L14_40OHM_6INCH" )
			)
			( signal "@baseboard_fab2_lib.baseboard_fab2(sch_1):l14_50ohm_6inch"
				( attribute "CDS_PHYS_NET_NAME" "L14_50OHM_6INCH"
					( Origin gPackager )
				)
				( objectStatus "L14_50OHM_6INCH" )
			)
			( signal "@baseboard_fab2_lib.baseboard_fab2(sch_1):l1_40ohm_6inch"
				( attribute "CDS_PHYS_NET_NAME" "L1_40OHM_6INCH"
					( Origin gPackager )
				)
				( objectStatus "L1_40OHM_6INCH" )
			)
			( signal "@baseboard_fab2_lib.baseboard_fab2(sch_1):l1_50ohm_6inch"
				( attribute "CDS_PHYS_NET_NAME" "L1_50OHM_6INCH"
					( Origin gPackager )
				)
				( objectStatus "L1_50OHM_6INCH" )
			)
			( signal "@baseboard_fab2_lib.baseboard_fab2(sch_1):l3_40ohm_6inch"
				( attribute "CDS_PHYS_NET_NAME" "L3_40OHM_6INCH"
					( Origin gPackager )
				)
				( objectStatus "L3_40OHM_6INCH" )
			)
			( signal "@baseboard_fab2_lib.baseboard_fab2(sch_1):l3_50ohm_6inch"
				( attribute "CDS_PHYS_NET_NAME" "L3_50OHM_6INCH"
					( Origin gPackager )
				)
				( objectStatus "L3_50OHM_6INCH" )
			)
			( signal "@baseboard_fab2_lib.baseboard_fab2(sch_1):l5_40ohm_6inch"
				( attribute "CDS_PHYS_NET_NAME" "L5_40OHM_6INCH"
					( Origin gPackager )
				)
				( objectStatus "L5_40OHM_6INCH" )
			)
			( signal "@baseboard_fab2_lib.baseboard_fab2(sch_1):l5_50ohm_6inch"
				( attribute "CDS_PHYS_NET_NAME" "L5_50OHM_6INCH"
					( Origin gPackager )
				)
				( objectStatus "L5_50OHM_6INCH" )
			)
			( signal "@baseboard_fab2_lib.baseboard_fab2(sch_1):l12_95ohm_6inch_dn"
				( attribute "CDS_PHYS_NET_NAME" "L12_95OHM_6INCH_DN"
					( Origin gPackager )
				)
				( objectStatus "L12_95OHM_6INCH_DN" )
			)
			( signal "@baseboard_fab2_lib.baseboard_fab2(sch_1):l1_95ohm_6inch_dn"
				( attribute "CDS_PHYS_NET_NAME" "L1_95OHM_6INCH_DN"
					( Origin gPackager )
				)
				( objectStatus "L1_95OHM_6INCH_DN" )
			)
			( signal "@baseboard_fab2_lib.baseboard_fab2(sch_1):fm_battery_sense_en_r_n"
				( attribute "CDS_PHYS_NET_NAME" "FM_BATTERY_SENSE_EN_R_N"
					( Origin gPackager )
				)
				( objectStatus "FM_BATTERY_SENSE_EN_R_N" )
			)
			( signal "@baseboard_fab2_lib.baseboard_fab2(sch_1):l1_95ohm_6inch_dp"
				( attribute "CDS_PHYS_NET_NAME" "L1_95OHM_6INCH_DP"
					( Origin gPackager )
				)
				( objectStatus "L1_95OHM_6INCH_DP" )
			)
			( signal "@baseboard_fab2_lib.baseboard_fab2(sch_1):fm_cpu0_rc_error_r_n"
				( attribute "CDS_PHYS_NET_NAME" "FM_CPU0_RC_ERROR_R_N"
					( Origin gPackager )
				)
				( objectStatus "FM_CPU0_RC_ERROR_R_N" )
			)
			( signal "@baseboard_fab2_lib.baseboard_fab2(sch_1):fm_post_card_pres_bmc_r1_n"
				( attribute "CDS_PHYS_NET_NAME" "FM_POST_CARD_PRES_BMC_R1_N"
					( Origin gPackager )
				)
				( objectStatus "FM_POST_CARD_PRES_BMC_R1_N" )
			)
			( signal "@baseboard_fab2_lib.baseboard_fab2(sch_1):fm_cpu0_rc_error_r1_n"
				( attribute "CDS_PHYS_NET_NAME" "FM_CPU0_RC_ERROR_R1_N"
					( Origin gPackager )
				)
				( objectStatus "FM_CPU0_RC_ERROR_R1_N" )
			)
			( signal "@baseboard_fab2_lib.baseboard_fab2(sch_1):fm_cpu1_rc_error_r1_n"
				( attribute "CDS_PHYS_NET_NAME" "FM_CPU1_RC_ERROR_R1_N"
					( Origin gPackager )
				)
				( objectStatus "FM_CPU1_RC_ERROR_R1_N" )
			)
			( signal "@baseboard_fab2_lib.baseboard_fab2(sch_1):fm_cpu1_rc_error_r_n"
				( attribute "CDS_PHYS_NET_NAME" "FM_CPU1_RC_ERROR_R_N"
					( Origin gPackager )
				)
				( objectStatus "FM_CPU1_RC_ERROR_R_N" )
			)
			( signal "@baseboard_fab2_lib.baseboard_fab2(sch_1):jtag_bmc_buf_tdo_r"
				( attribute "CDS_PHYS_NET_NAME" "JTAG_BMC_BUF_TDO_R"
					( Origin gPackager )
				)
				( objectStatus "JTAG_BMC_BUF_TDO_R" )
			)
			( signal "@baseboard_fab2_lib.baseboard_fab2(sch_1):ext_mdio_i2c_sel"
				( attribute "CDS_PHYS_NET_NAME" "EXT_MDIO_I2C_SEL"
					( Origin gPackager )
				)
				( objectStatus "EXT_MDIO_I2C_SEL" )
			)
			( signal "@baseboard_fab2_lib.baseboard_fab2(sch_1):fm_bmc_ready_r_n"
				( attribute "CDS_PHYS_NET_NAME" "FM_BMC_READY_R_N"
					( Origin gPackager )
				)
				( objectStatus "FM_BMC_READY_R_N" )
			)
			( signal "@baseboard_fab2_lib.baseboard_fab2(sch_1):fm_bmc_ready_r1_n"
				( attribute "CDS_PHYS_NET_NAME" "FM_BMC_READY_R1_N"
					( Origin gPackager )
				)
				( objectStatus "FM_BMC_READY_R1_N" )
			)
			( signal "@baseboard_fab2_lib.baseboard_fab2(sch_1):fm_ocp_mezza_pres_r"
				( attribute "CDS_PHYS_NET_NAME" "FM_OCP_MEZZA_PRES_R"
					( Origin gPackager )
				)
				( objectStatus "FM_OCP_MEZZA_PRES_R" )
			)
			( signal "@baseboard_fab2_lib.baseboard_fab2(sch_1):fm_throttle_r2_n"
				( attribute "CDS_PHYS_NET_NAME" "FM_THROTTLE_R2_N"
					( Origin gPackager )
				)
				( objectStatus "FM_THROTTLE_R2_N" )
			)
			( signal "@baseboard_fab2_lib.baseboard_fab2(sch_1):irq_dimm_save_lvt3_r_n"
				( attribute "CDS_PHYS_NET_NAME" "IRQ_DIMM_SAVE_LVT3_R_N"
					( Origin gPackager )
				)
				( objectStatus "IRQ_DIMM_SAVE_LVT3_R_N" )
			)
			( signal "@baseboard_fab2_lib.baseboard_fab2(sch_1):irq_sml1_pmbus_alert_r1_n"
				( attribute "CDS_PHYS_NET_NAME" "IRQ_SML1_PMBUS_ALERT_R1_N"
					( Origin gPackager )
				)
				( objectStatus "IRQ_SML1_PMBUS_ALERT_R1_N" )
			)
			( signal "@baseboard_fab2_lib.baseboard_fab2(sch_1):jtag_bmc_tck_buf"
				( attribute "CDS_PHYS_NET_NAME" "JTAG_BMC_TCK_BUF"
					( Origin gPackager )
				)
				( objectStatus "JTAG_BMC_TCK_BUF" )
			)
			( signal "@baseboard_fab2_lib.baseboard_fab2(sch_1):jtag_riser_trst"
				( attribute "CDS_PHYS_NET_NAME" "JTAG_RISER_TRST"
					( Origin gPackager )
				)
				( objectStatus "JTAG_RISER_TRST" )
			)
			( signal "@baseboard_fab2_lib.baseboard_fab2(sch_1):jtag_riser_tdi_r"
				( attribute "CDS_PHYS_NET_NAME" "JTAG_RISER_TDI_R"
					( Origin gPackager )
				)
				( objectStatus "JTAG_RISER_TDI_R" )
			)
			( signal "@baseboard_fab2_lib.baseboard_fab2(sch_1):jtag_riser_tdo_r"
				( attribute "CDS_PHYS_NET_NAME" "JTAG_RISER_TDO_R"
					( Origin gPackager )
				)
				( objectStatus "JTAG_RISER_TDO_R" )
			)
			( signal "@baseboard_fab2_lib.baseboard_fab2(sch_1):jtag_pld_tdo_mux_r"
				( attribute "CDS_PHYS_NET_NAME" "JTAG_PLD_TDO_MUX_R"
					( Origin gPackager )
				)
				( objectStatus "JTAG_PLD_TDO_MUX_R" )
			)
			( signal "@baseboard_fab2_lib.baseboard_fab2(sch_1):jtag_riser_n"
				( attribute "CDS_PHYS_NET_NAME" "JTAG_RISER_N"
					( Origin gPackager )
				)
				( objectStatus "JTAG_RISER_N" )
			)
			( gate "@baseboard_fab2_lib.baseboard_fab2(sch_1):page21_i149"
				( attribute "BOM_COST" "PROC_SIDEBAND"
					( Origin gFrontEnd )
				)
				( attribute "CDS_LIB" "mstr_discrete"
					( Origin gPackager )
				)
				( attribute "CDS_LOCATION" "R6N10"
					( Origin gPackager )
				)
				( attribute "LOCATION" "R6N10"
					( Origin gFrontEnd )
				)
				( attribute "MATERIAL" "CHIP"
					( Origin gFrontEnd )
				)
				( attribute "PACK_TYPE" "0402"
					( Origin gFrontEnd )
				)
				( attribute "PART_NUMBER" "G21796-271"
					( Origin gFrontEnd )
				)
				( attribute "PHYS_PAGE" "21"
					( Origin gFrontEnd )
				)
				( attribute "ROOM" "CPU0"
					( Origin gFrontEnd )
				)
				( attribute "ROT" "0"
					( Origin gFrontEnd )
				)
				( attribute "SEC" "1"
					( Origin gFrontEnd )
				)
				( attribute "SEC_TYPE" "0402"
					( Origin gFrontEnd )
				)
				( attribute "TOLERANCE" "1.0%"
					( Origin gFrontEnd )
				)
				( attribute "VALUE" "221"
					( Origin gFrontEnd )
				)
				( attribute "VER" "1"
					( Origin gFrontEnd )
				)
				( attribute "WATTAGE" "1/16W"
					( Origin gFrontEnd )
				)
				( attribute "XY" "(-2000,3750)"
					( Origin gFrontEnd )
				)
				( attribute "CHIPS_PART_NAME" "RES"
					( Origin gPackager )
				)
				( attribute "CDS_PART_NAME" "RES_0402-221,1.0%,1/16W,CHIP,GA"
					( Origin gPackager )
				)
				( attribute "CDS_SEC" "1"
					( Origin gPackager )
				)
				( objectStatus "R6N10" )
			)
			( gate "@baseboard_fab2_lib.baseboard_fab2(sch_1):page21_i150"
				( attribute "BOM_COST" "PROC_SIDEBAND"
					( Origin gFrontEnd )
				)
				( attribute "CDS_LIB" "mstr_discrete"
					( Origin gPackager )
				)
				( attribute "CDS_LOCATION" "R6N12"
					( Origin gPackager )
				)
				( attribute "LOCATION" "R6N12"
					( Origin gFrontEnd )
				)
				( attribute "MATERIAL" "CHIP"
					( Origin gFrontEnd )
				)
				( attribute "PACK_TYPE" "0402"
					( Origin gFrontEnd )
				)
				( attribute "PART_NUMBER" "G21497-005"
					( Origin gFrontEnd )
				)
				( attribute "PHYS_PAGE" "21"
					( Origin gFrontEnd )
				)
				( attribute "ROOM" "CPU0"
					( Origin gFrontEnd )
				)
				( attribute "ROT" "0"
					( Origin gFrontEnd )
				)
				( attribute "SEC" "1"
					( Origin gFrontEnd )
				)
				( attribute "SEC_TYPE" "0402"
					( Origin gFrontEnd )
				)
				( attribute "TOLERANCE" "5%"
					( Origin gFrontEnd )
				)
				( attribute "VALUE" "0.0"
					( Origin gFrontEnd )
				)
				( attribute "VER" "1"
					( Origin gFrontEnd )
				)
				( attribute "WATTAGE" "1/16W"
					( Origin gFrontEnd )
				)
				( attribute "XY" "(-2000,3800)"
					( Origin gFrontEnd )
				)
				( attribute "CHIPS_PART_NAME" "RES"
					( Origin gPackager )
				)
				( attribute "CDS_PART_NAME" "RES_0402-0.0,5%,1/16W,CHIP,G21A"
					( Origin gPackager )
				)
				( attribute "CDS_SEC" "1"
					( Origin gPackager )
				)
				( objectStatus "R6N12" )
			)
			( gate "@baseboard_fab2_lib.baseboard_fab2(sch_1):page21_i151"
				( attribute "BOM_COST" "PROC_SIDEBAND"
					( Origin gFrontEnd )
				)
				( attribute "CDS_LIB" "mstr_discrete"
					( Origin gPackager )
				)
				( attribute "CDS_LOCATION" "R6N11"
					( Origin gPackager )
				)
				( attribute "LOCATION" "R6N11"
					( Origin gFrontEnd )
				)
				( attribute "MATERIAL" "CHIP"
					( Origin gFrontEnd )
				)
				( attribute "PACK_TYPE" "0402"
					( Origin gFrontEnd )
				)
				( attribute "PART_NUMBER" "G21497-005"
					( Origin gFrontEnd )
				)
				( attribute "PHYS_PAGE" "21"
					( Origin gFrontEnd )
				)
				( attribute "ROOM" "CPU0"
					( Origin gFrontEnd )
				)
				( attribute "ROT" "0"
					( Origin gFrontEnd )
				)
				( attribute "SEC" "1"
					( Origin gFrontEnd )
				)
				( attribute "SEC_TYPE" "0402"
					( Origin gFrontEnd )
				)
				( attribute "TOLERANCE" "5%"
					( Origin gFrontEnd )
				)
				( attribute "VALUE" "0.0"
					( Origin gFrontEnd )
				)
				( attribute "VER" "1"
					( Origin gFrontEnd )
				)
				( attribute "WATTAGE" "1/16W"
					( Origin gFrontEnd )
				)
				( attribute "XY" "(-2000,3850)"
					( Origin gFrontEnd )
				)
				( attribute "CHIPS_PART_NAME" "RES"
					( Origin gPackager )
				)
				( attribute "CDS_PART_NAME" "RES_0402-0.0,5%,1/16W,CHIP,G21A"
					( Origin gPackager )
				)
				( attribute "CDS_SEC" "1"
					( Origin gPackager )
				)
				( objectStatus "R6N11" )
			)
			( gate "@baseboard_fab2_lib.baseboard_fab2(sch_1):page21_i152"
				( attribute "BOM_COST" "PROC_SIDEBAND"
					( Origin gFrontEnd )
				)
				( attribute "CDS_LIB" "mstr_discrete"
					( Origin gPackager )
				)
				( attribute "CDS_LOCATION" "R6B3"
					( Origin gPackager )
				)
				( attribute "LOCATION" "R6B3"
					( Origin gFrontEnd )
				)
				( attribute "MATERIAL" "CHIP"
					( Origin gFrontEnd )
				)
				( attribute "PACK_TYPE" "0402"
					( Origin gFrontEnd )
				)
				( attribute "PART_NUMBER" "G21796-271"
					( Origin gFrontEnd )
				)
				( attribute "PHYS_PAGE" "21"
					( Origin gFrontEnd )
				)
				( attribute "ROOM" "CPU0"
					( Origin gFrontEnd )
				)
				( attribute "ROT" "0"
					( Origin gFrontEnd )
				)
				( attribute "SEC" "1"
					( Origin gFrontEnd )
				)
				( attribute "SEC_TYPE" "0402"
					( Origin gFrontEnd )
				)
				( attribute "TOLERANCE" "1.0%"
					( Origin gFrontEnd )
				)
				( attribute "VALUE" "221"
					( Origin gFrontEnd )
				)
				( attribute "VER" "1"
					( Origin gFrontEnd )
				)
				( attribute "WATTAGE" "1/16W"
					( Origin gFrontEnd )
				)
				( attribute "XY" "(-2000,3900)"
					( Origin gFrontEnd )
				)
				( attribute "CHIPS_PART_NAME" "RES"
					( Origin gPackager )
				)
				( attribute "CDS_PART_NAME" "RES_0402-221,1.0%,1/16W,CHIP,GA"
					( Origin gPackager )
				)
				( attribute "CDS_SEC" "1"
					( Origin gPackager )
				)
				( objectStatus "R6B3" )
			)
			( gate "@baseboard_fab2_lib.baseboard_fab2(sch_1):page21_i153"
				( attribute "BOM_COST" "PROC_SIDEBAND"
					( Origin gFrontEnd )
				)
				( attribute "CDS_LIB" "mstr_discrete"
					( Origin gPackager )
				)
				( attribute "CDS_LOCATION" "R6B5"
					( Origin gPackager )
				)
				( attribute "LOCATION" "R6B5"
					( Origin gFrontEnd )
				)
				( attribute "MATERIAL" "CHIP"
					( Origin gFrontEnd )
				)
				( attribute "PACK_TYPE" "0402"
					( Origin gFrontEnd )
				)
				( attribute "PART_NUMBER" "G21497-005"
					( Origin gFrontEnd )
				)
				( attribute "PHYS_PAGE" "21"
					( Origin gFrontEnd )
				)
				( attribute "ROOM" "CPU0"
					( Origin gFrontEnd )
				)
				( attribute "ROT" "0"
					( Origin gFrontEnd )
				)
				( attribute "SEC" "1"
					( Origin gFrontEnd )
				)
				( attribute "SEC_TYPE" "0402"
					( Origin gFrontEnd )
				)
				( attribute "TOLERANCE" "5%"
					( Origin gFrontEnd )
				)
				( attribute "VALUE" "0.0"
					( Origin gFrontEnd )
				)
				( attribute "VER" "1"
					( Origin gFrontEnd )
				)
				( attribute "WATTAGE" "1/16W"
					( Origin gFrontEnd )
				)
				( attribute "XY" "(-2000,3950)"
					( Origin gFrontEnd )
				)
				( attribute "CHIPS_PART_NAME" "RES"
					( Origin gPackager )
				)
				( attribute "CDS_PART_NAME" "RES_0402-0.0,5%,1/16W,CHIP,G21A"
					( Origin gPackager )
				)
				( attribute "CDS_SEC" "1"
					( Origin gPackager )
				)
				( objectStatus "R6B5" )
			)
			( gate "@baseboard_fab2_lib.baseboard_fab2(sch_1):page21_i154"
				( attribute "BOM_COST" "PROC_SIDEBAND"
					( Origin gFrontEnd )
				)
				( attribute "CDS_LIB" "mstr_discrete"
					( Origin gPackager )
				)
				( attribute "CDS_LOCATION" "R6B4"
					( Origin gPackager )
				)
				( attribute "LOCATION" "R6B4"
					( Origin gFrontEnd )
				)
				( attribute "MATERIAL" "CHIP"
					( Origin gFrontEnd )
				)
				( attribute "PACK_TYPE" "0402"
					( Origin gFrontEnd )
				)
				( attribute "PART_NUMBER" "G21497-005"
					( Origin gFrontEnd )
				)
				( attribute "PHYS_PAGE" "21"
					( Origin gFrontEnd )
				)
				( attribute "ROOM" "CPU0"
					( Origin gFrontEnd )
				)
				( attribute "ROT" "0"
					( Origin gFrontEnd )
				)
				( attribute "SEC" "1"
					( Origin gFrontEnd )
				)
				( attribute "SEC_TYPE" "0402"
					( Origin gFrontEnd )
				)
				( attribute "TOLERANCE" "5%"
					( Origin gFrontEnd )
				)
				( attribute "VALUE" "0.0"
					( Origin gFrontEnd )
				)
				( attribute "VER" "1"
					( Origin gFrontEnd )
				)
				( attribute "WATTAGE" "1/16W"
					( Origin gFrontEnd )
				)
				( attribute "XY" "(-2000,4000)"
					( Origin gFrontEnd )
				)
				( attribute "CHIPS_PART_NAME" "RES"
					( Origin gPackager )
				)
				( attribute "CDS_PART_NAME" "RES_0402-0.0,5%,1/16W,CHIP,G21A"
					( Origin gPackager )
				)
				( attribute "CDS_SEC" "1"
					( Origin gPackager )
				)
				( objectStatus "R6B4" )
			)
			( gate "@baseboard_fab2_lib.baseboard_fab2(sch_1):page21_i159"
				( attribute "BOM_COST" "PROC_SIDEBAND"
					( Origin gFrontEnd )
				)
				( attribute "CDS_LIB" "mstr_discrete"
					( Origin gPackager )
				)
				( attribute "CDS_LOCATION" "R6B2"
					( Origin gPackager )
				)
				( attribute "LOCATION" "R6B2"
					( Origin gFrontEnd )
				)
				( attribute "MATERIAL" "CHIP"
					( Origin gFrontEnd )
				)
				( attribute "PACK_TYPE" "0402"
					( Origin gFrontEnd )
				)
				( attribute "PART_NUMBER" "G21796-017"
					( Origin gFrontEnd )
				)
				( attribute "PHYS_PAGE" "21"
					( Origin gFrontEnd )
				)
				( attribute "ROOM" "CPU0"
					( Origin gFrontEnd )
				)
				( attribute "ROT" "0"
					( Origin gFrontEnd )
				)
				( attribute "SEC" "1"
					( Origin gFrontEnd )
				)
				( attribute "SEC_TYPE" "0402"
					( Origin gFrontEnd )
				)
				( attribute "TOLERANCE" "1%"
					( Origin gFrontEnd )
				)
				( attribute "VALUE" "100.0"
					( Origin gFrontEnd )
				)
				( attribute "VER" "2"
					( Origin gFrontEnd )
				)
				( attribute "WATTAGE" "1/16W"
					( Origin gFrontEnd )
				)
				( attribute "XY" "(-1000,4300)"
					( Origin gFrontEnd )
				)
				( attribute "CHIPS_PART_NAME" "RES"
					( Origin gPackager )
				)
				( attribute "CDS_PART_NAME" "RES_0402-100.0,1%,1/16W,CHIP,GA"
					( Origin gPackager )
				)
				( attribute "CDS_SEC" "1"
					( Origin gPackager )
				)
				( objectStatus "R6B2" )
			)
			( gate "@baseboard_fab2_lib.baseboard_fab2(sch_1):page21_i161"
				( attribute "BOM_COST" "PROC_SIDEBAND"
					( Origin gFrontEnd )
				)
				( attribute "CDS_LIB" "mstr_discrete"
					( Origin gPackager )
				)
				( attribute "CDS_LOCATION" "R6B1"
					( Origin gPackager )
				)
				( attribute "LOCATION" "R6B1"
					( Origin gFrontEnd )
				)
				( attribute "MATERIAL" "CHIP"
					( Origin gFrontEnd )
				)
				( attribute "PACK_TYPE" "0402"
					( Origin gFrontEnd )
				)
				( attribute "PART_NUMBER" "G21796-047"
					( Origin gFrontEnd )
				)
				( attribute "PHYS_PAGE" "21"
					( Origin gFrontEnd )
				)
				( attribute "ROOM" "CPU0"
					( Origin gFrontEnd )
				)
				( attribute "ROT" "0"
					( Origin gFrontEnd )
				)
				( attribute "SEC" "1"
					( Origin gFrontEnd )
				)
				( attribute "SEC_TYPE" "0402"
					( Origin gFrontEnd )
				)
				( attribute "TOLERANCE" "1%"
					( Origin gFrontEnd )
				)
				( attribute "VALUE" "49.9"
					( Origin gFrontEnd )
				)
				( attribute "VER" "2"
					( Origin gFrontEnd )
				)
				( attribute "WATTAGE" "1/16W"
					( Origin gFrontEnd )
				)
				( attribute "XY" "(-750,4300)"
					( Origin gFrontEnd )
				)
				( attribute "CHIPS_PART_NAME" "RES"
					( Origin gPackager )
				)
				( attribute "CDS_PART_NAME" "RES_0402-49.9,1%,1/16W,CHIP,G2A"
					( Origin gPackager )
				)
				( attribute "CDS_SEC" "1"
					( Origin gPackager )
				)
				( objectStatus "R6B1" )
			)
			( gate "@baseboard_fab2_lib.baseboard_fab2(sch_1):page21_i163"
				( attribute "BOM_COST" "PROC_SIDEBAND"
					( Origin gFrontEnd )
				)
				( attribute "CDS_LIB" "mstr_discrete"
					( Origin gPackager )
				)
				( attribute "CDS_LOCATION" "R6N2"
					( Origin gPackager )
				)
				( attribute "LOCATION" "R6N2"
					( Origin gFrontEnd )
				)
				( attribute "MATERIAL" "CHIP"
					( Origin gFrontEnd )
				)
				( attribute "PACK_TYPE" "0402"
					( Origin gFrontEnd )
				)
				( attribute "PART_NUMBER" "G21796-017"
					( Origin gFrontEnd )
				)
				( attribute "PHYS_PAGE" "21"
					( Origin gFrontEnd )
				)
				( attribute "ROOM" "CPU0"
					( Origin gFrontEnd )
				)
				( attribute "ROT" "0"
					( Origin gFrontEnd )
				)
				( attribute "SEC" "1"
					( Origin gFrontEnd )
				)
				( attribute "SEC_TYPE" "0402"
					( Origin gFrontEnd )
				)
				( attribute "TOLERANCE" "1%"
					( Origin gFrontEnd )
				)
				( attribute "VALUE" "100.0"
					( Origin gFrontEnd )
				)
				( attribute "VER" "2"
					( Origin gFrontEnd )
				)
				( attribute "WATTAGE" "1/16W"
					( Origin gFrontEnd )
				)
				( attribute "XY" "(-1000,3500)"
					( Origin gFrontEnd )
				)
				( attribute "CHIPS_PART_NAME" "RES"
					( Origin gPackager )
				)
				( attribute "CDS_PART_NAME" "RES_0402-100.0,1%,1/16W,CHIP,GA"
					( Origin gPackager )
				)
				( attribute "CDS_SEC" "1"
					( Origin gPackager )
				)
				( objectStatus "R6N2" )
			)
			( gate "@baseboard_fab2_lib.baseboard_fab2(sch_1):page21_i164"
				( attribute "BOM_COST" "PROC_SIDEBAND"
					( Origin gFrontEnd )
				)
				( attribute "CDS_LIB" "mstr_discrete"
					( Origin gPackager )
				)
				( attribute "CDS_LOCATION" "R6N1"
					( Origin gPackager )
				)
				( attribute "LOCATION" "R6N1"
					( Origin gFrontEnd )
				)
				( attribute "MATERIAL" "CHIP"
					( Origin gFrontEnd )
				)
				( attribute "PACK_TYPE" "0402"
					( Origin gFrontEnd )
				)
				( attribute "PART_NUMBER" "G21796-047"
					( Origin gFrontEnd )
				)
				( attribute "PHYS_PAGE" "21"
					( Origin gFrontEnd )
				)
				( attribute "ROOM" "CPU0"
					( Origin gFrontEnd )
				)
				( attribute "ROT" "0"
					( Origin gFrontEnd )
				)
				( attribute "SEC" "1"
					( Origin gFrontEnd )
				)
				( attribute "SEC_TYPE" "0402"
					( Origin gFrontEnd )
				)
				( attribute "TOLERANCE" "1%"
					( Origin gFrontEnd )
				)
				( attribute "VALUE" "49.9"
					( Origin gFrontEnd )
				)
				( attribute "VER" "2"
					( Origin gFrontEnd )
				)
				( attribute "WATTAGE" "1/16W"
					( Origin gFrontEnd )
				)
				( attribute "XY" "(-750,3500)"
					( Origin gFrontEnd )
				)
				( attribute "CHIPS_PART_NAME" "RES"
					( Origin gPackager )
				)
				( attribute "CDS_PART_NAME" "RES_0402-49.9,1%,1/16W,CHIP,G2A"
					( Origin gPackager )
				)
				( attribute "CDS_SEC" "1"
					( Origin gPackager )
				)
				( objectStatus "R6N1" )
			)
			( gate "@baseboard_fab2_lib.baseboard_fab2(sch_1):page21_i177"
				( attribute "BOM_COST" "PROC_SOCKET"
					( Origin gFrontEnd )
				)
				( attribute "CDS_LIB" "mstr_discrete"
					( Origin gPackager )
				)
				( attribute "CDS_LOCATION" "R5D1"
					( Origin gPackager )
				)
				( attribute "LOCATION" "R5D1"
					( Origin gFrontEnd )
				)
				( attribute "MATERIAL" "CHIP"
					( Origin gFrontEnd )
				)
				( attribute "PACK_TYPE" "0402"
					( Origin gFrontEnd )
				)
				( attribute "PART_NUMBER" "G21796-365"
					( Origin gFrontEnd )
				)
				( attribute "PHYS_PAGE" "21"
					( Origin gFrontEnd )
				)
				( attribute "ROOM" "CPU0"
					( Origin gFrontEnd )
				)
				( attribute "ROT" "2"
					( Origin gFrontEnd )
				)
				( attribute "SEC" "1"
					( Origin gFrontEnd )
				)
				( attribute "SEC_TYPE" "0402"
					( Origin gFrontEnd )
				)
				( attribute "TOLERANCE" "1%"
					( Origin gFrontEnd )
				)
				( attribute "VALUE" "90.9"
					( Origin gFrontEnd )
				)
				( attribute "VER" "2"
					( Origin gFrontEnd )
				)
				( attribute "WATTAGE" "1/16W"
					( Origin gFrontEnd )
				)
				( attribute "XY" "(-6625,2875)"
					( Origin gFrontEnd )
				)
				( attribute "CHIPS_PART_NAME" "RES"
					( Origin gPackager )
				)
				( attribute "CDS_PART_NAME" "RES_0402-90.9,1%,1/16W,CHIP,G2A"
					( Origin gPackager )
				)
				( attribute "CDS_SEC" "1"
					( Origin gPackager )
				)
				( objectStatus "R5D1" )
			)
			( gate "@baseboard_fab2_lib.baseboard_fab2(sch_1):page21_i178"
				( attribute "BOM_COST" "PROC_SOCKET"
					( Origin gFrontEnd )
				)
				( attribute "CDS_LIB" "mstr_discrete"
					( Origin gPackager )
				)
				( attribute "CDS_LOCATION" "R5D2"
					( Origin gPackager )
				)
				( attribute "LOCATION" "R5D2"
					( Origin gFrontEnd )
				)
				( attribute "MATERIAL" "CHIP"
					( Origin gFrontEnd )
				)
				( attribute "PACK_TYPE" "0402"
					( Origin gFrontEnd )
				)
				( attribute "PART_NUMBER" "G21796-365"
					( Origin gFrontEnd )
				)
				( attribute "PHYS_PAGE" "21"
					( Origin gFrontEnd )
				)
				( attribute "ROOM" "CPU0"
					( Origin gFrontEnd )
				)
				( attribute "ROT" "2"
					( Origin gFrontEnd )
				)
				( attribute "SEC" "1"
					( Origin gFrontEnd )
				)
				( attribute "SEC_TYPE" "0402"
					( Origin gFrontEnd )
				)
				( attribute "TOLERANCE" "1%"
					( Origin gFrontEnd )
				)
				( attribute "VALUE" "90.9"
					( Origin gFrontEnd )
				)
				( attribute "VER" "2"
					( Origin gFrontEnd )
				)
				( attribute "WATTAGE" "1/16W"
					( Origin gFrontEnd )
				)
				( attribute "XY" "(-6875,2925)"
					( Origin gFrontEnd )
				)
				( attribute "CHIPS_PART_NAME" "RES"
					( Origin gPackager )
				)
				( attribute "CDS_PART_NAME" "RES_0402-90.9,1%,1/16W,CHIP,G2A"
					( Origin gPackager )
				)
				( attribute "CDS_SEC" "1"
					( Origin gPackager )
				)
				( objectStatus "R5D2" )
			)
			( gate "@baseboard_fab2_lib.baseboard_fab2(sch_1):page21_i179"
				( attribute "BOM_COST" "PROC_SOCKET"
					( Origin gFrontEnd )
				)
				( attribute "CDS_LIB" "mstr_discrete"
					( Origin gPackager )
				)
				( attribute "CDS_LOCATION" "R6D1"
					( Origin gPackager )
				)
				( attribute "LOCATION" "R6D1"
					( Origin gFrontEnd )
				)
				( attribute "MATERIAL" "CHIP"
					( Origin gFrontEnd )
				)
				( attribute "PACK_TYPE" "0402"
					( Origin gFrontEnd )
				)
				( attribute "PART_NUMBER" "G21796-017"
					( Origin gFrontEnd )
				)
				( attribute "PHYS_PAGE" "21"
					( Origin gFrontEnd )
				)
				( attribute "ROOM" "CPU0"
					( Origin gFrontEnd )
				)
				( attribute "ROT" "2"
					( Origin gFrontEnd )
				)
				( attribute "SEC" "1"
					( Origin gFrontEnd )
				)
				( attribute "SEC_TYPE" "0402"
					( Origin gFrontEnd )
				)
				( attribute "TOLERANCE" "1%"
					( Origin gFrontEnd )
				)
				( attribute "VALUE" "100.0"
					( Origin gFrontEnd )
				)
				( attribute "VER" "2"
					( Origin gFrontEnd )
				)
				( attribute "WATTAGE" "1/16W"
					( Origin gFrontEnd )
				)
				( attribute "XY" "(-7125,2925)"
					( Origin gFrontEnd )
				)
				( attribute "CHIPS_PART_NAME" "RES"
					( Origin gPackager )
				)
				( attribute "CDS_PART_NAME" "RES_0402-100.0,1%,1/16W,CHIP,GA"
					( Origin gPackager )
				)
				( attribute "CDS_SEC" "1"
					( Origin gPackager )
				)
				( objectStatus "R6D1" )
			)
			( gate "@baseboard_fab2_lib.baseboard_fab2(sch_1):page21_i180"
				( attribute "BOM_COST" "PROC_SOCKET"
					( Origin gFrontEnd )
				)
				( attribute "CDS_LIB" "mstr_discrete"
					( Origin gPackager )
				)
				( attribute "CDS_LOCATION" "R4P8"
					( Origin gPackager )
				)
				( attribute "LOCATION" "R4P8"
					( Origin gFrontEnd )
				)
				( attribute "MATERIAL" "CHIP"
					( Origin gFrontEnd )
				)
				( attribute "PACK_TYPE" "0402"
					( Origin gFrontEnd )
				)
				( attribute "PART_NUMBER" "G21796-365"
					( Origin gFrontEnd )
				)
				( attribute "PHYS_PAGE" "21"
					( Origin gFrontEnd )
				)
				( attribute "ROOM" "CPU0"
					( Origin gFrontEnd )
				)
				( attribute "ROT" "2"
					( Origin gFrontEnd )
				)
				( attribute "SEC" "1"
					( Origin gFrontEnd )
				)
				( attribute "SEC_TYPE" "0402"
					( Origin gFrontEnd )
				)
				( attribute "TOLERANCE" "1%"
					( Origin gFrontEnd )
				)
				( attribute "VALUE" "90.9"
					( Origin gFrontEnd )
				)
				( attribute "VER" "2"
					( Origin gFrontEnd )
				)
				( attribute "WATTAGE" "1/16W"
					( Origin gFrontEnd )
				)
				( attribute "XY" "(-7350,2925)"
					( Origin gFrontEnd )
				)
				( attribute "CHIPS_PART_NAME" "RES"
					( Origin gPackager )
				)
				( attribute "CDS_PART_NAME" "RES_0402-90.9,1%,1/16W,CHIP,G2A"
					( Origin gPackager )
				)
				( attribute "CDS_SEC" "1"
					( Origin gPackager )
				)
				( objectStatus "R4P8" )
			)
			( gate "@baseboard_fab2_lib.baseboard_fab2(sch_1):page21_i181"
				( attribute "BOM_COST" "PROC_SOCKET"
					( Origin gFrontEnd )
				)
				( attribute "CDS_LIB" "mstr_discrete"
					( Origin gPackager )
				)
				( attribute "CDS_LOCATION" "R4P10"
					( Origin gPackager )
				)
				( attribute "LOCATION" "R4P10"
					( Origin gFrontEnd )
				)
				( attribute "MATERIAL" "CHIP"
					( Origin gFrontEnd )
				)
				( attribute "PACK_TYPE" "0402"
					( Origin gFrontEnd )
				)
				( attribute "PART_NUMBER" "G21796-365"
					( Origin gFrontEnd )
				)
				( attribute "PHYS_PAGE" "21"
					( Origin gFrontEnd )
				)
				( attribute "ROOM" "CPU0"
					( Origin gFrontEnd )
				)
				( attribute "ROT" "2"
					( Origin gFrontEnd )
				)
				( attribute "SEC" "1"
					( Origin gFrontEnd )
				)
				( attribute "SEC_TYPE" "0402"
					( Origin gFrontEnd )
				)
				( attribute "TOLERANCE" "1%"
					( Origin gFrontEnd )
				)
				( attribute "VALUE" "90.9"
					( Origin gFrontEnd )
				)
				( attribute "VER" "2"
					( Origin gFrontEnd )
				)
				( attribute "WATTAGE" "1/16W"
					( Origin gFrontEnd )
				)
				( attribute "XY" "(-7575,3000)"
					( Origin gFrontEnd )
				)
				( attribute "CHIPS_PART_NAME" "RES"
					( Origin gPackager )
				)
				( attribute "CDS_PART_NAME" "RES_0402-90.9,1%,1/16W,CHIP,G2A"
					( Origin gPackager )
				)
				( attribute "CDS_SEC" "1"
					( Origin gPackager )
				)
				( objectStatus "R4P10" )
			)
			( gate "@baseboard_fab2_lib.baseboard_fab2(sch_1):page21_i182"
				( attribute "BOM_COST" "PROC_SOCKET"
					( Origin gFrontEnd )
				)
				( attribute "CDS_LIB" "mstr_discrete"
					( Origin gPackager )
				)
				( attribute "CDS_LOCATION" "R4P11"
					( Origin gPackager )
				)
				( attribute "LOCATION" "R4P11"
					( Origin gFrontEnd )
				)
				( attribute "MATERIAL" "CHIP"
					( Origin gFrontEnd )
				)
				( attribute "PACK_TYPE" "0402"
					( Origin gFrontEnd )
				)
				( attribute "PART_NUMBER" "G21796-017"
					( Origin gFrontEnd )
				)
				( attribute "PHYS_PAGE" "21"
					( Origin gFrontEnd )
				)
				( attribute "ROOM" "CPU0"
					( Origin gFrontEnd )
				)
				( attribute "ROT" "2"
					( Origin gFrontEnd )
				)
				( attribute "SEC" "1"
					( Origin gFrontEnd )
				)
				( attribute "SEC_TYPE" "0402"
					( Origin gFrontEnd )
				)
				( attribute "TOLERANCE" "1%"
					( Origin gFrontEnd )
				)
				( attribute "VALUE" "100.0"
					( Origin gFrontEnd )
				)
				( attribute "VER" "2"
					( Origin gFrontEnd )
				)
				( attribute "WATTAGE" "1/16W"
					( Origin gFrontEnd )
				)
				( attribute "XY" "(-7800,3000)"
					( Origin gFrontEnd )
				)
				( attribute "CHIPS_PART_NAME" "RES"
					( Origin gPackager )
				)
				( attribute "CDS_PART_NAME" "RES_0402-100.0,1%,1/16W,CHIP,GA"
					( Origin gPackager )
				)
				( attribute "CDS_SEC" "1"
					( Origin gPackager )
				)
				( objectStatus "R4P11" )
			)
			( gate "@baseboard_fab2_lib.baseboard_fab2(sch_1):page21_i184"
				( attribute "BOM_COST" "PROC_SOCKET"
					( Origin gFrontEnd )
				)
				( attribute "CDS_LIB" "mstr_discrete"
					( Origin gPackager )
				)
				( attribute "CDS_LOCATION" "R6D11"
					( Origin gPackager )
				)
				( attribute "LOCATION" "R6D11"
					( Origin gFrontEnd )
				)
				( attribute "MATERIAL" "CHIP"
					( Origin gFrontEnd )
				)
				( attribute "PACK_TYPE" "0402"
					( Origin gFrontEnd )
				)
				( attribute "PART_NUMBER" "G21796-047"
					( Origin gFrontEnd )
				)
				( attribute "PHYS_PAGE" "21"
					( Origin gFrontEnd )
				)
				( attribute "ROOM" "CPU0"
					( Origin gFrontEnd )
				)
				( attribute "ROT" "2"
					( Origin gFrontEnd )
				)
				( attribute "SEC" "1"
					( Origin gFrontEnd )
				)
				( attribute "SEC_TYPE" "0402"
					( Origin gFrontEnd )
				)
				( attribute "TOLERANCE" "1%"
					( Origin gFrontEnd )
				)
				( attribute "VALUE" "49.9"
					( Origin gFrontEnd )
				)
				( attribute "VER" "2"
					( Origin gFrontEnd )
				)
				( attribute "WATTAGE" "1/16W"
					( Origin gFrontEnd )
				)
				( attribute "XY" "(-7350,2000)"
					( Origin gFrontEnd )
				)
				( attribute "CHIPS_PART_NAME" "RES"
					( Origin gPackager )
				)
				( attribute "CDS_PART_NAME" "RES_0402-49.9,1%,1/16W,CHIP,G2A"
					( Origin gPackager )
				)
				( attribute "CDS_SEC" "1"
					( Origin gPackager )
				)
				( objectStatus "R6D11" )
			)
			( gate "@baseboard_fab2_lib.baseboard_fab2(sch_1):page21_i186"
				( attribute "BOM_COST" "PROC_SOCKET"
					( Origin gFrontEnd )
				)
				( attribute "CDS_LIB" "mstr_discrete"
					( Origin gPackager )
				)
				( attribute "CDS_LOCATION" "R4P3"
					( Origin gPackager )
				)
				( attribute "LOCATION" "R4P3"
					( Origin gFrontEnd )
				)
				( attribute "MATERIAL" "CHIP"
					( Origin gFrontEnd )
				)
				( attribute "PACK_TYPE" "0402"
					( Origin gFrontEnd )
				)
				( attribute "PART_NUMBER" "G21796-047"
					( Origin gFrontEnd )
				)
				( attribute "PHYS_PAGE" "21"
					( Origin gFrontEnd )
				)
				( attribute "ROOM" "CPU0"
					( Origin gFrontEnd )
				)
				( attribute "ROT" "2"
					( Origin gFrontEnd )
				)
				( attribute "SEC" "1"
					( Origin gFrontEnd )
				)
				( attribute "SEC_TYPE" "0402"
					( Origin gFrontEnd )
				)
				( attribute "TOLERANCE" "1%"
					( Origin gFrontEnd )
				)
				( attribute "VALUE" "49.9"
					( Origin gFrontEnd )
				)
				( attribute "VER" "2"
					( Origin gFrontEnd )
				)
				( attribute "WATTAGE" "1/16W"
					( Origin gFrontEnd )
				)
				( attribute "XY" "(-7575,2100)"
					( Origin gFrontEnd )
				)
				( attribute "CHIPS_PART_NAME" "RES"
					( Origin gPackager )
				)
				( attribute "CDS_PART_NAME" "RES_0402-49.9,1%,1/16W,CHIP,G2A"
					( Origin gPackager )
				)
				( attribute "CDS_SEC" "1"
					( Origin gPackager )
				)
				( objectStatus "R4P3" )
			)
			( gate "@baseboard_fab2_lib.baseboard_fab2(sch_1):page21_i188"
				( attribute "BOM_COST" "PROC_SOCKET"
					( Origin gFrontEnd )
				)
				( attribute "CDS_LIB" "mstr_discrete"
					( Origin gPackager )
				)
				( attribute "CDS_LOCATION" "R4P2"
					( Origin gPackager )
				)
				( attribute "LOCATION" "R4P2"
					( Origin gFrontEnd )
				)
				( attribute "MATERIAL" "CHIP"
					( Origin gFrontEnd )
				)
				( attribute "PACK_TYPE" "0402"
					( Origin gFrontEnd )
				)
				( attribute "PART_NUMBER" "G21796-047"
					( Origin gFrontEnd )
				)
				( attribute "PHYS_PAGE" "21"
					( Origin gFrontEnd )
				)
				( attribute "ROOM" "CPU0"
					( Origin gFrontEnd )
				)
				( attribute "ROT" "2"
					( Origin gFrontEnd )
				)
				( attribute "SEC" "1"
					( Origin gFrontEnd )
				)
				( attribute "SEC_TYPE" "0402"
					( Origin gFrontEnd )
				)
				( attribute "TOLERANCE" "1%"
					( Origin gFrontEnd )
				)
				( attribute "VALUE" "49.9"
					( Origin gFrontEnd )
				)
				( attribute "VER" "2"
					( Origin gFrontEnd )
				)
				( attribute "WATTAGE" "1/16W"
					( Origin gFrontEnd )
				)
				( attribute "XY" "(-7800,2200)"
					( Origin gFrontEnd )
				)
				( attribute "CHIPS_PART_NAME" "RES"
					( Origin gPackager )
				)
				( attribute "CDS_PART_NAME" "RES_0402-49.9,1%,1/16W,CHIP,G2A"
					( Origin gPackager )
				)
				( attribute "CDS_SEC" "1"
					( Origin gPackager )
				)
				( objectStatus "R4P2" )
			)
			( gate "@baseboard_fab2_lib.baseboard_fab2(sch_1):page21_i189"
				( attribute "BOM_COST" "PROC_SOCKET"
					( Origin gFrontEnd )
				)
				( attribute "CDS_LIB" "mstr_discrete"
					( Origin gPackager )
				)
				( attribute "CDS_LOCATION" "R4P4"
					( Origin gPackager )
				)
				( attribute "LOCATION" "R4P4"
					( Origin gFrontEnd )
				)
				( attribute "MATERIAL" "CHIP"
					( Origin gFrontEnd )
				)
				( attribute "PACK_TYPE" "0402"
					( Origin gFrontEnd )
				)
				( attribute "PART_NUMBER" "G21796-047"
					( Origin gFrontEnd )
				)
				( attribute "PHYS_PAGE" "21"
					( Origin gFrontEnd )
				)
				( attribute "ROOM" "CPU0"
					( Origin gFrontEnd )
				)
				( attribute "ROT" "2"
					( Origin gFrontEnd )
				)
				( attribute "SEC" "1"
					( Origin gFrontEnd )
				)
				( attribute "SEC_TYPE" "0402"
					( Origin gFrontEnd )
				)
				( attribute "TOLERANCE" "1%"
					( Origin gFrontEnd )
				)
				( attribute "VALUE" "49.9"
					( Origin gFrontEnd )
				)
				( attribute "VER" "2"
					( Origin gFrontEnd )
				)
				( attribute "WATTAGE" "1/16W"
					( Origin gFrontEnd )
				)
				( attribute "XY" "(-7125,2000)"
					( Origin gFrontEnd )
				)
				( attribute "CHIPS_PART_NAME" "RES"
					( Origin gPackager )
				)
				( attribute "CDS_PART_NAME" "RES_0402-49.9,1%,1/16W,CHIP,G2A"
					( Origin gPackager )
				)
				( attribute "CDS_SEC" "1"
					( Origin gPackager )
				)
				( objectStatus "R4P4" )
			)
			( gate "@baseboard_fab2_lib.baseboard_fab2(sch_1):page21_i204"
				( attribute "BOM_COST" "PROC_SOCKET"
					( Origin gFrontEnd )
				)
				( attribute "CDS_LIB" "mstr_discrete"
					( Origin gPackager )
				)
				( attribute "CDS_LOCATION" "R6D2"
					( Origin gPackager )
				)
				( attribute "LOCATION" "R6D2"
					( Origin gFrontEnd )
				)
				( attribute "MATERIAL" "CHIP"
					( Origin gFrontEnd )
				)
				( attribute "PACK_TYPE" "0402"
					( Origin gFrontEnd )
				)
				( attribute "PART_NUMBER" "G21796-047"
					( Origin gFrontEnd )
				)
				( attribute "PHYS_PAGE" "21"
					( Origin gFrontEnd )
				)
				( attribute "ROOM" "CPU0"
					( Origin gFrontEnd )
				)
				( attribute "ROT" "2"
					( Origin gFrontEnd )
				)
				( attribute "SEC" "1"
					( Origin gFrontEnd )
				)
				( attribute "SEC_TYPE" "0402"
					( Origin gFrontEnd )
				)
				( attribute "TOLERANCE" "1%"
					( Origin gFrontEnd )
				)
				( attribute "VALUE" "49.9"
					( Origin gFrontEnd )
				)
				( attribute "VER" "2"
					( Origin gFrontEnd )
				)
				( attribute "WATTAGE" "1/16W"
					( Origin gFrontEnd )
				)
				( attribute "XY" "(-6900,2000)"
					( Origin gFrontEnd )
				)
				( attribute "CHIPS_PART_NAME" "RES"
					( Origin gPackager )
				)
				( attribute "CDS_PART_NAME" "RES_0402-49.9,1%,1/16W,CHIP,G2A"
					( Origin gPackager )
				)
				( attribute "CDS_SEC" "1"
					( Origin gPackager )
				)
				( objectStatus "R6D2" )
			)
			( gate "@baseboard_fab2_lib.baseboard_fab2(sch_1):page21_i216"
				( attribute "BOM_COST" "PROC_SOCKET"
					( Origin gFrontEnd )
				)
				( attribute "CDS_LIB" "chpset_lib"
					( Origin gPackager )
				)
				( attribute "CDS_LOCATION" "XRU1"
					( Origin gPackager )
				)
				( attribute "LOCATION" "XRU1"
					( Origin gFrontEnd )
				)
				( attribute "MATERIAL" "PLASTIC"
					( Origin gFrontEnd )
				)
				( attribute "PACK_TYPE" "RIGHT"
					( Origin gFrontEnd )
				)
				( attribute "PART_NUMBER" "H37604-101"
					( Origin gFrontEnd )
				)
				( attribute "PHYS_PAGE" "21"
					( Origin gFrontEnd )
				)
				( attribute "ROOM" "CPU0"
					( Origin gFrontEnd )
				)
				( attribute "ROT" "0"
					( Origin gFrontEnd )
				)
				( attribute "SKT_NUMBER" "P0"
					( Origin gFrontEnd )
				)
				( attribute "VER" "1"
					( Origin gFrontEnd )
				)
				( attribute "XY" "(-7525,4450)"
					( Origin gFrontEnd )
				)
				( attribute "CHIPS_PART_NAME" "SOCKET_P_MECH_A"
					( Origin gPackager )
				)
				( attribute "CDS_PART_NAME" "SOCKET_P_MECH_A_RIGHT-P0,PLASTA"
					( Origin gPackager )
				)
				( objectStatus "XRU1" )
			)
			( gate "@baseboard_fab2_lib.baseboard_fab2(sch_1):page21_i217"
				( attribute "BOM_COST" "PROC_SOCKET"
					( Origin gFrontEnd )
				)
				( attribute "CDS_LIB" "chpset_lib"
					( Origin gPackager )
				)
				( attribute "CDS_LOCATION" "XLU1"
					( Origin gPackager )
				)
				( attribute "LOCATION" "XLU1"
					( Origin gFrontEnd )
				)
				( attribute "MATERIAL" "PLASTIC"
					( Origin gFrontEnd )
				)
				( attribute "PACK_TYPE" "LEFT"
					( Origin gFrontEnd )
				)
				( attribute "PART_NUMBER" "H37604-201"
					( Origin gFrontEnd )
				)
				( attribute "PHYS_PAGE" "21"
					( Origin gFrontEnd )
				)
				( attribute "ROOM" "CPU0"
					( Origin gFrontEnd )
				)
				( attribute "ROT" "0"
					( Origin gFrontEnd )
				)
				( attribute "SKT_NUMBER" "P0"
					( Origin gFrontEnd )
				)
				( attribute "VER" "1"
					( Origin gFrontEnd )
				)
				( attribute "XY" "(-7525,4150)"
					( Origin gFrontEnd )
				)
				( attribute "CHIPS_PART_NAME" "SOCKET_P_MECH_A"
					( Origin gPackager )
				)
				( attribute "CDS_PART_NAME" "SOCKET_P_MECH_A_LEFT-P0,PLASTIA"
					( Origin gPackager )
				)
				( objectStatus "XLU1" )
			)
			( gate "@baseboard_fab2_lib.baseboard_fab2(sch_1):page21_i219"
				( attribute "BOM_COST" "PROC_SOCKET"
					( Origin gFrontEnd )
				)
				( attribute "CDS_LIB" "mstr_discrete"
					( Origin gPackager )
				)
				( attribute "CDS_LOCATION" "R4P19"
					( Origin gPackager )
				)
				( attribute "LOCATION" "R4P19"
					( Origin gFrontEnd )
				)
				( attribute "MATERIAL" "CHIP"
					( Origin gFrontEnd )
				)
				( attribute "PACK_TYPE" "0402"
					( Origin gFrontEnd )
				)
				( attribute "PART_NUMBER" "G21796-047"
					( Origin gFrontEnd )
				)
				( attribute "PHYS_PAGE" "21"
					( Origin gFrontEnd )
				)
				( attribute "ROOM" "CPU0"
					( Origin gFrontEnd )
				)
				( attribute "ROT" "0"
					( Origin gFrontEnd )
				)
				( attribute "SEC" "1"
					( Origin gFrontEnd )
				)
				( attribute "SEC_TYPE" "0402"
					( Origin gFrontEnd )
				)
				( attribute "TOLERANCE" "1%"
					( Origin gFrontEnd )
				)
				( attribute "VALUE" "49.9"
					( Origin gFrontEnd )
				)
				( attribute "VER" "1"
					( Origin gFrontEnd )
				)
				( attribute "WATTAGE" "1/16W"
					( Origin gFrontEnd )
				)
				( attribute "XY" "(-2075,4200)"
					( Origin gFrontEnd )
				)
				( attribute "CHIPS_PART_NAME" "RES"
					( Origin gPackager )
				)
				( attribute "CDS_PART_NAME" "RES_0402-49.9,1%,1/16W,CHIP,G2A"
					( Origin gPackager )
				)
				( attribute "CDS_SEC" "1"
					( Origin gPackager )
				)
				( objectStatus "R4P19" )
			)
			( gate "@baseboard_fab2_lib.baseboard_fab2(sch_1):page21_i227"
				( attribute "BOM_COST" "PROC_SIDEBAND"
					( Origin gFrontEnd )
				)
				( attribute "CDS_LIB" "mstr_discrete"
					( Origin gPackager )
				)
				( attribute "CDS_LOCATION" "R5N2"
					( Origin gPackager )
				)
				( attribute "LOCATION" "R5N2"
					( Origin gFrontEnd )
				)
				( attribute "MATERIAL" "CHIP"
					( Origin gFrontEnd )
				)
				( attribute "PACK_TYPE" "0402"
					( Origin gFrontEnd )
				)
				( attribute "PART_NUMBER" "G21796-336"
					( Origin gFrontEnd )
				)
				( attribute "PHYS_PAGE" "21"
					( Origin gFrontEnd )
				)
				( attribute "ROOM" "CPU0"
					( Origin gFrontEnd )
				)
				( attribute "ROT" "0"
					( Origin gFrontEnd )
				)
				( attribute "SEC" "1"
					( Origin gFrontEnd )
				)
				( attribute "SEC_TYPE" "0402"
					( Origin gFrontEnd )
				)
				( attribute "TOLERANCE" "1%"
					( Origin gFrontEnd )
				)
				( attribute "VALUE" "1.8K"
					( Origin gFrontEnd )
				)
				( attribute "VER" "2"
					( Origin gFrontEnd )
				)
				( attribute "WATTAGE" "1/16W"
					( Origin gFrontEnd )
				)
				( attribute "XY" "(-1700,2700)"
					( Origin gFrontEnd )
				)
				( attribute "CHIPS_PART_NAME" "RES"
					( Origin gPackager )
				)
				( attribute "CDS_PART_NAME" "RES_0402-1.8K,1%,1/16W,CHIP,G2A"
					( Origin gPackager )
				)
				( attribute "CDS_SEC" "1"
					( Origin gPackager )
				)
				( objectStatus "R5N2" )
			)
			( gate "@baseboard_fab2_lib.baseboard_fab2(sch_1):page21_i238"
				( attribute "BOM_COST" "PROC_SIDEBAND"
					( Origin gFrontEnd )
				)
				( attribute "CDS_LIB" "mstr_discrete"
					( Origin gPackager )
				)
				( attribute "CDS_LOCATION" "R5N1"
					( Origin gPackager )
				)
				( attribute "LOCATION" "R5N1"
					( Origin gFrontEnd )
				)
				( attribute "MATERIAL" "CHIP"
					( Origin gFrontEnd )
				)
				( attribute "PACK_TYPE" "0402"
					( Origin gFrontEnd )
				)
				( attribute "PART_NUMBER" "G21796-016"
					( Origin gFrontEnd )
				)
				( attribute "PHYS_PAGE" "21"
					( Origin gFrontEnd )
				)
				( attribute "ROOM" "CPU0"
					( Origin gFrontEnd )
				)
				( attribute "ROT" "0"
					( Origin gFrontEnd )
				)
				( attribute "SEC" "1"
					( Origin gFrontEnd )
				)
				( attribute "SEC_TYPE" "0402"
					( Origin gFrontEnd )
				)
				( attribute "TOLERANCE" "1%"
					( Origin gFrontEnd )
				)
				( attribute "VALUE" "10.0K"
					( Origin gFrontEnd )
				)
				( attribute "VER" "2"
					( Origin gFrontEnd )
				)
				( attribute "WATTAGE" "1/16W"
					( Origin gFrontEnd )
				)
				( attribute "XY" "(-700,2700)"
					( Origin gFrontEnd )
				)
				( attribute "CHIPS_PART_NAME" "RES"
					( Origin gPackager )
				)
				( attribute "CDS_PART_NAME" "RES_0402-10.0K,1%,1/16W,CHIP,GA"
					( Origin gPackager )
				)
				( attribute "CDS_SEC" "1"
					( Origin gPackager )
				)
				( objectStatus "R5N1" )
			)
			( gate "@baseboard_fab2_lib.baseboard_fab2(sch_1):page21_i239"
				( attribute "BOM_COST" "PROC_SIDEBAND"
					( Origin gFrontEnd )
				)
				( attribute "CDS_LIB" "mstr_discrete"
					( Origin gPackager )
				)
				( attribute "CDS_LOCATION" "R5N5"
					( Origin gPackager )
				)
				( attribute "LOCATION" "R5N5"
					( Origin gFrontEnd )
				)
				( attribute "MATERIAL" "CHIP"
					( Origin gFrontEnd )
				)
				( attribute "PACK_TYPE" "0402"
					( Origin gFrontEnd )
				)
				( attribute "PART_NUMBER" "G21796-016"
					( Origin gFrontEnd )
				)
				( attribute "PHYS_PAGE" "21"
					( Origin gFrontEnd )
				)
				( attribute "ROOM" "CPU0"
					( Origin gFrontEnd )
				)
				( attribute "ROT" "0"
					( Origin gFrontEnd )
				)
				( attribute "SEC" "1"
					( Origin gFrontEnd )
				)
				( attribute "SEC_TYPE" "0402"
					( Origin gFrontEnd )
				)
				( attribute "TOLERANCE" "1%"
					( Origin gFrontEnd )
				)
				( attribute "VALUE" "10.0K"
					( Origin gFrontEnd )
				)
				( attribute "VER" "2"
					( Origin gFrontEnd )
				)
				( attribute "WATTAGE" "1/16W"
					( Origin gFrontEnd )
				)
				( attribute "XY" "(-950,2700)"
					( Origin gFrontEnd )
				)
				( attribute "CHIPS_PART_NAME" "RES"
					( Origin gPackager )
				)
				( attribute "CDS_PART_NAME" "RES_0402-10.0K,1%,1/16W,CHIP,GA"
					( Origin gPackager )
				)
				( attribute "CDS_SEC" "1"
					( Origin gPackager )
				)
				( objectStatus "R5N5" )
			)
			( gate "@baseboard_fab2_lib.baseboard_fab2(sch_1):page21_i240"
				( attribute "BOM_COST" "PROC_SIDEBAND"
					( Origin gFrontEnd )
				)
				( attribute "CDS_LIB" "mstr_discrete"
					( Origin gPackager )
				)
				( attribute "CDS_LOCATION" "R5N3"
					( Origin gPackager )
				)
				( attribute "LOCATION" "R5N3"
					( Origin gFrontEnd )
				)
				( attribute "MATERIAL" "CHIP"
					( Origin gFrontEnd )
				)
				( attribute "PACK_TYPE" "0402"
					( Origin gFrontEnd )
				)
				( attribute "PART_NUMBER" "G21796-016"
					( Origin gFrontEnd )
				)
				( attribute "PHYS_PAGE" "21"
					( Origin gFrontEnd )
				)
				( attribute "ROOM" "CPU0"
					( Origin gFrontEnd )
				)
				( attribute "ROT" "0"
					( Origin gFrontEnd )
				)
				( attribute "SEC" "1"
					( Origin gFrontEnd )
				)
				( attribute "SEC_TYPE" "0402"
					( Origin gFrontEnd )
				)
				( attribute "TOLERANCE" "1%"
					( Origin gFrontEnd )
				)
				( attribute "VALUE" "10.0K"
					( Origin gFrontEnd )
				)
				( attribute "VER" "2"
					( Origin gFrontEnd )
				)
				( attribute "WATTAGE" "1/16W"
					( Origin gFrontEnd )
				)
				( attribute "XY" "(-1200,2700)"
					( Origin gFrontEnd )
				)
				( attribute "CHIPS_PART_NAME" "RES"
					( Origin gPackager )
				)
				( attribute "CDS_PART_NAME" "RES_0402-10.0K,1%,1/16W,CHIP,GA"
					( Origin gPackager )
				)
				( attribute "CDS_SEC" "1"
					( Origin gPackager )
				)
				( objectStatus "R5N3" )
			)
			( gate "@baseboard_fab2_lib.baseboard_fab2(sch_1):page21_i241"
				( attribute "BOM_COST" "PROC_SIDEBAND"
					( Origin gFrontEnd )
				)
				( attribute "CDS_LIB" "mstr_discrete"
					( Origin gPackager )
				)
				( attribute "CDS_LOCATION" "R5N4"
					( Origin gPackager )
				)
				( attribute "LOCATION" "R5N4"
					( Origin gFrontEnd )
				)
				( attribute "MATERIAL" "CHIP"
					( Origin gFrontEnd )
				)
				( attribute "PACK_TYPE" "0402"
					( Origin gFrontEnd )
				)
				( attribute "PART_NUMBER" "G21796-336"
					( Origin gFrontEnd )
				)
				( attribute "PHYS_PAGE" "21"
					( Origin gFrontEnd )
				)
				( attribute "ROOM" "CPU0"
					( Origin gFrontEnd )
				)
				( attribute "ROT" "0"
					( Origin gFrontEnd )
				)
				( attribute "SEC" "1"
					( Origin gFrontEnd )
				)
				( attribute "SEC_TYPE" "0402"
					( Origin gFrontEnd )
				)
				( attribute "TOLERANCE" "1%"
					( Origin gFrontEnd )
				)
				( attribute "VALUE" "1.8K"
					( Origin gFrontEnd )
				)
				( attribute "VER" "2"
					( Origin gFrontEnd )
				)
				( attribute "WATTAGE" "1/16W"
					( Origin gFrontEnd )
				)
				( attribute "XY" "(-1450,2700)"
					( Origin gFrontEnd )
				)
				( attribute "CHIPS_PART_NAME" "RES"
					( Origin gPackager )
				)
				( attribute "CDS_PART_NAME" "RES_0402-1.8K,1%,1/16W,CHIP,G2A"
					( Origin gPackager )
				)
				( attribute "CDS_SEC" "1"
					( Origin gPackager )
				)
				( objectStatus "R5N4" )
			)
			( gate "@baseboard_fab2_lib.baseboard_fab2(sch_1):page21_i244"
				( attribute "BOM_COST" "PROC_SIDEBAND"
					( Origin gFrontEnd )
				)
				( attribute "CDS_LIB" "mstr_discrete"
					( Origin gPackager )
				)
				( attribute "CDS_LOCATION" "R4P18"
					( Origin gPackager )
				)
				( attribute "LOCATION" "R4P18"
					( Origin gFrontEnd )
				)
				( attribute "MATERIAL" "CHIP"
					( Origin gFrontEnd )
				)
				( attribute "PACK_TYPE" "0402"
					( Origin gFrontEnd )
				)
				( attribute "PART_NUMBER" "G21796-047"
					( Origin gFrontEnd )
				)
				( attribute "PHYS_PAGE" "21"
					( Origin gFrontEnd )
				)
				( attribute "ROOM" "CPU0"
					( Origin gFrontEnd )
				)
				( attribute "ROT" "0"
					( Origin gFrontEnd )
				)
				( attribute "SEC" "1"
					( Origin gFrontEnd )
				)
				( attribute "SEC_TYPE" "0402"
					( Origin gFrontEnd )
				)
				( attribute "TOLERANCE" "1%"
					( Origin gFrontEnd )
				)
				( attribute "VALUE" "49.9"
					( Origin gFrontEnd )
				)
				( attribute "VER" "1"
					( Origin gFrontEnd )
				)
				( attribute "WATTAGE" "1/16W"
					( Origin gFrontEnd )
				)
				( attribute "XY" "(-2075,4250)"
					( Origin gFrontEnd )
				)
				( attribute "CHIPS_PART_NAME" "RES"
					( Origin gPackager )
				)
				( attribute "CDS_PART_NAME" "RES_0402-49.9,1%,1/16W,CHIP,G2A"
					( Origin gPackager )
				)
				( attribute "CDS_SEC" "1"
					( Origin gPackager )
				)
				( objectStatus "R4P18" )
			)
			( gate "@baseboard_fab2_lib.baseboard_fab2(sch_1):page21_i258"
				( attribute "CDS_LIB" "mstr_discrete"
					( Origin gPackager )
				)
				( attribute "CDS_LOCATION" "R4R5"
					( Origin gPackager )
				)
				( attribute "LOCATION" "R4R5"
					( Origin gFrontEnd )
				)
				( attribute "MATERIAL" "CHIP"
					( Origin gFrontEnd )
				)
				( attribute "PACK_TYPE" "0402"
					( Origin gFrontEnd )
				)
				( attribute "PART_NUMBER" "G21796-072"
					( Origin gFrontEnd )
				)
				( attribute "PHYS_PAGE" "21"
					( Origin gFrontEnd )
				)
				( attribute "ROOM" "CPU0"
					( Origin gFrontEnd )
				)
				( attribute "ROT" "0"
					( Origin gFrontEnd )
				)
				( attribute "SEC" "1"
					( Origin gFrontEnd )
				)
				( attribute "SEC_TYPE" "0402"
					( Origin gFrontEnd )
				)
				( attribute "TOLERANCE" "1%"
					( Origin gFrontEnd )
				)
				( attribute "VALUE" "4.75K"
					( Origin gFrontEnd )
				)
				( attribute "VER" "2"
					( Origin gFrontEnd )
				)
				( attribute "WATTAGE" "1/16W"
					( Origin gFrontEnd )
				)
				( attribute "XY" "(-1075,1450)"
					( Origin gFrontEnd )
				)
				( attribute "CHIPS_PART_NAME" "RES"
					( Origin gPackager )
				)
				( attribute "CDS_PART_NAME" "RES_0402-4.75K,1%,1/16W,CHIP,GA"
					( Origin gPackager )
				)
				( attribute "CDS_SEC" "1"
					( Origin gPackager )
				)
				( objectStatus "R4R5" )
			)
			( gate "@baseboard_fab2_lib.baseboard_fab2(sch_1):page21_i259"
				( attribute "CDS_LIB" "chpset_lib"
					( Origin gPackager )
				)
				( attribute "CDS_LOCATION" "U5D1"
					( Origin gPackager )
				)
				( attribute "LOCATION" "U5D1"
					( Origin gFrontEnd )
				)
				( attribute "MATERIAL" "IC"
					( Origin gFrontEnd )
				)
				( attribute "PACK_TYPE" "BGA1"
					( Origin gFrontEnd )
				)
				( attribute "PART_NUMBER" "TBD"
					( Origin gFrontEnd )
				)
				( attribute "PHYS_PAGE" "21"
					( Origin gFrontEnd )
				)
				( attribute "ROOM" "CPU0"
					( Origin gFrontEnd )
				)
				( attribute "ROT" "0"
					( Origin gFrontEnd )
				)
				( attribute "SEC" "1"
					( Origin gFrontEnd )
				)
				( attribute "SEC_TYPE" "BGA1"
					( Origin gFrontEnd )
				)
				( attribute "VER" "1"
					( Origin gFrontEnd )
				)
				( attribute "XY" "(-4075,2850)"
					( Origin gFrontEnd )
				)
				( attribute "CHIPS_PART_NAME" "SKX_EXT_B"
					( Origin gPackager )
				)
				( attribute "CDS_PART_NAME" "SKX_EXT_B_BGA1-IC,TBD"
					( Origin gPackager )
				)
				( attribute "CDS_SEC" "1"
					( Origin gPackager )
				)
				( objectStatus "U5D1" )
			)
			( gate "@baseboard_fab2_lib.baseboard_fab2(sch_1):page22_i188"
				( attribute "CDS_LIB" "mstr_discrete"
					( Origin gPackager )
				)
				( attribute "CDS_LOCATION" "R5R1"
					( Origin gPackager )
				)
				( attribute "CDS_SEC" "1"
					( Origin gPackager )
				)
				( attribute "LOCATION" "R5R1"
					( Origin gFrontEnd )
				)
				( attribute "MATERIAL" "CHIP"
					( Origin gFrontEnd )
				)
				( attribute "PACK_TYPE" "0402"
					( Origin gFrontEnd )
				)
				( attribute "PART_NUMBER" "G21796-047"
					( Origin gFrontEnd )
				)
				( attribute "PHYS_PAGE" "22"
					( Origin gFrontEnd )
				)
				( attribute "ROOM" "CPU0"
					( Origin gFrontEnd )
				)
				( attribute "ROT" "0"
					( Origin gFrontEnd )
				)
				( attribute "SEC" "1"
					( Origin gFrontEnd )
				)
				( attribute "SEC_TYPE" "0402"
					( Origin gFrontEnd )
				)
				( attribute "TOLERANCE" "1%"
					( Origin gFrontEnd )
				)
				( attribute "VALUE" "49.9"
					( Origin gFrontEnd )
				)
				( attribute "VER" "2"
					( Origin gFrontEnd )
				)
				( attribute "WATTAGE" "1/16W"
					( Origin gFrontEnd )
				)
				( attribute "XY" "(-300,2775)"
					( Origin gFrontEnd )
				)
				( attribute "CHIPS_PART_NAME" "RES"
					( Origin gPackager )
				)
				( attribute "CDS_PART_NAME" "RES_0402-49.9,1%,1/16W,CHIP,G2A"
					( Origin gPackager )
				)
				( objectStatus "R5R1" )
			)
			( gate "@baseboard_fab2_lib.baseboard_fab2(sch_1):page22_i190"
				( attribute "CDS_LIB" "mstr_discrete"
					( Origin gPackager )
				)
				( attribute "CDS_LOCATION" "R5P4"
					( Origin gPackager )
				)
				( attribute "CDS_SEC" "1"
					( Origin gPackager )
				)
				( attribute "LOCATION" "R5P4"
					( Origin gFrontEnd )
				)
				( attribute "MATERIAL" "CHIP"
					( Origin gFrontEnd )
				)
				( attribute "PACK_TYPE" "0402"
					( Origin gFrontEnd )
				)
				( attribute "PART_NUMBER" "G21796-047"
					( Origin gFrontEnd )
				)
				( attribute "PHYS_PAGE" "22"
					( Origin gFrontEnd )
				)
				( attribute "ROOM" "CPU0"
					( Origin gFrontEnd )
				)
				( attribute "ROT" "0"
					( Origin gFrontEnd )
				)
				( attribute "SEC" "1"
					( Origin gFrontEnd )
				)
				( attribute "SEC_TYPE" "0402"
					( Origin gFrontEnd )
				)
				( attribute "TOLERANCE" "1%"
					( Origin gFrontEnd )
				)
				( attribute "VALUE" "49.9"
					( Origin gFrontEnd )
				)
				( attribute "VER" "2"
					( Origin gFrontEnd )
				)
				( attribute "WATTAGE" "1/16W"
					( Origin gFrontEnd )
				)
				( attribute "XY" "(-575,2775)"
					( Origin gFrontEnd )
				)
				( attribute "CHIPS_PART_NAME" "RES"
					( Origin gPackager )
				)
				( attribute "CDS_PART_NAME" "RES_0402-49.9,1%,1/16W,CHIP,G2A"
					( Origin gPackager )
				)
				( objectStatus "R5P4" )
			)
			( gate "@baseboard_fab2_lib.baseboard_fab2(sch_1):page22_i204"
				( attribute "CDS_LIB" "chpset_lib"
					( Origin gPackager )
				)
				( attribute "CDS_LOCATION" "U5D1"
					( Origin gPackager )
				)
				( attribute "CDS_SEC" "2"
					( Origin gPackager )
				)
				( attribute "LOCATION" "U5D1"
					( Origin gFrontEnd )
				)
				( attribute "MATERIAL" "IC"
					( Origin gFrontEnd )
				)
				( attribute "PACK_TYPE" "BGA1"
					( Origin gFrontEnd )
				)
				( attribute "PART_NUMBER" "TBD"
					( Origin gFrontEnd )
				)
				( attribute "PHYS_PAGE" "22"
					( Origin gFrontEnd )
				)
				( attribute "ROOM" "CPU0"
					( Origin gFrontEnd )
				)
				( attribute "ROT" "0"
					( Origin gFrontEnd )
				)
				( attribute "SEC" "2"
					( Origin gFrontEnd )
				)
				( attribute "SEC_TYPE" "BGA1"
					( Origin gFrontEnd )
				)
				( attribute "VER" "2"
					( Origin gFrontEnd )
				)
				( attribute "XY" "(-4150,2550)"
					( Origin gFrontEnd )
				)
				( attribute "CHIPS_PART_NAME" "SKX_EXT_B"
					( Origin gPackager )
				)
				( attribute "CDS_PART_NAME" "SKX_EXT_B_BGA1-IC,TBD"
					( Origin gPackager )
				)
				( objectStatus "U5D1" )
			)
			( gate "@baseboard_fab2_lib.baseboard_fab2(sch_1):page23_i172"
				( attribute "CDS_LIB" "chpset_lib"
					( Origin gPackager )
				)
				( attribute "CDS_LOCATION" "U5D1"
					( Origin gPackager )
				)
				( attribute "CDS_SEC" "3"
					( Origin gPackager )
				)
				( attribute "LOCATION" "U5D1"
					( Origin gFrontEnd )
				)
				( attribute "MATERIAL" "IC"
					( Origin gFrontEnd )
				)
				( attribute "PACK_TYPE" "BGA1"
					( Origin gFrontEnd )
				)
				( attribute "PART_NUMBER" "TBD"
					( Origin gFrontEnd )
				)
				( attribute "PHYS_PAGE" "23"
					( Origin gFrontEnd )
				)
				( attribute "ROOM" "CPU0"
					( Origin gFrontEnd )
				)
				( attribute "ROT" "0"
					( Origin gFrontEnd )
				)
				( attribute "SEC" "3"
					( Origin gFrontEnd )
				)
				( attribute "SEC_TYPE" "BGA1"
					( Origin gFrontEnd )
				)
				( attribute "VER" "3"
					( Origin gFrontEnd )
				)
				( attribute "XY" "(-4200,2600)"
					( Origin gFrontEnd )
				)
				( attribute "CHIPS_PART_NAME" "SKX_EXT_B"
					( Origin gPackager )
				)
				( attribute "CDS_PART_NAME" "SKX_EXT_B_BGA1-IC,TBD"
					( Origin gPackager )
				)
				( objectStatus "U5D1" )
			)
			( gate "@baseboard_fab2_lib.baseboard_fab2(sch_1):page24_i172"
				( attribute "CDS_LIB" "chpset_lib"
					( Origin gPackager )
				)
				( attribute "CDS_LOCATION" "U5D1"
					( Origin gPackager )
				)
				( attribute "CDS_SEC" "4"
					( Origin gPackager )
				)
				( attribute "LOCATION" "U5D1"
					( Origin gFrontEnd )
				)
				( attribute "MATERIAL" "IC"
					( Origin gFrontEnd )
				)
				( attribute "PACK_TYPE" "BGA1"
					( Origin gFrontEnd )
				)
				( attribute "PART_NUMBER" "TBD"
					( Origin gFrontEnd )
				)
				( attribute "PHYS_PAGE" "24"
					( Origin gFrontEnd )
				)
				( attribute "ROOM" "CPU0"
					( Origin gFrontEnd )
				)
				( attribute "ROT" "0"
					( Origin gFrontEnd )
				)
				( attribute "SEC" "4"
					( Origin gFrontEnd )
				)
				( attribute "SEC_TYPE" "BGA1"
					( Origin gFrontEnd )
				)
				( attribute "VER" "4"
					( Origin gFrontEnd )
				)
				( attribute "XY" "(-4125,2550)"
					( Origin gFrontEnd )
				)
				( attribute "CHIPS_PART_NAME" "SKX_EXT_B"
					( Origin gPackager )
				)
				( attribute "CDS_PART_NAME" "SKX_EXT_B_BGA1-IC,TBD"
					( Origin gPackager )
				)
				( objectStatus "U5D1" )
			)
			( gate "@baseboard_fab2_lib.baseboard_fab2(sch_1):page25_i172"
				( attribute "CDS_LIB" "chpset_lib"
					( Origin gPackager )
				)
				( attribute "CDS_LOCATION" "U5D1"
					( Origin gPackager )
				)
				( attribute "CDS_SEC" "5"
					( Origin gPackager )
				)
				( attribute "LOCATION" "U5D1"
					( Origin gFrontEnd )
				)
				( attribute "MATERIAL" "IC"
					( Origin gFrontEnd )
				)
				( attribute "PACK_TYPE" "BGA1"
					( Origin gFrontEnd )
				)
				( attribute "PART_NUMBER" "TBD"
					( Origin gFrontEnd )
				)
				( attribute "PHYS_PAGE" "25"
					( Origin gFrontEnd )
				)
				( attribute "ROOM" "CPU0"
					( Origin gFrontEnd )
				)
				( attribute "ROT" "0"
					( Origin gFrontEnd )
				)
				( attribute "SEC" "5"
					( Origin gFrontEnd )
				)
				( attribute "SEC_TYPE" "BGA1"
					( Origin gFrontEnd )
				)
				( attribute "VER" "5"
					( Origin gFrontEnd )
				)
				( attribute "XY" "(-4175,2600)"
					( Origin gFrontEnd )
				)
				( attribute "CHIPS_PART_NAME" "SKX_EXT_B"
					( Origin gPackager )
				)
				( attribute "CDS_PART_NAME" "SKX_EXT_B_BGA1-IC,TBD"
					( Origin gPackager )
				)
				( objectStatus "U5D1" )
			)
			( gate "@baseboard_fab2_lib.baseboard_fab2(sch_1):page26_i172"
				( attribute "CDS_LIB" "chpset_lib"
					( Origin gPackager )
				)
				( attribute "CDS_LOCATION" "U5D1"
					( Origin gPackager )
				)
				( attribute "CDS_SEC" "6"
					( Origin gPackager )
				)
				( attribute "LOCATION" "U5D1"
					( Origin gFrontEnd )
				)
				( attribute "MATERIAL" "IC"
					( Origin gFrontEnd )
				)
				( attribute "PACK_TYPE" "BGA1"
					( Origin gFrontEnd )
				)
				( attribute "PART_NUMBER" "TBD"
					( Origin gFrontEnd )
				)
				( attribute "PHYS_PAGE" "26"
					( Origin gFrontEnd )
				)
				( attribute "ROOM" "CPU0"
					( Origin gFrontEnd )
				)
				( attribute "ROT" "0"
					( Origin gFrontEnd )
				)
				( attribute "SEC" "6"
					( Origin gFrontEnd )
				)
				( attribute "SEC_TYPE" "BGA1"
					( Origin gFrontEnd )
				)
				( attribute "VER" "6"
					( Origin gFrontEnd )
				)
				( attribute "XY" "(-4100,2575)"
					( Origin gFrontEnd )
				)
				( attribute "CHIPS_PART_NAME" "SKX_EXT_B"
					( Origin gPackager )
				)
				( attribute "CDS_PART_NAME" "SKX_EXT_B_BGA1-IC,TBD"
					( Origin gPackager )
				)
				( objectStatus "U5D1" )
			)
			( gate "@baseboard_fab2_lib.baseboard_fab2(sch_1):page27_i172"
				( attribute "CDS_LIB" "chpset_lib"
					( Origin gPackager )
				)
				( attribute "CDS_LOCATION" "U5D1"
					( Origin gPackager )
				)
				( attribute "CDS_SEC" "7"
					( Origin gPackager )
				)
				( attribute "LOCATION" "U5D1"
					( Origin gFrontEnd )
				)
				( attribute "MATERIAL" "IC"
					( Origin gFrontEnd )
				)
				( attribute "PACK_TYPE" "BGA1"
					( Origin gFrontEnd )
				)
				( attribute "PART_NUMBER" "TBD"
					( Origin gFrontEnd )
				)
				( attribute "PHYS_PAGE" "27"
					( Origin gFrontEnd )
				)
				( attribute "ROOM" "CPU0"
					( Origin gFrontEnd )
				)
				( attribute "ROT" "0"
					( Origin gFrontEnd )
				)
				( attribute "SEC" "7"
					( Origin gFrontEnd )
				)
				( attribute "SEC_TYPE" "BGA1"
					( Origin gFrontEnd )
				)
				( attribute "VER" "7"
					( Origin gFrontEnd )
				)
				( attribute "XY" "(-4175,2550)"
					( Origin gFrontEnd )
				)
				( attribute "CHIPS_PART_NAME" "SKX_EXT_B"
					( Origin gPackager )
				)
				( attribute "CDS_PART_NAME" "SKX_EXT_B_BGA1-IC,TBD"
					( Origin gPackager )
				)
				( objectStatus "U5D1" )
			)
			( gate "@baseboard_fab2_lib.baseboard_fab2(sch_1):page28_i172"
				( attribute "CDS_LIB" "chpset_lib"
					( Origin gPackager )
				)
				( attribute "CDS_LOCATION" "U5D1"
					( Origin gPackager )
				)
				( attribute "CDS_SEC" "8"
					( Origin gPackager )
				)
				( attribute "LOCATION" "U5D1"
					( Origin gFrontEnd )
				)
				( attribute "MATERIAL" "IC"
					( Origin gFrontEnd )
				)
				( attribute "PACK_TYPE" "BGA1"
					( Origin gFrontEnd )
				)
				( attribute "PART_NUMBER" "TBD"
					( Origin gFrontEnd )
				)
				( attribute "PHYS_PAGE" "28"
					( Origin gFrontEnd )
				)
				( attribute "ROOM" "CPU0"
					( Origin gFrontEnd )
				)
				( attribute "ROT" "0"
					( Origin gFrontEnd )
				)
				( attribute "SEC" "8"
					( Origin gFrontEnd )
				)
				( attribute "SEC_TYPE" "BGA1"
					( Origin gFrontEnd )
				)
				( attribute "VER" "8"
					( Origin gFrontEnd )
				)
				( attribute "XY" "(-4175,2575)"
					( Origin gFrontEnd )
				)
				( attribute "CHIPS_PART_NAME" "SKX_EXT_B"
					( Origin gPackager )
				)
				( attribute "CDS_PART_NAME" "SKX_EXT_B_BGA1-IC,TBD"
					( Origin gPackager )
				)
				( objectStatus "U5D1" )
			)
			( gate "@baseboard_fab2_lib.baseboard_fab2(sch_1):page29_i61"
				( attribute "CDS_LIB" "chpset_lib"
					( Origin gPackager )
				)
				( attribute "CDS_LOCATION" "U5D1"
					( Origin gPackager )
				)
				( attribute "CDS_SEC" "9"
					( Origin gPackager )
				)
				( attribute "LOCATION" "U5D1"
					( Origin gFrontEnd )
				)
				( attribute "MATERIAL" "IC"
					( Origin gFrontEnd )
				)
				( attribute "PACK_TYPE" "BGA1"
					( Origin gFrontEnd )
				)
				( attribute "PART_NUMBER" "TBD"
					( Origin gFrontEnd )
				)
				( attribute "PHYS_PAGE" "29"
					( Origin gFrontEnd )
				)
				( attribute "ROOM" "CPU0"
					( Origin gFrontEnd )
				)
				( attribute "ROT" "0"
					( Origin gFrontEnd )
				)
				( attribute "SEC" "9"
					( Origin gFrontEnd )
				)
				( attribute "SEC_TYPE" "BGA1"
					( Origin gFrontEnd )
				)
				( attribute "VER" "9"
					( Origin gFrontEnd )
				)
				( attribute "XY" "(-3900,2550)"
					( Origin gFrontEnd )
				)
				( attribute "CHIPS_PART_NAME" "SKX_EXT_B"
					( Origin gPackager )
				)
				( attribute "CDS_PART_NAME" "SKX_EXT_B_BGA1-IC,TBD"
					( Origin gPackager )
				)
				( objectStatus "U5D1" )
			)
			( gate "@baseboard_fab2_lib.baseboard_fab2(sch_1):page30_i84"
				( attribute "CDS_LIB" "chpset_lib"
					( Origin gPackager )
				)
				( attribute "CDS_LOCATION" "U5D1"
					( Origin gPackager )
				)
				( attribute "CDS_SEC" "10"
					( Origin gPackager )
				)
				( attribute "LOCATION" "U5D1"
					( Origin gFrontEnd )
				)
				( attribute "MATERIAL" "IC"
					( Origin gFrontEnd )
				)
				( attribute "PACK_TYPE" "BGA1"
					( Origin gFrontEnd )
				)
				( attribute "PART_NUMBER" "TBD"
					( Origin gFrontEnd )
				)
				( attribute "PHYS_PAGE" "30"
					( Origin gFrontEnd )
				)
				( attribute "ROOM" "CPU0"
					( Origin gFrontEnd )
				)
				( attribute "ROT" "0"
					( Origin gFrontEnd )
				)
				( attribute "SEC" "10"
					( Origin gFrontEnd )
				)
				( attribute "SEC_TYPE" "BGA1"
					( Origin gFrontEnd )
				)
				( attribute "VER" "10"
					( Origin gFrontEnd )
				)
				( attribute "XY" "(-4100,2550)"
					( Origin gFrontEnd )
				)
				( attribute "CHIPS_PART_NAME" "SKX_EXT_B"
					( Origin gPackager )
				)
				( attribute "CDS_PART_NAME" "SKX_EXT_B_BGA1-IC,TBD"
					( Origin gPackager )
				)
				( objectStatus "U5D1" )
			)
			( gate "@baseboard_fab2_lib.baseboard_fab2(sch_1):page31_i106"
				( attribute "CDS_LIB" "chpset_lib"
					( Origin gPackager )
				)
				( attribute "CDS_LOCATION" "U5D1"
					( Origin gPackager )
				)
				( attribute "CDS_SEC" "11"
					( Origin gPackager )
				)
				( attribute "LOCATION" "U5D1"
					( Origin gFrontEnd )
				)
				( attribute "MATERIAL" "IC"
					( Origin gFrontEnd )
				)
				( attribute "PACK_TYPE" "BGA1"
					( Origin gFrontEnd )
				)
				( attribute "PART_NUMBER" "TBD"
					( Origin gFrontEnd )
				)
				( attribute "PHYS_PAGE" "31"
					( Origin gFrontEnd )
				)
				( attribute "ROOM" "CPU0"
					( Origin gFrontEnd )
				)
				( attribute "ROT" "0"
					( Origin gFrontEnd )
				)
				( attribute "SEC" "11"
					( Origin gFrontEnd )
				)
				( attribute "SEC_TYPE" "BGA1"
					( Origin gFrontEnd )
				)
				( attribute "VER" "11"
					( Origin gFrontEnd )
				)
				( attribute "XY" "(-4025,2600)"
					( Origin gFrontEnd )
				)
				( attribute "CHIPS_PART_NAME" "SKX_EXT_B"
					( Origin gPackager )
				)
				( attribute "CDS_PART_NAME" "SKX_EXT_B_BGA1-IC,TBD"
					( Origin gPackager )
				)
				( objectStatus "U5D1" )
			)
			( gate "@baseboard_fab2_lib.baseboard_fab2(sch_1):page32_i89"
				( attribute "CDS_LIB" "chpset_lib"
					( Origin gPackager )
				)
				( attribute "CDS_LOCATION" "U5D1"
					( Origin gPackager )
				)
				( attribute "CDS_SEC" "12"
					( Origin gPackager )
				)
				( attribute "LOCATION" "U5D1"
					( Origin gFrontEnd )
				)
				( attribute "MATERIAL" "IC"
					( Origin gFrontEnd )
				)
				( attribute "PACK_TYPE" "BGA1"
					( Origin gFrontEnd )
				)
				( attribute "PART_NUMBER" "TBD"
					( Origin gFrontEnd )
				)
				( attribute "PHYS_PAGE" "32"
					( Origin gFrontEnd )
				)
				( attribute "ROT" "0"
					( Origin gFrontEnd )
				)
				( attribute "SEC" "12"
					( Origin gFrontEnd )
				)
				( attribute "SEC_TYPE" "BGA1"
					( Origin gFrontEnd )
				)
				( attribute "VER" "12"
					( Origin gFrontEnd )
				)
				( attribute "XY" "(-4200,2575)"
					( Origin gFrontEnd )
				)
				( attribute "CHIPS_PART_NAME" "SKX_EXT_B"
					( Origin gPackager )
				)
				( attribute "CDS_PART_NAME" "SKX_EXT_B_BGA1-IC,TBD"
					( Origin gPackager )
				)
				( objectStatus "U5D1" )
			)
			( gate "@baseboard_fab2_lib.baseboard_fab2(sch_1):page33_i86"
				( attribute "CDS_LIB" "chpset_lib"
					( Origin gPackager )
				)
				( attribute "CDS_LOCATION" "U5D1"
					( Origin gPackager )
				)
				( attribute "CDS_SEC" "13"
					( Origin gPackager )
				)
				( attribute "LOCATION" "U5D1"
					( Origin gFrontEnd )
				)
				( attribute "MATERIAL" "IC"
					( Origin gFrontEnd )
				)
				( attribute "PACK_TYPE" "BGA1"
					( Origin gFrontEnd )
				)
				( attribute "PART_NUMBER" "TBD"
					( Origin gFrontEnd )
				)
				( attribute "PHYS_PAGE" "33"
					( Origin gFrontEnd )
				)
				( attribute "ROOM" "CPU0"
					( Origin gFrontEnd )
				)
				( attribute "ROT" "0"
					( Origin gFrontEnd )
				)
				( attribute "SEC" "13"
					( Origin gFrontEnd )
				)
				( attribute "SEC_TYPE" "BGA1"
					( Origin gFrontEnd )
				)
				( attribute "VER" "13"
					( Origin gFrontEnd )
				)
				( attribute "XY" "(-4075,2600)"
					( Origin gFrontEnd )
				)
				( attribute "CHIPS_PART_NAME" "SKX_EXT_B"
					( Origin gPackager )
				)
				( attribute "CDS_PART_NAME" "SKX_EXT_B_BGA1-IC,TBD"
					( Origin gPackager )
				)
				( objectStatus "U5D1" )
			)
			( gate "@baseboard_fab2_lib.baseboard_fab2(sch_1):page34_i86"
				( attribute "CDS_LIB" "chpset_lib"
					( Origin gPackager )
				)
				( attribute "CDS_LOCATION" "U5D1"
					( Origin gPackager )
				)
				( attribute "CDS_SEC" "14"
					( Origin gPackager )
				)
				( attribute "LOCATION" "U5D1"
					( Origin gFrontEnd )
				)
				( attribute "MATERIAL" "IC"
					( Origin gFrontEnd )
				)
				( attribute "PACK_TYPE" "BGA1"
					( Origin gFrontEnd )
				)
				( attribute "PART_NUMBER" "TBD"
					( Origin gFrontEnd )
				)
				( attribute "PHYS_PAGE" "34"
					( Origin gFrontEnd )
				)
				( attribute "ROOM" "CPU0"
					( Origin gFrontEnd )
				)
				( attribute "ROT" "0"
					( Origin gFrontEnd )
				)
				( attribute "SEC" "14"
					( Origin gFrontEnd )
				)
				( attribute "SEC_TYPE" "BGA1"
					( Origin gFrontEnd )
				)
				( attribute "VER" "14"
					( Origin gFrontEnd )
				)
				( attribute "XY" "(-4100,2575)"
					( Origin gFrontEnd )
				)
				( attribute "CHIPS_PART_NAME" "SKX_EXT_B"
					( Origin gPackager )
				)
				( attribute "CDS_PART_NAME" "SKX_EXT_B_BGA1-IC,TBD"
					( Origin gPackager )
				)
				( objectStatus "U5D1" )
			)
			( gate "@baseboard_fab2_lib.baseboard_fab2(sch_1):page35_i3"
				( attribute "CDS_LIB" "chpset_lib"
					( Origin gPackager )
				)
				( attribute "CDS_LOCATION" "U5D1"
					( Origin gPackager )
				)
				( attribute "CDS_SEC" "15"
					( Origin gPackager )
				)
				( attribute "LOCATION" "U5D1"
					( Origin gFrontEnd )
				)
				( attribute "MATERIAL" "IC"
					( Origin gFrontEnd )
				)
				( attribute "PACK_TYPE" "BGA1"
					( Origin gFrontEnd )
				)
				( attribute "PART_NUMBER" "TBD"
					( Origin gFrontEnd )
				)
				( attribute "PHYS_PAGE" "35"
					( Origin gFrontEnd )
				)
				( attribute "ROOM" "CPU0"
					( Origin gFrontEnd )
				)
				( attribute "ROT" "0"
					( Origin gFrontEnd )
				)
				( attribute "SEC" "15"
					( Origin gFrontEnd )
				)
				( attribute "SEC_TYPE" "BGA1"
					( Origin gFrontEnd )
				)
				( attribute "VER" "15"
					( Origin gFrontEnd )
				)
				( attribute "XY" "(-4225,2625)"
					( Origin gFrontEnd )
				)
				( attribute "CHIPS_PART_NAME" "SKX_EXT_B"
					( Origin gPackager )
				)
				( attribute "CDS_PART_NAME" "SKX_EXT_B_BGA1-IC,TBD"
					( Origin gPackager )
				)
				( objectStatus "U5D1" )
			)
			( gate "@baseboard_fab2_lib.baseboard_fab2(sch_1):page36_i15"
				( attribute "CDS_LIB" "chpset_lib"
					( Origin gPackager )
				)
				( attribute "CDS_LOCATION" "U5D1"
					( Origin gPackager )
				)
				( attribute "CDS_SEC" "16"
					( Origin gPackager )
				)
				( attribute "LOCATION" "U5D1"
					( Origin gFrontEnd )
				)
				( attribute "MATERIAL" "IC"
					( Origin gFrontEnd )
				)
				( attribute "PACK_TYPE" "BGA1"
					( Origin gFrontEnd )
				)
				( attribute "PART_NUMBER" "TBD"
					( Origin gFrontEnd )
				)
				( attribute "PHYS_PAGE" "36"
					( Origin gFrontEnd )
				)
				( attribute "ROOM" "CPU0"
					( Origin gFrontEnd )
				)
				( attribute "ROT" "0"
					( Origin gFrontEnd )
				)
				( attribute "SEC" "16"
					( Origin gFrontEnd )
				)
				( attribute "SEC_TYPE" "BGA1"
					( Origin gFrontEnd )
				)
				( attribute "VER" "16"
					( Origin gFrontEnd )
				)
				( attribute "XY" "(-6075,2550)"
					( Origin gFrontEnd )
				)
				( attribute "CHIPS_PART_NAME" "SKX_EXT_B"
					( Origin gPackager )
				)
				( attribute "CDS_PART_NAME" "SKX_EXT_B_BGA1-IC,TBD"
					( Origin gPackager )
				)
				( objectStatus "U5D1" )
			)
			( gate "@baseboard_fab2_lib.baseboard_fab2(sch_1):page36_i16"
				( attribute "CDS_LIB" "chpset_lib"
					( Origin gPackager )
				)
				( attribute "CDS_LOCATION" "U5D1"
					( Origin gPackager )
				)
				( attribute "CDS_SEC" "17"
					( Origin gPackager )
				)
				( attribute "LOCATION" "U5D1"
					( Origin gFrontEnd )
				)
				( attribute "MATERIAL" "IC"
					( Origin gFrontEnd )
				)
				( attribute "PACK_TYPE" "BGA1"
					( Origin gFrontEnd )
				)
				( attribute "PART_NUMBER" "TBD"
					( Origin gFrontEnd )
				)
				( attribute "PHYS_PAGE" "36"
					( Origin gFrontEnd )
				)
				( attribute "ROOM" "CPU0"
					( Origin gFrontEnd )
				)
				( attribute "ROT" "0"
					( Origin gFrontEnd )
				)
				( attribute "SEC" "17"
					( Origin gFrontEnd )
				)
				( attribute "SEC_TYPE" "BGA1"
					( Origin gFrontEnd )
				)
				( attribute "VER" "17"
					( Origin gFrontEnd )
				)
				( attribute "XY" "(-2550,2525)"
					( Origin gFrontEnd )
				)
				( attribute "CHIPS_PART_NAME" "SKX_EXT_B"
					( Origin gPackager )
				)
				( attribute "CDS_PART_NAME" "SKX_EXT_B_BGA1-IC,TBD"
					( Origin gPackager )
				)
				( objectStatus "U5D1" )
			)
			( gate "@baseboard_fab2_lib.baseboard_fab2(sch_1):page37_i303"
				( attribute "BOM_COST" "PROC_SOCKET"
					( Origin gFrontEnd )
				)
				( attribute "CDS_LIB" "mstr_discrete"
					( Origin gPackager )
				)
				( attribute "CDS_LOCATION" "R5D5"
					( Origin gPackager )
				)
				( attribute "CDS_SEC" "1"
					( Origin gPackager )
				)
				( attribute "LOCATION" "R5D5"
					( Origin gFrontEnd )
				)
				( attribute "MATERIAL" "CHIP"
					( Origin gFrontEnd )
				)
				( attribute "PACK_TYPE" "0402"
					( Origin gFrontEnd )
				)
				( attribute "PART_NUMBER" "G85996-031"
					( Origin gFrontEnd )
				)
				( attribute "PHYS_PAGE" "37"
					( Origin gFrontEnd )
				)
				( attribute "ROOM" "CPU0"
					( Origin gFrontEnd )
				)
				( attribute "ROT" "0"
					( Origin gFrontEnd )
				)
				( attribute "SEC" "1"
					( Origin gFrontEnd )
				)
				( attribute "SEC_TYPE" "0402"
					( Origin gFrontEnd )
				)
				( attribute "TOLERANCE" "0.1%"
					( Origin gFrontEnd )
				)
				( attribute "VALUE" "249"
					( Origin gFrontEnd )
				)
				( attribute "VER" "2"
					( Origin gFrontEnd )
				)
				( attribute "WATTAGE" "1/16W"
					( Origin gFrontEnd )
				)
				( attribute "XY" "(-375,750)"
					( Origin gFrontEnd )
				)
				( attribute "CHIPS_PART_NAME" "RES"
					( Origin gPackager )
				)
				( attribute "CDS_PART_NAME" "RES_0402-249,0.1%,1/16W,CHIP,GA"
					( Origin gPackager )
				)
				( objectStatus "R5D5" )
			)
			( gate "@baseboard_fab2_lib.baseboard_fab2(sch_1):page37_i309"
				( attribute "BOM_COST" "PROC_SOCKET"
					( Origin gFrontEnd )
				)
				( attribute "CDS_LIB" "mstr_discrete"
					( Origin gPackager )
				)
				( attribute "CDS_LOCATION" "R5P1"
					( Origin gPackager )
				)
				( attribute "CDS_SEC" "1"
					( Origin gPackager )
				)
				( attribute "LOCATION" "R5P1"
					( Origin gFrontEnd )
				)
				( attribute "MATERIAL" "CHIP"
					( Origin gFrontEnd )
				)
				( attribute "PACK_TYPE" "0603"
					( Origin gFrontEnd )
				)
				( attribute "PART_NUMBER" "G22026-050"
					( Origin gFrontEnd )
				)
				( attribute "PHYS_PAGE" "37"
					( Origin gFrontEnd )
				)
				( attribute "ROOM" "CPU0"
					( Origin gFrontEnd )
				)
				( attribute "ROT" "0"
					( Origin gFrontEnd )
				)
				( attribute "SEC" "1"
					( Origin gFrontEnd )
				)
				( attribute "SEC_TYPE" "0603"
					( Origin gFrontEnd )
				)
				( attribute "TOLERANCE" "1%"
					( Origin gFrontEnd )
				)
				( attribute "VALUE" "100.0K"
					( Origin gFrontEnd )
				)
				( attribute "VER" "2"
					( Origin gFrontEnd )
				)
				( attribute "WATTAGE" "1/10W"
					( Origin gFrontEnd )
				)
				( attribute "XY" "(-775,1350)"
					( Origin gFrontEnd )
				)
				( attribute "CHIPS_PART_NAME" "RES"
					( Origin gPackager )
				)
				( attribute "CDS_PART_NAME" "RES_0603-100.0K,1%,1/10W,CHIP,A"
					( Origin gPackager )
				)
				( objectStatus "R5P1" )
			)
			( gate "@baseboard_fab2_lib.baseboard_fab2(sch_1):page37_i310"
				( attribute "CDS_LIB" "chpset_lib"
					( Origin gPackager )
				)
				( attribute "CDS_LOCATION" "U5D1"
					( Origin gPackager )
				)
				( attribute "CDS_SEC" "18"
					( Origin gPackager )
				)
				( attribute "LOCATION" "U5D1"
					( Origin gFrontEnd )
				)
				( attribute "MATERIAL" "IC"
					( Origin gFrontEnd )
				)
				( attribute "PACK_TYPE" "BGA1"
					( Origin gFrontEnd )
				)
				( attribute "PART_NUMBER" "TBD"
					( Origin gFrontEnd )
				)
				( attribute "PHYS_PAGE" "37"
					( Origin gFrontEnd )
				)
				( attribute "ROOM" "CPU0"
					( Origin gFrontEnd )
				)
				( attribute "ROT" "0"
					( Origin gFrontEnd )
				)
				( attribute "SEC" "18"
					( Origin gFrontEnd )
				)
				( attribute "SEC_TYPE" "BGA1"
					( Origin gFrontEnd )
				)
				( attribute "VER" "18"
					( Origin gFrontEnd )
				)
				( attribute "XY" "(-6200,2475)"
					( Origin gFrontEnd )
				)
				( attribute "CHIPS_PART_NAME" "SKX_EXT_B"
					( Origin gPackager )
				)
				( attribute "CDS_PART_NAME" "SKX_EXT_B_BGA1-IC,TBD"
					( Origin gPackager )
				)
				( objectStatus "U5D1" )
			)
			( gate "@baseboard_fab2_lib.baseboard_fab2(sch_1):page37_i311"
				( attribute "CDS_LIB" "chpset_lib"
					( Origin gPackager )
				)
				( attribute "CDS_LOCATION" "U5D1"
					( Origin gPackager )
				)
				( attribute "CDS_SEC" "19"
					( Origin gPackager )
				)
				( attribute "LOCATION" "U5D1"
					( Origin gFrontEnd )
				)
				( attribute "MATERIAL" "IC"
					( Origin gFrontEnd )
				)
				( attribute "PACK_TYPE" "BGA1"
					( Origin gFrontEnd )
				)
				( attribute "PART_NUMBER" "TBD"
					( Origin gFrontEnd )
				)
				( attribute "PHYS_PAGE" "37"
					( Origin gFrontEnd )
				)
				( attribute "ROOM" "CPU0"
					( Origin gFrontEnd )
				)
				( attribute "ROT" "0"
					( Origin gFrontEnd )
				)
				( attribute "SEC" "19"
					( Origin gFrontEnd )
				)
				( attribute "SEC_TYPE" "BGA1"
					( Origin gFrontEnd )
				)
				( attribute "VER" "19"
					( Origin gFrontEnd )
				)
				( attribute "XY" "(-2425,2475)"
					( Origin gFrontEnd )
				)
				( attribute "CHIPS_PART_NAME" "SKX_EXT_B"
					( Origin gPackager )
				)
				( attribute "CDS_PART_NAME" "SKX_EXT_B_BGA1-IC,TBD"
					( Origin gPackager )
				)
				( objectStatus "U5D1" )
			)
			( gate "@baseboard_fab2_lib.baseboard_fab2(sch_1):page37_i312"
				( attribute "CDS_LIB" "mstr_discrete"
					( Origin gPackager )
				)
				( attribute "CDS_LOCATION" "R5D6"
					( Origin gPackager )
				)
				( attribute "CDS_SEC" "1"
					( Origin gPackager )
				)
				( attribute "LOCATION" "R5D6"
					( Origin gFrontEnd )
				)
				( attribute "MATERIAL" "EMPTY"
					( Origin gFrontEnd )
				)
				( attribute "PACK_TYPE" "0402"
					( Origin gFrontEnd )
				)
				( attribute "PART_NUMBER" "G21796-066"
					( Origin gFrontEnd )
				)
				( attribute "PHYS_PAGE" "37"
					( Origin gFrontEnd )
				)
				( attribute "ROOM" "CPU0"
					( Origin gFrontEnd )
				)
				( attribute "ROT" "0"
					( Origin gFrontEnd )
				)
				( attribute "SEC" "1"
					( Origin gFrontEnd )
				)
				( attribute "SEC_TYPE" "0402"
					( Origin gFrontEnd )
				)
				( attribute "TOLERANCE" "1%"
					( Origin gFrontEnd )
				)
				( attribute "VALUE" "10.0"
					( Origin gFrontEnd )
				)
				( attribute "VER" "2"
					( Origin gFrontEnd )
				)
				( attribute "WATTAGE" "1/16W"
					( Origin gFrontEnd )
				)
				( attribute "XY" "(-375,1125)"
					( Origin gFrontEnd )
				)
				( attribute "CHIPS_PART_NAME" "RES"
					( Origin gPackager )
				)
				( attribute "CDS_PART_NAME" "RES_0402-10.0,1%,1/16W,EMPTY,GA"
					( Origin gPackager )
				)
				( objectStatus "R5D6" )
			)
			( gate "@baseboard_fab2_lib.baseboard_fab2(sch_1):page38_i19"
				( attribute "BOM_COST" "PROC_SOCKET"
					( Origin gFrontEnd )
				)
				( attribute "CDS_LIB" "mstr_discrete"
					( Origin gPackager )
				)
				( attribute "CDS_LOCATION" "C6D1"
					( Origin gPackager )
				)
				( attribute "CDS_SEC" "1"
					( Origin gPackager )
				)
				( attribute "LOCATION" "C6D1"
					( Origin gFrontEnd )
				)
				( attribute "MATERIAL" "X6S"
					( Origin gFrontEnd )
				)
				( attribute "PACK_TYPE" "0603LF"
					( Origin gFrontEnd )
				)
				( attribute "PART_NUMBER" "E15431-001"
					( Origin gFrontEnd )
				)
				( attribute "PHYS_PAGE" "38"
					( Origin gFrontEnd )
				)
				( attribute "ROOM" "CPU0"
					( Origin gFrontEnd )
				)
				( attribute "ROT" "0"
					( Origin gFrontEnd )
				)
				( attribute "SEC" "1"
					( Origin gFrontEnd )
				)
				( attribute "SEC_TYPE" "0603LF"
					( Origin gFrontEnd )
				)
				( attribute "TOLERANCE" "20%"
					( Origin gFrontEnd )
				)
				( attribute "VALUE" "10UF"
					( Origin gFrontEnd )
				)
				( attribute "VER" "1"
					( Origin gFrontEnd )
				)
				( attribute "VOLTAGE" "4V"
					( Units "uVoltage" "V" 1.000000)
					( Origin gFrontEnd )
				)
				( attribute "XY" "(3000,1350)"
					( Origin gFrontEnd )
				)
				( attribute "CHIPS_PART_NAME" "CAP"
					( Origin gPackager )
				)
				( attribute "CDS_PART_NAME" "CAP_0603LF-10UF,4V,20%,X6S,E15A"
					( Origin gPackager )
				)
				( attribute "GROUP" "PWR_MCP_CAP"
					( Origin gFrontEnd )
				)
				( objectStatus "C6D1" )
			)
			( gate "@baseboard_fab2_lib.baseboard_fab2(sch_1):page38_i33"
				( attribute "CDS_LIB" "chpset_lib"
					( Origin gPackager )
				)
				( attribute "CDS_LOCATION" "U5D1"
					( Origin gPackager )
				)
				( attribute "CDS_SEC" "20"
					( Origin gPackager )
				)
				( attribute "LOCATION" "U5D1"
					( Origin gFrontEnd )
				)
				( attribute "MATERIAL" "IC"
					( Origin gFrontEnd )
				)
				( attribute "PACK_TYPE" "BGA1"
					( Origin gFrontEnd )
				)
				( attribute "PART_NUMBER" "TBD"
					( Origin gFrontEnd )
				)
				( attribute "PHYS_PAGE" "38"
					( Origin gFrontEnd )
				)
				( attribute "ROOM" "CPU0"
					( Origin gFrontEnd )
				)
				( attribute "ROT" "0"
					( Origin gFrontEnd )
				)
				( attribute "SEC" "20"
					( Origin gFrontEnd )
				)
				( attribute "SEC_TYPE" "BGA1"
					( Origin gFrontEnd )
				)
				( attribute "VER" "20"
					( Origin gFrontEnd )
				)
				( attribute "XY" "(-1950,2650)"
					( Origin gFrontEnd )
				)
				( attribute "CHIPS_PART_NAME" "SKX_EXT_B"
					( Origin gPackager )
				)
				( attribute "CDS_PART_NAME" "SKX_EXT_B_BGA1-IC,TBD"
					( Origin gPackager )
				)
				( objectStatus "U5D1" )
			)
			( gate "@baseboard_fab2_lib.baseboard_fab2(sch_1):page38_i34"
				( attribute "CDS_LIB" "chpset_lib"
					( Origin gPackager )
				)
				( attribute "CDS_LOCATION" "U5D1"
					( Origin gPackager )
				)
				( attribute "CDS_SEC" "21"
					( Origin gPackager )
				)
				( attribute "LOCATION" "U5D1"
					( Origin gFrontEnd )
				)
				( attribute "MATERIAL" "IC"
					( Origin gFrontEnd )
				)
				( attribute "PACK_TYPE" "BGA1"
					( Origin gFrontEnd )
				)
				( attribute "PART_NUMBER" "TBD"
					( Origin gFrontEnd )
				)
				( attribute "PHYS_PAGE" "38"
					( Origin gFrontEnd )
				)
				( attribute "ROOM" "CPU0"
					( Origin gFrontEnd )
				)
				( attribute "ROT" "0"
					( Origin gFrontEnd )
				)
				( attribute "SEC" "21"
					( Origin gFrontEnd )
				)
				( attribute "SEC_TYPE" "BGA1"
					( Origin gFrontEnd )
				)
				( attribute "VER" "21"
					( Origin gFrontEnd )
				)
				( attribute "XY" "(1050,2725)"
					( Origin gFrontEnd )
				)
				( attribute "CHIPS_PART_NAME" "SKX_EXT_B"
					( Origin gPackager )
				)
				( attribute "CDS_PART_NAME" "SKX_EXT_B_BGA1-IC,TBD"
					( Origin gPackager )
				)
				( objectStatus "U5D1" )
			)
			( gate "@baseboard_fab2_lib.baseboard_fab2(sch_1):page39_i127"
				( attribute "CDS_LIB" "chpset_lib"
					( Origin gPackager )
				)
				( attribute "CDS_LOCATION" "U5D1"
					( Origin gPackager )
				)
				( attribute "CDS_SEC" "22"
					( Origin gPackager )
				)
				( attribute "LOCATION" "U5D1"
					( Origin gFrontEnd )
				)
				( attribute "MATERIAL" "IC"
					( Origin gFrontEnd )
				)
				( attribute "PACK_TYPE" "BGA1"
					( Origin gFrontEnd )
				)
				( attribute "PART_NUMBER" "TBD"
					( Origin gFrontEnd )
				)
				( attribute "PHYS_PAGE" "39"
					( Origin gFrontEnd )
				)
				( attribute "ROOM" "CPU0"
					( Origin gFrontEnd )
				)
				( attribute "ROT" "0"
					( Origin gFrontEnd )
				)
				( attribute "SEC" "22"
					( Origin gFrontEnd )
				)
				( attribute "SEC_TYPE" "BGA1"
					( Origin gFrontEnd )
				)
				( attribute "VER" "22"
					( Origin gFrontEnd )
				)
				( attribute "XY" "(-4250,2550)"
					( Origin gFrontEnd )
				)
				( attribute "CHIPS_PART_NAME" "SKX_EXT_B"
					( Origin gPackager )
				)
				( attribute "CDS_PART_NAME" "SKX_EXT_B_BGA1-IC,TBD"
					( Origin gPackager )
				)
				( objectStatus "U5D1" )
			)
			( gate "@baseboard_fab2_lib.baseboard_fab2(sch_1):page40_i20"
				( attribute "CDS_LIB" "chpset_lib"
					( Origin gPackager )
				)
				( attribute "CDS_LOCATION" "U5D1"
					( Origin gPackager )
				)
				( attribute "CDS_SEC" "23"
					( Origin gPackager )
				)
				( attribute "LOCATION" "U5D1"
					( Origin gFrontEnd )
				)
				( attribute "MATERIAL" "IC"
					( Origin gFrontEnd )
				)
				( attribute "PACK_TYPE" "BGA1"
					( Origin gFrontEnd )
				)
				( attribute "PART_NUMBER" "TBD"
					( Origin gFrontEnd )
				)
				( attribute "PHYS_PAGE" "40"
					( Origin gFrontEnd )
				)
				( attribute "ROOM" "CPU0"
					( Origin gFrontEnd )
				)
				( attribute "ROT" "0"
					( Origin gFrontEnd )
				)
				( attribute "SEC" "23"
					( Origin gFrontEnd )
				)
				( attribute "SEC_TYPE" "BGA1"
					( Origin gFrontEnd )
				)
				( attribute "VER" "23"
					( Origin gFrontEnd )
				)
				( attribute "XY" "(-7050,2575)"
					( Origin gFrontEnd )
				)
				( attribute "CHIPS_PART_NAME" "SKX_EXT_B"
					( Origin gPackager )
				)
				( attribute "CDS_PART_NAME" "SKX_EXT_B_BGA1-IC,TBD"
					( Origin gPackager )
				)
				( objectStatus "U5D1" )
			)
			( gate "@baseboard_fab2_lib.baseboard_fab2(sch_1):page40_i21"
				( attribute "CDS_LIB" "chpset_lib"
					( Origin gPackager )
				)
				( attribute "CDS_LOCATION" "U5D1"
					( Origin gPackager )
				)
				( attribute "CDS_SEC" "24"
					( Origin gPackager )
				)
				( attribute "LOCATION" "U5D1"
					( Origin gFrontEnd )
				)
				( attribute "MATERIAL" "IC"
					( Origin gFrontEnd )
				)
				( attribute "PACK_TYPE" "BGA1"
					( Origin gFrontEnd )
				)
				( attribute "PART_NUMBER" "TBD"
					( Origin gFrontEnd )
				)
				( attribute "PHYS_PAGE" "40"
					( Origin gFrontEnd )
				)
				( attribute "ROOM" "CPU0"
					( Origin gFrontEnd )
				)
				( attribute "ROT" "0"
					( Origin gFrontEnd )
				)
				( attribute "SEC" "24"
					( Origin gFrontEnd )
				)
				( attribute "SEC_TYPE" "BGA1"
					( Origin gFrontEnd )
				)
				( attribute "VER" "24"
					( Origin gFrontEnd )
				)
				( attribute "XY" "(-5225,2575)"
					( Origin gFrontEnd )
				)
				( attribute "CHIPS_PART_NAME" "SKX_EXT_B"
					( Origin gPackager )
				)
				( attribute "CDS_PART_NAME" "SKX_EXT_B_BGA1-IC,TBD"
					( Origin gPackager )
				)
				( objectStatus "U5D1" )
			)
			( gate "@baseboard_fab2_lib.baseboard_fab2(sch_1):page40_i22"
				( attribute "CDS_LIB" "chpset_lib"
					( Origin gPackager )
				)
				( attribute "CDS_LOCATION" "U5D1"
					( Origin gPackager )
				)
				( attribute "CDS_SEC" "25"
					( Origin gPackager )
				)
				( attribute "LOCATION" "U5D1"
					( Origin gFrontEnd )
				)
				( attribute "MATERIAL" "IC"
					( Origin gFrontEnd )
				)
				( attribute "PACK_TYPE" "BGA1"
					( Origin gFrontEnd )
				)
				( attribute "PART_NUMBER" "TBD"
					( Origin gFrontEnd )
				)
				( attribute "PHYS_PAGE" "40"
					( Origin gFrontEnd )
				)
				( attribute "ROOM" "CPU0"
					( Origin gFrontEnd )
				)
				( attribute "ROT" "0"
					( Origin gFrontEnd )
				)
				( attribute "SEC" "25"
					( Origin gFrontEnd )
				)
				( attribute "SEC_TYPE" "BGA1"
					( Origin gFrontEnd )
				)
				( attribute "VER" "25"
					( Origin gFrontEnd )
				)
				( attribute "XY" "(-3400,2575)"
					( Origin gFrontEnd )
				)
				( attribute "CHIPS_PART_NAME" "SKX_EXT_B"
					( Origin gPackager )
				)
				( attribute "CDS_PART_NAME" "SKX_EXT_B_BGA1-IC,TBD"
					( Origin gPackager )
				)
				( objectStatus "U5D1" )
			)
			( gate "@baseboard_fab2_lib.baseboard_fab2(sch_1):page40_i23"
				( attribute "CDS_LIB" "chpset_lib"
					( Origin gPackager )
				)
				( attribute "CDS_LOCATION" "U5D1"
					( Origin gPackager )
				)
				( attribute "CDS_SEC" "26"
					( Origin gPackager )
				)
				( attribute "LOCATION" "U5D1"
					( Origin gFrontEnd )
				)
				( attribute "MATERIAL" "IC"
					( Origin gFrontEnd )
				)
				( attribute "PACK_TYPE" "BGA1"
					( Origin gFrontEnd )
				)
				( attribute "PART_NUMBER" "TBD"
					( Origin gFrontEnd )
				)
				( attribute "PHYS_PAGE" "40"
					( Origin gFrontEnd )
				)
				( attribute "ROOM" "CPU0"
					( Origin gFrontEnd )
				)
				( attribute "ROT" "0"
					( Origin gFrontEnd )
				)
				( attribute "SEC" "26"
					( Origin gFrontEnd )
				)
				( attribute "SEC_TYPE" "BGA1"
					( Origin gFrontEnd )
				)
				( attribute "VER" "26"
					( Origin gFrontEnd )
				)
				( attribute "XY" "(-1550,2575)"
					( Origin gFrontEnd )
				)
				( attribute "CHIPS_PART_NAME" "SKX_EXT_B"
					( Origin gPackager )
				)
				( attribute "CDS_PART_NAME" "SKX_EXT_B_BGA1-IC,TBD"
					( Origin gPackager )
				)
				( objectStatus "U5D1" )
			)
			( gate "@baseboard_fab2_lib.baseboard_fab2(sch_1):page41_i283"
				( attribute "CDS_LIB" "chpset_lib"
					( Origin gPackager )
				)
				( attribute "CDS_LOCATION" "U5D1"
					( Origin gPackager )
				)
				( attribute "CDS_SEC" "27"
					( Origin gPackager )
				)
				( attribute "LOCATION" "U5D1"
					( Origin gFrontEnd )
				)
				( attribute "MATERIAL" "IC"
					( Origin gFrontEnd )
				)
				( attribute "PACK_TYPE" "BGA1"
					( Origin gFrontEnd )
				)
				( attribute "PART_NUMBER" "TBD"
					( Origin gFrontEnd )
				)
				( attribute "PHYS_PAGE" "41"
					( Origin gFrontEnd )
				)
				( attribute "ROOM" "CPU0"
					( Origin gFrontEnd )
				)
				( attribute "ROT" "0"
					( Origin gFrontEnd )
				)
				( attribute "SEC" "27"
					( Origin gFrontEnd )
				)
				( attribute "SEC_TYPE" "BGA1"
					( Origin gFrontEnd )
				)
				( attribute "VER" "27"
					( Origin gFrontEnd )
				)
				( attribute "XY" "(-5275,2650)"
					( Origin gFrontEnd )
				)
				( attribute "CHIPS_PART_NAME" "SKX_EXT_B"
					( Origin gPackager )
				)
				( attribute "CDS_PART_NAME" "SKX_EXT_B_BGA1-IC,TBD"
					( Origin gPackager )
				)
				( objectStatus "U5D1" )
			)
			( gate "@baseboard_fab2_lib.baseboard_fab2(sch_1):page41_i284"
				( attribute "CDS_LIB" "chpset_lib"
					( Origin gPackager )
				)
				( attribute "CDS_LOCATION" "U5D1"
					( Origin gPackager )
				)
				( attribute "CDS_SEC" "28"
					( Origin gPackager )
				)
				( attribute "LOCATION" "U5D1"
					( Origin gFrontEnd )
				)
				( attribute "MATERIAL" "IC"
					( Origin gFrontEnd )
				)
				( attribute "PACK_TYPE" "BGA1"
					( Origin gFrontEnd )
				)
				( attribute "PART_NUMBER" "TBD"
					( Origin gFrontEnd )
				)
				( attribute "PHYS_PAGE" "41"
					( Origin gFrontEnd )
				)
				( attribute "ROOM" "CPU0"
					( Origin gFrontEnd )
				)
				( attribute "ROT" "0"
					( Origin gFrontEnd )
				)
				( attribute "SEC" "28"
					( Origin gFrontEnd )
				)
				( attribute "SEC_TYPE" "BGA1"
					( Origin gFrontEnd )
				)
				( attribute "VER" "28"
					( Origin gFrontEnd )
				)
				( attribute "XY" "(-3575,2650)"
					( Origin gFrontEnd )
				)
				( attribute "CHIPS_PART_NAME" "SKX_EXT_B"
					( Origin gPackager )
				)
				( attribute "CDS_PART_NAME" "SKX_EXT_B_BGA1-IC,TBD"
					( Origin gPackager )
				)
				( objectStatus "U5D1" )
			)
			( gate "@baseboard_fab2_lib.baseboard_fab2(sch_1):page41_i285"
				( attribute "CDS_LIB" "chpset_lib"
					( Origin gPackager )
				)
				( attribute "CDS_LOCATION" "U5D1"
					( Origin gPackager )
				)
				( attribute "CDS_SEC" "29"
					( Origin gPackager )
				)
				( attribute "LOCATION" "U5D1"
					( Origin gFrontEnd )
				)
				( attribute "MATERIAL" "IC"
					( Origin gFrontEnd )
				)
				( attribute "PACK_TYPE" "BGA1"
					( Origin gFrontEnd )
				)
				( attribute "PART_NUMBER" "TBD"
					( Origin gFrontEnd )
				)
				( attribute "PHYS_PAGE" "41"
					( Origin gFrontEnd )
				)
				( attribute "ROOM" "CPU0"
					( Origin gFrontEnd )
				)
				( attribute "ROT" "0"
					( Origin gFrontEnd )
				)
				( attribute "SEC" "29"
					( Origin gFrontEnd )
				)
				( attribute "SEC_TYPE" "BGA1"
					( Origin gFrontEnd )
				)
				( attribute "VER" "29"
					( Origin gFrontEnd )
				)
				( attribute "XY" "(-1850,2600)"
					( Origin gFrontEnd )
				)
				( attribute "CHIPS_PART_NAME" "SKX_EXT_B"
					( Origin gPackager )
				)
				( attribute "CDS_PART_NAME" "SKX_EXT_B_BGA1-IC,TBD"
					( Origin gPackager )
				)
				( objectStatus "U5D1" )
			)
			( gate "@baseboard_fab2_lib.baseboard_fab2(sch_1):page41_i286"
				( attribute "CDS_LIB" "chpset_lib"
					( Origin gPackager )
				)
				( attribute "CDS_LOCATION" "U5D1"
					( Origin gPackager )
				)
				( attribute "CDS_SEC" "30"
					( Origin gPackager )
				)
				( attribute "LOCATION" "U5D1"
					( Origin gFrontEnd )
				)
				( attribute "MATERIAL" "IC"
					( Origin gFrontEnd )
				)
				( attribute "PACK_TYPE" "BGA1"
					( Origin gFrontEnd )
				)
				( attribute "PART_NUMBER" "TBD"
					( Origin gFrontEnd )
				)
				( attribute "PHYS_PAGE" "41"
					( Origin gFrontEnd )
				)
				( attribute "ROOM" "CPU0"
					( Origin gFrontEnd )
				)
				( attribute "ROT" "0"
					( Origin gFrontEnd )
				)
				( attribute "SEC" "30"
					( Origin gFrontEnd )
				)
				( attribute "SEC_TYPE" "BGA1"
					( Origin gFrontEnd )
				)
				( attribute "VER" "30"
					( Origin gFrontEnd )
				)
				( attribute "XY" "(-175,2650)"
					( Origin gFrontEnd )
				)
				( attribute "CHIPS_PART_NAME" "SKX_EXT_B"
					( Origin gPackager )
				)
				( attribute "CDS_PART_NAME" "SKX_EXT_B_BGA1-IC,TBD"
					( Origin gPackager )
				)
				( objectStatus "U5D1" )
			)
			( gate "@baseboard_fab2_lib.baseboard_fab2(sch_1):page42_i10"
				( attribute "BOM_COST" "PROC_SOCKET"
					( Origin gFrontEnd )
				)
				( attribute "CDS_LIB" "mstr_discrete"
					( Origin gPackager )
				)
				( attribute "CDS_LOCATION" "C4P1"
					( Origin gPackager )
				)
				( attribute "CDS_SEC" "1"
					( Origin gPackager )
				)
				( attribute "LOCATION" "C4P1"
					( Origin gFrontEnd )
				)
				( attribute "MATERIAL" "X6S"
					( Origin gFrontEnd )
				)
				( attribute "PACK_TYPE" "0805"
					( Origin gFrontEnd )
				)
				( attribute "PART_NUMBER" "C95333-006"
					( Origin gFrontEnd )
				)
				( attribute "PHYS_PAGE" "42"
					( Origin gFrontEnd )
				)
				( attribute "ROOM" "PVCCIN_CPU0_DECAP_VR"
					( Origin gFrontEnd )
				)
				( attribute "ROT" "0"
					( Origin gFrontEnd )
				)
				( attribute "SEC" "1"
					( Origin gPackager )
				)
				( attribute "TOLERANCE" "20%"
					( Origin gFrontEnd )
				)
				( attribute "VALUE" "47UF"
					( Origin gFrontEnd )
				)
				( attribute "VER" "1"
					( Origin gFrontEnd )
				)
				( attribute "VOLTAGE" "4V"
					( Units "uVoltage" "V" 1.000000)
					( Origin gFrontEnd )
				)
				( attribute "XY" "(-2550,950)"
					( Origin gFrontEnd )
				)
				( attribute "CHIPS_PART_NAME" "CAP"
					( Origin gPackager )
				)
				( attribute "CDS_PART_NAME" "CAP_0805-47UF,4V,20%,X6S,C9533A"
					( Origin gPackager )
				)
				( attribute "GROUP" "PWR_MLCC_CAP"
					( Origin gFrontEnd )
				)
				( objectStatus "C4P1" )
			)
			( gate "@baseboard_fab2_lib.baseboard_fab2(sch_1):page42_i12"
				( attribute "BOM_COST" "PROC_SOCKET"
					( Origin gFrontEnd )
				)
				( attribute "CDS_LIB" "mstr_discrete"
					( Origin gPackager )
				)
				( attribute "CDS_LOCATION" "C4P9"
					( Origin gPackager )
				)
				( attribute "CDS_SEC" "1"
					( Origin gPackager )
				)
				( attribute "LOCATION" "C4P9"
					( Origin gFrontEnd )
				)
				( attribute "MATERIAL" "X6S"
					( Origin gFrontEnd )
				)
				( attribute "PACK_TYPE" "0805"
					( Origin gFrontEnd )
				)
				( attribute "PART_NUMBER" "C95333-006"
					( Origin gFrontEnd )
				)
				( attribute "PHYS_PAGE" "42"
					( Origin gFrontEnd )
				)
				( attribute "ROOM" "PVCCIN_CPU0_DECAP_VR"
					( Origin gFrontEnd )
				)
				( attribute "ROT" "0"
					( Origin gFrontEnd )
				)
				( attribute "SEC" "1"
					( Origin gPackager )
				)
				( attribute "TOLERANCE" "20%"
					( Origin gFrontEnd )
				)
				( attribute "VALUE" "47UF"
					( Origin gFrontEnd )
				)
				( attribute "VER" "1"
					( Origin gFrontEnd )
				)
				( attribute "VOLTAGE" "4V"
					( Units "uVoltage" "V" 1.000000)
					( Origin gFrontEnd )
				)
				( attribute "XY" "(-2850,950)"
					( Origin gFrontEnd )
				)
				( attribute "CHIPS_PART_NAME" "CAP"
					( Origin gPackager )
				)
				( attribute "CDS_PART_NAME" "CAP_0805-47UF,4V,20%,X6S,C9533A"
					( Origin gPackager )
				)
				( attribute "GROUP" "PWR_MLCC_CAP"
					( Origin gFrontEnd )
				)
				( objectStatus "C4P9" )
			)
			( gate "@baseboard_fab2_lib.baseboard_fab2(sch_1):page42_i17"
				( attribute "BOM_COST" "PROC_SOCKET"
					( Origin gFrontEnd )
				)
				( attribute "CDS_LIB" "mstr_discrete"
					( Origin gPackager )
				)
				( attribute "CDS_LOCATION" "C4P10"
					( Origin gPackager )
				)
				( attribute "CDS_SEC" "1"
					( Origin gPackager )
				)
				( attribute "LOCATION" "C4P10"
					( Origin gFrontEnd )
				)
				( attribute "MATERIAL" "X6S"
					( Origin gFrontEnd )
				)
				( attribute "PACK_TYPE" "0805"
					( Origin gFrontEnd )
				)
				( attribute "PART_NUMBER" "C95333-006"
					( Origin gFrontEnd )
				)
				( attribute "PHYS_PAGE" "42"
					( Origin gFrontEnd )
				)
				( attribute "ROOM" "PVCCIN_CPU0_DECAP_VR"
					( Origin gFrontEnd )
				)
				( attribute "ROT" "0"
					( Origin gFrontEnd )
				)
				( attribute "SEC" "1"
					( Origin gPackager )
				)
				( attribute "TOLERANCE" "20%"
					( Origin gFrontEnd )
				)
				( attribute "VALUE" "47UF"
					( Origin gFrontEnd )
				)
				( attribute "VER" "1"
					( Origin gFrontEnd )
				)
				( attribute "VOLTAGE" "4V"
					( Units "uVoltage" "V" 1.000000)
					( Origin gFrontEnd )
				)
				( attribute "XY" "(-3200,950)"
					( Origin gFrontEnd )
				)
				( attribute "CHIPS_PART_NAME" "CAP"
					( Origin gPackager )
				)
				( attribute "CDS_PART_NAME" "CAP_0805-47UF,4V,20%,X6S,C9533A"
					( Origin gPackager )
				)
				( attribute "GROUP" "PWR_MLCC_CAP"
					( Origin gFrontEnd )
				)
				( objectStatus "C4P10" )
			)
			( gate "@baseboard_fab2_lib.baseboard_fab2(sch_1):page76_i246"
				( attribute "BOM_COST" "PROC_SOCKET"
					( Origin gFrontEnd )
				)
				( attribute "CDS_LIB" "mstr_discrete"
					( Origin gPackager )
				)
				( attribute "CDS_LOCATION" "C8P5"
					( Origin gPackager )
				)
				( attribute "CDS_SEC" "1"
					( Origin gPackager )
				)
				( attribute "LOCATION" "C8P5"
					( Origin gFrontEnd )
				)
				( attribute "MATERIAL" "X6S"
					( Origin gFrontEnd )
				)
				( attribute "PACK_TYPE" "0805LF"
					( Origin gFrontEnd )
				)
				( attribute "PART_NUMBER" "C95333-002"
					( Origin gFrontEnd )
				)
				( attribute "PHYS_PAGE" "76"
					( Origin gFrontEnd )
				)
				( attribute "ROOM" "PVCCIN_CPU0_DECAP_VR"
					( Origin gFrontEnd )
				)
				( attribute "ROT" "0"
					( Origin gFrontEnd )
				)
				( attribute "SEC" "1"
					( Origin gPackager )
				)
				( attribute "TOLERANCE" "20%"
					( Origin gFrontEnd )
				)
				( attribute "VALUE" "22UF"
					( Origin gFrontEnd )
				)
				( attribute "VER" "1"
					( Origin gFrontEnd )
				)
				( attribute "VOLTAGE" "4V"
					( Units "uVoltage" "V" 1.000000)
					( Origin gFrontEnd )
				)
				( attribute "XY" "(-4550,1150)"
					( Origin gFrontEnd )
				)
				( attribute "CHIPS_PART_NAME" "CAP"
					( Origin gPackager )
				)
				( attribute "CDS_PART_NAME" "CAP_0805LF-22UF,4V,20%,X6S,C95A"
					( Origin gPackager )
				)
				( attribute "GROUP" "PWR_MLCC_CAP"
					( Origin gFrontEnd )
				)
				( objectStatus "C8P5" )
			)
			( gate "@baseboard_fab2_lib.baseboard_fab2(sch_1):page42_i215"
				( attribute "BOM_COST" "PROC_SOCKET"
					( Origin gFrontEnd )
				)
				( attribute "CDS_LIB" "mstr_discrete"
					( Origin gPackager )
				)
				( attribute "CDS_LOCATION" "C5P9"
					( Origin gPackager )
				)
				( attribute "CDS_SEC" "1"
					( Origin gPackager )
				)
				( attribute "LOCATION" "C5P9"
					( Origin gFrontEnd )
				)
				( attribute "MATERIAL" "X6S"
					( Origin gFrontEnd )
				)
				( attribute "PACK_TYPE" "0805LF"
					( Origin gFrontEnd )
				)
				( attribute "PART_NUMBER" "C95333-002"
					( Origin gFrontEnd )
				)
				( attribute "PHYS_PAGE" "42"
					( Origin gFrontEnd )
				)
				( attribute "ROOM" "PVCCIN_CPU0_DECAP_VR"
					( Origin gFrontEnd )
				)
				( attribute "ROT" "0"
					( Origin gFrontEnd )
				)
				( attribute "SEC" "1"
					( Origin gPackager )
				)
				( attribute "TOLERANCE" "20%"
					( Origin gFrontEnd )
				)
				( attribute "VALUE" "22UF"
					( Origin gFrontEnd )
				)
				( attribute "VER" "1"
					( Origin gFrontEnd )
				)
				( attribute "VOLTAGE" "4V"
					( Units "uVoltage" "V" 1.000000)
					( Origin gFrontEnd )
				)
				( attribute "XY" "(-3850,950)"
					( Origin gFrontEnd )
				)
				( attribute "CHIPS_PART_NAME" "CAP"
					( Origin gPackager )
				)
				( attribute "CDS_PART_NAME" "CAP_0805LF-22UF,4V,20%,X6S,C95A"
					( Origin gPackager )
				)
				( attribute "GROUP" "PWR_MLCC_CAP"
					( Origin gFrontEnd )
				)
				( objectStatus "C5P9" )
			)
			( gate "@baseboard_fab2_lib.baseboard_fab2(sch_1):page42_i25"
				( attribute "BOM_COST" "PROC_SOCKET"
					( Origin gFrontEnd )
				)
				( attribute "CDS_LIB" "mstr_discrete"
					( Origin gPackager )
				)
				( attribute "CDS_LOCATION" "C5P7"
					( Origin gPackager )
				)
				( attribute "CDS_SEC" "1"
					( Origin gPackager )
				)
				( attribute "LOCATION" "C5P7"
					( Origin gFrontEnd )
				)
				( attribute "MATERIAL" "X6S"
					( Origin gFrontEnd )
				)
				( attribute "PACK_TYPE" "0805LF"
					( Origin gFrontEnd )
				)
				( attribute "PART_NUMBER" "C95333-002"
					( Origin gFrontEnd )
				)
				( attribute "PHYS_PAGE" "42"
					( Origin gFrontEnd )
				)
				( attribute "ROOM" "PVCCIN_CPU0_DECAP_VR"
					( Origin gFrontEnd )
				)
				( attribute "ROT" "0"
					( Origin gFrontEnd )
				)
				( attribute "SEC" "1"
					( Origin gPackager )
				)
				( attribute "TOLERANCE" "20%"
					( Origin gFrontEnd )
				)
				( attribute "VALUE" "22UF"
					( Origin gFrontEnd )
				)
				( attribute "VER" "1"
					( Origin gFrontEnd )
				)
				( attribute "VOLTAGE" "4V"
					( Units "uVoltage" "V" 1.000000)
					( Origin gFrontEnd )
				)
				( attribute "XY" "(-4450,950)"
					( Origin gFrontEnd )
				)
				( attribute "CHIPS_PART_NAME" "CAP"
					( Origin gPackager )
				)
				( attribute "CDS_PART_NAME" "CAP_0805LF-22UF,4V,20%,X6S,C95A"
					( Origin gPackager )
				)
				( attribute "GROUP" "PWR_MLCC_CAP"
					( Origin gFrontEnd )
				)
				( objectStatus "C5P7" )
			)
			( gate "@baseboard_fab2_lib.baseboard_fab2(sch_1):page42_i28"
				( attribute "BOM_COST" "PROC_SOCKET"
					( Origin gFrontEnd )
				)
				( attribute "CDS_LIB" "mstr_discrete"
					( Origin gPackager )
				)
				( attribute "CDS_LOCATION" "C5P23"
					( Origin gPackager )
				)
				( attribute "CDS_SEC" "1"
					( Origin gPackager )
				)
				( attribute "LOCATION" "C5P23"
					( Origin gFrontEnd )
				)
				( attribute "MATERIAL" "X6S"
					( Origin gFrontEnd )
				)
				( attribute "PACK_TYPE" "0805"
					( Origin gFrontEnd )
				)
				( attribute "PART_NUMBER" "C95333-006"
					( Origin gFrontEnd )
				)
				( attribute "PHYS_PAGE" "42"
					( Origin gFrontEnd )
				)
				( attribute "ROOM" "PVCCIN_CPU0_DECAP_VR"
					( Origin gFrontEnd )
				)
				( attribute "ROT" "0"
					( Origin gFrontEnd )
				)
				( attribute "SEC" "1"
					( Origin gPackager )
				)
				( attribute "TOLERANCE" "20%"
					( Origin gFrontEnd )
				)
				( attribute "VALUE" "47UF"
					( Origin gFrontEnd )
				)
				( attribute "VER" "1"
					( Origin gFrontEnd )
				)
				( attribute "VOLTAGE" "4V"
					( Units "uVoltage" "V" 1.000000)
					( Origin gFrontEnd )
				)
				( attribute "XY" "(-5350,2250)"
					( Origin gFrontEnd )
				)
				( attribute "CHIPS_PART_NAME" "CAP"
					( Origin gPackager )
				)
				( attribute "CDS_PART_NAME" "CAP_0805-47UF,4V,20%,X6S,C9533A"
					( Origin gPackager )
				)
				( attribute "GROUP" "PWR_MLCC_CAP"
					( Origin gFrontEnd )
				)
				( objectStatus "C5P23" )
			)
			( gate "@baseboard_fab2_lib.baseboard_fab2(sch_1):page42_i33"
				( attribute "BOM_COST" "PROC_SOCKET"
					( Origin gFrontEnd )
				)
				( attribute "CDS_LIB" "mstr_discrete"
					( Origin gPackager )
				)
				( attribute "CDS_LOCATION" "C5P24"
					( Origin gPackager )
				)
				( attribute "CDS_SEC" "1"
					( Origin gPackager )
				)
				( attribute "LOCATION" "C5P24"
					( Origin gFrontEnd )
				)
				( attribute "MATERIAL" "X6S"
					( Origin gFrontEnd )
				)
				( attribute "PACK_TYPE" "0805"
					( Origin gFrontEnd )
				)
				( attribute "PART_NUMBER" "C95333-006"
					( Origin gFrontEnd )
				)
				( attribute "PHYS_PAGE" "42"
					( Origin gFrontEnd )
				)
				( attribute "ROOM" "PVCCIN_CPU0_DECAP_VR"
					( Origin gFrontEnd )
				)
				( attribute "ROT" "0"
					( Origin gFrontEnd )
				)
				( attribute "SEC" "1"
					( Origin gPackager )
				)
				( attribute "TOLERANCE" "20%"
					( Origin gFrontEnd )
				)
				( attribute "VALUE" "47UF"
					( Origin gFrontEnd )
				)
				( attribute "VER" "1"
					( Origin gFrontEnd )
				)
				( attribute "VOLTAGE" "4V"
					( Units "uVoltage" "V" 1.000000)
					( Origin gFrontEnd )
				)
				( attribute "XY" "(-5050,1550)"
					( Origin gFrontEnd )
				)
				( attribute "CHIPS_PART_NAME" "CAP"
					( Origin gPackager )
				)
				( attribute "CDS_PART_NAME" "CAP_0805-47UF,4V,20%,X6S,C9533A"
					( Origin gPackager )
				)
				( attribute "GROUP" "PWR_MLCC_CAP"
					( Origin gFrontEnd )
				)
				( objectStatus "C5P24" )
			)
			( gate "@baseboard_fab2_lib.baseboard_fab2(sch_1):page42_i37"
				( attribute "BOM_COST" "PROC_SOCKET"
					( Origin gFrontEnd )
				)
				( attribute "CDS_LIB" "mstr_discrete"
					( Origin gPackager )
				)
				( attribute "CDS_LOCATION" "C5P25"
					( Origin gPackager )
				)
				( attribute "CDS_SEC" "1"
					( Origin gPackager )
				)
				( attribute "LOCATION" "C5P25"
					( Origin gFrontEnd )
				)
				( attribute "MATERIAL" "X6S"
					( Origin gFrontEnd )
				)
				( attribute "PACK_TYPE" "0805"
					( Origin gFrontEnd )
				)
				( attribute "PART_NUMBER" "C95333-006"
					( Origin gFrontEnd )
				)
				( attribute "PHYS_PAGE" "42"
					( Origin gFrontEnd )
				)
				( attribute "ROOM" "PVCCIN_CPU0_DECAP_VR"
					( Origin gFrontEnd )
				)
				( attribute "ROT" "0"
					( Origin gFrontEnd )
				)
				( attribute "SEC" "1"
					( Origin gPackager )
				)
				( attribute "TOLERANCE" "20%"
					( Origin gFrontEnd )
				)
				( attribute "VALUE" "47UF"
					( Origin gFrontEnd )
				)
				( attribute "VER" "1"
					( Origin gFrontEnd )
				)
				( attribute "VOLTAGE" "4V"
					( Units "uVoltage" "V" 1.000000)
					( Origin gFrontEnd )
				)
				( attribute "XY" "(-5350,850)"
					( Origin gFrontEnd )
				)
				( attribute "CHIPS_PART_NAME" "CAP"
					( Origin gPackager )
				)
				( attribute "CDS_PART_NAME" "CAP_0805-47UF,4V,20%,X6S,C9533A"
					( Origin gPackager )
				)
				( attribute "GROUP" "PWR_MLCC_CAP"
					( Origin gFrontEnd )
				)
				( objectStatus "C5P25" )
			)
			( gate "@baseboard_fab2_lib.baseboard_fab2(sch_1):page42_i41"
				( attribute "BOM_COST" "PROC_SOCKET"
					( Origin gFrontEnd )
				)
				( attribute "CDS_LIB" "mstr_discrete"
					( Origin gPackager )
				)
				( attribute "CDS_LOCATION" "C5P14"
					( Origin gPackager )
				)
				( attribute "CDS_SEC" "1"
					( Origin gPackager )
				)
				( attribute "LOCATION" "C5P14"
					( Origin gFrontEnd )
				)
				( attribute "MATERIAL" "X6S"
					( Origin gFrontEnd )
				)
				( attribute "PACK_TYPE" "0805"
					( Origin gFrontEnd )
				)
				( attribute "PART_NUMBER" "C95333-006"
					( Origin gFrontEnd )
				)
				( attribute "PHYS_PAGE" "42"
					( Origin gFrontEnd )
				)
				( attribute "ROOM" "PVCCIN_CPU0_DECAP_VR"
					( Origin gFrontEnd )
				)
				( attribute "ROT" "0"
					( Origin gFrontEnd )
				)
				( attribute "SEC" "1"
					( Origin gPackager )
				)
				( attribute "TOLERANCE" "20%"
					( Origin gFrontEnd )
				)
				( attribute "VALUE" "47UF"
					( Origin gFrontEnd )
				)
				( attribute "VER" "1"
					( Origin gFrontEnd )
				)
				( attribute "VOLTAGE" "4V"
					( Units "uVoltage" "V" 1.000000)
					( Origin gFrontEnd )
				)
				( attribute "XY" "(-6550,2250)"
					( Origin gFrontEnd )
				)
				( attribute "CHIPS_PART_NAME" "CAP"
					( Origin gPackager )
				)
				( attribute "CDS_PART_NAME" "CAP_0805-47UF,4V,20%,X6S,C9533A"
					( Origin gPackager )
				)
				( attribute "GROUP" "PWR_MLCC_CAP"
					( Origin gFrontEnd )
				)
				( objectStatus "C5P14" )
			)
			( gate "@baseboard_fab2_lib.baseboard_fab2(sch_1):page42_i44"
				( attribute "BOM_COST" "PROC_SOCKET"
					( Origin gFrontEnd )
				)
				( attribute "CDS_LIB" "mstr_discrete"
					( Origin gPackager )
				)
				( attribute "CDS_LOCATION" "C5P27"
					( Origin gPackager )
				)
				( attribute "CDS_SEC" "1"
					( Origin gPackager )
				)
				( attribute "LOCATION" "C5P27"
					( Origin gFrontEnd )
				)
				( attribute "MATERIAL" "X6S"
					( Origin gFrontEnd )
				)
				( attribute "PACK_TYPE" "0805"
					( Origin gFrontEnd )
				)
				( attribute "PART_NUMBER" "C95333-006"
					( Origin gFrontEnd )
				)
				( attribute "PHYS_PAGE" "42"
					( Origin gFrontEnd )
				)
				( attribute "ROOM" "PVCCIN_CPU0_DECAP_VR"
					( Origin gFrontEnd )
				)
				( attribute "ROT" "0"
					( Origin gFrontEnd )
				)
				( attribute "SEC" "1"
					( Origin gPackager )
				)
				( attribute "TOLERANCE" "20%"
					( Origin gFrontEnd )
				)
				( attribute "VALUE" "47UF"
					( Origin gFrontEnd )
				)
				( attribute "VER" "1"
					( Origin gFrontEnd )
				)
				( attribute "VOLTAGE" "4V"
					( Units "uVoltage" "V" 1.000000)
					( Origin gFrontEnd )
				)
				( attribute "XY" "(-5950,1550)"
					( Origin gFrontEnd )
				)
				( attribute "CHIPS_PART_NAME" "CAP"
					( Origin gPackager )
				)
				( attribute "CDS_PART_NAME" "CAP_0805-47UF,4V,20%,X6S,C9533A"
					( Origin gPackager )
				)
				( attribute "GROUP" "PWR_MLCC_CAP"
					( Origin gFrontEnd )
				)
				( objectStatus "C5P27" )
			)
			( gate "@baseboard_fab2_lib.baseboard_fab2(sch_1):page42_i50"
				( attribute "BOM_COST" "PROC_SOCKET"
					( Origin gFrontEnd )
				)
				( attribute "CDS_LIB" "mstr_discrete"
					( Origin gPackager )
				)
				( attribute "CDS_LOCATION" "C5P33"
					( Origin gPackager )
				)
				( attribute "CDS_SEC" "1"
					( Origin gPackager )
				)
				( attribute "LOCATION" "C5P33"
					( Origin gFrontEnd )
				)
				( attribute "MATERIAL" "X6S"
					( Origin gFrontEnd )
				)
				( attribute "PACK_TYPE" "0805"
					( Origin gFrontEnd )
				)
				( attribute "PART_NUMBER" "C95333-006"
					( Origin gFrontEnd )
				)
				( attribute "PHYS_PAGE" "42"
					( Origin gFrontEnd )
				)
				( attribute "ROOM" "PVCCIN_CPU0_DECAP_VR"
					( Origin gFrontEnd )
				)
				( attribute "ROT" "0"
					( Origin gFrontEnd )
				)
				( attribute "SEC" "1"
					( Origin gPackager )
				)
				( attribute "TOLERANCE" "20%"
					( Origin gFrontEnd )
				)
				( attribute "VALUE" "47UF"
					( Origin gFrontEnd )
				)
				( attribute "VER" "1"
					( Origin gFrontEnd )
				)
				( attribute "VOLTAGE" "4V"
					( Units "uVoltage" "V" 1.000000)
					( Origin gFrontEnd )
				)
				( attribute "XY" "(-7150,2250)"
					( Origin gFrontEnd )
				)
				( attribute "CHIPS_PART_NAME" "CAP"
					( Origin gPackager )
				)
				( attribute "CDS_PART_NAME" "CAP_0805-47UF,4V,20%,X6S,C9533A"
					( Origin gPackager )
				)
				( attribute "GROUP" "PWR_MLCC_CAP"
					( Origin gFrontEnd )
				)
				( objectStatus "C5P33" )
			)
			( gate "@baseboard_fab2_lib.baseboard_fab2(sch_1):page42_i51"
				( attribute "BOM_COST" "PROC_SOCKET"
					( Origin gFrontEnd )
				)
				( attribute "CDS_LIB" "mstr_discrete"
					( Origin gPackager )
				)
				( attribute "CDS_LOCATION" "C5P35"
					( Origin gPackager )
				)
				( attribute "CDS_SEC" "1"
					( Origin gPackager )
				)
				( attribute "LOCATION" "C5P35"
					( Origin gFrontEnd )
				)
				( attribute "MATERIAL" "X6S"
					( Origin gFrontEnd )
				)
				( attribute "PACK_TYPE" "0805"
					( Origin gFrontEnd )
				)
				( attribute "PART_NUMBER" "C95333-006"
					( Origin gFrontEnd )
				)
				( attribute "PHYS_PAGE" "42"
					( Origin gFrontEnd )
				)
				( attribute "ROOM" "PVCCIN_CPU0_DECAP_VR"
					( Origin gFrontEnd )
				)
				( attribute "ROT" "0"
					( Origin gFrontEnd )
				)
				( attribute "SEC" "1"
					( Origin gPackager )
				)
				( attribute "TOLERANCE" "20%"
					( Origin gFrontEnd )
				)
				( attribute "VALUE" "47UF"
					( Origin gFrontEnd )
				)
				( attribute "VER" "1"
					( Origin gFrontEnd )
				)
				( attribute "VOLTAGE" "4V"
					( Units "uVoltage" "V" 1.000000)
					( Origin gFrontEnd )
				)
				( attribute "XY" "(-7450,2250)"
					( Origin gFrontEnd )
				)
				( attribute "CHIPS_PART_NAME" "CAP"
					( Origin gPackager )
				)
				( attribute "CDS_PART_NAME" "CAP_0805-47UF,4V,20%,X6S,C9533A"
					( Origin gPackager )
				)
				( attribute "GROUP" "PWR_MLCC_CAP"
					( Origin gFrontEnd )
				)
				( objectStatus "C5P35" )
			)
			( gate "@baseboard_fab2_lib.baseboard_fab2(sch_1):page42_i53"
				( attribute "BOM_COST" "PROC_SOCKET"
					( Origin gFrontEnd )
				)
				( attribute "CDS_LIB" "mstr_discrete"
					( Origin gPackager )
				)
				( attribute "CDS_LOCATION" "C5P32"
					( Origin gPackager )
				)
				( attribute "CDS_SEC" "1"
					( Origin gPackager )
				)
				( attribute "LOCATION" "C5P32"
					( Origin gFrontEnd )
				)
				( attribute "MATERIAL" "X6S"
					( Origin gFrontEnd )
				)
				( attribute "PACK_TYPE" "0805"
					( Origin gFrontEnd )
				)
				( attribute "PART_NUMBER" "C95333-006"
					( Origin gFrontEnd )
				)
				( attribute "PHYS_PAGE" "42"
					( Origin gFrontEnd )
				)
				( attribute "ROOM" "PVCCIN_CPU0_DECAP_VR"
					( Origin gFrontEnd )
				)
				( attribute "ROT" "0"
					( Origin gFrontEnd )
				)
				( attribute "SEC" "1"
					( Origin gPackager )
				)
				( attribute "TOLERANCE" "20%"
					( Origin gFrontEnd )
				)
				( attribute "VALUE" "47UF"
					( Origin gFrontEnd )
				)
				( attribute "VER" "1"
					( Origin gFrontEnd )
				)
				( attribute "VOLTAGE" "4V"
					( Units "uVoltage" "V" 1.000000)
					( Origin gFrontEnd )
				)
				( attribute "XY" "(-7150,1550)"
					( Origin gFrontEnd )
				)
				( attribute "CHIPS_PART_NAME" "CAP"
					( Origin gPackager )
				)
				( attribute "CDS_PART_NAME" "CAP_0805-47UF,4V,20%,X6S,C9533A"
					( Origin gPackager )
				)
				( attribute "GROUP" "PWR_MLCC_CAP"
					( Origin gFrontEnd )
				)
				( objectStatus "C5P32" )
			)
			( gate "@baseboard_fab2_lib.baseboard_fab2(sch_1):page42_i54"
				( attribute "BOM_COST" "PROC_SOCKET"
					( Origin gFrontEnd )
				)
				( attribute "CDS_LIB" "mstr_discrete"
					( Origin gPackager )
				)
				( attribute "CDS_LOCATION" "C5P34"
					( Origin gPackager )
				)
				( attribute "CDS_SEC" "1"
					( Origin gPackager )
				)
				( attribute "LOCATION" "C5P34"
					( Origin gFrontEnd )
				)
				( attribute "MATERIAL" "X6S"
					( Origin gFrontEnd )
				)
				( attribute "PACK_TYPE" "0805"
					( Origin gFrontEnd )
				)
				( attribute "PART_NUMBER" "C95333-006"
					( Origin gFrontEnd )
				)
				( attribute "PHYS_PAGE" "42"
					( Origin gFrontEnd )
				)
				( attribute "ROOM" "PVCCIN_CPU0_DECAP_VR"
					( Origin gFrontEnd )
				)
				( attribute "ROT" "0"
					( Origin gFrontEnd )
				)
				( attribute "SEC" "1"
					( Origin gPackager )
				)
				( attribute "TOLERANCE" "20%"
					( Origin gFrontEnd )
				)
				( attribute "VALUE" "47UF"
					( Origin gFrontEnd )
				)
				( attribute "VER" "1"
					( Origin gFrontEnd )
				)
				( attribute "VOLTAGE" "4V"
					( Units "uVoltage" "V" 1.000000)
					( Origin gFrontEnd )
				)
				( attribute "XY" "(-7450,1550)"
					( Origin gFrontEnd )
				)
				( attribute "CHIPS_PART_NAME" "CAP"
					( Origin gPackager )
				)
				( attribute "CDS_PART_NAME" "CAP_0805-47UF,4V,20%,X6S,C9533A"
					( Origin gPackager )
				)
				( attribute "GROUP" "PWR_MLCC_CAP"
					( Origin gFrontEnd )
				)
				( objectStatus "C5P34" )
			)
			( gate "@baseboard_fab2_lib.baseboard_fab2(sch_1):page42_i55"
				( attribute "BOM_COST" "PROC_SOCKET"
					( Origin gFrontEnd )
				)
				( attribute "CDS_LIB" "mstr_discrete"
					( Origin gPackager )
				)
				( attribute "CDS_LOCATION" "C5P22"
					( Origin gPackager )
				)
				( attribute "CDS_SEC" "1"
					( Origin gPackager )
				)
				( attribute "LOCATION" "C5P22"
					( Origin gFrontEnd )
				)
				( attribute "MATERIAL" "X6S"
					( Origin gFrontEnd )
				)
				( attribute "PACK_TYPE" "0805"
					( Origin gFrontEnd )
				)
				( attribute "PART_NUMBER" "C95333-006"
					( Origin gFrontEnd )
				)
				( attribute "PHYS_PAGE" "42"
					( Origin gFrontEnd )
				)
				( attribute "ROOM" "PVCCIN_CPU0_DECAP_VR"
					( Origin gFrontEnd )
				)
				( attribute "ROT" "0"
					( Origin gFrontEnd )
				)
				( attribute "SEC" "1"
					( Origin gPackager )
				)
				( attribute "TOLERANCE" "20%"
					( Origin gFrontEnd )
				)
				( attribute "VALUE" "47UF"
					( Origin gFrontEnd )
				)
				( attribute "VER" "1"
					( Origin gFrontEnd )
				)
				( attribute "VOLTAGE" "4V"
					( Units "uVoltage" "V" 1.000000)
					( Origin gFrontEnd )
				)
				( attribute "XY" "(-5650,850)"
					( Origin gFrontEnd )
				)
				( attribute "CHIPS_PART_NAME" "CAP"
					( Origin gPackager )
				)
				( attribute "CDS_PART_NAME" "CAP_0805-47UF,4V,20%,X6S,C9533A"
					( Origin gPackager )
				)
				( attribute "GROUP" "PWR_MLCC_CAP"
					( Origin gFrontEnd )
				)
				( objectStatus "C5P22" )
			)
			( gate "@baseboard_fab2_lib.baseboard_fab2(sch_1):page42_i56"
				( attribute "BOM_COST" "PROC_SOCKET"
					( Origin gFrontEnd )
				)
				( attribute "CDS_LIB" "mstr_discrete"
					( Origin gPackager )
				)
				( attribute "CDS_LOCATION" "C5P26"
					( Origin gPackager )
				)
				( attribute "CDS_SEC" "1"
					( Origin gPackager )
				)
				( attribute "LOCATION" "C5P26"
					( Origin gFrontEnd )
				)
				( attribute "MATERIAL" "X6S"
					( Origin gFrontEnd )
				)
				( attribute "PACK_TYPE" "0805"
					( Origin gFrontEnd )
				)
				( attribute "PART_NUMBER" "C95333-006"
					( Origin gFrontEnd )
				)
				( attribute "PHYS_PAGE" "42"
					( Origin gFrontEnd )
				)
				( attribute "ROOM" "PVCCIN_CPU0_DECAP_VR"
					( Origin gFrontEnd )
				)
				( attribute "ROT" "0"
					( Origin gFrontEnd )
				)
				( attribute "SEC" "1"
					( Origin gPackager )
				)
				( attribute "TOLERANCE" "20%"
					( Origin gFrontEnd )
				)
				( attribute "VALUE" "47UF"
					( Origin gFrontEnd )
				)
				( attribute "VER" "1"
					( Origin gFrontEnd )
				)
				( attribute "VOLTAGE" "4V"
					( Units "uVoltage" "V" 1.000000)
					( Origin gFrontEnd )
				)
				( attribute "XY" "(-5950,850)"
					( Origin gFrontEnd )
				)
				( attribute "CHIPS_PART_NAME" "CAP"
					( Origin gPackager )
				)
				( attribute "CDS_PART_NAME" "CAP_0805-47UF,4V,20%,X6S,C9533A"
					( Origin gPackager )
				)
				( attribute "GROUP" "PWR_MLCC_CAP"
					( Origin gFrontEnd )
				)
				( objectStatus "C5P26" )
			)
			( gate "@baseboard_fab2_lib.baseboard_fab2(sch_1):page42_i57"
				( attribute "BOM_COST" "PROC_SOCKET"
					( Origin gFrontEnd )
				)
				( attribute "CDS_LIB" "mstr_discrete"
					( Origin gPackager )
				)
				( attribute "CDS_LOCATION" "C5P40"
					( Origin gPackager )
				)
				( attribute "CDS_SEC" "1"
					( Origin gPackager )
				)
				( attribute "LOCATION" "C5P40"
					( Origin gFrontEnd )
				)
				( attribute "MATERIAL" "X6S"
					( Origin gFrontEnd )
				)
				( attribute "PACK_TYPE" "0805"
					( Origin gFrontEnd )
				)
				( attribute "PART_NUMBER" "C95333-006"
					( Origin gFrontEnd )
				)
				( attribute "PHYS_PAGE" "42"
					( Origin gFrontEnd )
				)
				( attribute "ROOM" "PVCCIN_CPU0_DECAP_VR"
					( Origin gFrontEnd )
				)
				( attribute "ROT" "0"
					( Origin gFrontEnd )
				)
				( attribute "SEC" "1"
					( Origin gPackager )
				)
				( attribute "TOLERANCE" "20%"
					( Origin gFrontEnd )
				)
				( attribute "VALUE" "47UF"
					( Origin gFrontEnd )
				)
				( attribute "VER" "1"
					( Origin gFrontEnd )
				)
				( attribute "VOLTAGE" "4V"
					( Units "uVoltage" "V" 1.000000)
					( Origin gFrontEnd )
				)
				( attribute "XY" "(-6550,850)"
					( Origin gFrontEnd )
				)
				( attribute "CHIPS_PART_NAME" "CAP"
					( Origin gPackager )
				)
				( attribute "CDS_PART_NAME" "CAP_0805-47UF,4V,20%,X6S,C9533A"
					( Origin gPackager )
				)
				( attribute "GROUP" "PWR_MLCC_CAP"
					( Origin gFrontEnd )
				)
				( objectStatus "C5P40" )
			)
			( gate "@baseboard_fab2_lib.baseboard_fab2(sch_1):page225_i317"
				( attribute "BOM_COST" "MEM_VRD_PVDDQ_CD"
					( Origin gFrontEnd )
				)
				( attribute "CDS_LIB" "mstr_discrete"
					( Origin gPackager )
				)
				( attribute "CDS_LOCATION" "C8P32"
					( Origin gPackager )
				)
				( attribute "CDS_SEC" "1"
					( Origin gPackager )
				)
				( attribute "LOCATION" "C8P32"
					( Origin gFrontEnd )
				)
				( attribute "MATERIAL" "X5R"
					( Origin gFrontEnd )
				)
				( attribute "NEW_MATERIAL" "X6S"
					( Origin gFrontEnd )
				)
				( attribute "PACK_TYPE" "0805"
					( Origin gFrontEnd )
				)
				( attribute "PART_NUMBER" "602433-112"
					( Origin gFrontEnd )
				)
				( attribute "PHYS_PAGE" "225"
					( Origin gFrontEnd )
				)
				( attribute "ROOM" "VDDQ_ABC_PWR_VR"
					( Origin gFrontEnd )
				)
				( attribute "ROT" "0"
					( Origin gFrontEnd )
				)
				( attribute "SEC" "1"
					( Origin gFrontEnd )
				)
				( attribute "SEC_TYPE" "0805"
					( Origin gFrontEnd )
				)
				( attribute "TOLERANCE" "20%"
					( Origin gFrontEnd )
				)
				( attribute "VALUE" "100UF"
					( Origin gFrontEnd )
				)
				( attribute "VER" "1"
					( Origin gFrontEnd )
				)
				( attribute "VOLTAGE" "4V"
					( Units "uVoltage" "V" 1.000000)
					( Origin gFrontEnd )
				)
				( attribute "XY" "(800,3025)"
					( Origin gFrontEnd )
				)
				( attribute "CHIPS_PART_NAME" "CAP"
					( Origin gPackager )
				)
				( attribute "CDS_PART_NAME" "CAP_0805-100UF,4V,20%,X5R,6024A"
					( Origin gPackager )
				)
				( attribute "GROUP" "PWR_MLCC_CAP"
					( Origin gFrontEnd )
				)
				( attribute "NEW_PN" "078.1071T.M002"
					( Origin gFrontEnd )
				)
				( attribute "BOM_SS" "NOPOP"
					( Origin gFrontEnd )
				)
				( objectStatus "C8P32" )
			)
			( gate "@baseboard_fab2_lib.baseboard_fab2(sch_1):page225_i318"
				( attribute "BOM_COST" "MEM_VRD_PVDDQ_CD"
					( Origin gFrontEnd )
				)
				( attribute "CDS_LIB" "mstr_discrete"
					( Origin gPackager )
				)
				( attribute "CDS_LOCATION" "C7P20"
					( Origin gPackager )
				)
				( attribute "CDS_SEC" "1"
					( Origin gPackager )
				)
				( attribute "LOCATION" "C7P20"
					( Origin gFrontEnd )
				)
				( attribute "MATERIAL" "X5R"
					( Origin gFrontEnd )
				)
				( attribute "NEW_MATERIAL" "X6S"
					( Origin gFrontEnd )
				)
				( attribute "PACK_TYPE" "0805"
					( Origin gFrontEnd )
				)
				( attribute "PART_NUMBER" "602433-112"
					( Origin gFrontEnd )
				)
				( attribute "PHYS_PAGE" "225"
					( Origin gFrontEnd )
				)
				( attribute "ROOM" "VDDQ_ABC_PWR_VR"
					( Origin gFrontEnd )
				)
				( attribute "ROT" "0"
					( Origin gFrontEnd )
				)
				( attribute "SEC" "1"
					( Origin gFrontEnd )
				)
				( attribute "SEC_TYPE" "0805"
					( Origin gFrontEnd )
				)
				( attribute "TOLERANCE" "20%"
					( Origin gFrontEnd )
				)
				( attribute "VALUE" "100UF"
					( Origin gFrontEnd )
				)
				( attribute "VER" "1"
					( Origin gFrontEnd )
				)
				( attribute "VOLTAGE" "4V"
					( Units "uVoltage" "V" 1.000000)
					( Origin gFrontEnd )
				)
				( attribute "XY" "(1625,3050)"
					( Origin gFrontEnd )
				)
				( attribute "CHIPS_PART_NAME" "CAP"
					( Origin gPackager )
				)
				( attribute "CDS_PART_NAME" "CAP_0805-100UF,4V,20%,X5R,6024A"
					( Origin gPackager )
				)
				( attribute "GROUP" "PWR_MLCC_CAP"
					( Origin gFrontEnd )
				)
				( attribute "NEW_PN" "078.1071T.M002"
					( Origin gFrontEnd )
				)
				( attribute "BOM_SS" "NOPOP"
					( Origin gFrontEnd )
				)
				( objectStatus "C7P20" )
			)
			( gate "@baseboard_fab2_lib.baseboard_fab2(sch_1):page225_i316"
				( attribute "BOM_COST" "MEM_VRD_PVDDQ_CD"
					( Origin gFrontEnd )
				)
				( attribute "CDS_LIB" "mstr_discrete"
					( Origin gPackager )
				)
				( attribute "CDS_LOCATION" "C8P33"
					( Origin gPackager )
				)
				( attribute "CDS_SEC" "1"
					( Origin gPackager )
				)
				( attribute "LOCATION" "C8P33"
					( Origin gFrontEnd )
				)
				( attribute "MATERIAL" "X5R"
					( Origin gFrontEnd )
				)
				( attribute "NEW_MATERIAL" "X6S"
					( Origin gFrontEnd )
				)
				( attribute "PACK_TYPE" "0805"
					( Origin gFrontEnd )
				)
				( attribute "PART_NUMBER" "602433-112"
					( Origin gFrontEnd )
				)
				( attribute "PHYS_PAGE" "225"
					( Origin gFrontEnd )
				)
				( attribute "ROOM" "VDDQ_ABC_PWR_VR"
					( Origin gFrontEnd )
				)
				( attribute "ROT" "0"
					( Origin gFrontEnd )
				)
				( attribute "SEC" "1"
					( Origin gFrontEnd )
				)
				( attribute "SEC_TYPE" "0805"
					( Origin gFrontEnd )
				)
				( attribute "TOLERANCE" "20%"
					( Origin gFrontEnd )
				)
				( attribute "VALUE" "100UF"
					( Origin gFrontEnd )
				)
				( attribute "VER" "1"
					( Origin gFrontEnd )
				)
				( attribute "VOLTAGE" "4V"
					( Units "uVoltage" "V" 1.000000)
					( Origin gFrontEnd )
				)
				( attribute "XY" "(450,3025)"
					( Origin gFrontEnd )
				)
				( attribute "CHIPS_PART_NAME" "CAP"
					( Origin gPackager )
				)
				( attribute "CDS_PART_NAME" "CAP_0805-100UF,4V,20%,X5R,6024A"
					( Origin gPackager )
				)
				( attribute "GROUP" "PWR_MLCC_CAP"
					( Origin gFrontEnd )
				)
				( attribute "NEW_PN" "078.1071T.M002"
					( Origin gFrontEnd )
				)
				( attribute "BOM_SS" "NOPOP"
					( Origin gFrontEnd )
				)
				( objectStatus "C8P33" )
			)
			( gate "@baseboard_fab2_lib.baseboard_fab2(sch_1):page42_i63"
				( attribute "BOM_COST" "PROC_SOCKET"
					( Origin gFrontEnd )
				)
				( attribute "CDS_LIB" "mstr_discrete"
					( Origin gPackager )
				)
				( attribute "CDS_LOCATION" "C5P37"
					( Origin gPackager )
				)
				( attribute "CDS_SEC" "1"
					( Origin gPackager )
				)
				( attribute "LOCATION" "C5P37"
					( Origin gFrontEnd )
				)
				( attribute "MATERIAL" "X6S"
					( Origin gFrontEnd )
				)
				( attribute "PACK_TYPE" "0805"
					( Origin gFrontEnd )
				)
				( attribute "PART_NUMBER" "C95333-006"
					( Origin gFrontEnd )
				)
				( attribute "PHYS_PAGE" "42"
					( Origin gFrontEnd )
				)
				( attribute "ROOM" "PVCCIN_CPU0_DECAP_VR"
					( Origin gFrontEnd )
				)
				( attribute "ROT" "0"
					( Origin gFrontEnd )
				)
				( attribute "SEC" "1"
					( Origin gPackager )
				)
				( attribute "TOLERANCE" "20%"
					( Origin gFrontEnd )
				)
				( attribute "VALUE" "47UF"
					( Origin gFrontEnd )
				)
				( attribute "VER" "1"
					( Origin gFrontEnd )
				)
				( attribute "VOLTAGE" "4V"
					( Units "uVoltage" "V" 1.000000)
					( Origin gFrontEnd )
				)
				( attribute "XY" "(-7750,2250)"
					( Origin gFrontEnd )
				)
				( attribute "CHIPS_PART_NAME" "CAP"
					( Origin gPackager )
				)
				( attribute "CDS_PART_NAME" "CAP_0805-47UF,4V,20%,X6S,C9533A"
					( Origin gPackager )
				)
				( attribute "GROUP" "PWR_MLCC_CAP"
					( Origin gFrontEnd )
				)
				( objectStatus "C5P37" )
			)
			( gate "@baseboard_fab2_lib.baseboard_fab2(sch_1):page42_i65"
				( attribute "BOM_COST" "PROC_SOCKET"
					( Origin gFrontEnd )
				)
				( attribute "CDS_LIB" "mstr_discrete"
					( Origin gPackager )
				)
				( attribute "CDS_LOCATION" "C5P36"
					( Origin gPackager )
				)
				( attribute "CDS_SEC" "1"
					( Origin gPackager )
				)
				( attribute "LOCATION" "C5P36"
					( Origin gFrontEnd )
				)
				( attribute "MATERIAL" "X6S"
					( Origin gFrontEnd )
				)
				( attribute "PACK_TYPE" "0805"
					( Origin gFrontEnd )
				)
				( attribute "PART_NUMBER" "C95333-006"
					( Origin gFrontEnd )
				)
				( attribute "PHYS_PAGE" "42"
					( Origin gFrontEnd )
				)
				( attribute "ROOM" "PVCCIN_CPU0_DECAP_VR"
					( Origin gFrontEnd )
				)
				( attribute "ROT" "0"
					( Origin gFrontEnd )
				)
				( attribute "SEC" "1"
					( Origin gPackager )
				)
				( attribute "TOLERANCE" "20%"
					( Origin gFrontEnd )
				)
				( attribute "VALUE" "47UF"
					( Origin gFrontEnd )
				)
				( attribute "VER" "1"
					( Origin gFrontEnd )
				)
				( attribute "VOLTAGE" "4V"
					( Units "uVoltage" "V" 1.000000)
					( Origin gFrontEnd )
				)
				( attribute "XY" "(-7750,1550)"
					( Origin gFrontEnd )
				)
				( attribute "CHIPS_PART_NAME" "CAP"
					( Origin gPackager )
				)
				( attribute "CDS_PART_NAME" "CAP_0805-47UF,4V,20%,X6S,C9533A"
					( Origin gPackager )
				)
				( attribute "GROUP" "PWR_MLCC_CAP"
					( Origin gFrontEnd )
				)
				( objectStatus "C5P36" )
			)
			( gate "@baseboard_fab2_lib.baseboard_fab2(sch_1):page42_i68"
				( attribute "BOM_COST" "PROC_SOCKET"
					( Origin gFrontEnd )
				)
				( attribute "CDS_LIB" "dev_discrete"
					( Origin gPackager )
				)
				( attribute "CDS_LOCATION" "C6D8"
					( Origin gPackager )
				)
				( attribute "CDS_SEC" "1"
					( Origin gPackager )
				)
				( attribute "LOCATION" "C6D8"
					( Origin gFrontEnd )
				)
				( attribute "MATERIAL" "X6S"
					( Origin gFrontEnd )
				)
				( attribute "PACK_TYPE" "0603V"
					( Origin gFrontEnd )
				)
				( attribute "PART_NUMBER" "E15431-004"
					( Origin gFrontEnd )
				)
				( attribute "PHYS_PAGE" "42"
					( Origin gFrontEnd )
				)
				( attribute "ROOM" "PVCCIN_CPU0_DECAP_VR"
					( Origin gFrontEnd )
				)
				( attribute "ROT" "0"
					( Origin gFrontEnd )
				)
				( attribute "SEC" "1"
					( Origin gPackager )
				)
				( attribute "TOLERANCE" "20%"
					( Origin gFrontEnd )
				)
				( attribute "VALUE" "22.0UF"
					( Origin gFrontEnd )
				)
				( attribute "VER" "1"
					( Origin gFrontEnd )
				)
				( attribute "VOLTAGE" "4V"
					( Units "uVoltage" "V" 1.000000)
					( Origin gFrontEnd )
				)
				( attribute "XY" "(-800,4500)"
					( Origin gFrontEnd )
				)
				( attribute "CHIPS_PART_NAME" "CAP_A"
					( Origin gPackager )
				)
				( attribute "CDS_PART_NAME" "CAP_A_0603V-22.0UF,4V,20%,X6S,A"
					( Origin gPackager )
				)
				( attribute "GROUP" "PWR_MCP_CAP"
					( Origin gFrontEnd )
				)
				( objectStatus "C6D8" )
			)
			( gate "@baseboard_fab2_lib.baseboard_fab2(sch_1):page42_i69"
				( attribute "BOM_COST" "PROC_SOCKET"
					( Origin gFrontEnd )
				)
				( attribute "CDS_LIB" "dev_discrete"
					( Origin gPackager )
				)
				( attribute "CDS_LOCATION" "C5D38"
					( Origin gPackager )
				)
				( attribute "CDS_SEC" "1"
					( Origin gPackager )
				)
				( attribute "LOCATION" "C5D38"
					( Origin gFrontEnd )
				)
				( attribute "MATERIAL" "X6S"
					( Origin gFrontEnd )
				)
				( attribute "PACK_TYPE" "0603V"
					( Origin gFrontEnd )
				)
				( attribute "PART_NUMBER" "E15431-004"
					( Origin gFrontEnd )
				)
				( attribute "PHYS_PAGE" "42"
					( Origin gFrontEnd )
				)
				( attribute "ROOM" "PVCCIN_CPU0_DECAP_VR"
					( Origin gFrontEnd )
				)
				( attribute "ROT" "0"
					( Origin gFrontEnd )
				)
				( attribute "SEC" "1"
					( Origin gPackager )
				)
				( attribute "TOLERANCE" "20%"
					( Origin gFrontEnd )
				)
				( attribute "VALUE" "22.0UF"
					( Origin gFrontEnd )
				)
				( attribute "VER" "1"
					( Origin gFrontEnd )
				)
				( attribute "VOLTAGE" "4V"
					( Units "uVoltage" "V" 1.000000)
					( Origin gFrontEnd )
				)
				( attribute "XY" "(-1050,4500)"
					( Origin gFrontEnd )
				)
				( attribute "CHIPS_PART_NAME" "CAP_A"
					( Origin gPackager )
				)
				( attribute "CDS_PART_NAME" "CAP_A_0603V-22.0UF,4V,20%,X6S,A"
					( Origin gPackager )
				)
				( attribute "GROUP" "PWR_MCP_CAP"
					( Origin gFrontEnd )
				)
				( objectStatus "C5D38" )
			)
			( gate "@baseboard_fab2_lib.baseboard_fab2(sch_1):page42_i70"
				( attribute "BOM_COST" "PROC_SOCKET"
					( Origin gFrontEnd )
				)
				( attribute "CDS_LIB" "dev_discrete"
					( Origin gPackager )
				)
				( attribute "CDS_LOCATION" "C5D37"
					( Origin gPackager )
				)
				( attribute "CDS_SEC" "1"
					( Origin gPackager )
				)
				( attribute "LOCATION" "C5D37"
					( Origin gFrontEnd )
				)
				( attribute "MATERIAL" "X6S"
					( Origin gFrontEnd )
				)
				( attribute "PACK_TYPE" "0603V"
					( Origin gFrontEnd )
				)
				( attribute "PART_NUMBER" "E15431-004"
					( Origin gFrontEnd )
				)
				( attribute "PHYS_PAGE" "42"
					( Origin gFrontEnd )
				)
				( attribute "ROOM" "PVCCIN_CPU0_DECAP_VR"
					( Origin gFrontEnd )
				)
				( attribute "ROT" "0"
					( Origin gFrontEnd )
				)
				( attribute "SEC" "1"
					( Origin gPackager )
				)
				( attribute "TOLERANCE" "20%"
					( Origin gFrontEnd )
				)
				( attribute "VALUE" "22.0UF"
					( Origin gFrontEnd )
				)
				( attribute "VER" "1"
					( Origin gFrontEnd )
				)
				( attribute "VOLTAGE" "4V"
					( Units "uVoltage" "V" 1.000000)
					( Origin gFrontEnd )
				)
				( attribute "XY" "(-1300,4500)"
					( Origin gFrontEnd )
				)
				( attribute "CHIPS_PART_NAME" "CAP_A"
					( Origin gPackager )
				)
				( attribute "CDS_PART_NAME" "CAP_A_0603V-22.0UF,4V,20%,X6S,A"
					( Origin gPackager )
				)
				( attribute "GROUP" "PWR_MCP_CAP"
					( Origin gFrontEnd )
				)
				( objectStatus "C5D37" )
			)
			( gate "@baseboard_fab2_lib.baseboard_fab2(sch_1):page42_i72"
				( attribute "BOM_COST" "PROC_SOCKET"
					( Origin gFrontEnd )
				)
				( attribute "CDS_LIB" "dev_discrete"
					( Origin gPackager )
				)
				( attribute "CDS_LOCATION" "C6D7"
					( Origin gPackager )
				)
				( attribute "CDS_SEC" "1"
					( Origin gPackager )
				)
				( attribute "LOCATION" "C6D7"
					( Origin gFrontEnd )
				)
				( attribute "MATERIAL" "X6S"
					( Origin gFrontEnd )
				)
				( attribute "PACK_TYPE" "0603V"
					( Origin gFrontEnd )
				)
				( attribute "PART_NUMBER" "E15431-004"
					( Origin gFrontEnd )
				)
				( attribute "PHYS_PAGE" "42"
					( Origin gFrontEnd )
				)
				( attribute "ROOM" "PVCCIN_CPU0_DECAP_VR"
					( Origin gFrontEnd )
				)
				( attribute "ROT" "0"
					( Origin gFrontEnd )
				)
				( attribute "SEC" "1"
					( Origin gPackager )
				)
				( attribute "TOLERANCE" "20%"
					( Origin gFrontEnd )
				)
				( attribute "VALUE" "22.0UF"
					( Origin gFrontEnd )
				)
				( attribute "VER" "1"
					( Origin gFrontEnd )
				)
				( attribute "VOLTAGE" "4V"
					( Units "uVoltage" "V" 1.000000)
					( Origin gFrontEnd )
				)
				( attribute "XY" "(-3350,3800)"
					( Origin gFrontEnd )
				)
				( attribute "CHIPS_PART_NAME" "CAP_A"
					( Origin gPackager )
				)
				( attribute "CDS_PART_NAME" "CAP_A_0603V-22.0UF,4V,20%,X6S,A"
					( Origin gPackager )
				)
				( attribute "GROUP" "PWR_MLCC_CAP"
					( Origin gFrontEnd )
				)
				( objectStatus "C6D7" )
			)
			( gate "@baseboard_fab2_lib.baseboard_fab2(sch_1):page42_i74"
				( attribute "BOM_COST" "PROC_SOCKET"
					( Origin gFrontEnd )
				)
				( attribute "CDS_LIB" "dev_discrete"
					( Origin gPackager )
				)
				( attribute "CDS_LOCATION" "C6D4"
					( Origin gPackager )
				)
				( attribute "CDS_SEC" "1"
					( Origin gPackager )
				)
				( attribute "LOCATION" "C6D4"
					( Origin gFrontEnd )
				)
				( attribute "MATERIAL" "X6S"
					( Origin gFrontEnd )
				)
				( attribute "PACK_TYPE" "0603V"
					( Origin gFrontEnd )
				)
				( attribute "PART_NUMBER" "E15431-004"
					( Origin gFrontEnd )
				)
				( attribute "PHYS_PAGE" "42"
					( Origin gFrontEnd )
				)
				( attribute "ROOM" "PVCCIN_CPU0_DECAP_VR"
					( Origin gFrontEnd )
				)
				( attribute "ROT" "0"
					( Origin gFrontEnd )
				)
				( attribute "SEC" "1"
					( Origin gPackager )
				)
				( attribute "TOLERANCE" "20%"
					( Origin gFrontEnd )
				)
				( attribute "VALUE" "22.0UF"
					( Origin gFrontEnd )
				)
				( attribute "VER" "1"
					( Origin gFrontEnd )
				)
				( attribute "VOLTAGE" "4V"
					( Units "uVoltage" "V" 1.000000)
					( Origin gFrontEnd )
				)
				( attribute "XY" "(-3600,3800)"
					( Origin gFrontEnd )
				)
				( attribute "CHIPS_PART_NAME" "CAP_A"
					( Origin gPackager )
				)
				( attribute "CDS_PART_NAME" "CAP_A_0603V-22.0UF,4V,20%,X6S,A"
					( Origin gPackager )
				)
				( attribute "GROUP" "PWR_MLCC_CAP"
					( Origin gFrontEnd )
				)
				( objectStatus "C6D4" )
			)
			( gate "@baseboard_fab2_lib.baseboard_fab2(sch_1):page42_i75"
				( attribute "BOM_COST" "PROC_SOCKET"
					( Origin gFrontEnd )
				)
				( attribute "CDS_LIB" "dev_discrete"
					( Origin gPackager )
				)
				( attribute "CDS_LOCATION" "C6D5"
					( Origin gPackager )
				)
				( attribute "CDS_SEC" "1"
					( Origin gPackager )
				)
				( attribute "LOCATION" "C6D5"
					( Origin gFrontEnd )
				)
				( attribute "MATERIAL" "X6S"
					( Origin gFrontEnd )
				)
				( attribute "PACK_TYPE" "0603V"
					( Origin gFrontEnd )
				)
				( attribute "PART_NUMBER" "E15431-004"
					( Origin gFrontEnd )
				)
				( attribute "PHYS_PAGE" "42"
					( Origin gFrontEnd )
				)
				( attribute "ROOM" "PVCCIN_CPU0_DECAP_VR"
					( Origin gFrontEnd )
				)
				( attribute "ROT" "0"
					( Origin gFrontEnd )
				)
				( attribute "SEC" "1"
					( Origin gPackager )
				)
				( attribute "TOLERANCE" "20%"
					( Origin gFrontEnd )
				)
				( attribute "VALUE" "22.0UF"
					( Origin gFrontEnd )
				)
				( attribute "VER" "1"
					( Origin gFrontEnd )
				)
				( attribute "VOLTAGE" "4V"
					( Units "uVoltage" "V" 1.000000)
					( Origin gFrontEnd )
				)
				( attribute "XY" "(-1550,4500)"
					( Origin gFrontEnd )
				)
				( attribute "CHIPS_PART_NAME" "CAP_A"
					( Origin gPackager )
				)
				( attribute "CDS_PART_NAME" "CAP_A_0603V-22.0UF,4V,20%,X6S,A"
					( Origin gPackager )
				)
				( attribute "GROUP" "PWR_MCP_CAP"
					( Origin gFrontEnd )
				)
				( objectStatus "C6D5" )
			)
			( gate "@baseboard_fab2_lib.baseboard_fab2(sch_1):page42_i77"
				( attribute "BOM_COST" "PROC_SOCKET"
					( Origin gFrontEnd )
				)
				( attribute "CDS_LIB" "dev_discrete"
					( Origin gPackager )
				)
				( attribute "CDS_LOCATION" "C6D2"
					( Origin gPackager )
				)
				( attribute "CDS_SEC" "1"
					( Origin gPackager )
				)
				( attribute "LOCATION" "C6D2"
					( Origin gFrontEnd )
				)
				( attribute "MATERIAL" "X6S"
					( Origin gFrontEnd )
				)
				( attribute "PACK_TYPE" "0603V"
					( Origin gFrontEnd )
				)
				( attribute "PART_NUMBER" "E15431-004"
					( Origin gFrontEnd )
				)
				( attribute "PHYS_PAGE" "42"
					( Origin gFrontEnd )
				)
				( attribute "ROOM" "PVCCIN_CPU0_DECAP_VR"
					( Origin gFrontEnd )
				)
				( attribute "ROT" "0"
					( Origin gFrontEnd )
				)
				( attribute "SEC" "1"
					( Origin gPackager )
				)
				( attribute "TOLERANCE" "20%"
					( Origin gFrontEnd )
				)
				( attribute "VALUE" "22.0UF"
					( Origin gFrontEnd )
				)
				( attribute "VER" "1"
					( Origin gFrontEnd )
				)
				( attribute "VOLTAGE" "4V"
					( Units "uVoltage" "V" 1.000000)
					( Origin gFrontEnd )
				)
				( attribute "XY" "(-1800,4500)"
					( Origin gFrontEnd )
				)
				( attribute "CHIPS_PART_NAME" "CAP_A"
					( Origin gPackager )
				)
				( attribute "CDS_PART_NAME" "CAP_A_0603V-22.0UF,4V,20%,X6S,A"
					( Origin gPackager )
				)
				( attribute "GROUP" "PWR_MCP_CAP"
					( Origin gFrontEnd )
				)
				( objectStatus "C6D2" )
			)
			( gate "@baseboard_fab2_lib.baseboard_fab2(sch_1):page42_i80"
				( attribute "BOM_COST" "PROC_SOCKET"
					( Origin gFrontEnd )
				)
				( attribute "CDS_LIB" "dev_discrete"
					( Origin gPackager )
				)
				( attribute "CDS_LOCATION" "C6D3"
					( Origin gPackager )
				)
				( attribute "CDS_SEC" "1"
					( Origin gPackager )
				)
				( attribute "LOCATION" "C6D3"
					( Origin gFrontEnd )
				)
				( attribute "MATERIAL" "X6S"
					( Origin gFrontEnd )
				)
				( attribute "PACK_TYPE" "0603V"
					( Origin gFrontEnd )
				)
				( attribute "PART_NUMBER" "E15431-004"
					( Origin gFrontEnd )
				)
				( attribute "PHYS_PAGE" "42"
					( Origin gFrontEnd )
				)
				( attribute "ROOM" "PVCCIN_CPU0_DECAP_VR"
					( Origin gFrontEnd )
				)
				( attribute "ROT" "0"
					( Origin gFrontEnd )
				)
				( attribute "SEC" "1"
					( Origin gPackager )
				)
				( attribute "TOLERANCE" "20%"
					( Origin gFrontEnd )
				)
				( attribute "VALUE" "22.0UF"
					( Origin gFrontEnd )
				)
				( attribute "VER" "1"
					( Origin gFrontEnd )
				)
				( attribute "VOLTAGE" "4V"
					( Units "uVoltage" "V" 1.000000)
					( Origin gFrontEnd )
				)
				( attribute "XY" "(-3850,3800)"
					( Origin gFrontEnd )
				)
				( attribute "CHIPS_PART_NAME" "CAP_A"
					( Origin gPackager )
				)
				( attribute "CDS_PART_NAME" "CAP_A_0603V-22.0UF,4V,20%,X6S,A"
					( Origin gPackager )
				)
				( attribute "GROUP" "PWR_MLCC_CAP"
					( Origin gFrontEnd )
				)
				( objectStatus "C6D3" )
			)
			( gate "@baseboard_fab2_lib.baseboard_fab2(sch_1):page42_i81"
				( attribute "BOM_COST" "PROC_SOCKET"
					( Origin gFrontEnd )
				)
				( attribute "CDS_LIB" "dev_discrete"
					( Origin gPackager )
				)
				( attribute "CDS_LOCATION" "C6D6"
					( Origin gPackager )
				)
				( attribute "CDS_SEC" "1"
					( Origin gPackager )
				)
				( attribute "LOCATION" "C6D6"
					( Origin gFrontEnd )
				)
				( attribute "MATERIAL" "X6S"
					( Origin gFrontEnd )
				)
				( attribute "PACK_TYPE" "0603V"
					( Origin gFrontEnd )
				)
				( attribute "PART_NUMBER" "E15431-004"
					( Origin gFrontEnd )
				)
				( attribute "PHYS_PAGE" "42"
					( Origin gFrontEnd )
				)
				( attribute "ROOM" "PVCCIN_CPU0_DECAP_VR"
					( Origin gFrontEnd )
				)
				( attribute "ROT" "0"
					( Origin gFrontEnd )
				)
				( attribute "SEC" "1"
					( Origin gPackager )
				)
				( attribute "TOLERANCE" "20%"
					( Origin gFrontEnd )
				)
				( attribute "VALUE" "22.0UF"
					( Origin gFrontEnd )
				)
				( attribute "VER" "1"
					( Origin gFrontEnd )
				)
				( attribute "VOLTAGE" "4V"
					( Units "uVoltage" "V" 1.000000)
					( Origin gFrontEnd )
				)
				( attribute "XY" "(-4100,3800)"
					( Origin gFrontEnd )
				)
				( attribute "CHIPS_PART_NAME" "CAP_A"
					( Origin gPackager )
				)
				( attribute "CDS_PART_NAME" "CAP_A_0603V-22.0UF,4V,20%,X6S,A"
					( Origin gPackager )
				)
				( attribute "GROUP" "PWR_MLCC_CAP"
					( Origin gFrontEnd )
				)
				( objectStatus "C6D6" )
			)
			( gate "@baseboard_fab2_lib.baseboard_fab2(sch_1):page42_i83"
				( attribute "BOM_COST" "PROC_SOCKET"
					( Origin gFrontEnd )
				)
				( attribute "CDS_LIB" "dev_discrete"
					( Origin gPackager )
				)
				( attribute "CDS_LOCATION" "C5D51"
					( Origin gPackager )
				)
				( attribute "CDS_SEC" "1"
					( Origin gPackager )
				)
				( attribute "LOCATION" "C5D51"
					( Origin gFrontEnd )
				)
				( attribute "MATERIAL" "X6S"
					( Origin gFrontEnd )
				)
				( attribute "PACK_TYPE" "0603V"
					( Origin gFrontEnd )
				)
				( attribute "PART_NUMBER" "E15431-004"
					( Origin gFrontEnd )
				)
				( attribute "PHYS_PAGE" "42"
					( Origin gFrontEnd )
				)
				( attribute "ROOM" "PVCCIN_CPU0_DECAP_VR"
					( Origin gFrontEnd )
				)
				( attribute "ROT" "0"
					( Origin gFrontEnd )
				)
				( attribute "SEC" "1"
					( Origin gPackager )
				)
				( attribute "TOLERANCE" "20%"
					( Origin gFrontEnd )
				)
				( attribute "VALUE" "22.0UF"
					( Origin gFrontEnd )
				)
				( attribute "VER" "1"
					( Origin gFrontEnd )
				)
				( attribute "VOLTAGE" "4V"
					( Units "uVoltage" "V" 1.000000)
					( Origin gFrontEnd )
				)
				( attribute "XY" "(-2550,4500)"
					( Origin gFrontEnd )
				)
				( attribute "CHIPS_PART_NAME" "CAP_A"
					( Origin gPackager )
				)
				( attribute "CDS_PART_NAME" "CAP_A_0603V-22.0UF,4V,20%,X6S,A"
					( Origin gPackager )
				)
				( attribute "GROUP" "PWR_MCP_CAP"
					( Origin gFrontEnd )
				)
				( objectStatus "C5D51" )
			)
			( gate "@baseboard_fab2_lib.baseboard_fab2(sch_1):page42_i88"
				( attribute "BOM_COST" "PROC_SOCKET"
					( Origin gFrontEnd )
				)
				( attribute "CDS_LIB" "dev_discrete"
					( Origin gPackager )
				)
				( attribute "CDS_LOCATION" "C5D21"
					( Origin gPackager )
				)
				( attribute "CDS_SEC" "1"
					( Origin gPackager )
				)
				( attribute "LOCATION" "C5D21"
					( Origin gFrontEnd )
				)
				( attribute "MATERIAL" "X6S"
					( Origin gFrontEnd )
				)
				( attribute "PACK_TYPE" "0603V"
					( Origin gFrontEnd )
				)
				( attribute "PART_NUMBER" "E15431-004"
					( Origin gFrontEnd )
				)
				( attribute "PHYS_PAGE" "42"
					( Origin gFrontEnd )
				)
				( attribute "ROOM" "PVCCIN_CPU0_DECAP_VR"
					( Origin gFrontEnd )
				)
				( attribute "ROT" "0"
					( Origin gFrontEnd )
				)
				( attribute "SEC" "1"
					( Origin gPackager )
				)
				( attribute "TOLERANCE" "20%"
					( Origin gFrontEnd )
				)
				( attribute "VALUE" "22.0UF"
					( Origin gFrontEnd )
				)
				( attribute "VER" "1"
					( Origin gFrontEnd )
				)
				( attribute "VOLTAGE" "4V"
					( Units "uVoltage" "V" 1.000000)
					( Origin gFrontEnd )
				)
				( attribute "XY" "(-2800,4500)"
					( Origin gFrontEnd )
				)
				( attribute "CHIPS_PART_NAME" "CAP_A"
					( Origin gPackager )
				)
				( attribute "CDS_PART_NAME" "CAP_A_0603V-22.0UF,4V,20%,X6S,A"
					( Origin gPackager )
				)
				( attribute "GROUP" "PWR_MCP_CAP"
					( Origin gFrontEnd )
				)
				( objectStatus "C5D21" )
			)
			( gate "@baseboard_fab2_lib.baseboard_fab2(sch_1):page42_i89"
				( attribute "BOM_COST" "PROC_SOCKET"
					( Origin gFrontEnd )
				)
				( attribute "CDS_LIB" "dev_discrete"
					( Origin gPackager )
				)
				( attribute "CDS_LOCATION" "C5D50"
					( Origin gPackager )
				)
				( attribute "CDS_SEC" "1"
					( Origin gPackager )
				)
				( attribute "LOCATION" "C5D50"
					( Origin gFrontEnd )
				)
				( attribute "MATERIAL" "X6S"
					( Origin gFrontEnd )
				)
				( attribute "PACK_TYPE" "0603V"
					( Origin gFrontEnd )
				)
				( attribute "PART_NUMBER" "E15431-004"
					( Origin gFrontEnd )
				)
				( attribute "PHYS_PAGE" "42"
					( Origin gFrontEnd )
				)
				( attribute "ROOM" "PVCCIN_CPU0_DECAP_VR"
					( Origin gFrontEnd )
				)
				( attribute "ROT" "0"
					( Origin gFrontEnd )
				)
				( attribute "SEC" "1"
					( Origin gPackager )
				)
				( attribute "TOLERANCE" "20%"
					( Origin gFrontEnd )
				)
				( attribute "VALUE" "22.0UF"
					( Origin gFrontEnd )
				)
				( attribute "VER" "1"
					( Origin gFrontEnd )
				)
				( attribute "VOLTAGE" "4V"
					( Units "uVoltage" "V" 1.000000)
					( Origin gFrontEnd )
				)
				( attribute "XY" "(-3050,4500)"
					( Origin gFrontEnd )
				)
				( attribute "CHIPS_PART_NAME" "CAP_A"
					( Origin gPackager )
				)
				( attribute "CDS_PART_NAME" "CAP_A_0603V-22.0UF,4V,20%,X6S,A"
					( Origin gPackager )
				)
				( attribute "GROUP" "PWR_MCP_CAP"
					( Origin gFrontEnd )
				)
				( objectStatus "C5D50" )
			)
			( gate "@baseboard_fab2_lib.baseboard_fab2(sch_1):page42_i90"
				( attribute "BOM_COST" "PROC_SOCKET"
					( Origin gFrontEnd )
				)
				( attribute "CDS_LIB" "dev_discrete"
					( Origin gPackager )
				)
				( attribute "CDS_LOCATION" "C5D48"
					( Origin gPackager )
				)
				( attribute "CDS_SEC" "1"
					( Origin gPackager )
				)
				( attribute "LOCATION" "C5D48"
					( Origin gFrontEnd )
				)
				( attribute "MATERIAL" "X6S"
					( Origin gFrontEnd )
				)
				( attribute "PACK_TYPE" "0603V"
					( Origin gFrontEnd )
				)
				( attribute "PART_NUMBER" "E15431-004"
					( Origin gFrontEnd )
				)
				( attribute "PHYS_PAGE" "42"
					( Origin gFrontEnd )
				)
				( attribute "ROOM" "PVCCIN_CPU0_DECAP_VR"
					( Origin gFrontEnd )
				)
				( attribute "ROT" "0"
					( Origin gFrontEnd )
				)
				( attribute "SEC" "1"
					( Origin gPackager )
				)
				( attribute "TOLERANCE" "20%"
					( Origin gFrontEnd )
				)
				( attribute "VALUE" "22.0UF"
					( Origin gFrontEnd )
				)
				( attribute "VER" "1"
					( Origin gFrontEnd )
				)
				( attribute "VOLTAGE" "4V"
					( Units "uVoltage" "V" 1.000000)
					( Origin gFrontEnd )
				)
				( attribute "XY" "(-3300,4500)"
					( Origin gFrontEnd )
				)
				( attribute "CHIPS_PART_NAME" "CAP_A"
					( Origin gPackager )
				)
				( attribute "CDS_PART_NAME" "CAP_A_0603V-22.0UF,4V,20%,X6S,A"
					( Origin gPackager )
				)
				( attribute "GROUP" "PWR_MCP_CAP"
					( Origin gFrontEnd )
				)
				( objectStatus "C5D48" )
			)
			( gate "@baseboard_fab2_lib.baseboard_fab2(sch_1):page42_i91"
				( attribute "BOM_COST" "PROC_SOCKET"
					( Origin gFrontEnd )
				)
				( attribute "CDS_LIB" "mstr_discrete"
					( Origin gPackager )
				)
				( attribute "CDS_LOCATION" "C5D13"
					( Origin gPackager )
				)
				( attribute "CDS_SEC" "1"
					( Origin gPackager )
				)
				( attribute "LOCATION" "C5D13"
					( Origin gFrontEnd )
				)
				( attribute "MATERIAL" "X6S"
					( Origin gFrontEnd )
				)
				( attribute "PACK_TYPE" "0603LF"
					( Origin gFrontEnd )
				)
				( attribute "PART_NUMBER" "E15431-001"
					( Origin gFrontEnd )
				)
				( attribute "PHYS_PAGE" "42"
					( Origin gFrontEnd )
				)
				( attribute "ROOM" "PVCCIN_CPU0_DECAP_VR"
					( Origin gFrontEnd )
				)
				( attribute "ROT" "0"
					( Origin gFrontEnd )
				)
				( attribute "SEC" "1"
					( Origin gPackager )
				)
				( attribute "TOLERANCE" "20%"
					( Origin gFrontEnd )
				)
				( attribute "VALUE" "10UF"
					( Origin gFrontEnd )
				)
				( attribute "VER" "1"
					( Origin gFrontEnd )
				)
				( attribute "VOLTAGE" "4V"
					( Units "uVoltage" "V" 1.000000)
					( Origin gFrontEnd )
				)
				( attribute "XY" "(-3200,3150)"
					( Origin gFrontEnd )
				)
				( attribute "CHIPS_PART_NAME" "CAP"
					( Origin gPackager )
				)
				( attribute "CDS_PART_NAME" "CAP_0603LF-10UF,4V,20%,X6S,E15A"
					( Origin gPackager )
				)
				( attribute "GROUP" "PWR_MLCC_CAP"
					( Origin gFrontEnd )
				)
				( objectStatus "C5D13" )
			)
			( gate "@baseboard_fab2_lib.baseboard_fab2(sch_1):page42_i93"
				( attribute "BOM_COST" "PROC_SOCKET"
					( Origin gFrontEnd )
				)
				( attribute "CDS_LIB" "mstr_discrete"
					( Origin gPackager )
				)
				( attribute "CDS_LOCATION" "C5D11"
					( Origin gPackager )
				)
				( attribute "CDS_SEC" "1"
					( Origin gPackager )
				)
				( attribute "LOCATION" "C5D11"
					( Origin gFrontEnd )
				)
				( attribute "MATERIAL" "X6S"
					( Origin gFrontEnd )
				)
				( attribute "PACK_TYPE" "0603LF"
					( Origin gFrontEnd )
				)
				( attribute "PART_NUMBER" "E15431-001"
					( Origin gFrontEnd )
				)
				( attribute "PHYS_PAGE" "42"
					( Origin gFrontEnd )
				)
				( attribute "ROOM" "PVCCIN_CPU0_DECAP_VR"
					( Origin gFrontEnd )
				)
				( attribute "ROT" "0"
					( Origin gFrontEnd )
				)
				( attribute "SEC" "1"
					( Origin gPackager )
				)
				( attribute "TOLERANCE" "20%"
					( Origin gFrontEnd )
				)
				( attribute "VALUE" "10UF"
					( Origin gFrontEnd )
				)
				( attribute "VER" "1"
					( Origin gFrontEnd )
				)
				( attribute "VOLTAGE" "4V"
					( Units "uVoltage" "V" 1.000000)
					( Origin gFrontEnd )
				)
				( attribute "XY" "(-3500,3150)"
					( Origin gFrontEnd )
				)
				( attribute "CHIPS_PART_NAME" "CAP"
					( Origin gPackager )
				)
				( attribute "CDS_PART_NAME" "CAP_0603LF-10UF,4V,20%,X6S,E15A"
					( Origin gPackager )
				)
				( attribute "GROUP" "PWR_MLCC_CAP"
					( Origin gFrontEnd )
				)
				( objectStatus "C5D11" )
			)
			( gate "@baseboard_fab2_lib.baseboard_fab2(sch_1):page42_i94"
				( attribute "BOM_COST" "PROC_SOCKET"
					( Origin gFrontEnd )
				)
				( attribute "CDS_LIB" "mstr_discrete"
					( Origin gPackager )
				)
				( attribute "CDS_LOCATION" "C5D12"
					( Origin gPackager )
				)
				( attribute "CDS_SEC" "1"
					( Origin gPackager )
				)
				( attribute "LOCATION" "C5D12"
					( Origin gFrontEnd )
				)
				( attribute "MATERIAL" "X6S"
					( Origin gFrontEnd )
				)
				( attribute "PACK_TYPE" "0603LF"
					( Origin gFrontEnd )
				)
				( attribute "PART_NUMBER" "E15431-001"
					( Origin gFrontEnd )
				)
				( attribute "PHYS_PAGE" "42"
					( Origin gFrontEnd )
				)
				( attribute "ROOM" "PVCCIN_CPU0_DECAP_VR"
					( Origin gFrontEnd )
				)
				( attribute "ROT" "0"
					( Origin gFrontEnd )
				)
				( attribute "SEC" "1"
					( Origin gPackager )
				)
				( attribute "TOLERANCE" "20%"
					( Origin gFrontEnd )
				)
				( attribute "VALUE" "10UF"
					( Origin gFrontEnd )
				)
				( attribute "VER" "1"
					( Origin gFrontEnd )
				)
				( attribute "VOLTAGE" "4V"
					( Units "uVoltage" "V" 1.000000)
					( Origin gFrontEnd )
				)
				( attribute "XY" "(-3800,3150)"
					( Origin gFrontEnd )
				)
				( attribute "CHIPS_PART_NAME" "CAP"
					( Origin gPackager )
				)
				( attribute "CDS_PART_NAME" "CAP_0603LF-10UF,4V,20%,X6S,E15A"
					( Origin gPackager )
				)
				( attribute "GROUP" "PWR_MLCC_CAP"
					( Origin gFrontEnd )
				)
				( objectStatus "C5D12" )
			)
			( gate "@baseboard_fab2_lib.baseboard_fab2(sch_1):page42_i98"
				( attribute "BOM_COST" "PROC_SOCKET"
					( Origin gFrontEnd )
				)
				( attribute "CDS_LIB" "dev_discrete"
					( Origin gPackager )
				)
				( attribute "CDS_LOCATION" "C5D23"
					( Origin gPackager )
				)
				( attribute "CDS_SEC" "1"
					( Origin gPackager )
				)
				( attribute "LOCATION" "C5D23"
					( Origin gFrontEnd )
				)
				( attribute "MATERIAL" "X6S"
					( Origin gFrontEnd )
				)
				( attribute "PACK_TYPE" "0603V"
					( Origin gFrontEnd )
				)
				( attribute "PART_NUMBER" "E15431-004"
					( Origin gFrontEnd )
				)
				( attribute "PHYS_PAGE" "42"
					( Origin gFrontEnd )
				)
				( attribute "ROOM" "PVCCIN_CPU0_DECAP_VR"
					( Origin gFrontEnd )
				)
				( attribute "ROT" "0"
					( Origin gFrontEnd )
				)
				( attribute "SEC" "1"
					( Origin gPackager )
				)
				( attribute "TOLERANCE" "20%"
					( Origin gFrontEnd )
				)
				( attribute "VALUE" "22.0UF"
					( Origin gFrontEnd )
				)
				( attribute "VER" "1"
					( Origin gFrontEnd )
				)
				( attribute "VOLTAGE" "4V"
					( Units "uVoltage" "V" 1.000000)
					( Origin gFrontEnd )
				)
				( attribute "XY" "(-3550,4500)"
					( Origin gFrontEnd )
				)
				( attribute "CHIPS_PART_NAME" "CAP_A"
					( Origin gPackager )
				)
				( attribute "CDS_PART_NAME" "CAP_A_0603V-22.0UF,4V,20%,X6S,A"
					( Origin gPackager )
				)
				( attribute "GROUP" "PWR_MCP_CAP"
					( Origin gFrontEnd )
				)
				( objectStatus "C5D23" )
			)
			( gate "@baseboard_fab2_lib.baseboard_fab2(sch_1):page42_i100"
				( attribute "BOM_COST" "PROC_SOCKET"
					( Origin gFrontEnd )
				)
				( attribute "CDS_LIB" "dev_discrete"
					( Origin gPackager )
				)
				( attribute "CDS_LOCATION" "C5D28"
					( Origin gPackager )
				)
				( attribute "CDS_SEC" "1"
					( Origin gPackager )
				)
				( attribute "LOCATION" "C5D28"
					( Origin gFrontEnd )
				)
				( attribute "MATERIAL" "X6S"
					( Origin gFrontEnd )
				)
				( attribute "PACK_TYPE" "0603V"
					( Origin gFrontEnd )
				)
				( attribute "PART_NUMBER" "E15431-004"
					( Origin gFrontEnd )
				)
				( attribute "PHYS_PAGE" "42"
					( Origin gFrontEnd )
				)
				( attribute "ROOM" "PVCCIN_CPU0_DECAP_VR"
					( Origin gFrontEnd )
				)
				( attribute "ROT" "0"
					( Origin gFrontEnd )
				)
				( attribute "SEC" "1"
					( Origin gPackager )
				)
				( attribute "TOLERANCE" "20%"
					( Origin gFrontEnd )
				)
				( attribute "VALUE" "22.0UF"
					( Origin gFrontEnd )
				)
				( attribute "VER" "1"
					( Origin gFrontEnd )
				)
				( attribute "VOLTAGE" "4V"
					( Units "uVoltage" "V" 1.000000)
					( Origin gFrontEnd )
				)
				( attribute "XY" "(-4900,3800)"
					( Origin gFrontEnd )
				)
				( attribute "CHIPS_PART_NAME" "CAP_A"
					( Origin gPackager )
				)
				( attribute "CDS_PART_NAME" "CAP_A_0603V-22.0UF,4V,20%,X6S,A"
					( Origin gPackager )
				)
				( attribute "GROUP" "PWR_MLCC_CAP"
					( Origin gFrontEnd )
				)
				( objectStatus "C5D28" )
			)
			( gate "@baseboard_fab2_lib.baseboard_fab2(sch_1):page42_i102"
				( attribute "BOM_COST" "PROC_SOCKET"
					( Origin gFrontEnd )
				)
				( attribute "CDS_LIB" "dev_discrete"
					( Origin gPackager )
				)
				( attribute "CDS_LOCATION" "C5D29"
					( Origin gPackager )
				)
				( attribute "CDS_SEC" "1"
					( Origin gPackager )
				)
				( attribute "LOCATION" "C5D29"
					( Origin gFrontEnd )
				)
				( attribute "MATERIAL" "X6S"
					( Origin gFrontEnd )
				)
				( attribute "PACK_TYPE" "0603V"
					( Origin gFrontEnd )
				)
				( attribute "PART_NUMBER" "E15431-004"
					( Origin gFrontEnd )
				)
				( attribute "PHYS_PAGE" "42"
					( Origin gFrontEnd )
				)
				( attribute "ROOM" "PVCCIN_CPU0_DECAP_VR"
					( Origin gFrontEnd )
				)
				( attribute "ROT" "0"
					( Origin gFrontEnd )
				)
				( attribute "SEC" "1"
					( Origin gPackager )
				)
				( attribute "TOLERANCE" "20%"
					( Origin gFrontEnd )
				)
				( attribute "VALUE" "22.0UF"
					( Origin gFrontEnd )
				)
				( attribute "VER" "1"
					( Origin gFrontEnd )
				)
				( attribute "VOLTAGE" "4V"
					( Units "uVoltage" "V" 1.000000)
					( Origin gFrontEnd )
				)
				( attribute "XY" "(-4750,4500)"
					( Origin gFrontEnd )
				)
				( attribute "CHIPS_PART_NAME" "CAP_A"
					( Origin gPackager )
				)
				( attribute "CDS_PART_NAME" "CAP_A_0603V-22.0UF,4V,20%,X6S,A"
					( Origin gPackager )
				)
				( attribute "GROUP" "PWR_MLCC_CAP"
					( Origin gFrontEnd )
				)
				( objectStatus "C5D29" )
			)
			( gate "@baseboard_fab2_lib.baseboard_fab2(sch_1):page42_i103"
				( attribute "BOM_COST" "PROC_SOCKET"
					( Origin gFrontEnd )
				)
				( attribute "CDS_LIB" "dev_discrete"
					( Origin gPackager )
				)
				( attribute "CDS_LOCATION" "C5D32"
					( Origin gPackager )
				)
				( attribute "CDS_SEC" "1"
					( Origin gPackager )
				)
				( attribute "LOCATION" "C5D32"
					( Origin gFrontEnd )
				)
				( attribute "MATERIAL" "X6S"
					( Origin gFrontEnd )
				)
				( attribute "PACK_TYPE" "0603V"
					( Origin gFrontEnd )
				)
				( attribute "PART_NUMBER" "E15431-004"
					( Origin gFrontEnd )
				)
				( attribute "PHYS_PAGE" "42"
					( Origin gFrontEnd )
				)
				( attribute "ROOM" "PVCCIN_CPU0_DECAP_VR"
					( Origin gFrontEnd )
				)
				( attribute "ROT" "0"
					( Origin gFrontEnd )
				)
				( attribute "SEC" "1"
					( Origin gPackager )
				)
				( attribute "TOLERANCE" "20%"
					( Origin gFrontEnd )
				)
				( attribute "VALUE" "22.0UF"
					( Origin gFrontEnd )
				)
				( attribute "VER" "1"
					( Origin gFrontEnd )
				)
				( attribute "VOLTAGE" "4V"
					( Units "uVoltage" "V" 1.000000)
					( Origin gFrontEnd )
				)
				( attribute "XY" "(-5050,4500)"
					( Origin gFrontEnd )
				)
				( attribute "CHIPS_PART_NAME" "CAP_A"
					( Origin gPackager )
				)
				( attribute "CDS_PART_NAME" "CAP_A_0603V-22.0UF,4V,20%,X6S,A"
					( Origin gPackager )
				)
				( attribute "GROUP" "PWR_MLCC_CAP"
					( Origin gFrontEnd )
				)
				( objectStatus "C5D32" )
			)
			( gate "@baseboard_fab2_lib.baseboard_fab2(sch_1):page42_i104"
				( attribute "BOM_COST" "PROC_SOCKET"
					( Origin gFrontEnd )
				)
				( attribute "CDS_LIB" "dev_discrete"
					( Origin gPackager )
				)
				( attribute "CDS_LOCATION" "C5D47"
					( Origin gPackager )
				)
				( attribute "CDS_SEC" "1"
					( Origin gPackager )
				)
				( attribute "LOCATION" "C5D47"
					( Origin gFrontEnd )
				)
				( attribute "MATERIAL" "X6S"
					( Origin gFrontEnd )
				)
				( attribute "PACK_TYPE" "0603V"
					( Origin gFrontEnd )
				)
				( attribute "PART_NUMBER" "E15431-004"
					( Origin gFrontEnd )
				)
				( attribute "PHYS_PAGE" "42"
					( Origin gFrontEnd )
				)
				( attribute "ROOM" "PVCCIN_CPU0_DECAP_VR"
					( Origin gFrontEnd )
				)
				( attribute "ROT" "0"
					( Origin gFrontEnd )
				)
				( attribute "SEC" "1"
					( Origin gPackager )
				)
				( attribute "TOLERANCE" "20%"
					( Origin gFrontEnd )
				)
				( attribute "VALUE" "22.0UF"
					( Origin gFrontEnd )
				)
				( attribute "VER" "1"
					( Origin gFrontEnd )
				)
				( attribute "VOLTAGE" "4V"
					( Units "uVoltage" "V" 1.000000)
					( Origin gFrontEnd )
				)
				( attribute "XY" "(-5350,4500)"
					( Origin gFrontEnd )
				)
				( attribute "CHIPS_PART_NAME" "CAP_A"
					( Origin gPackager )
				)
				( attribute "CDS_PART_NAME" "CAP_A_0603V-22.0UF,4V,20%,X6S,A"
					( Origin gPackager )
				)
				( attribute "GROUP" "PWR_MLCC_CAP"
					( Origin gFrontEnd )
				)
				( objectStatus "C5D47" )
			)
			( gate "@baseboard_fab2_lib.baseboard_fab2(sch_1):page42_i106"
				( attribute "BOM_COST" "PROC_SOCKET"
					( Origin gFrontEnd )
				)
				( attribute "CDS_LIB" "dev_discrete"
					( Origin gPackager )
				)
				( attribute "CDS_LOCATION" "C5D31"
					( Origin gPackager )
				)
				( attribute "CDS_SEC" "1"
					( Origin gPackager )
				)
				( attribute "LOCATION" "C5D31"
					( Origin gFrontEnd )
				)
				( attribute "MATERIAL" "X6S"
					( Origin gFrontEnd )
				)
				( attribute "PACK_TYPE" "0603V"
					( Origin gFrontEnd )
				)
				( attribute "PART_NUMBER" "E15431-004"
					( Origin gFrontEnd )
				)
				( attribute "PHYS_PAGE" "42"
					( Origin gFrontEnd )
				)
				( attribute "ROOM" "PVCCIN_CPU0_DECAP_VR"
					( Origin gFrontEnd )
				)
				( attribute "ROT" "0"
					( Origin gFrontEnd )
				)
				( attribute "SEC" "1"
					( Origin gPackager )
				)
				( attribute "TOLERANCE" "20%"
					( Origin gFrontEnd )
				)
				( attribute "VALUE" "22.0UF"
					( Origin gFrontEnd )
				)
				( attribute "VER" "1"
					( Origin gFrontEnd )
				)
				( attribute "VOLTAGE" "4V"
					( Units "uVoltage" "V" 1.000000)
					( Origin gFrontEnd )
				)
				( attribute "XY" "(-5200,3800)"
					( Origin gFrontEnd )
				)
				( attribute "CHIPS_PART_NAME" "CAP_A"
					( Origin gPackager )
				)
				( attribute "CDS_PART_NAME" "CAP_A_0603V-22.0UF,4V,20%,X6S,A"
					( Origin gPackager )
				)
				( attribute "GROUP" "PWR_MLCC_CAP"
					( Origin gFrontEnd )
				)
				( objectStatus "C5D31" )
			)
			( gate "@baseboard_fab2_lib.baseboard_fab2(sch_1):page42_i107"
				( attribute "BOM_COST" "PROC_SOCKET"
					( Origin gFrontEnd )
				)
				( attribute "CDS_LIB" "dev_discrete"
					( Origin gPackager )
				)
				( attribute "CDS_LOCATION" "C5D46"
					( Origin gPackager )
				)
				( attribute "CDS_SEC" "1"
					( Origin gPackager )
				)
				( attribute "LOCATION" "C5D46"
					( Origin gFrontEnd )
				)
				( attribute "MATERIAL" "X6S"
					( Origin gFrontEnd )
				)
				( attribute "PACK_TYPE" "0603V"
					( Origin gFrontEnd )
				)
				( attribute "PART_NUMBER" "E15431-004"
					( Origin gFrontEnd )
				)
				( attribute "PHYS_PAGE" "42"
					( Origin gFrontEnd )
				)
				( attribute "ROOM" "PVCCIN_CPU0_DECAP_VR"
					( Origin gFrontEnd )
				)
				( attribute "ROT" "0"
					( Origin gFrontEnd )
				)
				( attribute "SEC" "1"
					( Origin gPackager )
				)
				( attribute "TOLERANCE" "20%"
					( Origin gFrontEnd )
				)
				( attribute "VALUE" "22.0UF"
					( Origin gFrontEnd )
				)
				( attribute "VER" "1"
					( Origin gFrontEnd )
				)
				( attribute "VOLTAGE" "4V"
					( Units "uVoltage" "V" 1.000000)
					( Origin gFrontEnd )
				)
				( attribute "XY" "(-5500,3800)"
					( Origin gFrontEnd )
				)
				( attribute "CHIPS_PART_NAME" "CAP_A"
					( Origin gPackager )
				)
				( attribute "CDS_PART_NAME" "CAP_A_0603V-22.0UF,4V,20%,X6S,A"
					( Origin gPackager )
				)
				( attribute "GROUP" "PWR_MLCC_CAP"
					( Origin gFrontEnd )
				)
				( objectStatus "C5D46" )
			)
			( gate "@baseboard_fab2_lib.baseboard_fab2(sch_1):page42_i108"
				( attribute "BOM_COST" "PROC_SOCKET"
					( Origin gFrontEnd )
				)
				( attribute "CDS_LIB" "mstr_discrete"
					( Origin gPackager )
				)
				( attribute "CDS_LOCATION" "C5D10"
					( Origin gPackager )
				)
				( attribute "CDS_SEC" "1"
					( Origin gPackager )
				)
				( attribute "LOCATION" "C5D10"
					( Origin gFrontEnd )
				)
				( attribute "MATERIAL" "X6S"
					( Origin gFrontEnd )
				)
				( attribute "PACK_TYPE" "0603LF"
					( Origin gFrontEnd )
				)
				( attribute "PART_NUMBER" "E15431-001"
					( Origin gFrontEnd )
				)
				( attribute "PHYS_PAGE" "42"
					( Origin gFrontEnd )
				)
				( attribute "ROOM" "PVCCIN_CPU0_DECAP_VR"
					( Origin gFrontEnd )
				)
				( attribute "ROT" "0"
					( Origin gFrontEnd )
				)
				( attribute "SEC" "1"
					( Origin gPackager )
				)
				( attribute "TOLERANCE" "20%"
					( Origin gFrontEnd )
				)
				( attribute "VALUE" "10UF"
					( Origin gFrontEnd )
				)
				( attribute "VER" "1"
					( Origin gFrontEnd )
				)
				( attribute "VOLTAGE" "4V"
					( Units "uVoltage" "V" 1.000000)
					( Origin gFrontEnd )
				)
				( attribute "XY" "(-4100,3150)"
					( Origin gFrontEnd )
				)
				( attribute "CHIPS_PART_NAME" "CAP"
					( Origin gPackager )
				)
				( attribute "CDS_PART_NAME" "CAP_0603LF-10UF,4V,20%,X6S,E15A"
					( Origin gPackager )
				)
				( attribute "GROUP" "PWR_MLCC_CAP"
					( Origin gFrontEnd )
				)
				( objectStatus "C5D10" )
			)
			( gate "@baseboard_fab2_lib.baseboard_fab2(sch_1):page42_i109"
				( attribute "BOM_COST" "PROC_SOCKET"
					( Origin gFrontEnd )
				)
				( attribute "CDS_LIB" "dev_discrete"
					( Origin gPackager )
				)
				( attribute "CDS_LOCATION" "C5D27"
					( Origin gPackager )
				)
				( attribute "CDS_SEC" "1"
					( Origin gPackager )
				)
				( attribute "LOCATION" "C5D27"
					( Origin gFrontEnd )
				)
				( attribute "MATERIAL" "X6S"
					( Origin gFrontEnd )
				)
				( attribute "PACK_TYPE" "0603V"
					( Origin gFrontEnd )
				)
				( attribute "PART_NUMBER" "E15431-004"
					( Origin gFrontEnd )
				)
				( attribute "PHYS_PAGE" "42"
					( Origin gFrontEnd )
				)
				( attribute "ROOM" "PVCCIN_CPU0_DECAP_VR"
					( Origin gFrontEnd )
				)
				( attribute "ROT" "0"
					( Origin gFrontEnd )
				)
				( attribute "SEC" "1"
					( Origin gPackager )
				)
				( attribute "TOLERANCE" "20%"
					( Origin gFrontEnd )
				)
				( attribute "VALUE" "22.0UF"
					( Origin gFrontEnd )
				)
				( attribute "VER" "1"
					( Origin gFrontEnd )
				)
				( attribute "VOLTAGE" "4V"
					( Units "uVoltage" "V" 1.000000)
					( Origin gFrontEnd )
				)
				( attribute "XY" "(-5000,3150)"
					( Origin gFrontEnd )
				)
				( attribute "CHIPS_PART_NAME" "CAP_A"
					( Origin gPackager )
				)
				( attribute "CDS_PART_NAME" "CAP_A_0603V-22.0UF,4V,20%,X6S,A"
					( Origin gPackager )
				)
				( attribute "GROUP" "PWR_MLCC_CAP"
					( Origin gFrontEnd )
				)
				( objectStatus "C5D27" )
			)
			( gate "@baseboard_fab2_lib.baseboard_fab2(sch_1):page42_i111"
				( attribute "BOM_COST" "PROC_SOCKET"
					( Origin gFrontEnd )
				)
				( attribute "CDS_LIB" "dev_discrete"
					( Origin gPackager )
				)
				( attribute "CDS_LOCATION" "C5D30"
					( Origin gPackager )
				)
				( attribute "CDS_SEC" "1"
					( Origin gPackager )
				)
				( attribute "LOCATION" "C5D30"
					( Origin gFrontEnd )
				)
				( attribute "MATERIAL" "X6S"
					( Origin gFrontEnd )
				)
				( attribute "PACK_TYPE" "0603V"
					( Origin gFrontEnd )
				)
				( attribute "PART_NUMBER" "E15431-004"
					( Origin gFrontEnd )
				)
				( attribute "PHYS_PAGE" "42"
					( Origin gFrontEnd )
				)
				( attribute "ROOM" "PVCCIN_CPU0_DECAP_VR"
					( Origin gFrontEnd )
				)
				( attribute "ROT" "0"
					( Origin gFrontEnd )
				)
				( attribute "SEC" "1"
					( Origin gPackager )
				)
				( attribute "TOLERANCE" "20%"
					( Origin gFrontEnd )
				)
				( attribute "VALUE" "22.0UF"
					( Origin gFrontEnd )
				)
				( attribute "VER" "1"
					( Origin gFrontEnd )
				)
				( attribute "VOLTAGE" "4V"
					( Units "uVoltage" "V" 1.000000)
					( Origin gFrontEnd )
				)
				( attribute "XY" "(-5300,3150)"
					( Origin gFrontEnd )
				)
				( attribute "CHIPS_PART_NAME" "CAP_A"
					( Origin gPackager )
				)
				( attribute "CDS_PART_NAME" "CAP_A_0603V-22.0UF,4V,20%,X6S,A"
					( Origin gPackager )
				)
				( attribute "GROUP" "PWR_MLCC_CAP"
					( Origin gFrontEnd )
				)
				( objectStatus "C5D30" )
			)
			( gate "@baseboard_fab2_lib.baseboard_fab2(sch_1):page217_i272"
				( attribute "BOM_COST" "PROC_SOCKET"
					( Origin gFrontEnd )
				)
				( attribute "CDS_LIB" "dev_discrete"
					( Origin gPackager )
				)
				( attribute "CDS_LOCATION" "C5D60"
					( Origin gPackager )
				)
				( attribute "CDS_SEC" "1"
					( Origin gPackager )
				)
				( attribute "LOCATION" "C5D60"
					( Origin gFrontEnd )
				)
				( attribute "MATERIAL" "X6S"
					( Origin gFrontEnd )
				)
				( attribute "PACK_TYPE" "0603V"
					( Origin gFrontEnd )
				)
				( attribute "PART_NUMBER" "E15431-004"
					( Origin gFrontEnd )
				)
				( attribute "PHYS_PAGE" "217"
					( Origin gFrontEnd )
				)
				( attribute "ROOM" "PVCCIN_CPU0_DECAP_VR"
					( Origin gFrontEnd )
				)
				( attribute "ROT" "0"
					( Origin gFrontEnd )
				)
				( attribute "SEC" "1"
					( Origin gPackager )
				)
				( attribute "TOLERANCE" "20%"
					( Origin gFrontEnd )
				)
				( attribute "VALUE" "22.0UF"
					( Origin gFrontEnd )
				)
				( attribute "VER" "1"
					( Origin gFrontEnd )
				)
				( attribute "VOLTAGE" "4V"
					( Units "uVoltage" "V" 1.000000)
					( Origin gFrontEnd )
				)
				( attribute "XY" "(1600,1950)"
					( Origin gFrontEnd )
				)
				( attribute "CHIPS_PART_NAME" "CAP_A"
					( Origin gPackager )
				)
				( attribute "CDS_PART_NAME" "CAP_A_0603V-22.0UF,4V,20%,X6S,A"
					( Origin gPackager )
				)
				( attribute "GROUP" "PWR_MLCC_CAP"
					( Origin gFrontEnd )
				)
				( objectStatus "C5D60" )
			)
			( gate "@baseboard_fab2_lib.baseboard_fab2(sch_1):page217_i271"
				( attribute "BOM_COST" "PROC_SOCKET"
					( Origin gFrontEnd )
				)
				( attribute "CDS_LIB" "dev_discrete"
					( Origin gPackager )
				)
				( attribute "CDS_LOCATION" "C5D59"
					( Origin gPackager )
				)
				( attribute "CDS_SEC" "1"
					( Origin gPackager )
				)
				( attribute "LOCATION" "C5D59"
					( Origin gFrontEnd )
				)
				( attribute "MATERIAL" "X6S"
					( Origin gFrontEnd )
				)
				( attribute "PACK_TYPE" "0603V"
					( Origin gFrontEnd )
				)
				( attribute "PART_NUMBER" "E15431-004"
					( Origin gFrontEnd )
				)
				( attribute "PHYS_PAGE" "217"
					( Origin gFrontEnd )
				)
				( attribute "ROOM" "PVCCIN_CPU0_DECAP_VR"
					( Origin gFrontEnd )
				)
				( attribute "ROT" "0"
					( Origin gFrontEnd )
				)
				( attribute "SEC" "1"
					( Origin gPackager )
				)
				( attribute "TOLERANCE" "20%"
					( Origin gFrontEnd )
				)
				( attribute "VALUE" "22.0UF"
					( Origin gFrontEnd )
				)
				( attribute "VER" "1"
					( Origin gFrontEnd )
				)
				( attribute "VOLTAGE" "4V"
					( Units "uVoltage" "V" 1.000000)
					( Origin gFrontEnd )
				)
				( attribute "XY" "(1300,1950)"
					( Origin gFrontEnd )
				)
				( attribute "CHIPS_PART_NAME" "CAP_A"
					( Origin gPackager )
				)
				( attribute "CDS_PART_NAME" "CAP_A_0603V-22.0UF,4V,20%,X6S,A"
					( Origin gPackager )
				)
				( attribute "GROUP" "PWR_MLCC_CAP"
					( Origin gFrontEnd )
				)
				( objectStatus "C5D59" )
			)
			( gate "@baseboard_fab2_lib.baseboard_fab2(sch_1):page42_i114"
				( attribute "BOM_COST" "PROC_SOCKET"
					( Origin gFrontEnd )
				)
				( attribute "CDS_LIB" "dev_discrete"
					( Origin gPackager )
				)
				( attribute "CDS_LOCATION" "C5D41"
					( Origin gPackager )
				)
				( attribute "CDS_SEC" "1"
					( Origin gPackager )
				)
				( attribute "LOCATION" "C5D41"
					( Origin gFrontEnd )
				)
				( attribute "MATERIAL" "X6S"
					( Origin gFrontEnd )
				)
				( attribute "PACK_TYPE" "0603V"
					( Origin gFrontEnd )
				)
				( attribute "PART_NUMBER" "E15431-004"
					( Origin gFrontEnd )
				)
				( attribute "PHYS_PAGE" "42"
					( Origin gFrontEnd )
				)
				( attribute "ROOM" "PVCCIN_CPU0_DECAP_VR"
					( Origin gFrontEnd )
				)
				( attribute "ROT" "0"
					( Origin gFrontEnd )
				)
				( attribute "SEC" "1"
					( Origin gPackager )
				)
				( attribute "TOLERANCE" "20%"
					( Origin gFrontEnd )
				)
				( attribute "VALUE" "22.0UF"
					( Origin gFrontEnd )
				)
				( attribute "VER" "1"
					( Origin gFrontEnd )
				)
				( attribute "VOLTAGE" "4V"
					( Units "uVoltage" "V" 1.000000)
					( Origin gFrontEnd )
				)
				( attribute "XY" "(-5800,3800)"
					( Origin gFrontEnd )
				)
				( attribute "CHIPS_PART_NAME" "CAP_A"
					( Origin gPackager )
				)
				( attribute "CDS_PART_NAME" "CAP_A_0603V-22.0UF,4V,20%,X6S,A"
					( Origin gPackager )
				)
				( attribute "GROUP" "PWR_MLCC_CAP"
					( Origin gFrontEnd )
				)
				( objectStatus "C5D41" )
			)
			( gate "@baseboard_fab2_lib.baseboard_fab2(sch_1):page42_i115"
				( attribute "BOM_COST" "PROC_SOCKET"
					( Origin gFrontEnd )
				)
				( attribute "CDS_LIB" "dev_discrete"
					( Origin gPackager )
				)
				( attribute "CDS_LOCATION" "C5D40"
					( Origin gPackager )
				)
				( attribute "CDS_SEC" "1"
					( Origin gPackager )
				)
				( attribute "LOCATION" "C5D40"
					( Origin gFrontEnd )
				)
				( attribute "MATERIAL" "X6S"
					( Origin gFrontEnd )
				)
				( attribute "PACK_TYPE" "0603V"
					( Origin gFrontEnd )
				)
				( attribute "PART_NUMBER" "E15431-004"
					( Origin gFrontEnd )
				)
				( attribute "PHYS_PAGE" "42"
					( Origin gFrontEnd )
				)
				( attribute "ROOM" "PVCCIN_CPU0_DECAP_VR"
					( Origin gFrontEnd )
				)
				( attribute "ROT" "0"
					( Origin gFrontEnd )
				)
				( attribute "SEC" "1"
					( Origin gPackager )
				)
				( attribute "TOLERANCE" "20%"
					( Origin gFrontEnd )
				)
				( attribute "VALUE" "22.0UF"
					( Origin gFrontEnd )
				)
				( attribute "VER" "1"
					( Origin gFrontEnd )
				)
				( attribute "VOLTAGE" "4V"
					( Units "uVoltage" "V" 1.000000)
					( Origin gFrontEnd )
				)
				( attribute "XY" "(-5650,4500)"
					( Origin gFrontEnd )
				)
				( attribute "CHIPS_PART_NAME" "CAP_A"
					( Origin gPackager )
				)
				( attribute "CDS_PART_NAME" "CAP_A_0603V-22.0UF,4V,20%,X6S,A"
					( Origin gPackager )
				)
				( attribute "GROUP" "PWR_MLCC_CAP"
					( Origin gFrontEnd )
				)
				( objectStatus "C5D40" )
			)
			( gate "@baseboard_fab2_lib.baseboard_fab2(sch_1):page42_i117"
				( attribute "BOM_COST" "PROC_SOCKET"
					( Origin gFrontEnd )
				)
				( attribute "CDS_LIB" "dev_discrete"
					( Origin gPackager )
				)
				( attribute "CDS_LOCATION" "C5D14"
					( Origin gPackager )
				)
				( attribute "CDS_SEC" "1"
					( Origin gPackager )
				)
				( attribute "LOCATION" "C5D14"
					( Origin gFrontEnd )
				)
				( attribute "MATERIAL" "X6S"
					( Origin gFrontEnd )
				)
				( attribute "PACK_TYPE" "0603V"
					( Origin gFrontEnd )
				)
				( attribute "PART_NUMBER" "E15431-004"
					( Origin gFrontEnd )
				)
				( attribute "PHYS_PAGE" "42"
					( Origin gFrontEnd )
				)
				( attribute "ROOM" "PVCCIN_CPU0_DECAP_VR"
					( Origin gFrontEnd )
				)
				( attribute "ROT" "0"
					( Origin gFrontEnd )
				)
				( attribute "SEC" "1"
					( Origin gPackager )
				)
				( attribute "TOLERANCE" "20%"
					( Origin gFrontEnd )
				)
				( attribute "VALUE" "22.0UF"
					( Origin gFrontEnd )
				)
				( attribute "VER" "1"
					( Origin gFrontEnd )
				)
				( attribute "VOLTAGE" "4V"
					( Units "uVoltage" "V" 1.000000)
					( Origin gFrontEnd )
				)
				( attribute "XY" "(-5950,4500)"
					( Origin gFrontEnd )
				)
				( attribute "CHIPS_PART_NAME" "CAP_A"
					( Origin gPackager )
				)
				( attribute "CDS_PART_NAME" "CAP_A_0603V-22.0UF,4V,20%,X6S,A"
					( Origin gPackager )
				)
				( attribute "GROUP" "PWR_MLCC_CAP"
					( Origin gFrontEnd )
				)
				( objectStatus "C5D14" )
			)
			( gate "@baseboard_fab2_lib.baseboard_fab2(sch_1):page42_i118"
				( attribute "BOM_COST" "PROC_SOCKET"
					( Origin gFrontEnd )
				)
				( attribute "CDS_LIB" "dev_discrete"
					( Origin gPackager )
				)
				( attribute "CDS_LOCATION" "C5D17"
					( Origin gPackager )
				)
				( attribute "CDS_SEC" "1"
					( Origin gPackager )
				)
				( attribute "LOCATION" "C5D17"
					( Origin gFrontEnd )
				)
				( attribute "MATERIAL" "X6S"
					( Origin gFrontEnd )
				)
				( attribute "PACK_TYPE" "0603V"
					( Origin gFrontEnd )
				)
				( attribute "PART_NUMBER" "E15431-004"
					( Origin gFrontEnd )
				)
				( attribute "PHYS_PAGE" "42"
					( Origin gFrontEnd )
				)
				( attribute "ROOM" "PVCCIN_CPU0_DECAP_VR"
					( Origin gFrontEnd )
				)
				( attribute "ROT" "0"
					( Origin gFrontEnd )
				)
				( attribute "SEC" "1"
					( Origin gPackager )
				)
				( attribute "TOLERANCE" "20%"
					( Origin gFrontEnd )
				)
				( attribute "VALUE" "22.0UF"
					( Origin gFrontEnd )
				)
				( attribute "VER" "1"
					( Origin gFrontEnd )
				)
				( attribute "VOLTAGE" "4V"
					( Units "uVoltage" "V" 1.000000)
					( Origin gFrontEnd )
				)
				( attribute "XY" "(-6750,4500)"
					( Origin gFrontEnd )
				)
				( attribute "CHIPS_PART_NAME" "CAP_A"
					( Origin gPackager )
				)
				( attribute "CDS_PART_NAME" "CAP_A_0603V-22.0UF,4V,20%,X6S,A"
					( Origin gPackager )
				)
				( attribute "GROUP" "PWR_MLCC_CAP"
					( Origin gFrontEnd )
				)
				( objectStatus "C5D17" )
			)
			( gate "@baseboard_fab2_lib.baseboard_fab2(sch_1):page217_i270"
				( attribute "BOM_COST" "PROC_SOCKET"
					( Origin gFrontEnd )
				)
				( attribute "CDS_LIB" "dev_discrete"
					( Origin gPackager )
				)
				( attribute "CDS_LOCATION" "C5D61"
					( Origin gPackager )
				)
				( attribute "CDS_SEC" "1"
					( Origin gPackager )
				)
				( attribute "LOCATION" "C5D61"
					( Origin gFrontEnd )
				)
				( attribute "MATERIAL" "X6S"
					( Origin gFrontEnd )
				)
				( attribute "PACK_TYPE" "0603V"
					( Origin gFrontEnd )
				)
				( attribute "PART_NUMBER" "E15431-004"
					( Origin gFrontEnd )
				)
				( attribute "PHYS_PAGE" "217"
					( Origin gFrontEnd )
				)
				( attribute "ROOM" "PVCCIN_CPU0_DECAP_VR"
					( Origin gFrontEnd )
				)
				( attribute "ROT" "0"
					( Origin gFrontEnd )
				)
				( attribute "SEC" "1"
					( Origin gPackager )
				)
				( attribute "TOLERANCE" "20%"
					( Origin gFrontEnd )
				)
				( attribute "VALUE" "22.0UF"
					( Origin gFrontEnd )
				)
				( attribute "VER" "1"
					( Origin gFrontEnd )
				)
				( attribute "VOLTAGE" "4V"
					( Units "uVoltage" "V" 1.000000)
					( Origin gFrontEnd )
				)
				( attribute "XY" "(1900,1950)"
					( Origin gFrontEnd )
				)
				( attribute "CHIPS_PART_NAME" "CAP_A"
					( Origin gPackager )
				)
				( attribute "CDS_PART_NAME" "CAP_A_0603V-22.0UF,4V,20%,X6S,A"
					( Origin gPackager )
				)
				( attribute "GROUP" "PWR_MLCC_CAP"
					( Origin gFrontEnd )
				)
				( objectStatus "C5D61" )
			)
			( gate "@baseboard_fab2_lib.baseboard_fab2(sch_1):page42_i123"
				( attribute "BOM_COST" "PROC_SOCKET"
					( Origin gFrontEnd )
				)
				( attribute "CDS_LIB" "dev_discrete"
					( Origin gPackager )
				)
				( attribute "CDS_LOCATION" "C5D16"
					( Origin gPackager )
				)
				( attribute "CDS_SEC" "1"
					( Origin gPackager )
				)
				( attribute "LOCATION" "C5D16"
					( Origin gFrontEnd )
				)
				( attribute "MATERIAL" "X6S"
					( Origin gFrontEnd )
				)
				( attribute "PACK_TYPE" "0603V"
					( Origin gFrontEnd )
				)
				( attribute "PART_NUMBER" "E15431-004"
					( Origin gFrontEnd )
				)
				( attribute "PHYS_PAGE" "42"
					( Origin gFrontEnd )
				)
				( attribute "ROOM" "PVCCIN_CPU0_DECAP_VR"
					( Origin gFrontEnd )
				)
				( attribute "ROT" "0"
					( Origin gFrontEnd )
				)
				( attribute "SEC" "1"
					( Origin gPackager )
				)
				( attribute "TOLERANCE" "20%"
					( Origin gFrontEnd )
				)
				( attribute "VALUE" "22.0UF"
					( Origin gFrontEnd )
				)
				( attribute "VER" "1"
					( Origin gFrontEnd )
				)
				( attribute "VOLTAGE" "4V"
					( Units "uVoltage" "V" 1.000000)
					( Origin gFrontEnd )
				)
				( attribute "XY" "(-6750,3800)"
					( Origin gFrontEnd )
				)
				( attribute "CHIPS_PART_NAME" "CAP_A"
					( Origin gPackager )
				)
				( attribute "CDS_PART_NAME" "CAP_A_0603V-22.0UF,4V,20%,X6S,A"
					( Origin gPackager )
				)
				( attribute "GROUP" "PWR_MLCC_CAP"
					( Origin gFrontEnd )
				)
				( objectStatus "C5D16" )
			)
			( gate "@baseboard_fab2_lib.baseboard_fab2(sch_1):page42_i125"
				( attribute "BOM_COST" "PROC_SOCKET"
					( Origin gFrontEnd )
				)
				( attribute "CDS_LIB" "dev_discrete"
					( Origin gPackager )
				)
				( attribute "CDS_LOCATION" "C5D5"
					( Origin gPackager )
				)
				( attribute "CDS_SEC" "1"
					( Origin gPackager )
				)
				( attribute "LOCATION" "C5D5"
					( Origin gFrontEnd )
				)
				( attribute "MATERIAL" "X6S"
					( Origin gFrontEnd )
				)
				( attribute "PACK_TYPE" "0603V"
					( Origin gFrontEnd )
				)
				( attribute "PART_NUMBER" "E15431-004"
					( Origin gFrontEnd )
				)
				( attribute "PHYS_PAGE" "42"
					( Origin gFrontEnd )
				)
				( attribute "ROOM" "PVCCIN_CPU0_DECAP_VR"
					( Origin gFrontEnd )
				)
				( attribute "ROT" "0"
					( Origin gFrontEnd )
				)
				( attribute "SEC" "1"
					( Origin gPackager )
				)
				( attribute "TOLERANCE" "20%"
					( Origin gFrontEnd )
				)
				( attribute "VALUE" "22.0UF"
					( Origin gFrontEnd )
				)
				( attribute "VER" "1"
					( Origin gFrontEnd )
				)
				( attribute "VOLTAGE" "4V"
					( Units "uVoltage" "V" 1.000000)
					( Origin gFrontEnd )
				)
				( attribute "XY" "(-7050,4500)"
					( Origin gFrontEnd )
				)
				( attribute "CHIPS_PART_NAME" "CAP_A"
					( Origin gPackager )
				)
				( attribute "CDS_PART_NAME" "CAP_A_0603V-22.0UF,4V,20%,X6S,A"
					( Origin gPackager )
				)
				( attribute "GROUP" "PWR_MLCC_CAP"
					( Origin gFrontEnd )
				)
				( objectStatus "C5D5" )
			)
			( gate "@baseboard_fab2_lib.baseboard_fab2(sch_1):page220_i252"
				( attribute "BOM_COST" "PROC_SOCKET"
					( Origin gFrontEnd )
				)
				( attribute "CDS_LIB" "dev_discrete"
					( Origin gPackager )
				)
				( attribute "CDS_LOCATION" "C5D1"
					( Origin gPackager )
				)
				( attribute "CDS_SEC" "1"
					( Origin gPackager )
				)
				( attribute "LOCATION" "C5D1"
					( Origin gFrontEnd )
				)
				( attribute "MATERIAL" "X6S"
					( Origin gFrontEnd )
				)
				( attribute "PACK_TYPE" "0603V"
					( Origin gFrontEnd )
				)
				( attribute "PART_NUMBER" "E15431-004"
					( Origin gFrontEnd )
				)
				( attribute "PHYS_PAGE" "220"
					( Origin gFrontEnd )
				)
				( attribute "ROOM" "PVCCIN_CPU0_DECAP_VR"
					( Origin gFrontEnd )
				)
				( attribute "ROT" "0"
					( Origin gFrontEnd )
				)
				( attribute "SEC" "1"
					( Origin gPackager )
				)
				( attribute "TOLERANCE" "20%"
					( Origin gFrontEnd )
				)
				( attribute "VALUE" "22.0UF"
					( Origin gFrontEnd )
				)
				( attribute "VER" "1"
					( Origin gFrontEnd )
				)
				( attribute "VOLTAGE" "4V"
					( Units "uVoltage" "V" 1.000000)
					( Origin gFrontEnd )
				)
				( attribute "XY" "(500,2050)"
					( Origin gFrontEnd )
				)
				( attribute "CHIPS_PART_NAME" "CAP_A"
					( Origin gPackager )
				)
				( attribute "CDS_PART_NAME" "CAP_A_0603V-22.0UF,4V,20%,X6S,A"
					( Origin gPackager )
				)
				( attribute "GROUP" "PWR_MLCC_CAP"
					( Origin gFrontEnd )
				)
				( objectStatus "C5D1" )
			)
			( gate "@baseboard_fab2_lib.baseboard_fab2(sch_1):page220_i251"
				( attribute "BOM_COST" "PROC_SOCKET"
					( Origin gFrontEnd )
				)
				( attribute "CDS_LIB" "dev_discrete"
					( Origin gPackager )
				)
				( attribute "CDS_LOCATION" "C5D2"
					( Origin gPackager )
				)
				( attribute "CDS_SEC" "1"
					( Origin gPackager )
				)
				( attribute "LOCATION" "C5D2"
					( Origin gFrontEnd )
				)
				( attribute "MATERIAL" "X6S"
					( Origin gFrontEnd )
				)
				( attribute "PACK_TYPE" "0603V"
					( Origin gFrontEnd )
				)
				( attribute "PART_NUMBER" "E15431-004"
					( Origin gFrontEnd )
				)
				( attribute "PHYS_PAGE" "220"
					( Origin gFrontEnd )
				)
				( attribute "ROOM" "PVCCIN_CPU0_DECAP_VR"
					( Origin gFrontEnd )
				)
				( attribute "ROT" "0"
					( Origin gFrontEnd )
				)
				( attribute "SEC" "1"
					( Origin gPackager )
				)
				( attribute "TOLERANCE" "20%"
					( Origin gFrontEnd )
				)
				( attribute "VALUE" "22.0UF"
					( Origin gFrontEnd )
				)
				( attribute "VER" "1"
					( Origin gFrontEnd )
				)
				( attribute "VOLTAGE" "4V"
					( Units "uVoltage" "V" 1.000000)
					( Origin gFrontEnd )
				)
				( attribute "XY" "(850,2050)"
					( Origin gFrontEnd )
				)
				( attribute "CHIPS_PART_NAME" "CAP_A"
					( Origin gPackager )
				)
				( attribute "CDS_PART_NAME" "CAP_A_0603V-22.0UF,4V,20%,X6S,A"
					( Origin gPackager )
				)
				( attribute "GROUP" "PWR_MLCC_CAP"
					( Origin gFrontEnd )
				)
				( objectStatus "C5D2" )
			)
			( gate "@baseboard_fab2_lib.baseboard_fab2(sch_1):page42_i128"
				( attribute "BOM_COST" "PROC_SOCKET"
					( Origin gFrontEnd )
				)
				( attribute "CDS_LIB" "dev_discrete"
					( Origin gPackager )
				)
				( attribute "CDS_LOCATION" "C5D19"
					( Origin gPackager )
				)
				( attribute "CDS_SEC" "1"
					( Origin gPackager )
				)
				( attribute "LOCATION" "C5D19"
					( Origin gFrontEnd )
				)
				( attribute "MATERIAL" "X6S"
					( Origin gFrontEnd )
				)
				( attribute "PACK_TYPE" "0603V"
					( Origin gFrontEnd )
				)
				( attribute "PART_NUMBER" "E15431-004"
					( Origin gFrontEnd )
				)
				( attribute "PHYS_PAGE" "42"
					( Origin gFrontEnd )
				)
				( attribute "ROOM" "PVCCIN_CPU0_DECAP_VR"
					( Origin gFrontEnd )
				)
				( attribute "ROT" "0"
					( Origin gFrontEnd )
				)
				( attribute "SEC" "1"
					( Origin gPackager )
				)
				( attribute "TOLERANCE" "20%"
					( Origin gFrontEnd )
				)
				( attribute "VALUE" "22.0UF"
					( Origin gFrontEnd )
				)
				( attribute "VER" "1"
					( Origin gFrontEnd )
				)
				( attribute "VOLTAGE" "4V"
					( Units "uVoltage" "V" 1.000000)
					( Origin gFrontEnd )
				)
				( attribute "XY" "(-7050,3800)"
					( Origin gFrontEnd )
				)
				( attribute "CHIPS_PART_NAME" "CAP_A"
					( Origin gPackager )
				)
				( attribute "CDS_PART_NAME" "CAP_A_0603V-22.0UF,4V,20%,X6S,A"
					( Origin gPackager )
				)
				( attribute "GROUP" "PWR_MLCC_CAP"
					( Origin gFrontEnd )
				)
				( objectStatus "C5D19" )
			)
			( gate "@baseboard_fab2_lib.baseboard_fab2(sch_1):page217_i269"
				( attribute "BOM_COST" "PROC_SOCKET"
					( Origin gFrontEnd )
				)
				( attribute "CDS_LIB" "dev_discrete"
					( Origin gPackager )
				)
				( attribute "CDS_LOCATION" "C5D58"
					( Origin gPackager )
				)
				( attribute "CDS_SEC" "1"
					( Origin gPackager )
				)
				( attribute "LOCATION" "C5D58"
					( Origin gFrontEnd )
				)
				( attribute "MATERIAL" "X6S"
					( Origin gFrontEnd )
				)
				( attribute "PACK_TYPE" "0603V"
					( Origin gFrontEnd )
				)
				( attribute "PART_NUMBER" "E15431-004"
					( Origin gFrontEnd )
				)
				( attribute "PHYS_PAGE" "217"
					( Origin gFrontEnd )
				)
				( attribute "ROOM" "PVCCIN_CPU0_DECAP_VR"
					( Origin gFrontEnd )
				)
				( attribute "ROT" "0"
					( Origin gFrontEnd )
				)
				( attribute "SEC" "1"
					( Origin gPackager )
				)
				( attribute "TOLERANCE" "20%"
					( Origin gFrontEnd )
				)
				( attribute "VALUE" "22.0UF"
					( Origin gFrontEnd )
				)
				( attribute "VER" "1"
					( Origin gFrontEnd )
				)
				( attribute "VOLTAGE" "4V"
					( Units "uVoltage" "V" 1.000000)
					( Origin gFrontEnd )
				)
				( attribute "XY" "(1000,1950)"
					( Origin gFrontEnd )
				)
				( attribute "CHIPS_PART_NAME" "CAP_A"
					( Origin gPackager )
				)
				( attribute "CDS_PART_NAME" "CAP_A_0603V-22.0UF,4V,20%,X6S,A"
					( Origin gPackager )
				)
				( attribute "GROUP" "PWR_MLCC_CAP"
					( Origin gFrontEnd )
				)
				( objectStatus "C5D58" )
			)
			( gate "@baseboard_fab2_lib.baseboard_fab2(sch_1):page220_i250"
				( attribute "BOM_COST" "PROC_SOCKET"
					( Origin gFrontEnd )
				)
				( attribute "CDS_LIB" "dev_discrete"
					( Origin gPackager )
				)
				( attribute "CDS_LOCATION" "C5D3"
					( Origin gPackager )
				)
				( attribute "CDS_SEC" "1"
					( Origin gPackager )
				)
				( attribute "LOCATION" "C5D3"
					( Origin gFrontEnd )
				)
				( attribute "MATERIAL" "X6S"
					( Origin gFrontEnd )
				)
				( attribute "PACK_TYPE" "0603V"
					( Origin gFrontEnd )
				)
				( attribute "PART_NUMBER" "E15431-004"
					( Origin gFrontEnd )
				)
				( attribute "PHYS_PAGE" "220"
					( Origin gFrontEnd )
				)
				( attribute "ROOM" "PVCCIN_CPU0_DECAP_VR"
					( Origin gFrontEnd )
				)
				( attribute "ROT" "0"
					( Origin gFrontEnd )
				)
				( attribute "SEC" "1"
					( Origin gPackager )
				)
				( attribute "TOLERANCE" "20%"
					( Origin gFrontEnd )
				)
				( attribute "VALUE" "22.0UF"
					( Origin gFrontEnd )
				)
				( attribute "VER" "1"
					( Origin gFrontEnd )
				)
				( attribute "VOLTAGE" "4V"
					( Units "uVoltage" "V" 1.000000)
					( Origin gFrontEnd )
				)
				( attribute "XY" "(1200,2050)"
					( Origin gFrontEnd )
				)
				( attribute "CHIPS_PART_NAME" "CAP_A"
					( Origin gPackager )
				)
				( attribute "CDS_PART_NAME" "CAP_A_0603V-22.0UF,4V,20%,X6S,A"
					( Origin gPackager )
				)
				( attribute "GROUP" "PWR_MLCC_CAP"
					( Origin gFrontEnd )
				)
				( objectStatus "C5D3" )
			)
			( gate "@baseboard_fab2_lib.baseboard_fab2(sch_1):page42_i131"
				( attribute "BOM_COST" "PROC_SOCKET"
					( Origin gFrontEnd )
				)
				( attribute "CDS_LIB" "dev_discrete"
					( Origin gPackager )
				)
				( attribute "CDS_LOCATION" "C5D43"
					( Origin gPackager )
				)
				( attribute "CDS_SEC" "1"
					( Origin gPackager )
				)
				( attribute "LOCATION" "C5D43"
					( Origin gFrontEnd )
				)
				( attribute "MATERIAL" "X6S"
					( Origin gFrontEnd )
				)
				( attribute "PACK_TYPE" "0603V"
					( Origin gFrontEnd )
				)
				( attribute "PART_NUMBER" "E15431-004"
					( Origin gFrontEnd )
				)
				( attribute "PHYS_PAGE" "42"
					( Origin gFrontEnd )
				)
				( attribute "ROOM" "PVCCIN_CPU0_DECAP_VR"
					( Origin gFrontEnd )
				)
				( attribute "ROT" "0"
					( Origin gFrontEnd )
				)
				( attribute "SEC" "1"
					( Origin gPackager )
				)
				( attribute "TOLERANCE" "20%"
					( Origin gFrontEnd )
				)
				( attribute "VALUE" "22.0UF"
					( Origin gFrontEnd )
				)
				( attribute "VER" "1"
					( Origin gFrontEnd )
				)
				( attribute "VOLTAGE" "4V"
					( Units "uVoltage" "V" 1.000000)
					( Origin gFrontEnd )
				)
				( attribute "XY" "(-5950,3150)"
					( Origin gFrontEnd )
				)
				( attribute "CHIPS_PART_NAME" "CAP_A"
					( Origin gPackager )
				)
				( attribute "CDS_PART_NAME" "CAP_A_0603V-22.0UF,4V,20%,X6S,A"
					( Origin gPackager )
				)
				( attribute "GROUP" "PWR_MLCC_CAP"
					( Origin gFrontEnd )
				)
				( objectStatus "C5D43" )
			)
			( gate "@baseboard_fab2_lib.baseboard_fab2(sch_1):page42_i132"
				( attribute "BOM_COST" "PROC_SOCKET"
					( Origin gFrontEnd )
				)
				( attribute "CDS_LIB" "dev_discrete"
					( Origin gPackager )
				)
				( attribute "CDS_LOCATION" "C5D15"
					( Origin gPackager )
				)
				( attribute "CDS_SEC" "1"
					( Origin gPackager )
				)
				( attribute "LOCATION" "C5D15"
					( Origin gFrontEnd )
				)
				( attribute "MATERIAL" "X6S"
					( Origin gFrontEnd )
				)
				( attribute "PACK_TYPE" "0603V"
					( Origin gFrontEnd )
				)
				( attribute "PART_NUMBER" "E15431-004"
					( Origin gFrontEnd )
				)
				( attribute "PHYS_PAGE" "42"
					( Origin gFrontEnd )
				)
				( attribute "ROOM" "PVCCIN_CPU0_DECAP_VR"
					( Origin gFrontEnd )
				)
				( attribute "ROT" "0"
					( Origin gFrontEnd )
				)
				( attribute "SEC" "1"
					( Origin gPackager )
				)
				( attribute "TOLERANCE" "20%"
					( Origin gFrontEnd )
				)
				( attribute "VALUE" "22.0UF"
					( Origin gFrontEnd )
				)
				( attribute "VER" "1"
					( Origin gFrontEnd )
				)
				( attribute "VOLTAGE" "4V"
					( Units "uVoltage" "V" 1.000000)
					( Origin gFrontEnd )
				)
				( attribute "XY" "(-6650,3100)"
					( Origin gFrontEnd )
				)
				( attribute "CHIPS_PART_NAME" "CAP_A"
					( Origin gPackager )
				)
				( attribute "CDS_PART_NAME" "CAP_A_0603V-22.0UF,4V,20%,X6S,A"
					( Origin gPackager )
				)
				( attribute "GROUP" "PWR_MLCC_CAP"
					( Origin gFrontEnd )
				)
				( objectStatus "C5D15" )
			)
			( gate "@baseboard_fab2_lib.baseboard_fab2(sch_1):page42_i134"
				( attribute "BOM_COST" "PROC_SOCKET"
					( Origin gFrontEnd )
				)
				( attribute "CDS_LIB" "dev_discrete"
					( Origin gPackager )
				)
				( attribute "CDS_LOCATION" "C5D18"
					( Origin gPackager )
				)
				( attribute "CDS_SEC" "1"
					( Origin gPackager )
				)
				( attribute "LOCATION" "C5D18"
					( Origin gFrontEnd )
				)
				( attribute "MATERIAL" "X6S"
					( Origin gFrontEnd )
				)
				( attribute "PACK_TYPE" "0603V"
					( Origin gFrontEnd )
				)
				( attribute "PART_NUMBER" "E15431-004"
					( Origin gFrontEnd )
				)
				( attribute "PHYS_PAGE" "42"
					( Origin gFrontEnd )
				)
				( attribute "ROOM" "PVCCIN_CPU0_DECAP_VR"
					( Origin gFrontEnd )
				)
				( attribute "ROT" "0"
					( Origin gFrontEnd )
				)
				( attribute "SEC" "1"
					( Origin gPackager )
				)
				( attribute "TOLERANCE" "20%"
					( Origin gFrontEnd )
				)
				( attribute "VALUE" "22.0UF"
					( Origin gFrontEnd )
				)
				( attribute "VER" "1"
					( Origin gFrontEnd )
				)
				( attribute "VOLTAGE" "4V"
					( Units "uVoltage" "V" 1.000000)
					( Origin gFrontEnd )
				)
				( attribute "XY" "(-6950,3100)"
					( Origin gFrontEnd )
				)
				( attribute "CHIPS_PART_NAME" "CAP_A"
					( Origin gPackager )
				)
				( attribute "CDS_PART_NAME" "CAP_A_0603V-22.0UF,4V,20%,X6S,A"
					( Origin gPackager )
				)
				( attribute "GROUP" "PWR_MLCC_CAP"
					( Origin gFrontEnd )
				)
				( objectStatus "C5D18" )
			)
			( gate "@baseboard_fab2_lib.baseboard_fab2(sch_1):page42_i135"
				( attribute "BOM_COST" "PROC_SOCKET"
					( Origin gFrontEnd )
				)
				( attribute "CDS_LIB" "dev_discrete"
					( Origin gPackager )
				)
				( attribute "CDS_LOCATION" "C5D42"
					( Origin gPackager )
				)
				( attribute "CDS_SEC" "1"
					( Origin gPackager )
				)
				( attribute "LOCATION" "C5D42"
					( Origin gFrontEnd )
				)
				( attribute "MATERIAL" "X6S"
					( Origin gFrontEnd )
				)
				( attribute "PACK_TYPE" "0603V"
					( Origin gFrontEnd )
				)
				( attribute "PART_NUMBER" "E15431-004"
					( Origin gFrontEnd )
				)
				( attribute "PHYS_PAGE" "42"
					( Origin gFrontEnd )
				)
				( attribute "ROOM" "PVCCIN_CPU0_DECAP_VR"
					( Origin gFrontEnd )
				)
				( attribute "ROT" "0"
					( Origin gFrontEnd )
				)
				( attribute "SEC" "1"
					( Origin gPackager )
				)
				( attribute "TOLERANCE" "20%"
					( Origin gFrontEnd )
				)
				( attribute "VALUE" "22.0UF"
					( Origin gFrontEnd )
				)
				( attribute "VER" "1"
					( Origin gFrontEnd )
				)
				( attribute "VOLTAGE" "4V"
					( Units "uVoltage" "V" 1.000000)
					( Origin gFrontEnd )
				)
				( attribute "XY" "(-7250,3100)"
					( Origin gFrontEnd )
				)
				( attribute "CHIPS_PART_NAME" "CAP_A"
					( Origin gPackager )
				)
				( attribute "CDS_PART_NAME" "CAP_A_0603V-22.0UF,4V,20%,X6S,A"
					( Origin gPackager )
				)
				( attribute "GROUP" "PWR_MLCC_CAP"
					( Origin gFrontEnd )
				)
				( objectStatus "C5D42" )
			)
			( gate "@baseboard_fab2_lib.baseboard_fab2(sch_1):page220_i249"
				( attribute "BOM_COST" "PROC_SOCKET"
					( Origin gFrontEnd )
				)
				( attribute "CDS_LIB" "dev_discrete"
					( Origin gPackager )
				)
				( attribute "CDS_LOCATION" "C5D4"
					( Origin gPackager )
				)
				( attribute "CDS_SEC" "1"
					( Origin gPackager )
				)
				( attribute "LOCATION" "C5D4"
					( Origin gFrontEnd )
				)
				( attribute "MATERIAL" "X6S"
					( Origin gFrontEnd )
				)
				( attribute "PACK_TYPE" "0603V"
					( Origin gFrontEnd )
				)
				( attribute "PART_NUMBER" "E15431-004"
					( Origin gFrontEnd )
				)
				( attribute "PHYS_PAGE" "220"
					( Origin gFrontEnd )
				)
				( attribute "ROOM" "PVCCIN_CPU0_DECAP_VR"
					( Origin gFrontEnd )
				)
				( attribute "ROT" "0"
					( Origin gFrontEnd )
				)
				( attribute "SEC" "1"
					( Origin gPackager )
				)
				( attribute "TOLERANCE" "20%"
					( Origin gFrontEnd )
				)
				( attribute "VALUE" "22.0UF"
					( Origin gFrontEnd )
				)
				( attribute "VER" "1"
					( Origin gFrontEnd )
				)
				( attribute "VOLTAGE" "4V"
					( Units "uVoltage" "V" 1.000000)
					( Origin gFrontEnd )
				)
				( attribute "XY" "(1550,2050)"
					( Origin gFrontEnd )
				)
				( attribute "CHIPS_PART_NAME" "CAP_A"
					( Origin gPackager )
				)
				( attribute "CDS_PART_NAME" "CAP_A_0603V-22.0UF,4V,20%,X6S,A"
					( Origin gPackager )
				)
				( attribute "GROUP" "PWR_MLCC_CAP"
					( Origin gFrontEnd )
				)
				( objectStatus "C5D4" )
			)
			( gate "@baseboard_fab2_lib.baseboard_fab2(sch_1):page42_i138"
				( attribute "BOM_COST" "PROC_SOCKET"
					( Origin gFrontEnd )
				)
				( attribute "CDS_LIB" "dev_discrete"
					( Origin gPackager )
				)
				( attribute "CDS_LOCATION" "C5D24"
					( Origin gPackager )
				)
				( attribute "CDS_SEC" "1"
					( Origin gPackager )
				)
				( attribute "LOCATION" "C5D24"
					( Origin gFrontEnd )
				)
				( attribute "MATERIAL" "X6S"
					( Origin gFrontEnd )
				)
				( attribute "PACK_TYPE" "0603V"
					( Origin gFrontEnd )
				)
				( attribute "PART_NUMBER" "E15431-004"
					( Origin gFrontEnd )
				)
				( attribute "PHYS_PAGE" "42"
					( Origin gFrontEnd )
				)
				( attribute "ROOM" "PVCCIN_CPU0_DECAP_VR"
					( Origin gFrontEnd )
				)
				( attribute "ROT" "0"
					( Origin gFrontEnd )
				)
				( attribute "SEC" "1"
					( Origin gPackager )
				)
				( attribute "TOLERANCE" "20%"
					( Origin gFrontEnd )
				)
				( attribute "VALUE" "22.0UF"
					( Origin gFrontEnd )
				)
				( attribute "VER" "1"
					( Origin gFrontEnd )
				)
				( attribute "VOLTAGE" "4V"
					( Units "uVoltage" "V" 1.000000)
					( Origin gFrontEnd )
				)
				( attribute "XY" "(-7750,4500)"
					( Origin gFrontEnd )
				)
				( attribute "CHIPS_PART_NAME" "CAP_A"
					( Origin gPackager )
				)
				( attribute "CDS_PART_NAME" "CAP_A_0603V-22.0UF,4V,20%,X6S,A"
					( Origin gPackager )
				)
				( attribute "GROUP" "PWR_MLCC_CAP"
					( Origin gFrontEnd )
				)
				( objectStatus "C5D24" )
			)
			( gate "@baseboard_fab2_lib.baseboard_fab2(sch_1):page42_i140"
				( attribute "BOM_COST" "PROC_SOCKET"
					( Origin gFrontEnd )
				)
				( attribute "CDS_LIB" "dev_discrete"
					( Origin gPackager )
				)
				( attribute "CDS_LOCATION" "C5D39"
					( Origin gPackager )
				)
				( attribute "CDS_SEC" "1"
					( Origin gPackager )
				)
				( attribute "LOCATION" "C5D39"
					( Origin gFrontEnd )
				)
				( attribute "MATERIAL" "X6S"
					( Origin gFrontEnd )
				)
				( attribute "PACK_TYPE" "0603V"
					( Origin gFrontEnd )
				)
				( attribute "PART_NUMBER" "E15431-004"
					( Origin gFrontEnd )
				)
				( attribute "PHYS_PAGE" "42"
					( Origin gFrontEnd )
				)
				( attribute "ROOM" "PVCCIN_CPU0_DECAP_VR"
					( Origin gFrontEnd )
				)
				( attribute "ROT" "0"
					( Origin gFrontEnd )
				)
				( attribute "SEC" "1"
					( Origin gPackager )
				)
				( attribute "TOLERANCE" "20%"
					( Origin gFrontEnd )
				)
				( attribute "VALUE" "22.0UF"
					( Origin gFrontEnd )
				)
				( attribute "VER" "1"
					( Origin gFrontEnd )
				)
				( attribute "VOLTAGE" "4V"
					( Units "uVoltage" "V" 1.000000)
					( Origin gFrontEnd )
				)
				( attribute "XY" "(-7750,3800)"
					( Origin gFrontEnd )
				)
				( attribute "CHIPS_PART_NAME" "CAP_A"
					( Origin gPackager )
				)
				( attribute "CDS_PART_NAME" "CAP_A_0603V-22.0UF,4V,20%,X6S,A"
					( Origin gPackager )
				)
				( attribute "GROUP" "PWR_MLCC_CAP"
					( Origin gFrontEnd )
				)
				( objectStatus "C5D39" )
			)
			( gate "@baseboard_fab2_lib.baseboard_fab2(sch_1):page42_i142"
				( attribute "BOM_COST" "PROC_SOCKET"
					( Origin gFrontEnd )
				)
				( attribute "CDS_LIB" "dev_discrete"
					( Origin gPackager )
				)
				( attribute "CDS_LOCATION" "C5D44"
					( Origin gPackager )
				)
				( attribute "CDS_SEC" "1"
					( Origin gPackager )
				)
				( attribute "LOCATION" "C5D44"
					( Origin gFrontEnd )
				)
				( attribute "MATERIAL" "X6S"
					( Origin gFrontEnd )
				)
				( attribute "PACK_TYPE" "0603V"
					( Origin gFrontEnd )
				)
				( attribute "PART_NUMBER" "E15431-004"
					( Origin gFrontEnd )
				)
				( attribute "PHYS_PAGE" "42"
					( Origin gFrontEnd )
				)
				( attribute "ROOM" "PVCCIN_CPU0_DECAP_VR"
					( Origin gFrontEnd )
				)
				( attribute "ROT" "0"
					( Origin gFrontEnd )
				)
				( attribute "SEC" "1"
					( Origin gPackager )
				)
				( attribute "TOLERANCE" "20%"
					( Origin gFrontEnd )
				)
				( attribute "VALUE" "22.0UF"
					( Origin gFrontEnd )
				)
				( attribute "VER" "1"
					( Origin gFrontEnd )
				)
				( attribute "VOLTAGE" "4V"
					( Units "uVoltage" "V" 1.000000)
					( Origin gFrontEnd )
				)
				( attribute "XY" "(-7750,3100)"
					( Origin gFrontEnd )
				)
				( attribute "CHIPS_PART_NAME" "CAP_A"
					( Origin gPackager )
				)
				( attribute "CDS_PART_NAME" "CAP_A_0603V-22.0UF,4V,20%,X6S,A"
					( Origin gPackager )
				)
				( attribute "GROUP" "PWR_MLCC_CAP"
					( Origin gFrontEnd )
				)
				( objectStatus "C5D44" )
			)
			( gate "@baseboard_fab2_lib.baseboard_fab2(sch_1):page42_i145"
				( attribute "CDS_LIB" "dev_discrete"
					( Origin gPackager )
				)
				( attribute "CDS_LOCATION" "C6D9"
					( Origin gPackager )
				)
				( attribute "CDS_SEC" "1"
					( Origin gPackager )
				)
				( attribute "LOCATION" "C6D9"
					( Origin gFrontEnd )
				)
				( attribute "MATERIAL" "X6S"
					( Origin gFrontEnd )
				)
				( attribute "PACK_TYPE" "0603V"
					( Origin gFrontEnd )
				)
				( attribute "PART_NUMBER" "E15431-004"
					( Origin gFrontEnd )
				)
				( attribute "PHYS_PAGE" "42"
					( Origin gFrontEnd )
				)
				( attribute "ROOM" "PVCCIN_CPU0_DECAP_VR"
					( Origin gFrontEnd )
				)
				( attribute "ROT" "0"
					( Origin gFrontEnd )
				)
				( attribute "SEC" "1"
					( Origin gPackager )
				)
				( attribute "TOLERANCE" "20%"
					( Origin gFrontEnd )
				)
				( attribute "VALUE" "22.0UF"
					( Origin gFrontEnd )
				)
				( attribute "VER" "1"
					( Origin gFrontEnd )
				)
				( attribute "VOLTAGE" "4V"
					( Units "uVoltage" "V" 1.000000)
					( Origin gFrontEnd )
				)
				( attribute "XY" "(-2850,3800)"
					( Origin gFrontEnd )
				)
				( attribute "CHIPS_PART_NAME" "CAP_A"
					( Origin gPackager )
				)
				( attribute "CDS_PART_NAME" "CAP_A_0603V-22.0UF,4V,20%,X6S,A"
					( Origin gPackager )
				)
				( attribute "GROUP" "PWR_MLCC_CAP"
					( Origin gFrontEnd )
				)
				( objectStatus "C6D9" )
			)
			( gate "@baseboard_fab2_lib.baseboard_fab2(sch_1):page42_i147"
				( attribute "CDS_LIB" "dev_discrete"
					( Origin gPackager )
				)
				( attribute "CDS_LOCATION" "C6D10"
					( Origin gPackager )
				)
				( attribute "CDS_SEC" "1"
					( Origin gPackager )
				)
				( attribute "LOCATION" "C6D10"
					( Origin gFrontEnd )
				)
				( attribute "MATERIAL" "X6S"
					( Origin gFrontEnd )
				)
				( attribute "PACK_TYPE" "0603V"
					( Origin gFrontEnd )
				)
				( attribute "PART_NUMBER" "E15431-004"
					( Origin gFrontEnd )
				)
				( attribute "PHYS_PAGE" "42"
					( Origin gFrontEnd )
				)
				( attribute "ROOM" "PVCCIN_CPU0_DECAP_VR"
					( Origin gFrontEnd )
				)
				( attribute "ROT" "0"
					( Origin gFrontEnd )
				)
				( attribute "SEC" "1"
					( Origin gPackager )
				)
				( attribute "TOLERANCE" "20%"
					( Origin gFrontEnd )
				)
				( attribute "VALUE" "22.0UF"
					( Origin gFrontEnd )
				)
				( attribute "VER" "1"
					( Origin gFrontEnd )
				)
				( attribute "VOLTAGE" "4V"
					( Units "uVoltage" "V" 1.000000)
					( Origin gFrontEnd )
				)
				( attribute "XY" "(-3100,3800)"
					( Origin gFrontEnd )
				)
				( attribute "CHIPS_PART_NAME" "CAP_A"
					( Origin gPackager )
				)
				( attribute "CDS_PART_NAME" "CAP_A_0603V-22.0UF,4V,20%,X6S,A"
					( Origin gPackager )
				)
				( attribute "GROUP" "PWR_MLCC_CAP"
					( Origin gFrontEnd )
				)
				( objectStatus "C6D10" )
			)
			( gate "@baseboard_fab2_lib.baseboard_fab2(sch_1):page42_i151"
				( attribute "BOM_COST" "PROC_SOCKET"
					( Origin gFrontEnd )
				)
				( attribute "CDS_LIB" "dev_discrete"
					( Origin gPackager )
				)
				( attribute "CDS_LOCATION" "C5D36"
					( Origin gPackager )
				)
				( attribute "CDS_SEC" "1"
					( Origin gPackager )
				)
				( attribute "LOCATION" "C5D36"
					( Origin gFrontEnd )
				)
				( attribute "MATERIAL" "X6S"
					( Origin gFrontEnd )
				)
				( attribute "PACK_TYPE" "0603V"
					( Origin gFrontEnd )
				)
				( attribute "PART_NUMBER" "E15431-004"
					( Origin gFrontEnd )
				)
				( attribute "PHYS_PAGE" "42"
					( Origin gFrontEnd )
				)
				( attribute "ROOM" "PVCCIN_CPU0_DECAP_VR"
					( Origin gFrontEnd )
				)
				( attribute "ROT" "0"
					( Origin gFrontEnd )
				)
				( attribute "SEC" "1"
					( Origin gPackager )
				)
				( attribute "TOLERANCE" "20%"
					( Origin gFrontEnd )
				)
				( attribute "VALUE" "22.0UF"
					( Origin gFrontEnd )
				)
				( attribute "VER" "1"
					( Origin gFrontEnd )
				)
				( attribute "VOLTAGE" "4V"
					( Units "uVoltage" "V" 1.000000)
					( Origin gFrontEnd )
				)
				( attribute "XY" "(-2300,4500)"
					( Origin gFrontEnd )
				)
				( attribute "CHIPS_PART_NAME" "CAP_A"
					( Origin gPackager )
				)
				( attribute "CDS_PART_NAME" "CAP_A_0603V-22.0UF,4V,20%,X6S,A"
					( Origin gPackager )
				)
				( attribute "GROUP" "PWR_MCP_CAP"
					( Origin gFrontEnd )
				)
				( objectStatus "C5D36" )
			)
			( gate "@baseboard_fab2_lib.baseboard_fab2(sch_1):page42_i152"
				( attribute "BOM_COST" "PROC_SOCKET"
					( Origin gFrontEnd )
				)
				( attribute "CDS_LIB" "dev_discrete"
					( Origin gPackager )
				)
				( attribute "CDS_LOCATION" "C5D49"
					( Origin gPackager )
				)
				( attribute "CDS_SEC" "1"
					( Origin gPackager )
				)
				( attribute "LOCATION" "C5D49"
					( Origin gFrontEnd )
				)
				( attribute "MATERIAL" "X6S"
					( Origin gFrontEnd )
				)
				( attribute "PACK_TYPE" "0603V"
					( Origin gFrontEnd )
				)
				( attribute "PART_NUMBER" "E15431-004"
					( Origin gFrontEnd )
				)
				( attribute "PHYS_PAGE" "42"
					( Origin gFrontEnd )
				)
				( attribute "ROOM" "PVCCIN_CPU0_DECAP_VR"
					( Origin gFrontEnd )
				)
				( attribute "ROT" "0"
					( Origin gFrontEnd )
				)
				( attribute "SEC" "1"
					( Origin gPackager )
				)
				( attribute "TOLERANCE" "20%"
					( Origin gFrontEnd )
				)
				( attribute "VALUE" "22.0UF"
					( Origin gFrontEnd )
				)
				( attribute "VER" "1"
					( Origin gFrontEnd )
				)
				( attribute "VOLTAGE" "4V"
					( Units "uVoltage" "V" 1.000000)
					( Origin gFrontEnd )
				)
				( attribute "XY" "(-2050,4500)"
					( Origin gFrontEnd )
				)
				( attribute "CHIPS_PART_NAME" "CAP_A"
					( Origin gPackager )
				)
				( attribute "CDS_PART_NAME" "CAP_A_0603V-22.0UF,4V,20%,X6S,A"
					( Origin gPackager )
				)
				( attribute "GROUP" "PWR_MCP_CAP"
					( Origin gFrontEnd )
				)
				( objectStatus "C5D49" )
			)
			( gate "@baseboard_fab2_lib.baseboard_fab2(sch_1):page42_i153"
				( attribute "BOM_COST" "PROC_SOCKET"
					( Origin gFrontEnd )
				)
				( attribute "CDS_LIB" "dev_discrete"
					( Origin gPackager )
				)
				( attribute "CDS_LOCATION" "C5D22"
					( Origin gPackager )
				)
				( attribute "CDS_SEC" "1"
					( Origin gPackager )
				)
				( attribute "LOCATION" "C5D22"
					( Origin gFrontEnd )
				)
				( attribute "MATERIAL" "X6S"
					( Origin gFrontEnd )
				)
				( attribute "PACK_TYPE" "0603V"
					( Origin gFrontEnd )
				)
				( attribute "PART_NUMBER" "E15431-004"
					( Origin gFrontEnd )
				)
				( attribute "PHYS_PAGE" "42"
					( Origin gFrontEnd )
				)
				( attribute "ROOM" "PVCCIN_CPU0_DECAP_VR"
					( Origin gFrontEnd )
				)
				( attribute "ROT" "0"
					( Origin gFrontEnd )
				)
				( attribute "SEC" "1"
					( Origin gPackager )
				)
				( attribute "TOLERANCE" "20%"
					( Origin gFrontEnd )
				)
				( attribute "VALUE" "22.0UF"
					( Origin gFrontEnd )
				)
				( attribute "VER" "1"
					( Origin gFrontEnd )
				)
				( attribute "VOLTAGE" "4V"
					( Units "uVoltage" "V" 1.000000)
					( Origin gFrontEnd )
				)
				( attribute "XY" "(-550,4500)"
					( Origin gFrontEnd )
				)
				( attribute "CHIPS_PART_NAME" "CAP_A"
					( Origin gPackager )
				)
				( attribute "CDS_PART_NAME" "CAP_A_0603V-22.0UF,4V,20%,X6S,A"
					( Origin gPackager )
				)
				( attribute "GROUP" "PWR_MCP_CAP"
					( Origin gFrontEnd )
				)
				( objectStatus "C5D22" )
			)
			( gate "@baseboard_fab2_lib.baseboard_fab2(sch_1):page42_i154"
				( attribute "BOM_COST" "PROC_SOCKET"
					( Origin gFrontEnd )
				)
				( attribute "CDS_LIB" "dev_discrete"
					( Origin gPackager )
				)
				( attribute "CDS_LOCATION" "C5D26"
					( Origin gPackager )
				)
				( attribute "CDS_SEC" "1"
					( Origin gPackager )
				)
				( attribute "LOCATION" "C5D26"
					( Origin gFrontEnd )
				)
				( attribute "MATERIAL" "X6S"
					( Origin gFrontEnd )
				)
				( attribute "PACK_TYPE" "0603V"
					( Origin gFrontEnd )
				)
				( attribute "PART_NUMBER" "E15431-004"
					( Origin gFrontEnd )
				)
				( attribute "PHYS_PAGE" "42"
					( Origin gFrontEnd )
				)
				( attribute "ROOM" "PVCCIN_CPU0_DECAP_VR"
					( Origin gFrontEnd )
				)
				( attribute "ROT" "0"
					( Origin gFrontEnd )
				)
				( attribute "SEC" "1"
					( Origin gPackager )
				)
				( attribute "TOLERANCE" "20%"
					( Origin gFrontEnd )
				)
				( attribute "VALUE" "22.0UF"
					( Origin gFrontEnd )
				)
				( attribute "VER" "1"
					( Origin gFrontEnd )
				)
				( attribute "VOLTAGE" "4V"
					( Units "uVoltage" "V" 1.000000)
					( Origin gFrontEnd )
				)
				( attribute "XY" "(-4450,4500)"
					( Origin gFrontEnd )
				)
				( attribute "CHIPS_PART_NAME" "CAP_A"
					( Origin gPackager )
				)
				( attribute "CDS_PART_NAME" "CAP_A_0603V-22.0UF,4V,20%,X6S,A"
					( Origin gPackager )
				)
				( attribute "GROUP" "PWR_MLCC_CAP"
					( Origin gFrontEnd )
				)
				( objectStatus "C5D26" )
			)
			( gate "@baseboard_fab2_lib.baseboard_fab2(sch_1):page42_i155"
				( attribute "BOM_COST" "PROC_SOCKET"
					( Origin gFrontEnd )
				)
				( attribute "CDS_LIB" "dev_discrete"
					( Origin gPackager )
				)
				( attribute "CDS_LOCATION" "C5D25"
					( Origin gPackager )
				)
				( attribute "CDS_SEC" "1"
					( Origin gPackager )
				)
				( attribute "LOCATION" "C5D25"
					( Origin gFrontEnd )
				)
				( attribute "MATERIAL" "X6S"
					( Origin gFrontEnd )
				)
				( attribute "PACK_TYPE" "0603V"
					( Origin gFrontEnd )
				)
				( attribute "PART_NUMBER" "E15431-004"
					( Origin gFrontEnd )
				)
				( attribute "PHYS_PAGE" "42"
					( Origin gFrontEnd )
				)
				( attribute "ROOM" "PVCCIN_CPU0_DECAP_VR"
					( Origin gFrontEnd )
				)
				( attribute "ROT" "0"
					( Origin gFrontEnd )
				)
				( attribute "SEC" "1"
					( Origin gPackager )
				)
				( attribute "TOLERANCE" "20%"
					( Origin gFrontEnd )
				)
				( attribute "VALUE" "22.0UF"
					( Origin gFrontEnd )
				)
				( attribute "VER" "1"
					( Origin gFrontEnd )
				)
				( attribute "VOLTAGE" "4V"
					( Units "uVoltage" "V" 1.000000)
					( Origin gFrontEnd )
				)
				( attribute "XY" "(-4600,3800)"
					( Origin gFrontEnd )
				)
				( attribute "CHIPS_PART_NAME" "CAP_A"
					( Origin gPackager )
				)
				( attribute "CDS_PART_NAME" "CAP_A_0603V-22.0UF,4V,20%,X6S,A"
					( Origin gPackager )
				)
				( attribute "GROUP" "PWR_MLCC_CAP"
					( Origin gFrontEnd )
				)
				( objectStatus "C5D25" )
			)
			( gate "@baseboard_fab2_lib.baseboard_fab2(sch_1):page42_i156"
				( attribute "BOM_COST" "PROC_SOCKET"
					( Origin gFrontEnd )
				)
				( attribute "CDS_LIB" "dev_discrete"
					( Origin gPackager )
				)
				( attribute "CDS_LOCATION" "C5D45"
					( Origin gPackager )
				)
				( attribute "CDS_SEC" "1"
					( Origin gPackager )
				)
				( attribute "LOCATION" "C5D45"
					( Origin gFrontEnd )
				)
				( attribute "MATERIAL" "X6S"
					( Origin gFrontEnd )
				)
				( attribute "PACK_TYPE" "0603V"
					( Origin gFrontEnd )
				)
				( attribute "PART_NUMBER" "E15431-004"
					( Origin gFrontEnd )
				)
				( attribute "PHYS_PAGE" "42"
					( Origin gFrontEnd )
				)
				( attribute "ROOM" "PVCCIN_CPU0_DECAP_VR"
					( Origin gFrontEnd )
				)
				( attribute "ROT" "0"
					( Origin gFrontEnd )
				)
				( attribute "SEC" "1"
					( Origin gPackager )
				)
				( attribute "TOLERANCE" "20%"
					( Origin gFrontEnd )
				)
				( attribute "VALUE" "22.0UF"
					( Origin gFrontEnd )
				)
				( attribute "VER" "1"
					( Origin gFrontEnd )
				)
				( attribute "VOLTAGE" "4V"
					( Units "uVoltage" "V" 1.000000)
					( Origin gFrontEnd )
				)
				( attribute "XY" "(-4700,3150)"
					( Origin gFrontEnd )
				)
				( attribute "CHIPS_PART_NAME" "CAP_A"
					( Origin gPackager )
				)
				( attribute "CDS_PART_NAME" "CAP_A_0603V-22.0UF,4V,20%,X6S,A"
					( Origin gPackager )
				)
				( attribute "GROUP" "PWR_MLCC_CAP"
					( Origin gFrontEnd )
				)
				( objectStatus "C5D45" )
			)
			( gate "@baseboard_fab2_lib.baseboard_fab2(sch_1):page42_i164"
				( attribute "CDS_LIB" "dev_discrete"
					( Origin gPackager )
				)
				( attribute "CDS_LOCATION" "C4P6"
					( Origin gPackager )
				)
				( attribute "CDS_SEC" "1"
					( Origin gPackager )
				)
				( attribute "LOCATION" "C4P6"
					( Origin gFrontEnd )
				)
				( attribute "MATERIAL" "X6S"
					( Origin gFrontEnd )
				)
				( attribute "PACK_TYPE" "0603V"
					( Origin gFrontEnd )
				)
				( attribute "PART_NUMBER" "E15431-004"
					( Origin gFrontEnd )
				)
				( attribute "PHYS_PAGE" "42"
					( Origin gFrontEnd )
				)
				( attribute "ROOM" "PVCCIN_CPU0_DECAP_VR"
					( Origin gFrontEnd )
				)
				( attribute "ROT" "0"
					( Origin gFrontEnd )
				)
				( attribute "SEC" "1"
					( Origin gPackager )
				)
				( attribute "TOLERANCE" "20%"
					( Origin gFrontEnd )
				)
				( attribute "VALUE" "22.0UF"
					( Origin gFrontEnd )
				)
				( attribute "VER" "1"
					( Origin gFrontEnd )
				)
				( attribute "VOLTAGE" "4V"
					( Units "uVoltage" "V" 1.000000)
					( Origin gFrontEnd )
				)
				( attribute "XY" "(-2250,950)"
					( Origin gFrontEnd )
				)
				( attribute "CHIPS_PART_NAME" "CAP_A"
					( Origin gPackager )
				)
				( attribute "CDS_PART_NAME" "CAP_A_0603V-22.0UF,4V,20%,X6S,A"
					( Origin gPackager )
				)
				( attribute "GROUP" "PWR_MLCC_CAP"
					( Origin gFrontEnd )
				)
				( objectStatus "C4P6" )
			)
			( gate "@baseboard_fab2_lib.baseboard_fab2(sch_1):page42_i173"
				( attribute "BOM_COST" "PROC_SOCKET"
					( Origin gFrontEnd )
				)
				( attribute "CDS_LIB" "dev_discrete"
					( Origin gPackager )
				)
				( attribute "CDS_LOCATION" "C5D20"
					( Origin gPackager )
				)
				( attribute "CDS_SEC" "1"
					( Origin gPackager )
				)
				( attribute "LOCATION" "C5D20"
					( Origin gFrontEnd )
				)
				( attribute "MATERIAL" "X6S"
					( Origin gFrontEnd )
				)
				( attribute "PACK_TYPE" "0603V"
					( Origin gFrontEnd )
				)
				( attribute "PART_NUMBER" "E15431-004"
					( Origin gFrontEnd )
				)
				( attribute "PHYS_PAGE" "42"
					( Origin gFrontEnd )
				)
				( attribute "ROOM" "PVCCIN_CPU0_DECAP_VR"
					( Origin gFrontEnd )
				)
				( attribute "ROT" "0"
					( Origin gFrontEnd )
				)
				( attribute "SEC" "1"
					( Origin gPackager )
				)
				( attribute "TOLERANCE" "20%"
					( Origin gFrontEnd )
				)
				( attribute "VALUE" "22.0UF"
					( Origin gFrontEnd )
				)
				( attribute "VER" "1"
					( Origin gFrontEnd )
				)
				( attribute "VOLTAGE" "4V"
					( Units "uVoltage" "V" 1.000000)
					( Origin gFrontEnd )
				)
				( attribute "XY" "(-1050,3850)"
					( Origin gFrontEnd )
				)
				( attribute "CHIPS_PART_NAME" "CAP_A"
					( Origin gPackager )
				)
				( attribute "CDS_PART_NAME" "CAP_A_0603V-22.0UF,4V,20%,X6S,A"
					( Origin gPackager )
				)
				( attribute "GROUP" "PWR_MCP_CAP"
					( Origin gFrontEnd )
				)
				( objectStatus "C5D20" )
			)
			( gate "@baseboard_fab2_lib.baseboard_fab2(sch_1):page42_i174"
				( attribute "BOM_COST" "PROC_SOCKET"
					( Origin gFrontEnd )
				)
				( attribute "CDS_LIB" "dev_discrete"
					( Origin gPackager )
				)
				( attribute "CDS_LOCATION" "C5D33"
					( Origin gPackager )
				)
				( attribute "CDS_SEC" "1"
					( Origin gPackager )
				)
				( attribute "LOCATION" "C5D33"
					( Origin gFrontEnd )
				)
				( attribute "MATERIAL" "X6S"
					( Origin gFrontEnd )
				)
				( attribute "PACK_TYPE" "0603V"
					( Origin gFrontEnd )
				)
				( attribute "PART_NUMBER" "E15431-004"
					( Origin gFrontEnd )
				)
				( attribute "PHYS_PAGE" "42"
					( Origin gFrontEnd )
				)
				( attribute "ROOM" "PVCCIN_CPU0_DECAP_VR"
					( Origin gFrontEnd )
				)
				( attribute "ROT" "0"
					( Origin gFrontEnd )
				)
				( attribute "SEC" "1"
					( Origin gPackager )
				)
				( attribute "TOLERANCE" "20%"
					( Origin gFrontEnd )
				)
				( attribute "VALUE" "22.0UF"
					( Origin gFrontEnd )
				)
				( attribute "VER" "1"
					( Origin gFrontEnd )
				)
				( attribute "VOLTAGE" "4V"
					( Units "uVoltage" "V" 1.000000)
					( Origin gFrontEnd )
				)
				( attribute "XY" "(-800,3850)"
					( Origin gFrontEnd )
				)
				( attribute "CHIPS_PART_NAME" "CAP_A"
					( Origin gPackager )
				)
				( attribute "CDS_PART_NAME" "CAP_A_0603V-22.0UF,4V,20%,X6S,A"
					( Origin gPackager )
				)
				( attribute "GROUP" "PWR_MCP_CAP"
					( Origin gFrontEnd )
				)
				( objectStatus "C5D33" )
			)
			( gate "@baseboard_fab2_lib.baseboard_fab2(sch_1):page42_i175"
				( attribute "BOM_COST" "PROC_SOCKET"
					( Origin gFrontEnd )
				)
				( attribute "CDS_LIB" "dev_discrete"
					( Origin gPackager )
				)
				( attribute "CDS_LOCATION" "C5D34"
					( Origin gPackager )
				)
				( attribute "CDS_SEC" "1"
					( Origin gPackager )
				)
				( attribute "LOCATION" "C5D34"
					( Origin gFrontEnd )
				)
				( attribute "MATERIAL" "X6S"
					( Origin gFrontEnd )
				)
				( attribute "PACK_TYPE" "0603V"
					( Origin gFrontEnd )
				)
				( attribute "PART_NUMBER" "E15431-004"
					( Origin gFrontEnd )
				)
				( attribute "PHYS_PAGE" "42"
					( Origin gFrontEnd )
				)
				( attribute "ROOM" "PVCCIN_CPU0_DECAP_VR"
					( Origin gFrontEnd )
				)
				( attribute "ROT" "0"
					( Origin gFrontEnd )
				)
				( attribute "SEC" "1"
					( Origin gPackager )
				)
				( attribute "TOLERANCE" "20%"
					( Origin gFrontEnd )
				)
				( attribute "VALUE" "22.0UF"
					( Origin gFrontEnd )
				)
				( attribute "VER" "1"
					( Origin gFrontEnd )
				)
				( attribute "VOLTAGE" "4V"
					( Units "uVoltage" "V" 1.000000)
					( Origin gFrontEnd )
				)
				( attribute "XY" "(-550,3850)"
					( Origin gFrontEnd )
				)
				( attribute "CHIPS_PART_NAME" "CAP_A"
					( Origin gPackager )
				)
				( attribute "CDS_PART_NAME" "CAP_A_0603V-22.0UF,4V,20%,X6S,A"
					( Origin gPackager )
				)
				( attribute "GROUP" "PWR_MCP_CAP"
					( Origin gFrontEnd )
				)
				( objectStatus "C5D34" )
			)
			( gate "@baseboard_fab2_lib.baseboard_fab2(sch_1):page42_i176"
				( attribute "BOM_COST" "PROC_SOCKET"
					( Origin gFrontEnd )
				)
				( attribute "CDS_LIB" "dev_discrete"
					( Origin gPackager )
				)
				( attribute "CDS_LOCATION" "C5D35"
					( Origin gPackager )
				)
				( attribute "CDS_SEC" "1"
					( Origin gPackager )
				)
				( attribute "LOCATION" "C5D35"
					( Origin gFrontEnd )
				)
				( attribute "MATERIAL" "X6S"
					( Origin gFrontEnd )
				)
				( attribute "PACK_TYPE" "0603V"
					( Origin gFrontEnd )
				)
				( attribute "PART_NUMBER" "E15431-004"
					( Origin gFrontEnd )
				)
				( attribute "PHYS_PAGE" "42"
					( Origin gFrontEnd )
				)
				( attribute "ROOM" "PVCCIN_CPU0_DECAP_VR"
					( Origin gFrontEnd )
				)
				( attribute "ROT" "0"
					( Origin gFrontEnd )
				)
				( attribute "SEC" "1"
					( Origin gPackager )
				)
				( attribute "TOLERANCE" "20%"
					( Origin gFrontEnd )
				)
				( attribute "VALUE" "22.0UF"
					( Origin gFrontEnd )
				)
				( attribute "VER" "1"
					( Origin gFrontEnd )
				)
				( attribute "VOLTAGE" "4V"
					( Units "uVoltage" "V" 1.000000)
					( Origin gFrontEnd )
				)
				( attribute "XY" "(-1300,3850)"
					( Origin gFrontEnd )
				)
				( attribute "CHIPS_PART_NAME" "CAP_A"
					( Origin gPackager )
				)
				( attribute "CDS_PART_NAME" "CAP_A_0603V-22.0UF,4V,20%,X6S,A"
					( Origin gPackager )
				)
				( attribute "GROUP" "PWR_MCP_CAP"
					( Origin gFrontEnd )
				)
				( objectStatus "C5D35" )
			)
			( gate "@baseboard_fab2_lib.baseboard_fab2(sch_1):page42_i178"
				( attribute "CDS_LIB" "dev_discrete"
					( Origin gPackager )
				)
				( attribute "CDS_LOCATION" "C4P8"
					( Origin gPackager )
				)
				( attribute "CDS_SEC" "1"
					( Origin gPackager )
				)
				( attribute "LOCATION" "C4P8"
					( Origin gFrontEnd )
				)
				( attribute "MATERIAL" "X6S"
					( Origin gFrontEnd )
				)
				( attribute "PACK_TYPE" "0603V"
					( Origin gFrontEnd )
				)
				( attribute "PART_NUMBER" "E15431-004"
					( Origin gFrontEnd )
				)
				( attribute "PHYS_PAGE" "42"
					( Origin gFrontEnd )
				)
				( attribute "ROOM" "PVCCIN_CPU0_DECAP_VR"
					( Origin gFrontEnd )
				)
				( attribute "ROT" "0"
					( Origin gFrontEnd )
				)
				( attribute "SEC" "1"
					( Origin gPackager )
				)
				( attribute "TOLERANCE" "20%"
					( Origin gFrontEnd )
				)
				( attribute "VALUE" "22.0UF"
					( Origin gFrontEnd )
				)
				( attribute "VER" "1"
					( Origin gFrontEnd )
				)
				( attribute "VOLTAGE" "4V"
					( Units "uVoltage" "V" 1.000000)
					( Origin gFrontEnd )
				)
				( attribute "XY" "(-1950,950)"
					( Origin gFrontEnd )
				)
				( attribute "CHIPS_PART_NAME" "CAP_A"
					( Origin gPackager )
				)
				( attribute "CDS_PART_NAME" "CAP_A_0603V-22.0UF,4V,20%,X6S,A"
					( Origin gPackager )
				)
				( attribute "GROUP" "PWR_MLCC_CAP"
					( Origin gFrontEnd )
				)
				( objectStatus "C4P8" )
			)
			( gate "@baseboard_fab2_lib.baseboard_fab2(sch_1):page42_i179"
				( attribute "CDS_LIB" "dev_discrete"
					( Origin gPackager )
				)
				( attribute "CDS_LOCATION" "C5D53"
					( Origin gPackager )
				)
				( attribute "CDS_SEC" "1"
					( Origin gPackager )
				)
				( attribute "LOCATION" "C5D53"
					( Origin gFrontEnd )
				)
				( attribute "MATERIAL" "X6S"
					( Origin gFrontEnd )
				)
				( attribute "PACK_TYPE" "0603V"
					( Origin gFrontEnd )
				)
				( attribute "PART_NUMBER" "E15431-004"
					( Origin gFrontEnd )
				)
				( attribute "PHYS_PAGE" "42"
					( Origin gFrontEnd )
				)
				( attribute "ROOM" "PVCCIN_CPU0_DECAP_VR"
					( Origin gFrontEnd )
				)
				( attribute "ROT" "0"
					( Origin gFrontEnd )
				)
				( attribute "SEC" "1"
					( Origin gPackager )
				)
				( attribute "TOLERANCE" "20%"
					( Origin gFrontEnd )
				)
				( attribute "VALUE" "22.0UF"
					( Origin gFrontEnd )
				)
				( attribute "VER" "1"
					( Origin gFrontEnd )
				)
				( attribute "VOLTAGE" "4V"
					( Units "uVoltage" "V" 1.000000)
					( Origin gFrontEnd )
				)
				( attribute "XY" "(-1550,3850)"
					( Origin gFrontEnd )
				)
				( attribute "CHIPS_PART_NAME" "CAP_A"
					( Origin gPackager )
				)
				( attribute "CDS_PART_NAME" "CAP_A_0603V-22.0UF,4V,20%,X6S,A"
					( Origin gPackager )
				)
				( attribute "GROUP" "PWR_MCP_CAP"
					( Origin gFrontEnd )
				)
				( objectStatus "C5D53" )
			)
			( gate "@baseboard_fab2_lib.baseboard_fab2(sch_1):page42_i180"
				( attribute "CDS_LIB" "dev_discrete"
					( Origin gPackager )
				)
				( attribute "CDS_LOCATION" "C5D52"
					( Origin gPackager )
				)
				( attribute "CDS_SEC" "1"
					( Origin gPackager )
				)
				( attribute "LOCATION" "C5D52"
					( Origin gFrontEnd )
				)
				( attribute "MATERIAL" "X6S"
					( Origin gFrontEnd )
				)
				( attribute "PACK_TYPE" "0603V"
					( Origin gFrontEnd )
				)
				( attribute "PART_NUMBER" "E15431-004"
					( Origin gFrontEnd )
				)
				( attribute "PHYS_PAGE" "42"
					( Origin gFrontEnd )
				)
				( attribute "ROOM" "PVCCIN_CPU0_DECAP_VR"
					( Origin gFrontEnd )
				)
				( attribute "ROT" "0"
					( Origin gFrontEnd )
				)
				( attribute "SEC" "1"
					( Origin gPackager )
				)
				( attribute "TOLERANCE" "20%"
					( Origin gFrontEnd )
				)
				( attribute "VALUE" "22.0UF"
					( Origin gFrontEnd )
				)
				( attribute "VER" "1"
					( Origin gFrontEnd )
				)
				( attribute "VOLTAGE" "4V"
					( Units "uVoltage" "V" 1.000000)
					( Origin gFrontEnd )
				)
				( attribute "XY" "(-1800,3850)"
					( Origin gFrontEnd )
				)
				( attribute "CHIPS_PART_NAME" "CAP_A"
					( Origin gPackager )
				)
				( attribute "CDS_PART_NAME" "CAP_A_0603V-22.0UF,4V,20%,X6S,A"
					( Origin gPackager )
				)
				( attribute "GROUP" "PWR_MCP_CAP"
					( Origin gFrontEnd )
				)
				( objectStatus "C5D52" )
			)
			( gate "@baseboard_fab2_lib.baseboard_fab2(sch_1):page42_i187"
				( attribute "BOM_COST" "PROC_SOCKET"
					( Origin gFrontEnd )
				)
				( attribute "CDS_LIB" "mstr_discrete"
					( Origin gPackager )
				)
				( attribute "CDS_LOCATION" "C5P15"
					( Origin gPackager )
				)
				( attribute "LOCATION" "C5P15"
					( Origin gFrontEnd )
				)
				( attribute "MATERIAL" "X6S"
					( Origin gFrontEnd )
				)
				( attribute "PACK_TYPE" "0805"
					( Origin gFrontEnd )
				)
				( attribute "PART_NUMBER" "C95333-006"
					( Origin gFrontEnd )
				)
				( attribute "PHYS_PAGE" "42"
					( Origin gFrontEnd )
				)
				( attribute "ROOM" "PVCCIN_CPU0_DECAP_VR"
					( Origin gFrontEnd )
				)
				( attribute "ROT" "0"
					( Origin gFrontEnd )
				)
				( attribute "SEC" "1"
					( Origin gFrontEnd )
				)
				( attribute "TOLERANCE" "20%"
					( Origin gFrontEnd )
				)
				( attribute "VALUE" "47UF"
					( Origin gFrontEnd )
				)
				( attribute "VER" "1"
					( Origin gFrontEnd )
				)
				( attribute "VOLTAGE" "4V"
					( Units "uVoltage" "V" 1.000000)
					( Origin gFrontEnd )
				)
				( attribute "XY" "(-6850,1550)"
					( Origin gFrontEnd )
				)
				( attribute "CHIPS_PART_NAME" "CAP"
					( Origin gPackager )
				)
				( attribute "CDS_PART_NAME" "CAP_0805-47UF,4V,20%,X6S,C9533A"
					( Origin gPackager )
				)
				( attribute "SEC_TYPE" "0805"
					( Origin gFrontEnd )
				)
				( attribute "CDS_SEC" "1"
					( Origin gPackager )
				)
				( attribute "GROUP" "PWR_MLCC_CAP"
					( Origin gFrontEnd )
				)
				( objectStatus "C5P15" )
			)
			( gate "@baseboard_fab2_lib.baseboard_fab2(sch_1):page42_i188"
				( attribute "BOM_COST" "PROC_SOCKET"
					( Origin gFrontEnd )
				)
				( attribute "CDS_LIB" "mstr_discrete"
					( Origin gPackager )
				)
				( attribute "CDS_LOCATION" "C5P16"
					( Origin gPackager )
				)
				( attribute "LOCATION" "C5P16"
					( Origin gFrontEnd )
				)
				( attribute "MATERIAL" "X6S"
					( Origin gFrontEnd )
				)
				( attribute "PACK_TYPE" "0805"
					( Origin gFrontEnd )
				)
				( attribute "PART_NUMBER" "C95333-006"
					( Origin gFrontEnd )
				)
				( attribute "PHYS_PAGE" "42"
					( Origin gFrontEnd )
				)
				( attribute "ROOM" "PVCCIN_CPU0_DECAP_VR"
					( Origin gFrontEnd )
				)
				( attribute "ROT" "0"
					( Origin gFrontEnd )
				)
				( attribute "SEC" "1"
					( Origin gFrontEnd )
				)
				( attribute "TOLERANCE" "20%"
					( Origin gFrontEnd )
				)
				( attribute "VALUE" "47UF"
					( Origin gFrontEnd )
				)
				( attribute "VER" "1"
					( Origin gFrontEnd )
				)
				( attribute "VOLTAGE" "4V"
					( Units "uVoltage" "V" 1.000000)
					( Origin gFrontEnd )
				)
				( attribute "XY" "(-6850,2250)"
					( Origin gFrontEnd )
				)
				( attribute "CHIPS_PART_NAME" "CAP"
					( Origin gPackager )
				)
				( attribute "CDS_PART_NAME" "CAP_0805-47UF,4V,20%,X6S,C9533A"
					( Origin gPackager )
				)
				( attribute "SEC_TYPE" "0805"
					( Origin gFrontEnd )
				)
				( attribute "GROUP" "PWR_MLCC_CAP"
					( Origin gFrontEnd )
				)
				( attribute "CDS_SEC" "1"
					( Origin gPackager )
				)
				( objectStatus "C5P16" )
			)
			( gate "@baseboard_fab2_lib.baseboard_fab2(sch_1):page42_i190"
				( attribute "BOM_COST" "PROC_SOCKET"
					( Origin gFrontEnd )
				)
				( attribute "CDS_LIB" "mstr_discrete"
					( Origin gPackager )
				)
				( attribute "CDS_LOCATION" "C5P17"
					( Origin gPackager )
				)
				( attribute "LOCATION" "C5P17"
					( Origin gFrontEnd )
				)
				( attribute "MATERIAL" "X6S"
					( Origin gFrontEnd )
				)
				( attribute "PACK_TYPE" "0805"
					( Origin gFrontEnd )
				)
				( attribute "PART_NUMBER" "C95333-006"
					( Origin gFrontEnd )
				)
				( attribute "PHYS_PAGE" "42"
					( Origin gFrontEnd )
				)
				( attribute "ROOM" "PVCCIN_CPU0_DECAP_VR"
					( Origin gFrontEnd )
				)
				( attribute "ROT" "0"
					( Origin gFrontEnd )
				)
				( attribute "SEC" "1"
					( Origin gFrontEnd )
				)
				( attribute "TOLERANCE" "20%"
					( Origin gFrontEnd )
				)
				( attribute "VALUE" "47UF"
					( Origin gFrontEnd )
				)
				( attribute "VER" "1"
					( Origin gFrontEnd )
				)
				( attribute "VOLTAGE" "4V"
					( Units "uVoltage" "V" 1.000000)
					( Origin gFrontEnd )
				)
				( attribute "XY" "(-6550,1550)"
					( Origin gFrontEnd )
				)
				( attribute "CHIPS_PART_NAME" "CAP"
					( Origin gPackager )
				)
				( attribute "CDS_PART_NAME" "CAP_0805-47UF,4V,20%,X6S,C9533A"
					( Origin gPackager )
				)
				( attribute "SEC_TYPE" "0805"
					( Origin gFrontEnd )
				)
				( attribute "CDS_SEC" "1"
					( Origin gPackager )
				)
				( attribute "GROUP" "PWR_MLCC_CAP"
					( Origin gFrontEnd )
				)
				( objectStatus "C5P17" )
			)
			( gate "@baseboard_fab2_lib.baseboard_fab2(sch_1):page43_i1"
				( attribute "BOM_COST" "MEM"
					( Origin gFrontEnd )
				)
				( attribute "CDS_LIB" "mstr_sconn"
					( Origin gPackager )
				)
				( attribute "CDS_LOCATION" "J4G1"
					( Origin gPackager )
				)
				( attribute "CDS_SEC" "1"
					( Origin gPackager )
				)
				( attribute "LOCATION" "J4G1"
					( Origin gFrontEnd )
				)
				( attribute "MATERIAL" "SCONN"
					( Origin gFrontEnd )
				)
				( attribute "PACK_TYPE" "PIP"
					( Origin gFrontEnd )
				)
				( attribute "PART_NUMBER" "H44441-004"
					( Origin gFrontEnd )
				)
				( attribute "PHYS_PAGE" "43"
					( Origin gFrontEnd )
				)
				( attribute "ROOM" "DDR4_CH_A"
					( Origin gFrontEnd )
				)
				( attribute "ROT" "0"
					( Origin gFrontEnd )
				)
				( attribute "SEC" "1"
					( Origin gFrontEnd )
				)
				( attribute "SEC_TYPE" "PIP"
					( Origin gFrontEnd )
				)
				( attribute "VER" "1"
					( Origin gFrontEnd )
				)
				( attribute "XY" "(-2400,2750)"
					( Origin gFrontEnd )
				)
				( attribute "CHIPS_PART_NAME" "SCONN288_H44441004"
					( Origin gPackager )
				)
				( attribute "CDS_PART_NAME" "SCONN288_H44441004_PIP-SCONN,HA"
					( Origin gPackager )
				)
				( objectStatus "J4G1" )
			)
			( gate "@baseboard_fab2_lib.baseboard_fab2(sch_1):page43_i2"
				( attribute "BOM_COST" "MEM"
					( Origin gFrontEnd )
				)
				( attribute "CDS_LIB" "mstr_sconn"
					( Origin gPackager )
				)
				( attribute "CDS_LOCATION" "J4G1"
					( Origin gPackager )
				)
				( attribute "CDS_SEC" "2"
					( Origin gPackager )
				)
				( attribute "LOCATION" "J4G1"
					( Origin gFrontEnd )
				)
				( attribute "MATERIAL" "SCONN"
					( Origin gFrontEnd )
				)
				( attribute "PACK_TYPE" "PIP"
					( Origin gFrontEnd )
				)
				( attribute "PART_NUMBER" "H44441-004"
					( Origin gFrontEnd )
				)
				( attribute "PHYS_PAGE" "43"
					( Origin gFrontEnd )
				)
				( attribute "ROOM" "DDR4_CH_A"
					( Origin gFrontEnd )
				)
				( attribute "ROT" "0"
					( Origin gFrontEnd )
				)
				( attribute "SEC" "2"
					( Origin gFrontEnd )
				)
				( attribute "SEC_TYPE" "PIP"
					( Origin gFrontEnd )
				)
				( attribute "VER" "2"
					( Origin gFrontEnd )
				)
				( attribute "XY" "(-50,4050)"
					( Origin gFrontEnd )
				)
				( attribute "CHIPS_PART_NAME" "SCONN288_H44441004"
					( Origin gPackager )
				)
				( attribute "CDS_PART_NAME" "SCONN288_H44441004_PIP-SCONN,HA"
					( Origin gPackager )
				)
				( objectStatus "J4G1" )
			)
			( gate "@baseboard_fab2_lib.baseboard_fab2(sch_1):page43_i259"
				( attribute "BOM_COST" "MEM"
					( Origin gFrontEnd )
				)
				( attribute "CDS_LIB" "mstr_sconn"
					( Origin gPackager )
				)
				( attribute "CDS_LOCATION" "J4G1"
					( Origin gPackager )
				)
				( attribute "CDS_SEC" "3"
					( Origin gPackager )
				)
				( attribute "LOCATION" "J4G1"
					( Origin gFrontEnd )
				)
				( attribute "MATERIAL" "SCONN"
					( Origin gFrontEnd )
				)
				( attribute "PACK_TYPE" "PIP"
					( Origin gFrontEnd )
				)
				( attribute "PART_NUMBER" "H44441-004"
					( Origin gFrontEnd )
				)
				( attribute "PHYS_PAGE" "43"
					( Origin gFrontEnd )
				)
				( attribute "ROOM" "DDR4_CH_A"
					( Origin gFrontEnd )
				)
				( attribute "ROT" "0"
					( Origin gFrontEnd )
				)
				( attribute "SEC" "3"
					( Origin gFrontEnd )
				)
				( attribute "SEC_TYPE" "PIP"
					( Origin gFrontEnd )
				)
				( attribute "VER" "3"
					( Origin gFrontEnd )
				)
				( attribute "XY" "(1750,2450)"
					( Origin gFrontEnd )
				)
				( attribute "CHIPS_PART_NAME" "SCONN288_H44441004"
					( Origin gPackager )
				)
				( attribute "CDS_PART_NAME" "SCONN288_H44441004_PIP-SCONN,HA"
					( Origin gPackager )
				)
				( objectStatus "J4G1" )
			)
			( gate "@baseboard_fab2_lib.baseboard_fab2(sch_1):page43_i260"
				( attribute "BOM_COST" "MEM"
					( Origin gFrontEnd )
				)
				( attribute "CDS_LIB" "mstr_sconn"
					( Origin gPackager )
				)
				( attribute "CDS_LOCATION" "J4G1"
					( Origin gPackager )
				)
				( attribute "CDS_SEC" "4"
					( Origin gPackager )
				)
				( attribute "LOCATION" "J4G1"
					( Origin gFrontEnd )
				)
				( attribute "MATERIAL" "SCONN"
					( Origin gFrontEnd )
				)
				( attribute "PACK_TYPE" "PIP"
					( Origin gFrontEnd )
				)
				( attribute "PART_NUMBER" "H44441-004"
					( Origin gFrontEnd )
				)
				( attribute "PHYS_PAGE" "43"
					( Origin gFrontEnd )
				)
				( attribute "ROOM" "DDR4_CH_A"
					( Origin gFrontEnd )
				)
				( attribute "ROT" "0"
					( Origin gFrontEnd )
				)
				( attribute "SEC" "4"
					( Origin gFrontEnd )
				)
				( attribute "SEC_TYPE" "PIP"
					( Origin gFrontEnd )
				)
				( attribute "VER" "4"
					( Origin gFrontEnd )
				)
				( attribute "XY" "(-100,1700)"
					( Origin gFrontEnd )
				)
				( attribute "CHIPS_PART_NAME" "SCONN288_H44441004"
					( Origin gPackager )
				)
				( attribute "CDS_PART_NAME" "SCONN288_H44441004_PIP-SCONN,HA"
					( Origin gPackager )
				)
				( objectStatus "J4G1" )
			)
			( gate "@baseboard_fab2_lib.baseboard_fab2(sch_1):page43_i272"
				( attribute "BOM_COST" "MEM"
					( Origin gFrontEnd )
				)
				( attribute "CDS_LIB" "dev_discrete"
					( Origin gPackager )
				)
				( attribute "CDS_LOCATION" "C4F10"
					( Origin gPackager )
				)
				( attribute "LOCATION" "C4F10"
					( Origin gFrontEnd )
				)
				( attribute "MATERIAL" "X7R"
					( Origin gFrontEnd )
				)
				( attribute "PACK_TYPE" "0402V"
					( Origin gFrontEnd )
				)
				( attribute "PART_NUMBER" "A36096-045"
					( Origin gFrontEnd )
				)
				( attribute "PHYS_PAGE" "43"
					( Origin gFrontEnd )
				)
				( attribute "ROOM" "DDR4_CH_A"
					( Origin gFrontEnd )
				)
				( attribute "ROT" "2"
					( Origin gFrontEnd )
				)
				( attribute "SEC" "1"
					( Origin gFrontEnd )
				)
				( attribute "TOLERANCE" "10%"
					( Origin gFrontEnd )
				)
				( attribute "VALUE" "0.01UF"
					( Origin gFrontEnd )
				)
				( attribute "VER" "1"
					( Origin gFrontEnd )
				)
				( attribute "VOLTAGE" "25V"
					( Units "uVoltage" "V" 1.000000)
					( Origin gFrontEnd )
				)
				( attribute "XY" "(-4350,1050)"
					( Origin gFrontEnd )
				)
				( attribute "CHIPS_PART_NAME" "CAP_A"
					( Origin gPackager )
				)
				( attribute "CDS_PART_NAME" "CAP_A_0402V-0.01UF,25V,10%,X7RA"
					( Origin gPackager )
				)
				( attribute "SEC_TYPE" "0402V"
					( Origin gFrontEnd )
				)
				( attribute "CDS_SEC" "1"
					( Origin gPackager )
				)
				( objectStatus "C4F10" )
			)
			( gate "@baseboard_fab2_lib.baseboard_fab2(sch_1):page44_i2"
				( attribute "BOM_COST" "MEM"
					( Origin gFrontEnd )
				)
				( attribute "CDS_LIB" "dev_discrete"
					( Origin gPackager )
				)
				( attribute "CDS_LOCATION" "C6T1"
					( Origin gPackager )
				)
				( attribute "CDS_SEC" "1"
					( Origin gPackager )
				)
				( attribute "LOCATION" "C6T1"
					( Origin gFrontEnd )
				)
				( attribute "MATERIAL" "X7R"
					( Origin gFrontEnd )
				)
				( attribute "PACK_TYPE" "0402V"
					( Origin gFrontEnd )
				)
				( attribute "PART_NUMBER" "A36096-045"
					( Origin gFrontEnd )
				)
				( attribute "PHYS_PAGE" "44"
					( Origin gFrontEnd )
				)
				( attribute "ROOM" "DDR4_CH_A"
					( Origin gFrontEnd )
				)
				( attribute "ROT" "2"
					( Origin gFrontEnd )
				)
				( attribute "SEC" "1"
					( Origin gFrontEnd )
				)
				( attribute "SEC_TYPE" "0402V"
					( Origin gFrontEnd )
				)
				( attribute "TOLERANCE" "10%"
					( Origin gFrontEnd )
				)
				( attribute "VALUE" "0.01UF"
					( Origin gFrontEnd )
				)
				( attribute "VER" "1"
					( Origin gFrontEnd )
				)
				( attribute "VOLTAGE" "25V"
					( Units "uVoltage" "V" 1.000000)
					( Origin gFrontEnd )
				)
				( attribute "XY" "(-2650,1000)"
					( Origin gFrontEnd )
				)
				( attribute "CHIPS_PART_NAME" "CAP_A"
					( Origin gPackager )
				)
				( attribute "CDS_PART_NAME" "CAP_A_0402V-0.01UF,25V,10%,X7RA"
					( Origin gPackager )
				)
				( objectStatus "C6T1" )
			)
			( gate "@baseboard_fab2_lib.baseboard_fab2(sch_1):page44_i13"
				( attribute "BOM_COST" "MEM"
					( Origin gFrontEnd )
				)
				( attribute "CDS_LIB" "mstr_sconn"
					( Origin gPackager )
				)
				( attribute "CDS_LOCATION" "J6T1"
					( Origin gPackager )
				)
				( attribute "CDS_SEC" "1"
					( Origin gPackager )
				)
				( attribute "LOCATION" "J6T1"
					( Origin gFrontEnd )
				)
				( attribute "MATERIAL" "SCONN"
					( Origin gFrontEnd )
				)
				( attribute "PACK_TYPE" "PIP"
					( Origin gFrontEnd )
				)
				( attribute "PART_NUMBER" "H44441-003"
					( Origin gFrontEnd )
				)
				( attribute "PHYS_PAGE" "44"
					( Origin gFrontEnd )
				)
				( attribute "ROOM" "DDR4_CH_A"
					( Origin gFrontEnd )
				)
				( attribute "ROT" "0"
					( Origin gFrontEnd )
				)
				( attribute "SEC" "1"
					( Origin gFrontEnd )
				)
				( attribute "SEC_TYPE" "PIP"
					( Origin gFrontEnd )
				)
				( attribute "VER" "1"
					( Origin gFrontEnd )
				)
				( attribute "XY" "(-700,2700)"
					( Origin gFrontEnd )
				)
				( attribute "CHIPS_PART_NAME" "SCONN288_H44441003"
					( Origin gPackager )
				)
				( attribute "CDS_PART_NAME" "SCONN288_H44441003_PIP-SCONN,HA"
					( Origin gPackager )
				)
				( attribute "BOM_SS" "NOPOP"
					( Origin gFrontEnd )
				)
				( objectStatus "J6T1" )
			)
			( gate "@baseboard_fab2_lib.baseboard_fab2(sch_1):page44_i75"
				( attribute "BOM_COST" "MEM"
					( Origin gFrontEnd )
				)
				( attribute "CDS_LIB" "mstr_sconn"
					( Origin gPackager )
				)
				( attribute "CDS_LOCATION" "J6T1"
					( Origin gPackager )
				)
				( attribute "CDS_SEC" "4"
					( Origin gPackager )
				)
				( attribute "LOCATION" "J6T1"
					( Origin gFrontEnd )
				)
				( attribute "MATERIAL" "SCONN"
					( Origin gFrontEnd )
				)
				( attribute "PACK_TYPE" "PIP"
					( Origin gFrontEnd )
				)
				( attribute "PART_NUMBER" "H44441-003"
					( Origin gFrontEnd )
				)
				( attribute "PHYS_PAGE" "44"
					( Origin gFrontEnd )
				)
				( attribute "ROOM" "DDR4_CH_A"
					( Origin gFrontEnd )
				)
				( attribute "ROT" "0"
					( Origin gFrontEnd )
				)
				( attribute "SEC" "4"
					( Origin gFrontEnd )
				)
				( attribute "SEC_TYPE" "PIP"
					( Origin gFrontEnd )
				)
				( attribute "VER" "4"
					( Origin gFrontEnd )
				)
				( attribute "XY" "(1600,1650)"
					( Origin gFrontEnd )
				)
				( attribute "CHIPS_PART_NAME" "SCONN288_H44441003"
					( Origin gPackager )
				)
				( attribute "CDS_PART_NAME" "SCONN288_H44441003_PIP-SCONN,HA"
					( Origin gPackager )
				)
				( attribute "BOM_SS" "NOPOP"
					( Origin gFrontEnd )
				)
				( objectStatus "J6T1" )
			)
			( gate "@baseboard_fab2_lib.baseboard_fab2(sch_1):page44_i120"
				( attribute "BOM_COST" "MEM"
					( Origin gFrontEnd )
				)
				( attribute "CDS_LIB" "mstr_sconn"
					( Origin gPackager )
				)
				( attribute "CDS_LOCATION" "J6T1"
					( Origin gPackager )
				)
				( attribute "CDS_SEC" "2"
					( Origin gPackager )
				)
				( attribute "LOCATION" "J6T1"
					( Origin gFrontEnd )
				)
				( attribute "MATERIAL" "SCONN"
					( Origin gFrontEnd )
				)
				( attribute "PACK_TYPE" "PIP"
					( Origin gFrontEnd )
				)
				( attribute "PART_NUMBER" "H44441-003"
					( Origin gFrontEnd )
				)
				( attribute "PHYS_PAGE" "44"
					( Origin gFrontEnd )
				)
				( attribute "ROOM" "DDR4_CH_A"
					( Origin gFrontEnd )
				)
				( attribute "ROT" "0"
					( Origin gFrontEnd )
				)
				( attribute "SEC" "2"
					( Origin gFrontEnd )
				)
				( attribute "SEC_TYPE" "PIP"
					( Origin gFrontEnd )
				)
				( attribute "VER" "2"
					( Origin gFrontEnd )
				)
				( attribute "XY" "(1650,4000)"
					( Origin gFrontEnd )
				)
				( attribute "CHIPS_PART_NAME" "SCONN288_H44441003"
					( Origin gPackager )
				)
				( attribute "CDS_PART_NAME" "SCONN288_H44441003_PIP-SCONN,HA"
					( Origin gPackager )
				)
				( attribute "BOM_SS" "NOPOP"
					( Origin gFrontEnd )
				)
				( objectStatus "J6T1" )
			)
			( gate "@baseboard_fab2_lib.baseboard_fab2(sch_1):page44_i139"
				( attribute "BOM_COST" "MEM"
					( Origin gFrontEnd )
				)
				( attribute "CDS_LIB" "mstr_sconn"
					( Origin gPackager )
				)
				( attribute "CDS_LOCATION" "J6T1"
					( Origin gPackager )
				)
				( attribute "CDS_SEC" "3"
					( Origin gPackager )
				)
				( attribute "LOCATION" "J6T1"
					( Origin gFrontEnd )
				)
				( attribute "MATERIAL" "SCONN"
					( Origin gFrontEnd )
				)
				( attribute "PACK_TYPE" "PIP"
					( Origin gFrontEnd )
				)
				( attribute "PART_NUMBER" "H44441-003"
					( Origin gFrontEnd )
				)
				( attribute "PHYS_PAGE" "44"
					( Origin gFrontEnd )
				)
				( attribute "ROOM" "DDR4_CH_A"
					( Origin gFrontEnd )
				)
				( attribute "ROT" "0"
					( Origin gFrontEnd )
				)
				( attribute "SEC" "3"
					( Origin gFrontEnd )
				)
				( attribute "SEC_TYPE" "PIP"
					( Origin gFrontEnd )
				)
				( attribute "VER" "3"
					( Origin gFrontEnd )
				)
				( attribute "XY" "(3450,2400)"
					( Origin gFrontEnd )
				)
				( attribute "CHIPS_PART_NAME" "SCONN288_H44441003"
					( Origin gPackager )
				)
				( attribute "CDS_PART_NAME" "SCONN288_H44441003_PIP-SCONN,HA"
					( Origin gPackager )
				)
				( attribute "BOM_SS" "NOPOP"
					( Origin gFrontEnd )
				)
				( objectStatus "J6T1" )
			)
			( gate "@baseboard_fab2_lib.baseboard_fab2(sch_1):page45_i43"
				( attribute "BOM_COST" "MEM"
					( Origin gFrontEnd )
				)
				( attribute "CDS_LIB" "mstr_sconn"
					( Origin gPackager )
				)
				( attribute "CDS_LOCATION" "J4G2"
					( Origin gPackager )
				)
				( attribute "CDS_SEC" "3"
					( Origin gPackager )
				)
				( attribute "LOCATION" "J4G2"
					( Origin gFrontEnd )
				)
				( attribute "MATERIAL" "SCONN"
					( Origin gFrontEnd )
				)
				( attribute "PACK_TYPE" "PIP"
					( Origin gFrontEnd )
				)
				( attribute "PART_NUMBER" "H44441-004"
					( Origin gFrontEnd )
				)
				( attribute "PHYS_PAGE" "45"
					( Origin gFrontEnd )
				)
				( attribute "ROOM" "DDR4_CH_B"
					( Origin gFrontEnd )
				)
				( attribute "ROT" "0"
					( Origin gFrontEnd )
				)
				( attribute "SEC" "3"
					( Origin gFrontEnd )
				)
				( attribute "SEC_TYPE" "PIP"
					( Origin gFrontEnd )
				)
				( attribute "VER" "3"
					( Origin gFrontEnd )
				)
				( attribute "XY" "(1800,2600)"
					( Origin gFrontEnd )
				)
				( attribute "CHIPS_PART_NAME" "SCONN288_H44441004"
					( Origin gPackager )
				)
				( attribute "CDS_PART_NAME" "SCONN288_H44441004_PIP-SCONN,HA"
					( Origin gPackager )
				)
				( objectStatus "J4G2" )
			)
			( gate "@baseboard_fab2_lib.baseboard_fab2(sch_1):page45_i61"
				( attribute "BOM_COST" "MEM"
					( Origin gFrontEnd )
				)
				( attribute "CDS_LIB" "mstr_sconn"
					( Origin gPackager )
				)
				( attribute "CDS_LOCATION" "J4G2"
					( Origin gPackager )
				)
				( attribute "CDS_SEC" "2"
					( Origin gPackager )
				)
				( attribute "LOCATION" "J4G2"
					( Origin gFrontEnd )
				)
				( attribute "MATERIAL" "SCONN"
					( Origin gFrontEnd )
				)
				( attribute "PACK_TYPE" "PIP"
					( Origin gFrontEnd )
				)
				( attribute "PART_NUMBER" "H44441-004"
					( Origin gFrontEnd )
				)
				( attribute "PHYS_PAGE" "45"
					( Origin gFrontEnd )
				)
				( attribute "ROOM" "DDR4_CH_B"
					( Origin gFrontEnd )
				)
				( attribute "ROT" "0"
					( Origin gFrontEnd )
				)
				( attribute "SEC" "2"
					( Origin gFrontEnd )
				)
				( attribute "SEC_TYPE" "PIP"
					( Origin gFrontEnd )
				)
				( attribute "VER" "2"
					( Origin gFrontEnd )
				)
				( attribute "XY" "(0,4300)"
					( Origin gFrontEnd )
				)
				( attribute "CHIPS_PART_NAME" "SCONN288_H44441004"
					( Origin gPackager )
				)
				( attribute "CDS_PART_NAME" "SCONN288_H44441004_PIP-SCONN,HA"
					( Origin gPackager )
				)
				( objectStatus "J4G2" )
			)
			( gate "@baseboard_fab2_lib.baseboard_fab2(sch_1):page45_i111"
				( attribute "BOM_COST" "MEM"
					( Origin gFrontEnd )
				)
				( attribute "CDS_LIB" "mstr_sconn"
					( Origin gPackager )
				)
				( attribute "CDS_LOCATION" "J4G2"
					( Origin gPackager )
				)
				( attribute "CDS_SEC" "1"
					( Origin gPackager )
				)
				( attribute "LOCATION" "J4G2"
					( Origin gFrontEnd )
				)
				( attribute "MATERIAL" "SCONN"
					( Origin gFrontEnd )
				)
				( attribute "PACK_TYPE" "PIP"
					( Origin gFrontEnd )
				)
				( attribute "PART_NUMBER" "H44441-004"
					( Origin gFrontEnd )
				)
				( attribute "PHYS_PAGE" "45"
					( Origin gFrontEnd )
				)
				( attribute "ROOM" "DDR4_CH_B"
					( Origin gFrontEnd )
				)
				( attribute "ROT" "0"
					( Origin gFrontEnd )
				)
				( attribute "SEC" "1"
					( Origin gFrontEnd )
				)
				( attribute "SEC_TYPE" "PIP"
					( Origin gFrontEnd )
				)
				( attribute "VER" "1"
					( Origin gFrontEnd )
				)
				( attribute "XY" "(-2450,2950)"
					( Origin gFrontEnd )
				)
				( attribute "CHIPS_PART_NAME" "SCONN288_H44441004"
					( Origin gPackager )
				)
				( attribute "CDS_PART_NAME" "SCONN288_H44441004_PIP-SCONN,HA"
					( Origin gPackager )
				)
				( objectStatus "J4G2" )
			)
			( gate "@baseboard_fab2_lib.baseboard_fab2(sch_1):page45_i169"
				( attribute "BOM_COST" "MEM"
					( Origin gFrontEnd )
				)
				( attribute "CDS_LIB" "mstr_sconn"
					( Origin gPackager )
				)
				( attribute "CDS_LOCATION" "J4G2"
					( Origin gPackager )
				)
				( attribute "CDS_SEC" "4"
					( Origin gPackager )
				)
				( attribute "LOCATION" "J4G2"
					( Origin gFrontEnd )
				)
				( attribute "MATERIAL" "SCONN"
					( Origin gFrontEnd )
				)
				( attribute "PACK_TYPE" "PIP"
					( Origin gFrontEnd )
				)
				( attribute "PART_NUMBER" "H44441-004"
					( Origin gFrontEnd )
				)
				( attribute "PHYS_PAGE" "45"
					( Origin gFrontEnd )
				)
				( attribute "ROOM" "DDR4_CH_B"
					( Origin gFrontEnd )
				)
				( attribute "ROT" "0"
					( Origin gFrontEnd )
				)
				( attribute "SEC" "4"
					( Origin gFrontEnd )
				)
				( attribute "SEC_TYPE" "PIP"
					( Origin gFrontEnd )
				)
				( attribute "VER" "4"
					( Origin gFrontEnd )
				)
				( attribute "XY" "(50,2000)"
					( Origin gFrontEnd )
				)
				( attribute "CHIPS_PART_NAME" "SCONN288_H44441004"
					( Origin gPackager )
				)
				( attribute "CDS_PART_NAME" "SCONN288_H44441004_PIP-SCONN,HA"
					( Origin gPackager )
				)
				( objectStatus "J4G2" )
			)
			( gate "@baseboard_fab2_lib.baseboard_fab2(sch_1):page45_i179"
				( attribute "BOM_COST" "MEM"
					( Origin gFrontEnd )
				)
				( attribute "CDS_LIB" "dev_discrete"
					( Origin gPackager )
				)
				( attribute "CDS_LOCATION" "C4G3"
					( Origin gPackager )
				)
				( attribute "LOCATION" "C4G3"
					( Origin gFrontEnd )
				)
				( attribute "MATERIAL" "X7R"
					( Origin gFrontEnd )
				)
				( attribute "PACK_TYPE" "0402V"
					( Origin gFrontEnd )
				)
				( attribute "PART_NUMBER" "A36096-045"
					( Origin gFrontEnd )
				)
				( attribute "PHYS_PAGE" "45"
					( Origin gFrontEnd )
				)
				( attribute "ROOM" "DDR4_CH_A"
					( Origin gFrontEnd )
				)
				( attribute "ROT" "2"
					( Origin gFrontEnd )
				)
				( attribute "SEC" "1"
					( Origin gFrontEnd )
				)
				( attribute "TOLERANCE" "10%"
					( Origin gFrontEnd )
				)
				( attribute "VALUE" "0.01UF"
					( Origin gFrontEnd )
				)
				( attribute "VER" "1"
					( Origin gFrontEnd )
				)
				( attribute "VOLTAGE" "25V"
					( Units "uVoltage" "V" 1.000000)
					( Origin gFrontEnd )
				)
				( attribute "XY" "(-4600,1250)"
					( Origin gFrontEnd )
				)
				( attribute "CHIPS_PART_NAME" "CAP_A"
					( Origin gPackager )
				)
				( attribute "CDS_PART_NAME" "CAP_A_0402V-0.01UF,25V,10%,X7RA"
					( Origin gPackager )
				)
				( attribute "SEC_TYPE" "0402V"
					( Origin gFrontEnd )
				)
				( attribute "CDS_SEC" "1"
					( Origin gPackager )
				)
				( objectStatus "C4G3" )
			)
			( gate "@baseboard_fab2_lib.baseboard_fab2(sch_1):page46_i5"
				( attribute "BOM_COST" "MEM"
					( Origin gFrontEnd )
				)
				( attribute "CDS_LIB" "dev_discrete"
					( Origin gPackager )
				)
				( attribute "CDS_LOCATION" "C6U9"
					( Origin gPackager )
				)
				( attribute "CDS_SEC" "1"
					( Origin gPackager )
				)
				( attribute "LOCATION" "C6U9"
					( Origin gFrontEnd )
				)
				( attribute "MATERIAL" "X7R"
					( Origin gFrontEnd )
				)
				( attribute "PACK_TYPE" "0402V"
					( Origin gFrontEnd )
				)
				( attribute "PART_NUMBER" "A36096-045"
					( Origin gFrontEnd )
				)
				( attribute "PHYS_PAGE" "46"
					( Origin gFrontEnd )
				)
				( attribute "ROOM" "DDR4_CH_A"
					( Origin gFrontEnd )
				)
				( attribute "ROT" "2"
					( Origin gFrontEnd )
				)
				( attribute "SEC" "1"
					( Origin gFrontEnd )
				)
				( attribute "SEC_TYPE" "0402V"
					( Origin gFrontEnd )
				)
				( attribute "TOLERANCE" "10%"
					( Origin gFrontEnd )
				)
				( attribute "VALUE" "0.01UF"
					( Origin gFrontEnd )
				)
				( attribute "VER" "1"
					( Origin gFrontEnd )
				)
				( attribute "VOLTAGE" "25V"
					( Units "uVoltage" "V" 1.000000)
					( Origin gFrontEnd )
				)
				( attribute "XY" "(-2975,900)"
					( Origin gFrontEnd )
				)
				( attribute "CHIPS_PART_NAME" "CAP_A"
					( Origin gPackager )
				)
				( attribute "CDS_PART_NAME" "CAP_A_0402V-0.01UF,25V,10%,X7RA"
					( Origin gPackager )
				)
				( objectStatus "C6U9" )
			)
			( gate "@baseboard_fab2_lib.baseboard_fab2(sch_1):page46_i14"
				( attribute "BOM_COST" "MEM"
					( Origin gFrontEnd )
				)
				( attribute "CDS_LIB" "mstr_sconn"
					( Origin gPackager )
				)
				( attribute "CDS_LOCATION" "J6U1"
					( Origin gPackager )
				)
				( attribute "CDS_SEC" "1"
					( Origin gPackager )
				)
				( attribute "LOCATION" "J6U1"
					( Origin gFrontEnd )
				)
				( attribute "MATERIAL" "SCONN"
					( Origin gFrontEnd )
				)
				( attribute "PACK_TYPE" "PIP"
					( Origin gFrontEnd )
				)
				( attribute "PART_NUMBER" "H44441-003"
					( Origin gFrontEnd )
				)
				( attribute "PHYS_PAGE" "46"
					( Origin gFrontEnd )
				)
				( attribute "ROOM" "DDR4_CH_B"
					( Origin gFrontEnd )
				)
				( attribute "ROT" "0"
					( Origin gFrontEnd )
				)
				( attribute "SEC" "1"
					( Origin gFrontEnd )
				)
				( attribute "SEC_TYPE" "PIP"
					( Origin gFrontEnd )
				)
				( attribute "VER" "1"
					( Origin gFrontEnd )
				)
				( attribute "XY" "(-825,2600)"
					( Origin gFrontEnd )
				)
				( attribute "CHIPS_PART_NAME" "SCONN288_H44441003"
					( Origin gPackager )
				)
				( attribute "CDS_PART_NAME" "SCONN288_H44441003_PIP-SCONN,HA"
					( Origin gPackager )
				)
				( attribute "BOM_SS" "NOPOP"
					( Origin gFrontEnd )
				)
				( objectStatus "J6U1" )
			)
			( gate "@baseboard_fab2_lib.baseboard_fab2(sch_1):page46_i67"
				( attribute "BOM_COST" "MEM"
					( Origin gFrontEnd )
				)
				( attribute "CDS_LIB" "mstr_sconn"
					( Origin gPackager )
				)
				( attribute "CDS_LOCATION" "J6U1"
					( Origin gPackager )
				)
				( attribute "CDS_SEC" "4"
					( Origin gPackager )
				)
				( attribute "LOCATION" "J6U1"
					( Origin gFrontEnd )
				)
				( attribute "MATERIAL" "SCONN"
					( Origin gFrontEnd )
				)
				( attribute "PACK_TYPE" "PIP"
					( Origin gFrontEnd )
				)
				( attribute "PART_NUMBER" "H44441-003"
					( Origin gFrontEnd )
				)
				( attribute "PHYS_PAGE" "46"
					( Origin gFrontEnd )
				)
				( attribute "ROOM" "DDR4_CH_B"
					( Origin gFrontEnd )
				)
				( attribute "ROT" "0"
					( Origin gFrontEnd )
				)
				( attribute "SEC" "4"
					( Origin gFrontEnd )
				)
				( attribute "SEC_TYPE" "PIP"
					( Origin gFrontEnd )
				)
				( attribute "VER" "4"
					( Origin gFrontEnd )
				)
				( attribute "XY" "(1675,1650)"
					( Origin gFrontEnd )
				)
				( attribute "CHIPS_PART_NAME" "SCONN288_H44441003"
					( Origin gPackager )
				)
				( attribute "CDS_PART_NAME" "SCONN288_H44441003_PIP-SCONN,HA"
					( Origin gPackager )
				)
				( attribute "BOM_SS" "NOPOP"
					( Origin gFrontEnd )
				)
				( objectStatus "J6U1" )
			)
			( gate "@baseboard_fab2_lib.baseboard_fab2(sch_1):page46_i112"
				( attribute "BOM_COST" "MEM"
					( Origin gFrontEnd )
				)
				( attribute "CDS_LIB" "mstr_sconn"
					( Origin gPackager )
				)
				( attribute "CDS_LOCATION" "J6U1"
					( Origin gPackager )
				)
				( attribute "CDS_SEC" "2"
					( Origin gPackager )
				)
				( attribute "LOCATION" "J6U1"
					( Origin gFrontEnd )
				)
				( attribute "MATERIAL" "SCONN"
					( Origin gFrontEnd )
				)
				( attribute "PACK_TYPE" "PIP"
					( Origin gFrontEnd )
				)
				( attribute "PART_NUMBER" "H44441-003"
					( Origin gFrontEnd )
				)
				( attribute "PHYS_PAGE" "46"
					( Origin gFrontEnd )
				)
				( attribute "ROOM" "DDR4_CH_B"
					( Origin gFrontEnd )
				)
				( attribute "ROT" "0"
					( Origin gFrontEnd )
				)
				( attribute "SEC" "2"
					( Origin gFrontEnd )
				)
				( attribute "SEC_TYPE" "PIP"
					( Origin gFrontEnd )
				)
				( attribute "VER" "2"
					( Origin gFrontEnd )
				)
				( attribute "XY" "(1625,3950)"
					( Origin gFrontEnd )
				)
				( attribute "CHIPS_PART_NAME" "SCONN288_H44441003"
					( Origin gPackager )
				)
				( attribute "CDS_PART_NAME" "SCONN288_H44441003_PIP-SCONN,HA"
					( Origin gPackager )
				)
				( attribute "BOM_SS" "NOPOP"
					( Origin gFrontEnd )
				)
				( objectStatus "J6U1" )
			)
			( gate "@baseboard_fab2_lib.baseboard_fab2(sch_1):page46_i138"
				( attribute "BOM_COST" "MEM"
					( Origin gFrontEnd )
				)
				( attribute "CDS_LIB" "mstr_sconn"
					( Origin gPackager )
				)
				( attribute "CDS_LOCATION" "J6U1"
					( Origin gPackager )
				)
				( attribute "CDS_SEC" "3"
					( Origin gPackager )
				)
				( attribute "LOCATION" "J6U1"
					( Origin gFrontEnd )
				)
				( attribute "MATERIAL" "SCONN"
					( Origin gFrontEnd )
				)
				( attribute "PACK_TYPE" "PIP"
					( Origin gFrontEnd )
				)
				( attribute "PART_NUMBER" "H44441-003"
					( Origin gFrontEnd )
				)
				( attribute "PHYS_PAGE" "46"
					( Origin gFrontEnd )
				)
				( attribute "ROOM" "DDR4_CH_B"
					( Origin gFrontEnd )
				)
				( attribute "ROT" "0"
					( Origin gFrontEnd )
				)
				( attribute "SEC" "3"
					( Origin gFrontEnd )
				)
				( attribute "SEC_TYPE" "PIP"
					( Origin gFrontEnd )
				)
				( attribute "VER" "3"
					( Origin gFrontEnd )
				)
				( attribute "XY" "(3425,2250)"
					( Origin gFrontEnd )
				)
				( attribute "CHIPS_PART_NAME" "SCONN288_H44441003"
					( Origin gPackager )
				)
				( attribute "CDS_PART_NAME" "SCONN288_H44441003_PIP-SCONN,HA"
					( Origin gPackager )
				)
				( attribute "BOM_SS" "NOPOP"
					( Origin gFrontEnd )
				)
				( objectStatus "J6U1" )
			)
			( gate "@baseboard_fab2_lib.baseboard_fab2(sch_1):page47_i43"
				( attribute "BOM_COST" "MEM"
					( Origin gFrontEnd )
				)
				( attribute "CDS_LIB" "mstr_sconn"
					( Origin gPackager )
				)
				( attribute "CDS_LOCATION" "J4G3"
					( Origin gPackager )
				)
				( attribute "CDS_SEC" "3"
					( Origin gPackager )
				)
				( attribute "LOCATION" "J4G3"
					( Origin gFrontEnd )
				)
				( attribute "MATERIAL" "SCONN"
					( Origin gFrontEnd )
				)
				( attribute "PACK_TYPE" "PIP"
					( Origin gFrontEnd )
				)
				( attribute "PART_NUMBER" "H44441-004"
					( Origin gFrontEnd )
				)
				( attribute "PHYS_PAGE" "47"
					( Origin gFrontEnd )
				)
				( attribute "ROOM" "DDR4_CH_C"
					( Origin gFrontEnd )
				)
				( attribute "ROT" "0"
					( Origin gFrontEnd )
				)
				( attribute "SEC" "3"
					( Origin gFrontEnd )
				)
				( attribute "SEC_TYPE" "PIP"
					( Origin gFrontEnd )
				)
				( attribute "VER" "3"
					( Origin gFrontEnd )
				)
				( attribute "XY" "(1800,2650)"
					( Origin gFrontEnd )
				)
				( attribute "CHIPS_PART_NAME" "SCONN288_H44441004"
					( Origin gPackager )
				)
				( attribute "CDS_PART_NAME" "SCONN288_H44441004_PIP-SCONN,HA"
					( Origin gPackager )
				)
				( objectStatus "J4G3" )
			)
			( gate "@baseboard_fab2_lib.baseboard_fab2(sch_1):page47_i61"
				( attribute "BOM_COST" "MEM"
					( Origin gFrontEnd )
				)
				( attribute "CDS_LIB" "mstr_sconn"
					( Origin gPackager )
				)
				( attribute "CDS_LOCATION" "J4G3"
					( Origin gPackager )
				)
				( attribute "CDS_SEC" "2"
					( Origin gPackager )
				)
				( attribute "LOCATION" "J4G3"
					( Origin gFrontEnd )
				)
				( attribute "MATERIAL" "SCONN"
					( Origin gFrontEnd )
				)
				( attribute "PACK_TYPE" "PIP"
					( Origin gFrontEnd )
				)
				( attribute "PART_NUMBER" "H44441-004"
					( Origin gFrontEnd )
				)
				( attribute "PHYS_PAGE" "47"
					( Origin gFrontEnd )
				)
				( attribute "ROOM" "DDR4_CH_C"
					( Origin gFrontEnd )
				)
				( attribute "ROT" "0"
					( Origin gFrontEnd )
				)
				( attribute "SEC" "2"
					( Origin gFrontEnd )
				)
				( attribute "SEC_TYPE" "PIP"
					( Origin gFrontEnd )
				)
				( attribute "VER" "2"
					( Origin gFrontEnd )
				)
				( attribute "XY" "(0,4350)"
					( Origin gFrontEnd )
				)
				( attribute "CHIPS_PART_NAME" "SCONN288_H44441004"
					( Origin gPackager )
				)
				( attribute "CDS_PART_NAME" "SCONN288_H44441004_PIP-SCONN,HA"
					( Origin gPackager )
				)
				( objectStatus "J4G3" )
			)
			( gate "@baseboard_fab2_lib.baseboard_fab2(sch_1):page47_i111"
				( attribute "BOM_COST" "MEM"
					( Origin gFrontEnd )
				)
				( attribute "CDS_LIB" "mstr_sconn"
					( Origin gPackager )
				)
				( attribute "CDS_LOCATION" "J4G3"
					( Origin gPackager )
				)
				( attribute "CDS_SEC" "1"
					( Origin gPackager )
				)
				( attribute "LOCATION" "J4G3"
					( Origin gFrontEnd )
				)
				( attribute "MATERIAL" "SCONN"
					( Origin gFrontEnd )
				)
				( attribute "PACK_TYPE" "PIP"
					( Origin gFrontEnd )
				)
				( attribute "PART_NUMBER" "H44441-004"
					( Origin gFrontEnd )
				)
				( attribute "PHYS_PAGE" "47"
					( Origin gFrontEnd )
				)
				( attribute "ROOM" "DDR4_CH_C"
					( Origin gFrontEnd )
				)
				( attribute "ROT" "0"
					( Origin gFrontEnd )
				)
				( attribute "SEC" "1"
					( Origin gFrontEnd )
				)
				( attribute "SEC_TYPE" "PIP"
					( Origin gFrontEnd )
				)
				( attribute "VER" "1"
					( Origin gFrontEnd )
				)
				( attribute "XY" "(-2450,3000)"
					( Origin gFrontEnd )
				)
				( attribute "CHIPS_PART_NAME" "SCONN288_H44441004"
					( Origin gPackager )
				)
				( attribute "CDS_PART_NAME" "SCONN288_H44441004_PIP-SCONN,HA"
					( Origin gPackager )
				)
				( objectStatus "J4G3" )
			)
			( gate "@baseboard_fab2_lib.baseboard_fab2(sch_1):page47_i179"
				( attribute "BOM_COST" "MEM"
					( Origin gFrontEnd )
				)
				( attribute "CDS_LIB" "mstr_sconn"
					( Origin gPackager )
				)
				( attribute "CDS_LOCATION" "J4G3"
					( Origin gPackager )
				)
				( attribute "CDS_SEC" "4"
					( Origin gPackager )
				)
				( attribute "LOCATION" "J4G3"
					( Origin gFrontEnd )
				)
				( attribute "MATERIAL" "SCONN"
					( Origin gFrontEnd )
				)
				( attribute "PACK_TYPE" "PIP"
					( Origin gFrontEnd )
				)
				( attribute "PART_NUMBER" "H44441-004"
					( Origin gFrontEnd )
				)
				( attribute "PHYS_PAGE" "47"
					( Origin gFrontEnd )
				)
				( attribute "ROOM" "DDR4_CH_C"
					( Origin gFrontEnd )
				)
				( attribute "ROT" "0"
					( Origin gFrontEnd )
				)
				( attribute "SEC" "4"
					( Origin gFrontEnd )
				)
				( attribute "SEC_TYPE" "PIP"
					( Origin gFrontEnd )
				)
				( attribute "VER" "4"
					( Origin gFrontEnd )
				)
				( attribute "XY" "(0,2050)"
					( Origin gFrontEnd )
				)
				( attribute "CHIPS_PART_NAME" "SCONN288_H44441004"
					( Origin gPackager )
				)
				( attribute "CDS_PART_NAME" "SCONN288_H44441004_PIP-SCONN,HA"
					( Origin gPackager )
				)
				( objectStatus "J4G3" )
			)
			( gate "@baseboard_fab2_lib.baseboard_fab2(sch_1):page47_i188"
				( attribute "BOM_COST" "MEM"
					( Origin gFrontEnd )
				)
				( attribute "CDS_LIB" "dev_discrete"
					( Origin gPackager )
				)
				( attribute "CDS_LOCATION" "C4G19"
					( Origin gPackager )
				)
				( attribute "CDS_SEC" "1"
					( Origin gPackager )
				)
				( attribute "LOCATION" "C4G19"
					( Origin gFrontEnd )
				)
				( attribute "MATERIAL" "X7R"
					( Origin gFrontEnd )
				)
				( attribute "PACK_TYPE" "0402V"
					( Origin gFrontEnd )
				)
				( attribute "PART_NUMBER" "A36096-045"
					( Origin gFrontEnd )
				)
				( attribute "PHYS_PAGE" "47"
					( Origin gFrontEnd )
				)
				( attribute "ROOM" "DDR4_CH_C"
					( Origin gFrontEnd )
				)
				( attribute "ROT" "2"
					( Origin gFrontEnd )
				)
				( attribute "SEC" "1"
					( Origin gFrontEnd )
				)
				( attribute "SEC_TYPE" "0402V"
					( Origin gFrontEnd )
				)
				( attribute "TOLERANCE" "10%"
					( Origin gFrontEnd )
				)
				( attribute "VALUE" "0.01UF"
					( Origin gFrontEnd )
				)
				( attribute "VER" "1"
					( Origin gFrontEnd )
				)
				( attribute "VOLTAGE" "25V"
					( Units "uVoltage" "V" 1.000000)
					( Origin gFrontEnd )
				)
				( attribute "XY" "(-4650,1300)"
					( Origin gFrontEnd )
				)
				( attribute "CHIPS_PART_NAME" "CAP_A"
					( Origin gPackager )
				)
				( attribute "CDS_PART_NAME" "CAP_A_0402V-0.01UF,25V,10%,X7RA"
					( Origin gPackager )
				)
				( objectStatus "C4G19" )
			)
			( gate "@baseboard_fab2_lib.baseboard_fab2(sch_1):page48_i43"
				( attribute "BOM_COST" "MEM"
					( Origin gFrontEnd )
				)
				( attribute "CDS_LIB" "mstr_sconn"
					( Origin gPackager )
				)
				( attribute "CDS_LOCATION" "J6U2"
					( Origin gPackager )
				)
				( attribute "CDS_SEC" "3"
					( Origin gPackager )
				)
				( attribute "LOCATION" "J6U2"
					( Origin gFrontEnd )
				)
				( attribute "MATERIAL" "SCONN"
					( Origin gFrontEnd )
				)
				( attribute "PACK_TYPE" "PIP"
					( Origin gFrontEnd )
				)
				( attribute "PART_NUMBER" "H44441-003"
					( Origin gFrontEnd )
				)
				( attribute "PHYS_PAGE" "48"
					( Origin gFrontEnd )
				)
				( attribute "ROOM" "DDR4_CH_C1"
					( Origin gFrontEnd )
				)
				( attribute "ROT" "0"
					( Origin gFrontEnd )
				)
				( attribute "SEC" "3"
					( Origin gFrontEnd )
				)
				( attribute "SEC_TYPE" "PIP"
					( Origin gFrontEnd )
				)
				( attribute "VER" "3"
					( Origin gFrontEnd )
				)
				( attribute "XY" "(1800,2600)"
					( Origin gFrontEnd )
				)
				( attribute "CHIPS_PART_NAME" "SCONN288_H44441003"
					( Origin gPackager )
				)
				( attribute "CDS_PART_NAME" "SCONN288_H44441003_PIP-SCONN,HA"
					( Origin gPackager )
				)
				( attribute "BOM_SS" "NOPOP"
					( Origin gFrontEnd )
				)
				( objectStatus "J6U2" )
			)
			( gate "@baseboard_fab2_lib.baseboard_fab2(sch_1):page48_i61"
				( attribute "BOM_COST" "MEM"
					( Origin gFrontEnd )
				)
				( attribute "CDS_LIB" "mstr_sconn"
					( Origin gPackager )
				)
				( attribute "CDS_LOCATION" "J6U2"
					( Origin gPackager )
				)
				( attribute "CDS_SEC" "2"
					( Origin gPackager )
				)
				( attribute "LOCATION" "J6U2"
					( Origin gFrontEnd )
				)
				( attribute "MATERIAL" "SCONN"
					( Origin gFrontEnd )
				)
				( attribute "PACK_TYPE" "PIP"
					( Origin gFrontEnd )
				)
				( attribute "PART_NUMBER" "H44441-003"
					( Origin gFrontEnd )
				)
				( attribute "PHYS_PAGE" "48"
					( Origin gFrontEnd )
				)
				( attribute "ROOM" "DDR4_CH_C1"
					( Origin gFrontEnd )
				)
				( attribute "ROT" "0"
					( Origin gFrontEnd )
				)
				( attribute "SEC" "2"
					( Origin gFrontEnd )
				)
				( attribute "SEC_TYPE" "PIP"
					( Origin gFrontEnd )
				)
				( attribute "VER" "2"
					( Origin gFrontEnd )
				)
				( attribute "XY" "(0,4300)"
					( Origin gFrontEnd )
				)
				( attribute "CHIPS_PART_NAME" "SCONN288_H44441003"
					( Origin gPackager )
				)
				( attribute "CDS_PART_NAME" "SCONN288_H44441003_PIP-SCONN,HA"
					( Origin gPackager )
				)
				( attribute "BOM_SS" "NOPOP"
					( Origin gFrontEnd )
				)
				( objectStatus "J6U2" )
			)
			( gate "@baseboard_fab2_lib.baseboard_fab2(sch_1):page48_i111"
				( attribute "BOM_COST" "MEM"
					( Origin gFrontEnd )
				)
				( attribute "CDS_LIB" "mstr_sconn"
					( Origin gPackager )
				)
				( attribute "CDS_LOCATION" "J6U2"
					( Origin gPackager )
				)
				( attribute "CDS_SEC" "1"
					( Origin gPackager )
				)
				( attribute "LOCATION" "J6U2"
					( Origin gFrontEnd )
				)
				( attribute "MATERIAL" "SCONN"
					( Origin gFrontEnd )
				)
				( attribute "PACK_TYPE" "PIP"
					( Origin gFrontEnd )
				)
				( attribute "PART_NUMBER" "H44441-003"
					( Origin gFrontEnd )
				)
				( attribute "PHYS_PAGE" "48"
					( Origin gFrontEnd )
				)
				( attribute "ROOM" "DDR4_CH_C1"
					( Origin gFrontEnd )
				)
				( attribute "ROT" "0"
					( Origin gFrontEnd )
				)
				( attribute "SEC" "1"
					( Origin gFrontEnd )
				)
				( attribute "SEC_TYPE" "PIP"
					( Origin gFrontEnd )
				)
				( attribute "VER" "1"
					( Origin gFrontEnd )
				)
				( attribute "XY" "(-2400,3200)"
					( Origin gFrontEnd )
				)
				( attribute "CHIPS_PART_NAME" "SCONN288_H44441003"
					( Origin gPackager )
				)
				( attribute "CDS_PART_NAME" "SCONN288_H44441003_PIP-SCONN,HA"
				)
				( attribute "BOM_SS" "NOPOP"
					( Origin gFrontEnd )
				)
				( objectStatus "J6U2" )
			)
			( gate "@baseboard_fab2_lib.baseboard_fab2(sch_1):page48_i171"
				( attribute "BOM_COST" "MEM"
					( Origin gFrontEnd )
				)
				( attribute "CDS_LIB" "mstr_sconn"
					( Origin gPackager )
				)
				( attribute "CDS_LOCATION" "J6U2"
					( Origin gPackager )
				)
				( attribute "CDS_SEC" "4"
					( Origin gPackager )
				)
				( attribute "LOCATION" "J6U2"
					( Origin gFrontEnd )
				)
				( attribute "MATERIAL" "SCONN"
					( Origin gFrontEnd )
				)
				( attribute "PACK_TYPE" "PIP"
					( Origin gFrontEnd )
				)
				( attribute "PART_NUMBER" "H44441-003"
					( Origin gFrontEnd )
				)
				( attribute "PHYS_PAGE" "48"
					( Origin gFrontEnd )
				)
				( attribute "ROOM" "DDR4_CH_C1"
					( Origin gFrontEnd )
				)
				( attribute "ROT" "0"
					( Origin gFrontEnd )
				)
				( attribute "SEC" "4"
					( Origin gFrontEnd )
				)
				( attribute "SEC_TYPE" "PIP"
					( Origin gFrontEnd )
				)
				( attribute "VER" "4"
					( Origin gFrontEnd )
				)
				( attribute "XY" "(-100,2000)"
					( Origin gFrontEnd )
				)
				( attribute "CHIPS_PART_NAME" "SCONN288_H44441003"
					( Origin gPackager )
				)
				( attribute "CDS_PART_NAME" "SCONN288_H44441003_PIP-SCONN,HA"
					( Origin gPackager )
				)
				( attribute "BOM_SS" "NOPOP"
					( Origin gFrontEnd )
				)
				( objectStatus "J6U2" )
			)
			( gate "@baseboard_fab2_lib.baseboard_fab2(sch_1):page48_i176"
				( attribute "BOM_COST" "MEM"
					( Origin gFrontEnd )
				)
				( attribute "CDS_LIB" "dev_discrete"
					( Origin gPackager )
				)
				( attribute "CDS_LOCATION" "C6U17"
					( Origin gPackager )
				)
				( attribute "CDS_SEC" "1"
					( Origin gPackager )
				)
				( attribute "LOCATION" "C6U17"
					( Origin gFrontEnd )
				)
				( attribute "MATERIAL" "X7R"
					( Origin gFrontEnd )
				)
				( attribute "PACK_TYPE" "0402V"
					( Origin gFrontEnd )
				)
				( attribute "PART_NUMBER" "A36096-045"
					( Origin gFrontEnd )
				)
				( attribute "PHYS_PAGE" "48"
					( Origin gFrontEnd )
				)
				( attribute "ROOM" "DDR4_CH_B"
					( Origin gFrontEnd )
				)
				( attribute "ROT" "2"
					( Origin gFrontEnd )
				)
				( attribute "SEC" "1"
					( Origin gFrontEnd )
				)
				( attribute "SEC_TYPE" "0402V"
					( Origin gFrontEnd )
				)
				( attribute "TOLERANCE" "10%"
					( Origin gFrontEnd )
				)
				( attribute "VALUE" "0.01UF"
					( Origin gFrontEnd )
				)
				( attribute "VER" "1"
					( Origin gFrontEnd )
				)
				( attribute "VOLTAGE" "25V"
					( Units "uVoltage" "V" 1.000000)
					( Origin gFrontEnd )
				)
				( attribute "XY" "(-4650,1500)"
					( Origin gFrontEnd )
				)
				( attribute "CHIPS_PART_NAME" "CAP_A"
					( Origin gPackager )
				)
				( attribute "CDS_PART_NAME" "CAP_A_0402V-0.01UF,25V,10%,X7RA"
					( Origin gPackager )
				)
				( objectStatus "C6U17" )
			)
			( gate "@baseboard_fab2_lib.baseboard_fab2(sch_1):page49_i43"
				( attribute "BOM_COST" "MEM"
					( Origin gFrontEnd )
				)
				( attribute "CDS_LIB" "mstr_sconn"
					( Origin gPackager )
				)
				( attribute "CDS_LOCATION" "J4B1"
					( Origin gPackager )
				)
				( attribute "CDS_SEC" "3"
					( Origin gPackager )
				)
				( attribute "LOCATION" "J4B1"
					( Origin gFrontEnd )
				)
				( attribute "MATERIAL" "SCONN"
					( Origin gFrontEnd )
				)
				( attribute "PACK_TYPE" "PIP"
					( Origin gFrontEnd )
				)
				( attribute "PART_NUMBER" "H44441-004"
					( Origin gFrontEnd )
				)
				( attribute "PHYS_PAGE" "49"
					( Origin gFrontEnd )
				)
				( attribute "ROOM" "DDR4_CH_D"
					( Origin gFrontEnd )
				)
				( attribute "ROT" "0"
					( Origin gFrontEnd )
				)
				( attribute "SEC" "3"
					( Origin gFrontEnd )
				)
				( attribute "SEC_TYPE" "PIP"
					( Origin gFrontEnd )
				)
				( attribute "VER" "3"
					( Origin gFrontEnd )
				)
				( attribute "XY" "(1800,2450)"
					( Origin gFrontEnd )
				)
				( attribute "CHIPS_PART_NAME" "SCONN288_H44441004"
					( Origin gPackager )
				)
				( attribute "CDS_PART_NAME" "SCONN288_H44441004_PIP-SCONN,HA"
					( Origin gPackager )
				)
				( objectStatus "J4B1" )
			)
			( gate "@baseboard_fab2_lib.baseboard_fab2(sch_1):page49_i66"
				( attribute "BOM_COST" "MEM"
					( Origin gFrontEnd )
				)
				( attribute "CDS_LIB" "mstr_sconn"
					( Origin gPackager )
				)
				( attribute "CDS_LOCATION" "J4B1"
					( Origin gPackager )
				)
				( attribute "CDS_SEC" "2"
					( Origin gPackager )
				)
				( attribute "LOCATION" "J4B1"
					( Origin gFrontEnd )
				)
				( attribute "MATERIAL" "SCONN"
					( Origin gFrontEnd )
				)
				( attribute "PACK_TYPE" "PIP"
					( Origin gFrontEnd )
				)
				( attribute "PART_NUMBER" "H44441-004"
					( Origin gFrontEnd )
				)
				( attribute "PHYS_PAGE" "49"
					( Origin gFrontEnd )
				)
				( attribute "ROOM" "DDR4_CH_D"
					( Origin gFrontEnd )
				)
				( attribute "ROT" "0"
					( Origin gFrontEnd )
				)
				( attribute "SEC" "2"
					( Origin gFrontEnd )
				)
				( attribute "SEC_TYPE" "PIP"
					( Origin gFrontEnd )
				)
				( attribute "VER" "2"
					( Origin gFrontEnd )
				)
				( attribute "XY" "(-50,4350)"
					( Origin gFrontEnd )
				)
				( attribute "CHIPS_PART_NAME" "SCONN288_H44441004"
					( Origin gPackager )
				)
				( attribute "CDS_PART_NAME" "SCONN288_H44441004_PIP-SCONN,HA"
					( Origin gPackager )
				)
				( objectStatus "J4B1" )
			)
			( gate "@baseboard_fab2_lib.baseboard_fab2(sch_1):page49_i111"
				( attribute "BOM_COST" "MEM"
					( Origin gFrontEnd )
				)
				( attribute "CDS_LIB" "mstr_sconn"
					( Origin gPackager )
				)
				( attribute "CDS_LOCATION" "J4B1"
					( Origin gPackager )
				)
				( attribute "CDS_SEC" "1"
					( Origin gPackager )
				)
				( attribute "LOCATION" "J4B1"
					( Origin gFrontEnd )
				)
				( attribute "MATERIAL" "SCONN"
					( Origin gFrontEnd )
				)
				( attribute "PACK_TYPE" "PIP"
					( Origin gFrontEnd )
				)
				( attribute "PART_NUMBER" "H44441-004"
					( Origin gFrontEnd )
				)
				( attribute "PHYS_PAGE" "49"
					( Origin gFrontEnd )
				)
				( attribute "ROOM" "DDR4_CH_D"
					( Origin gFrontEnd )
				)
				( attribute "ROT" "0"
					( Origin gFrontEnd )
				)
				( attribute "SEC" "1"
					( Origin gFrontEnd )
				)
				( attribute "SEC_TYPE" "PIP"
					( Origin gFrontEnd )
				)
				( attribute "VER" "1"
					( Origin gFrontEnd )
				)
				( attribute "XY" "(-2500,3500)"
					( Origin gFrontEnd )
				)
				( attribute "CHIPS_PART_NAME" "SCONN288_H44441004"
					( Origin gPackager )
				)
				( attribute "CDS_PART_NAME" "SCONN288_H44441004_PIP-SCONN,HA"
					( Origin gPackager )
				)
				( objectStatus "J4B1" )
			)
			( gate "@baseboard_fab2_lib.baseboard_fab2(sch_1):page49_i169"
				( attribute "BOM_COST" "MEM"
					( Origin gFrontEnd )
				)
				( attribute "CDS_LIB" "mstr_sconn"
					( Origin gPackager )
				)
				( attribute "CDS_LOCATION" "J4B1"
					( Origin gPackager )
				)
				( attribute "CDS_SEC" "4"
					( Origin gPackager )
				)
				( attribute "LOCATION" "J4B1"
					( Origin gFrontEnd )
				)
				( attribute "MATERIAL" "SCONN"
					( Origin gFrontEnd )
				)
				( attribute "PACK_TYPE" "PIP"
					( Origin gFrontEnd )
				)
				( attribute "PART_NUMBER" "H44441-004"
					( Origin gFrontEnd )
				)
				( attribute "PHYS_PAGE" "49"
					( Origin gFrontEnd )
				)
				( attribute "ROOM" "DDR4_CH_D"
					( Origin gFrontEnd )
				)
				( attribute "ROT" "0"
					( Origin gFrontEnd )
				)
				( attribute "SEC" "4"
					( Origin gFrontEnd )
				)
				( attribute "SEC_TYPE" "PIP"
					( Origin gFrontEnd )
				)
				( attribute "VER" "4"
					( Origin gFrontEnd )
				)
				( attribute "XY" "(-50,1950)"
					( Origin gFrontEnd )
				)
				( attribute "CHIPS_PART_NAME" "SCONN288_H44441004"
					( Origin gPackager )
				)
				( attribute "CDS_PART_NAME" "SCONN288_H44441004_PIP-SCONN,HA"
					( Origin gPackager )
				)
				( objectStatus "J4B1" )
			)
			( gate "@baseboard_fab2_lib.baseboard_fab2(sch_1):page49_i179"
				( attribute "BOM_COST" "MEM"
					( Origin gFrontEnd )
				)
				( attribute "CDS_LIB" "dev_discrete"
					( Origin gPackager )
				)
				( attribute "CDS_LOCATION" "C4B12"
					( Origin gPackager )
				)
				( attribute "LOCATION" "C4B12"
					( Origin gFrontEnd )
				)
				( attribute "MATERIAL" "X7R"
					( Origin gFrontEnd )
				)
				( attribute "PACK_TYPE" "0402V"
					( Origin gFrontEnd )
				)
				( attribute "PART_NUMBER" "A36096-045"
					( Origin gFrontEnd )
				)
				( attribute "PHYS_PAGE" "49"
					( Origin gFrontEnd )
				)
				( attribute "ROOM" "DDR4_CH_B"
					( Origin gFrontEnd )
				)
				( attribute "ROT" "2"
					( Origin gFrontEnd )
				)
				( attribute "SEC" "1"
					( Origin gFrontEnd )
				)
				( attribute "TOLERANCE" "10%"
					( Origin gFrontEnd )
				)
				( attribute "VALUE" "0.01UF"
					( Origin gFrontEnd )
				)
				( attribute "VER" "1"
					( Origin gFrontEnd )
				)
				( attribute "VOLTAGE" "25V"
					( Units "uVoltage" "V" 1.000000)
					( Origin gFrontEnd )
				)
				( attribute "XY" "(-4650,1800)"
					( Origin gFrontEnd )
				)
				( attribute "CHIPS_PART_NAME" "CAP_A"
					( Origin gPackager )
				)
				( attribute "CDS_PART_NAME" "CAP_A_0402V-0.01UF,25V,10%,X7RA"
					( Origin gPackager )
				)
				( attribute "SEC_TYPE" "0402V"
					( Origin gFrontEnd )
				)
				( attribute "CDS_SEC" "1"
					( Origin gPackager )
				)
				( objectStatus "C4B12" )
			)
			( gate "@baseboard_fab2_lib.baseboard_fab2(sch_1):page50_i44"
				( attribute "BOM_COST" "MEM"
					( Origin gFrontEnd )
				)
				( attribute "CDS_LIB" "mstr_sconn"
					( Origin gPackager )
				)
				( attribute "CDS_LOCATION" "J6M1"
					( Origin gPackager )
				)
				( attribute "CDS_SEC" "3"
					( Origin gPackager )
				)
				( attribute "LOCATION" "J6M1"
					( Origin gFrontEnd )
				)
				( attribute "MATERIAL" "SCONN"
					( Origin gFrontEnd )
				)
				( attribute "PACK_TYPE" "PIP"
					( Origin gFrontEnd )
				)
				( attribute "PART_NUMBER" "H44441-003"
					( Origin gFrontEnd )
				)
				( attribute "PHYS_PAGE" "50"
					( Origin gFrontEnd )
				)
				( attribute "ROOM" "DDR4_CH_D"
					( Origin gFrontEnd )
				)
				( attribute "ROT" "0"
					( Origin gFrontEnd )
				)
				( attribute "SEC" "3"
					( Origin gFrontEnd )
				)
				( attribute "SEC_TYPE" "PIP"
					( Origin gFrontEnd )
				)
				( attribute "VER" "3"
					( Origin gFrontEnd )
				)
				( attribute "XY" "(5250,2050)"
					( Origin gFrontEnd )
				)
				( attribute "CHIPS_PART_NAME" "SCONN288_H44441003"
					( Origin gPackager )
				)
				( attribute "CDS_PART_NAME" "SCONN288_H44441003_PIP-SCONN,HA"
					( Origin gPackager )
				)
				( attribute "BOM_SS" "NOPOP"
					( Origin gFrontEnd )
				)
				( objectStatus "J6M1" )
			)
			( gate "@baseboard_fab2_lib.baseboard_fab2(sch_1):page50_i46"
				( attribute "BOM_COST" "MEM"
					( Origin gFrontEnd )
				)
				( attribute "CDS_LIB" "mstr_sconn"
					( Origin gPackager )
				)
				( attribute "CDS_LOCATION" "J6M1"
					( Origin gPackager )
				)
				( attribute "CDS_SEC" "2"
					( Origin gPackager )
				)
				( attribute "LOCATION" "J6M1"
					( Origin gFrontEnd )
				)
				( attribute "MATERIAL" "SCONN"
					( Origin gFrontEnd )
				)
				( attribute "PACK_TYPE" "PIP"
					( Origin gFrontEnd )
				)
				( attribute "PART_NUMBER" "H44441-003"
					( Origin gFrontEnd )
				)
				( attribute "PHYS_PAGE" "50"
					( Origin gFrontEnd )
				)
				( attribute "ROOM" "DDR4_CH_D"
					( Origin gFrontEnd )
				)
				( attribute "ROT" "0"
					( Origin gFrontEnd )
				)
				( attribute "SEC" "2"
					( Origin gFrontEnd )
				)
				( attribute "SEC_TYPE" "PIP"
					( Origin gFrontEnd )
				)
				( attribute "VER" "2"
					( Origin gFrontEnd )
				)
				( attribute "XY" "(3400,3950)"
					( Origin gFrontEnd )
				)
				( attribute "CHIPS_PART_NAME" "SCONN288_H44441003"
					( Origin gPackager )
				)
				( attribute "CDS_PART_NAME" "SCONN288_H44441003_PIP-SCONN,HA"
					( Origin gPackager )
				)
				( attribute "BOM_SS" "NOPOP"
					( Origin gFrontEnd )
				)
				( objectStatus "J6M1" )
			)
			( gate "@baseboard_fab2_lib.baseboard_fab2(sch_1):page50_i50"
				( attribute "BOM_COST" "MEM"
					( Origin gFrontEnd )
				)
				( attribute "CDS_LIB" "mstr_sconn"
					( Origin gPackager )
				)
				( attribute "CDS_LOCATION" "J6M1"
					( Origin gPackager )
				)
				( attribute "CDS_SEC" "4"
					( Origin gPackager )
				)
				( attribute "LOCATION" "J6M1"
					( Origin gFrontEnd )
				)
				( attribute "MATERIAL" "SCONN"
					( Origin gFrontEnd )
				)
				( attribute "PACK_TYPE" "PIP"
					( Origin gFrontEnd )
				)
				( attribute "PART_NUMBER" "H44441-003"
					( Origin gFrontEnd )
				)
				( attribute "PHYS_PAGE" "50"
					( Origin gFrontEnd )
				)
				( attribute "ROOM" "DDR4_CH_D"
					( Origin gFrontEnd )
				)
				( attribute "ROT" "0"
					( Origin gFrontEnd )
				)
				( attribute "SEC" "4"
					( Origin gFrontEnd )
				)
				( attribute "SEC_TYPE" "PIP"
					( Origin gFrontEnd )
				)
				( attribute "VER" "4"
					( Origin gFrontEnd )
				)
				( attribute "XY" "(3400,1550)"
					( Origin gFrontEnd )
				)
				( attribute "CHIPS_PART_NAME" "SCONN288_H44441003"
					( Origin gPackager )
				)
				( attribute "CDS_PART_NAME" "SCONN288_H44441003_PIP-SCONN,HA"
					( Origin gPackager )
				)
				( attribute "BOM_SS" "NOPOP"
					( Origin gFrontEnd )
				)
				( objectStatus "J6M1" )
			)
			( gate "@baseboard_fab2_lib.baseboard_fab2(sch_1):page50_i158"
				( attribute "BOM_COST" "MEM"
					( Origin gFrontEnd )
				)
				( attribute "CDS_LIB" "mstr_sconn"
					( Origin gPackager )
				)
				( attribute "CDS_LOCATION" "J6M1"
					( Origin gPackager )
				)
				( attribute "CDS_SEC" "1"
					( Origin gPackager )
				)
				( attribute "LOCATION" "J6M1"
					( Origin gFrontEnd )
				)
				( attribute "MATERIAL" "SCONN"
					( Origin gFrontEnd )
				)
				( attribute "PACK_TYPE" "PIP"
					( Origin gFrontEnd )
				)
				( attribute "PART_NUMBER" "H44441-003"
					( Origin gFrontEnd )
				)
				( attribute "PHYS_PAGE" "50"
					( Origin gFrontEnd )
				)
				( attribute "ROOM" "DDR4_CH_D"
					( Origin gFrontEnd )
				)
				( attribute "ROT" "0"
					( Origin gFrontEnd )
				)
				( attribute "SEC" "1"
					( Origin gFrontEnd )
				)
				( attribute "SEC_TYPE" "PIP"
					( Origin gFrontEnd )
				)
				( attribute "VER" "1"
					( Origin gFrontEnd )
				)
				( attribute "XY" "(950,3100)"
					( Origin gFrontEnd )
				)
				( attribute "CHIPS_PART_NAME" "SCONN288_H44441003"
					( Origin gPackager )
				)
				( attribute "CDS_PART_NAME" "SCONN288_H44441003_PIP-SCONN,HA"
					( Origin gPackager )
				)
				( attribute "BOM_SS" "NOPOP"
					( Origin gFrontEnd )
				)
				( objectStatus "J6M1" )
			)
			( gate "@baseboard_fab2_lib.baseboard_fab2(sch_1):page50_i177"
				( attribute "BOM_COST" "MEM"
					( Origin gFrontEnd )
				)
				( attribute "CDS_LIB" "dev_discrete"
					( Origin gPackager )
				)
				( attribute "CDS_LOCATION" "C6M1"
					( Origin gPackager )
				)
				( attribute "LOCATION" "C6M1"
					( Origin gFrontEnd )
				)
				( attribute "MATERIAL" "X7R"
					( Origin gFrontEnd )
				)
				( attribute "PACK_TYPE" "0402V"
					( Origin gFrontEnd )
				)
				( attribute "PART_NUMBER" "A36096-045"
					( Origin gFrontEnd )
				)
				( attribute "PHYS_PAGE" "50"
					( Origin gFrontEnd )
				)
				( attribute "ROOM" "DDR4_CH_B"
					( Origin gFrontEnd )
				)
				( attribute "ROT" "2"
					( Origin gFrontEnd )
				)
				( attribute "SEC" "1"
					( Origin gFrontEnd )
				)
				( attribute "TOLERANCE" "10%"
					( Origin gFrontEnd )
				)
				( attribute "VALUE" "0.01UF"
					( Origin gFrontEnd )
				)
				( attribute "VER" "1"
					( Origin gFrontEnd )
				)
				( attribute "VOLTAGE" "25V"
					( Units "uVoltage" "V" 1.000000)
					( Origin gFrontEnd )
				)
				( attribute "XY" "(-1200,1400)"
					( Origin gFrontEnd )
				)
				( attribute "CHIPS_PART_NAME" "CAP_A"
					( Origin gPackager )
				)
				( attribute "CDS_PART_NAME" "CAP_A_0402V-0.01UF,25V,10%,X7RA"
					( Origin gPackager )
				)
				( attribute "SEC_TYPE" "0402V"
					( Origin gFrontEnd )
				)
				( attribute "CDS_SEC" "1"
					( Origin gPackager )
				)
				( objectStatus "C6M1" )
			)
			( gate "@baseboard_fab2_lib.baseboard_fab2(sch_1):page51_i43"
				( attribute "BOM_COST" "MEM"
					( Origin gFrontEnd )
				)
				( attribute "CDS_LIB" "mstr_sconn"
					( Origin gPackager )
				)
				( attribute "CDS_LOCATION" "J4A2"
					( Origin gPackager )
				)
				( attribute "CDS_SEC" "3"
					( Origin gPackager )
				)
				( attribute "LOCATION" "J4A2"
					( Origin gFrontEnd )
				)
				( attribute "MATERIAL" "SCONN"
					( Origin gFrontEnd )
				)
				( attribute "PACK_TYPE" "PIP"
					( Origin gFrontEnd )
				)
				( attribute "PART_NUMBER" "H44441-004"
					( Origin gFrontEnd )
				)
				( attribute "PHYS_PAGE" "51"
					( Origin gFrontEnd )
				)
				( attribute "ROOM" "DDR4_CH_E"
					( Origin gFrontEnd )
				)
				( attribute "ROT" "0"
					( Origin gFrontEnd )
				)
				( attribute "SEC" "3"
					( Origin gFrontEnd )
				)
				( attribute "SEC_TYPE" "PIP"
					( Origin gFrontEnd )
				)
				( attribute "VER" "3"
					( Origin gFrontEnd )
				)
				( attribute "XY" "(1800,2500)"
					( Origin gFrontEnd )
				)
				( attribute "CHIPS_PART_NAME" "SCONN288_H44441004"
					( Origin gPackager )
				)
				( attribute "CDS_PART_NAME" "SCONN288_H44441004_PIP-SCONN,HA"
					( Origin gPackager )
				)
				( objectStatus "J4A2" )
			)
			( gate "@baseboard_fab2_lib.baseboard_fab2(sch_1):page51_i66"
				( attribute "BOM_COST" "MEM"
					( Origin gFrontEnd )
				)
				( attribute "CDS_LIB" "mstr_sconn"
					( Origin gPackager )
				)
				( attribute "CDS_LOCATION" "J4A2"
					( Origin gPackager )
				)
				( attribute "CDS_SEC" "2"
					( Origin gPackager )
				)
				( attribute "LOCATION" "J4A2"
					( Origin gFrontEnd )
				)
				( attribute "MATERIAL" "SCONN"
					( Origin gFrontEnd )
				)
				( attribute "PACK_TYPE" "PIP"
					( Origin gFrontEnd )
				)
				( attribute "PART_NUMBER" "H44441-004"
					( Origin gFrontEnd )
				)
				( attribute "PHYS_PAGE" "51"
					( Origin gFrontEnd )
				)
				( attribute "ROOM" "DDR4_CH_E"
					( Origin gFrontEnd )
				)
				( attribute "ROT" "0"
					( Origin gFrontEnd )
				)
				( attribute "SEC" "2"
					( Origin gFrontEnd )
				)
				( attribute "SEC_TYPE" "PIP"
					( Origin gFrontEnd )
				)
				( attribute "VER" "2"
					( Origin gFrontEnd )
				)
				( attribute "XY" "(0,4300)"
					( Origin gFrontEnd )
				)
				( attribute "CHIPS_PART_NAME" "SCONN288_H44441004"
					( Origin gPackager )
				)
				( attribute "CDS_PART_NAME" "SCONN288_H44441004_PIP-SCONN,HA"
					( Origin gPackager )
				)
				( objectStatus "J4A2" )
			)
			( gate "@baseboard_fab2_lib.baseboard_fab2(sch_1):page51_i111"
				( attribute "BOM_COST" "MEM"
					( Origin gFrontEnd )
				)
				( attribute "CDS_LIB" "mstr_sconn"
					( Origin gPackager )
				)
				( attribute "CDS_LOCATION" "J4A2"
					( Origin gPackager )
				)
				( attribute "CDS_SEC" "1"
					( Origin gPackager )
				)
				( attribute "LOCATION" "J4A2"
					( Origin gFrontEnd )
				)
				( attribute "MATERIAL" "SCONN"
					( Origin gFrontEnd )
				)
				( attribute "PACK_TYPE" "PIP"
					( Origin gFrontEnd )
				)
				( attribute "PART_NUMBER" "H44441-004"
					( Origin gFrontEnd )
				)
				( attribute "PHYS_PAGE" "51"
					( Origin gFrontEnd )
				)
				( attribute "ROOM" "DDR4_CH_E"
					( Origin gFrontEnd )
				)
				( attribute "ROT" "0"
					( Origin gFrontEnd )
				)
				( attribute "SEC" "1"
					( Origin gFrontEnd )
				)
				( attribute "SEC_TYPE" "PIP"
					( Origin gFrontEnd )
				)
				( attribute "VER" "1"
					( Origin gFrontEnd )
				)
				( attribute "XY" "(-2350,3250)"
					( Origin gFrontEnd )
				)
				( attribute "CHIPS_PART_NAME" "SCONN288_H44441004"
					( Origin gPackager )
				)
				( attribute "CDS_PART_NAME" "SCONN288_H44441004_PIP-SCONN,HA"
					( Origin gPackager )
				)
				( objectStatus "J4A2" )
			)
			( gate "@baseboard_fab2_lib.baseboard_fab2(sch_1):page51_i167"
				( attribute "BOM_COST" "MEM"
					( Origin gFrontEnd )
				)
				( attribute "CDS_LIB" "mstr_sconn"
					( Origin gPackager )
				)
				( attribute "CDS_LOCATION" "J4A2"
					( Origin gPackager )
				)
				( attribute "CDS_SEC" "4"
					( Origin gPackager )
				)
				( attribute "LOCATION" "J4A2"
					( Origin gFrontEnd )
				)
				( attribute "MATERIAL" "SCONN"
					( Origin gFrontEnd )
				)
				( attribute "PACK_TYPE" "PIP"
					( Origin gFrontEnd )
				)
				( attribute "PART_NUMBER" "H44441-004"
					( Origin gFrontEnd )
				)
				( attribute "PHYS_PAGE" "51"
					( Origin gFrontEnd )
				)
				( attribute "ROOM" "DDR4_CH_E"
					( Origin gFrontEnd )
				)
				( attribute "ROT" "0"
					( Origin gFrontEnd )
				)
				( attribute "SEC" "4"
					( Origin gFrontEnd )
				)
				( attribute "SEC_TYPE" "PIP"
					( Origin gFrontEnd )
				)
				( attribute "VER" "4"
					( Origin gFrontEnd )
				)
				( attribute "XY" "(-150,2050)"
					( Origin gFrontEnd )
				)
				( attribute "CHIPS_PART_NAME" "SCONN288_H44441004"
					( Origin gPackager )
				)
				( attribute "CDS_PART_NAME" "SCONN288_H44441004_PIP-SCONN,HA"
					( Origin gPackager )
				)
				( objectStatus "J4A2" )
			)
			( gate "@baseboard_fab2_lib.baseboard_fab2(sch_1):page51_i175"
				( attribute "BOM_COST" "MEM"
					( Origin gFrontEnd )
				)
				( attribute "CDS_LIB" "dev_discrete"
					( Origin gPackager )
				)
				( attribute "CDS_LOCATION" "C6L6"
					( Origin gPackager )
				)
				( attribute "LOCATION" "C6L6"
					( Origin gFrontEnd )
				)
				( attribute "MATERIAL" "X7R"
					( Origin gFrontEnd )
				)
				( attribute "PACK_TYPE" "0402V"
					( Origin gFrontEnd )
				)
				( attribute "PART_NUMBER" "A36096-045"
					( Origin gFrontEnd )
				)
				( attribute "PHYS_PAGE" "51"
					( Origin gFrontEnd )
				)
				( attribute "ROOM" "DDR4_CH_E"
					( Origin gFrontEnd )
				)
				( attribute "ROT" "2"
					( Origin gFrontEnd )
				)
				( attribute "SEC" "1"
					( Origin gFrontEnd )
				)
				( attribute "TOLERANCE" "10%"
					( Origin gFrontEnd )
				)
				( attribute "VALUE" "0.01UF"
					( Origin gFrontEnd )
				)
				( attribute "VER" "1"
					( Origin gFrontEnd )
				)
				( attribute "VOLTAGE" "25V"
					( Units "uVoltage" "V" 1.000000)
					( Origin gFrontEnd )
				)
				( attribute "XY" "(-4650,1550)"
					( Origin gFrontEnd )
				)
				( attribute "CHIPS_PART_NAME" "CAP_A"
					( Origin gPackager )
				)
				( attribute "CDS_PART_NAME" "CAP_A_0402V-0.01UF,25V,10%,X7RA"
					( Origin gPackager )
				)
				( attribute "SEC_TYPE" "0402V"
					( Origin gFrontEnd )
				)
				( attribute "CDS_SEC" "1"
					( Origin gPackager )
				)
				( objectStatus "C6L6" )
			)
			( gate "@baseboard_fab2_lib.baseboard_fab2(sch_1):page52_i3"
				( attribute "BOM_COST" "MEM"
					( Origin gFrontEnd )
				)
				( attribute "CDS_LIB" "dev_discrete"
					( Origin gPackager )
				)
				( attribute "CDS_LOCATION" "C4A18"
					( Origin gPackager )
				)
				( attribute "LOCATION" "C4A18"
					( Origin gFrontEnd )
				)
				( attribute "MATERIAL" "X7R"
					( Origin gFrontEnd )
				)
				( attribute "PACK_TYPE" "0402V"
					( Origin gFrontEnd )
				)
				( attribute "PART_NUMBER" "A36096-045"
					( Origin gFrontEnd )
				)
				( attribute "PHYS_PAGE" "52"
					( Origin gFrontEnd )
				)
				( attribute "ROOM" "DDR4_CH_E"
					( Origin gFrontEnd )
				)
				( attribute "ROT" "2"
					( Origin gFrontEnd )
				)
				( attribute "SEC" "1"
					( Origin gFrontEnd )
				)
				( attribute "TOLERANCE" "10%"
					( Origin gFrontEnd )
				)
				( attribute "VALUE" "0.01UF"
					( Origin gFrontEnd )
				)
				( attribute "VER" "1"
					( Origin gFrontEnd )
				)
				( attribute "VOLTAGE" "25V"
					( Units "uVoltage" "V" 1.000000)
					( Origin gFrontEnd )
				)
				( attribute "XY" "(-3025,1150)"
					( Origin gFrontEnd )
				)
				( attribute "CHIPS_PART_NAME" "CAP_A"
					( Origin gPackager )
				)
				( attribute "CDS_PART_NAME" "CAP_A_0402V-0.01UF,25V,10%,X7RA"
					( Origin gPackager )
				)
				( attribute "SEC_TYPE" "0402V"
					( Origin gFrontEnd )
				)
				( attribute "CDS_SEC" "1"
					( Origin gPackager )
				)
				( objectStatus "C4A18" )
			)
			( gate "@baseboard_fab2_lib.baseboard_fab2(sch_1):page52_i12"
				( attribute "BOM_COST" "MEM"
					( Origin gFrontEnd )
				)
				( attribute "CDS_LIB" "mstr_sconn"
					( Origin gPackager )
				)
				( attribute "CDS_LOCATION" "J6L2"
					( Origin gPackager )
				)
				( attribute "CDS_SEC" "1"
					( Origin gPackager )
				)
				( attribute "LOCATION" "J6L2"
					( Origin gFrontEnd )
				)
				( attribute "MATERIAL" "SCONN"
					( Origin gFrontEnd )
				)
				( attribute "PACK_TYPE" "PIP"
					( Origin gFrontEnd )
				)
				( attribute "PART_NUMBER" "H44441-003"
					( Origin gFrontEnd )
				)
				( attribute "PHYS_PAGE" "52"
					( Origin gFrontEnd )
				)
				( attribute "ROOM" "DDR4_CH_E"
					( Origin gFrontEnd )
				)
				( attribute "ROT" "0"
					( Origin gFrontEnd )
				)
				( attribute "SEC" "1"
					( Origin gFrontEnd )
				)
				( attribute "SEC_TYPE" "PIP"
					( Origin gFrontEnd )
				)
				( attribute "VER" "1"
					( Origin gFrontEnd )
				)
				( attribute "XY" "(-725,2850)"
					( Origin gFrontEnd )
				)
				( attribute "CHIPS_PART_NAME" "SCONN288_H44441003"
					( Origin gPackager )
				)
				( attribute "CDS_PART_NAME" "SCONN288_H44441003_PIP-SCONN,HA"
					( Origin gPackager )
				)
				( attribute "BOM_SS" "NOPOP"
					( Origin gFrontEnd )
				)
				( objectStatus "J6L2" )
			)
			( gate "@baseboard_fab2_lib.baseboard_fab2(sch_1):page52_i55"
				( attribute "BOM_COST" "MEM"
					( Origin gFrontEnd )
				)
				( attribute "CDS_LIB" "mstr_sconn"
					( Origin gPackager )
				)
				( attribute "CDS_LOCATION" "J6L2"
					( Origin gPackager )
				)
				( attribute "CDS_SEC" "4"
					( Origin gPackager )
				)
				( attribute "LOCATION" "J6L2"
					( Origin gFrontEnd )
				)
				( attribute "MATERIAL" "SCONN"
					( Origin gFrontEnd )
				)
				( attribute "PACK_TYPE" "PIP"
					( Origin gFrontEnd )
				)
				( attribute "PART_NUMBER" "H44441-003"
					( Origin gFrontEnd )
				)
				( attribute "PHYS_PAGE" "52"
					( Origin gFrontEnd )
				)
				( attribute "ROOM" "DDR4_CH_E"
					( Origin gFrontEnd )
				)
				( attribute "ROT" "0"
					( Origin gFrontEnd )
				)
				( attribute "SEC" "4"
					( Origin gFrontEnd )
				)
				( attribute "SEC_TYPE" "PIP"
					( Origin gFrontEnd )
				)
				( attribute "VER" "4"
					( Origin gFrontEnd )
				)
				( attribute "XY" "(1475,1650)"
					( Origin gFrontEnd )
				)
				( attribute "CHIPS_PART_NAME" "SCONN288_H44441003"
					( Origin gPackager )
				)
				( attribute "CDS_PART_NAME" "SCONN288_H44441003_PIP-SCONN,HA"
					( Origin gPackager )
				)
				( attribute "BOM_SS" "NOPOP"
					( Origin gFrontEnd )
				)
				( objectStatus "J6L2" )
			)
			( gate "@baseboard_fab2_lib.baseboard_fab2(sch_1):page52_i100"
				( attribute "BOM_COST" "MEM"
					( Origin gFrontEnd )
				)
				( attribute "CDS_LIB" "mstr_sconn"
					( Origin gPackager )
				)
				( attribute "CDS_LOCATION" "J6L2"
					( Origin gPackager )
				)
				( attribute "CDS_SEC" "2"
					( Origin gPackager )
				)
				( attribute "LOCATION" "J6L2"
					( Origin gFrontEnd )
				)
				( attribute "MATERIAL" "SCONN"
					( Origin gFrontEnd )
				)
				( attribute "PACK_TYPE" "PIP"
					( Origin gFrontEnd )
				)
				( attribute "PART_NUMBER" "H44441-003"
					( Origin gFrontEnd )
				)
				( attribute "PHYS_PAGE" "52"
					( Origin gFrontEnd )
				)
				( attribute "ROOM" "DDR4_CH_E"
					( Origin gFrontEnd )
				)
				( attribute "ROT" "0"
					( Origin gFrontEnd )
				)
				( attribute "SEC" "2"
					( Origin gFrontEnd )
				)
				( attribute "SEC_TYPE" "PIP"
					( Origin gFrontEnd )
				)
				( attribute "VER" "2"
					( Origin gFrontEnd )
				)
				( attribute "XY" "(1625,3900)"
					( Origin gFrontEnd )
				)
				( attribute "CHIPS_PART_NAME" "SCONN288_H44441003"
					( Origin gPackager )
				)
				( attribute "CDS_PART_NAME" "SCONN288_H44441003_PIP-SCONN,HA"
					( Origin gPackager )
				)
				( attribute "BOM_SS" "NOPOP"
					( Origin gFrontEnd )
				)
				( objectStatus "J6L2" )
			)
			( gate "@baseboard_fab2_lib.baseboard_fab2(sch_1):page52_i138"
				( attribute "BOM_COST" "MEM"
					( Origin gFrontEnd )
				)
				( attribute "CDS_LIB" "mstr_sconn"
					( Origin gPackager )
				)
				( attribute "CDS_LOCATION" "J6L2"
					( Origin gPackager )
				)
				( attribute "CDS_SEC" "3"
					( Origin gPackager )
				)
				( attribute "LOCATION" "J6L2"
					( Origin gFrontEnd )
				)
				( attribute "MATERIAL" "SCONN"
					( Origin gFrontEnd )
				)
				( attribute "PACK_TYPE" "PIP"
					( Origin gFrontEnd )
				)
				( attribute "PART_NUMBER" "H44441-003"
					( Origin gFrontEnd )
				)
				( attribute "PHYS_PAGE" "52"
					( Origin gFrontEnd )
				)
				( attribute "ROOM" "DDR4_CH_E"
					( Origin gFrontEnd )
				)
				( attribute "ROT" "0"
					( Origin gFrontEnd )
				)
				( attribute "SEC" "3"
					( Origin gFrontEnd )
				)
				( attribute "SEC_TYPE" "PIP"
					( Origin gFrontEnd )
				)
				( attribute "VER" "3"
					( Origin gFrontEnd )
				)
				( attribute "XY" "(3425,2100)"
					( Origin gFrontEnd )
				)
				( attribute "CHIPS_PART_NAME" "SCONN288_H44441003"
					( Origin gPackager )
				)
				( attribute "CDS_PART_NAME" "SCONN288_H44441003_PIP-SCONN,HA"
					( Origin gPackager )
				)
				( attribute "BOM_SS" "NOPOP"
					( Origin gFrontEnd )
				)
				( objectStatus "J6L2" )
			)
			( gate "@baseboard_fab2_lib.baseboard_fab2(sch_1):page53_i43"
				( attribute "BOM_COST" "MEM"
					( Origin gFrontEnd )
				)
				( attribute "CDS_LIB" "mstr_sconn"
					( Origin gPackager )
				)
				( attribute "CDS_LOCATION" "J4A1"
					( Origin gPackager )
				)
				( attribute "CDS_SEC" "3"
					( Origin gPackager )
				)
				( attribute "LOCATION" "J4A1"
					( Origin gFrontEnd )
				)
				( attribute "MATERIAL" "SCONN"
					( Origin gFrontEnd )
				)
				( attribute "PACK_TYPE" "PIP"
					( Origin gFrontEnd )
				)
				( attribute "PART_NUMBER" "H44441-004"
					( Origin gFrontEnd )
				)
				( attribute "PHYS_PAGE" "53"
					( Origin gFrontEnd )
				)
				( attribute "ROOM" "DDR4_CH_F"
					( Origin gFrontEnd )
				)
				( attribute "ROT" "0"
					( Origin gFrontEnd )
				)
				( attribute "SEC" "3"
					( Origin gFrontEnd )
				)
				( attribute "SEC_TYPE" "PIP"
					( Origin gFrontEnd )
				)
				( attribute "VER" "3"
					( Origin gFrontEnd )
				)
				( attribute "XY" "(1750,2400)"
					( Origin gFrontEnd )
				)
				( attribute "CHIPS_PART_NAME" "SCONN288_H44441004"
					( Origin gPackager )
				)
				( attribute "CDS_PART_NAME" "SCONN288_H44441004_PIP-SCONN,HA"
					( Origin gPackager )
				)
				( objectStatus "J4A1" )
			)
			( gate "@baseboard_fab2_lib.baseboard_fab2(sch_1):page53_i66"
				( attribute "BOM_COST" "MEM"
					( Origin gFrontEnd )
				)
				( attribute "CDS_LIB" "mstr_sconn"
					( Origin gPackager )
				)
				( attribute "CDS_LOCATION" "J4A1"
					( Origin gPackager )
				)
				( attribute "CDS_SEC" "2"
					( Origin gPackager )
				)
				( attribute "LOCATION" "J4A1"
					( Origin gFrontEnd )
				)
				( attribute "MATERIAL" "SCONN"
					( Origin gFrontEnd )
				)
				( attribute "PACK_TYPE" "PIP"
					( Origin gFrontEnd )
				)
				( attribute "PART_NUMBER" "H44441-004"
					( Origin gFrontEnd )
				)
				( attribute "PHYS_PAGE" "53"
					( Origin gFrontEnd )
				)
				( attribute "ROOM" "DDR4_CH_F"
					( Origin gFrontEnd )
				)
				( attribute "ROT" "0"
					( Origin gFrontEnd )
				)
				( attribute "SEC" "2"
					( Origin gFrontEnd )
				)
				( attribute "SEC_TYPE" "PIP"
					( Origin gFrontEnd )
				)
				( attribute "VER" "2"
					( Origin gFrontEnd )
				)
				( attribute "XY" "(-50,4350)"
					( Origin gFrontEnd )
				)
				( attribute "CHIPS_PART_NAME" "SCONN288_H44441004"
					( Origin gPackager )
				)
				( attribute "CDS_PART_NAME" "SCONN288_H44441004_PIP-SCONN,HA"
					( Origin gPackager )
				)
				( objectStatus "J4A1" )
			)
			( gate "@baseboard_fab2_lib.baseboard_fab2(sch_1):page53_i111"
				( attribute "BOM_COST" "MEM"
					( Origin gFrontEnd )
				)
				( attribute "CDS_LIB" "mstr_sconn"
					( Origin gPackager )
				)
				( attribute "CDS_LOCATION" "J4A1"
					( Origin gPackager )
				)
				( attribute "CDS_SEC" "1"
					( Origin gPackager )
				)
				( attribute "LOCATION" "J4A1"
					( Origin gFrontEnd )
				)
				( attribute "MATERIAL" "SCONN"
					( Origin gFrontEnd )
				)
				( attribute "PACK_TYPE" "PIP"
					( Origin gFrontEnd )
				)
				( attribute "PART_NUMBER" "H44441-004"
					( Origin gFrontEnd )
				)
				( attribute "PHYS_PAGE" "53"
					( Origin gFrontEnd )
				)
				( attribute "ROOM" "DDR4_CH_F"
					( Origin gFrontEnd )
				)
				( attribute "ROT" "0"
					( Origin gFrontEnd )
				)
				( attribute "SEC" "1"
					( Origin gFrontEnd )
				)
				( attribute "SEC_TYPE" "PIP"
					( Origin gFrontEnd )
				)
				( attribute "VER" "1"
					( Origin gFrontEnd )
				)
				( attribute "XY" "(-2300,2825)"
					( Origin gFrontEnd )
				)
				( attribute "CHIPS_PART_NAME" "SCONN288_H44441004"
					( Origin gPackager )
				)
				( attribute "CDS_PART_NAME" "SCONN288_H44441004_PIP-SCONN,HA"
					( Origin gPackager )
				)
				( objectStatus "J4A1" )
			)
			( gate "@baseboard_fab2_lib.baseboard_fab2(sch_1):page53_i171"
				( attribute "BOM_COST" "MEM"
					( Origin gFrontEnd )
				)
				( attribute "CDS_LIB" "mstr_sconn"
					( Origin gPackager )
				)
				( attribute "CDS_LOCATION" "J4A1"
					( Origin gPackager )
				)
				( attribute "CDS_SEC" "4"
					( Origin gPackager )
				)
				( attribute "LOCATION" "J4A1"
					( Origin gFrontEnd )
				)
				( attribute "MATERIAL" "SCONN"
					( Origin gFrontEnd )
				)
				( attribute "PACK_TYPE" "PIP"
					( Origin gFrontEnd )
				)
				( attribute "PART_NUMBER" "H44441-004"
					( Origin gFrontEnd )
				)
				( attribute "PHYS_PAGE" "53"
					( Origin gFrontEnd )
				)
				( attribute "ROOM" "DDR4_CH_F"
					( Origin gFrontEnd )
				)
				( attribute "ROT" "0"
					( Origin gFrontEnd )
				)
				( attribute "SEC" "4"
					( Origin gFrontEnd )
				)
				( attribute "SEC_TYPE" "PIP"
					( Origin gFrontEnd )
				)
				( attribute "VER" "4"
					( Origin gFrontEnd )
				)
				( attribute "XY" "(-250,2050)"
					( Origin gFrontEnd )
				)
				( attribute "CHIPS_PART_NAME" "SCONN288_H44441004"
					( Origin gPackager )
				)
				( attribute "CDS_PART_NAME" "SCONN288_H44441004_PIP-SCONN,HA"
					( Origin gPackager )
				)
				( objectStatus "J4A1" )
			)
			( gate "@baseboard_fab2_lib.baseboard_fab2(sch_1):page53_i178"
				( attribute "BOM_COST" "MEM"
					( Origin gFrontEnd )
				)
				( attribute "CDS_LIB" "dev_discrete"
					( Origin gPackager )
				)
				( attribute "CDS_LOCATION" "C6L1"
					( Origin gPackager )
				)
				( attribute "LOCATION" "C6L1"
					( Origin gFrontEnd )
				)
				( attribute "MATERIAL" "X7R"
					( Origin gFrontEnd )
				)
				( attribute "PACK_TYPE" "0402V"
					( Origin gFrontEnd )
				)
				( attribute "PART_NUMBER" "A36096-045"
					( Origin gFrontEnd )
				)
				( attribute "PHYS_PAGE" "53"
					( Origin gFrontEnd )
				)
				( attribute "ROOM" "DDR4_CH_F"
					( Origin gFrontEnd )
				)
				( attribute "ROT" "2"
					( Origin gFrontEnd )
				)
				( attribute "SEC" "1"
					( Origin gFrontEnd )
				)
				( attribute "TOLERANCE" "10%"
					( Origin gFrontEnd )
				)
				( attribute "VALUE" "0.01UF"
					( Origin gFrontEnd )
				)
				( attribute "VER" "1"
					( Origin gFrontEnd )
				)
				( attribute "VOLTAGE" "25V"
					( Units "uVoltage" "V" 1.000000)
					( Origin gFrontEnd )
				)
				( attribute "XY" "(-4500,1125)"
					( Origin gFrontEnd )
				)
				( attribute "CHIPS_PART_NAME" "CAP_A"
					( Origin gPackager )
				)
				( attribute "CDS_PART_NAME" "CAP_A_0402V-0.01UF,25V,10%,X7RA"
					( Origin gPackager )
				)
				( attribute "SEC_TYPE" "0402V"
					( Origin gFrontEnd )
				)
				( attribute "CDS_SEC" "1"
					( Origin gPackager )
				)
				( objectStatus "C6L1" )
			)
			( gate "@baseboard_fab2_lib.baseboard_fab2(sch_1):page54_i43"
				( attribute "BOM_COST" "MEM"
					( Origin gFrontEnd )
				)
				( attribute "CDS_LIB" "mstr_sconn"
					( Origin gPackager )
				)
				( attribute "CDS_LOCATION" "J6L1"
					( Origin gPackager )
				)
				( attribute "CDS_SEC" "3"
					( Origin gPackager )
				)
				( attribute "LOCATION" "J6L1"
					( Origin gFrontEnd )
				)
				( attribute "MATERIAL" "SCONN"
					( Origin gFrontEnd )
				)
				( attribute "PACK_TYPE" "PIP"
					( Origin gFrontEnd )
				)
				( attribute "PART_NUMBER" "H44441-003"
					( Origin gFrontEnd )
				)
				( attribute "PHYS_PAGE" "54"
					( Origin gFrontEnd )
				)
				( attribute "ROOM" "DDR4_CH_F1"
					( Origin gFrontEnd )
				)
				( attribute "ROT" "0"
					( Origin gFrontEnd )
				)
				( attribute "SEC" "3"
					( Origin gFrontEnd )
				)
				( attribute "SEC_TYPE" "PIP"
					( Origin gFrontEnd )
				)
				( attribute "VER" "3"
					( Origin gFrontEnd )
				)
				( attribute "XY" "(1800,2550)"
					( Origin gFrontEnd )
				)
				( attribute "CHIPS_PART_NAME" "SCONN288_H44441003"
					( Origin gPackager )
				)
				( attribute "CDS_PART_NAME" "SCONN288_H44441003_PIP-SCONN,HA"
					( Origin gPackager )
				)
				( attribute "BOM_SS" "NOPOP"
					( Origin gFrontEnd )
				)
				( objectStatus "J6L1" )
			)
			( gate "@baseboard_fab2_lib.baseboard_fab2(sch_1):page54_i66"
				( attribute "BOM_COST" "MEM"
					( Origin gFrontEnd )
				)
				( attribute "CDS_LIB" "mstr_sconn"
					( Origin gPackager )
				)
				( attribute "CDS_LOCATION" "J6L1"
					( Origin gPackager )
				)
				( attribute "CDS_SEC" "2"
					( Origin gPackager )
				)
				( attribute "LOCATION" "J6L1"
					( Origin gFrontEnd )
				)
				( attribute "MATERIAL" "SCONN"
					( Origin gFrontEnd )
				)
				( attribute "PACK_TYPE" "PIP"
					( Origin gFrontEnd )
				)
				( attribute "PART_NUMBER" "H44441-003"
					( Origin gFrontEnd )
				)
				( attribute "PHYS_PAGE" "54"
					( Origin gFrontEnd )
				)
				( attribute "ROOM" "DDR4_CH_F1"
					( Origin gFrontEnd )
				)
				( attribute "ROT" "0"
					( Origin gFrontEnd )
				)
				( attribute "SEC" "2"
					( Origin gFrontEnd )
				)
				( attribute "SEC_TYPE" "PIP"
					( Origin gFrontEnd )
				)
				( attribute "VER" "2"
					( Origin gFrontEnd )
				)
				( attribute "XY" "(0,4300)"
					( Origin gFrontEnd )
				)
				( attribute "CHIPS_PART_NAME" "SCONN288_H44441003"
					( Origin gPackager )
				)
				( attribute "CDS_PART_NAME" "SCONN288_H44441003_PIP-SCONN,HA"
					( Origin gPackager )
				)
				( attribute "BOM_SS" "NOPOP"
					( Origin gFrontEnd )
				)
				( objectStatus "J6L1" )
			)
			( gate "@baseboard_fab2_lib.baseboard_fab2(sch_1):page54_i111"
				( attribute "BOM_COST" "MEM"
					( Origin gFrontEnd )
				)
				( attribute "CDS_LIB" "mstr_sconn"
					( Origin gPackager )
				)
				( attribute "CDS_LOCATION" "J6L1"
					( Origin gPackager )
				)
				( attribute "CDS_SEC" "1"
					( Origin gPackager )
				)
				( attribute "LOCATION" "J6L1"
					( Origin gFrontEnd )
				)
				( attribute "MATERIAL" "SCONN"
					( Origin gFrontEnd )
				)
				( attribute "PACK_TYPE" "PIP"
					( Origin gFrontEnd )
				)
				( attribute "PART_NUMBER" "H44441-003"
					( Origin gFrontEnd )
				)
				( attribute "PHYS_PAGE" "54"
					( Origin gFrontEnd )
				)
				( attribute "ROOM" "DDR4_CH_F1"
					( Origin gFrontEnd )
				)
				( attribute "ROT" "0"
					( Origin gFrontEnd )
				)
				( attribute "SEC" "1"
					( Origin gFrontEnd )
				)
				( attribute "SEC_TYPE" "PIP"
					( Origin gFrontEnd )
				)
				( attribute "VER" "1"
					( Origin gFrontEnd )
				)
				( attribute "XY" "(-2400,3100)"
					( Origin gFrontEnd )
				)
				( attribute "CHIPS_PART_NAME" "SCONN288_H44441003"
					( Origin gPackager )
				)
				( attribute "CDS_PART_NAME" "SCONN288_H44441003_PIP-SCONN,HA"
					( Origin gPackager )
				)
				( attribute "BOM_SS" "NOPOP"
					( Origin gFrontEnd )
				)
				( objectStatus "J6L1" )
			)
			( gate "@baseboard_fab2_lib.baseboard_fab2(sch_1):page54_i170"
				( attribute "BOM_COST" "MEM"
					( Origin gFrontEnd )
				)
				( attribute "CDS_LIB" "mstr_sconn"
					( Origin gPackager )
				)
				( attribute "CDS_LOCATION" "J6L1"
					( Origin gPackager )
				)
				( attribute "CDS_SEC" "4"
					( Origin gPackager )
				)
				( attribute "LOCATION" "J6L1"
					( Origin gFrontEnd )
				)
				( attribute "MATERIAL" "SCONN"
					( Origin gFrontEnd )
				)
				( attribute "PACK_TYPE" "PIP"
					( Origin gFrontEnd )
				)
				( attribute "PART_NUMBER" "H44441-003"
					( Origin gFrontEnd )
				)
				( attribute "PHYS_PAGE" "54"
					( Origin gFrontEnd )
				)
				( attribute "ROOM" "DDR4_CH_F1"
					( Origin gFrontEnd )
				)
				( attribute "ROT" "0"
					( Origin gFrontEnd )
				)
				( attribute "SEC" "4"
					( Origin gFrontEnd )
				)
				( attribute "SEC_TYPE" "PIP"
					( Origin gFrontEnd )
				)
				( attribute "VER" "4"
					( Origin gFrontEnd )
				)
				( attribute "XY" "(-50,1900)"
					( Origin gFrontEnd )
				)
				( attribute "CHIPS_PART_NAME" "SCONN288_H44441003"
					( Origin gPackager )
				)
				( attribute "CDS_PART_NAME" "SCONN288_H44441003_PIP-SCONN,HA"
					( Origin gPackager )
				)
				( attribute "BOM_SS" "NOPOP"
					( Origin gFrontEnd )
				)
				( objectStatus "J6L1" )
			)
			( gate "@baseboard_fab2_lib.baseboard_fab2(sch_1):page54_i179"
				( attribute "BOM_COST" "MEM"
					( Origin gFrontEnd )
				)
				( attribute "CDS_LIB" "dev_discrete"
					( Origin gPackager )
				)
				( attribute "CDS_LOCATION" "C4A5"
					( Origin gPackager )
				)
				( attribute "LOCATION" "C4A5"
					( Origin gFrontEnd )
				)
				( attribute "MATERIAL" "X7R"
					( Origin gFrontEnd )
				)
				( attribute "PACK_TYPE" "0402V"
					( Origin gFrontEnd )
				)
				( attribute "PART_NUMBER" "A36096-045"
					( Origin gFrontEnd )
				)
				( attribute "PHYS_PAGE" "54"
					( Origin gFrontEnd )
				)
				( attribute "ROOM" "DDR4_CH_F1"
					( Origin gFrontEnd )
				)
				( attribute "ROT" "2"
					( Origin gFrontEnd )
				)
				( attribute "SEC" "1"
					( Origin gFrontEnd )
				)
				( attribute "TOLERANCE" "10%"
					( Origin gFrontEnd )
				)
				( attribute "VALUE" "0.01UF"
					( Origin gFrontEnd )
				)
				( attribute "VER" "1"
					( Origin gFrontEnd )
				)
				( attribute "VOLTAGE" "25V"
					( Units "uVoltage" "V" 1.000000)
					( Origin gFrontEnd )
				)
				( attribute "XY" "(-4600,1400)"
					( Origin gFrontEnd )
				)
				( attribute "CHIPS_PART_NAME" "CAP_A"
					( Origin gPackager )
				)
				( attribute "CDS_PART_NAME" "CAP_A_0402V-0.01UF,25V,10%,X7RA"
					( Origin gPackager )
				)
				( attribute "SEC_TYPE" "0402V"
					( Origin gFrontEnd )
				)
				( attribute "CDS_SEC" "1"
					( Origin gPackager )
				)
				( objectStatus "C4A5" )
			)
			( gate "@baseboard_fab2_lib.baseboard_fab2(sch_1):page55_i4"
				( attribute "BOM_COST" "PROC_SOCKET"
					( Origin gFrontEnd )
				)
				( attribute "CDS_LIB" "mstr_discrete"
					( Origin gPackager )
				)
				( attribute "CDS_LOCATION" "R9N1"
					( Origin gPackager )
				)
				( attribute "CDS_SEC" "1"
					( Origin gPackager )
				)
				( attribute "LOCATION" "R9N1"
					( Origin gFrontEnd )
				)
				( attribute "MATERIAL" "CHIP"
					( Origin gFrontEnd )
				)
				( attribute "PACK_TYPE" "0402"
					( Origin gFrontEnd )
				)
				( attribute "PART_NUMBER" "G21796-047"
					( Origin gFrontEnd )
				)
				( attribute "PHYS_PAGE" "55"
					( Origin gFrontEnd )
				)
				( attribute "ROOM" "CPU1"
					( Origin gFrontEnd )
				)
				( attribute "ROT" "0"
					( Origin gFrontEnd )
				)
				( attribute "SEC" "1"
					( Origin gFrontEnd )
				)
				( attribute "SEC_TYPE" "0402"
					( Origin gFrontEnd )
				)
				( attribute "TOLERANCE" "1%"
					( Origin gFrontEnd )
				)
				( attribute "VALUE" "49.9"
					( Origin gFrontEnd )
				)
				( attribute "VER" "2"
					( Origin gFrontEnd )
				)
				( attribute "WATTAGE" "1/16W"
					( Origin gFrontEnd )
				)
				( attribute "XY" "(13600,3925)"
					( Origin gFrontEnd )
				)
				( attribute "CHIPS_PART_NAME" "RES"
					( Origin gPackager )
				)
				( attribute "CDS_PART_NAME" "RES_0402-49.9,1%,1/16W,CHIP,G2A"
					( Origin gPackager )
				)
				( objectStatus "R9N1" )
			)
			( gate "@baseboard_fab2_lib.baseboard_fab2(sch_1):page55_i7"
				( attribute "BOM_COST" "PROC_SOCKET"
					( Origin gFrontEnd )
				)
				( attribute "CDS_LIB" "mstr_discrete"
					( Origin gPackager )
				)
				( attribute "CDS_LOCATION" "R9N2"
					( Origin gPackager )
				)
				( attribute "CDS_SEC" "1"
					( Origin gPackager )
				)
				( attribute "LOCATION" "R9N2"
					( Origin gFrontEnd )
				)
				( attribute "MATERIAL" "CHIP"
					( Origin gFrontEnd )
				)
				( attribute "PACK_TYPE" "0402"
					( Origin gFrontEnd )
				)
				( attribute "PART_NUMBER" "G21796-017"
					( Origin gFrontEnd )
				)
				( attribute "PHYS_PAGE" "55"
					( Origin gFrontEnd )
				)
				( attribute "ROOM" "CPU1"
					( Origin gFrontEnd )
				)
				( attribute "ROT" "0"
					( Origin gFrontEnd )
				)
				( attribute "SEC" "1"
					( Origin gFrontEnd )
				)
				( attribute "SEC_TYPE" "0402"
					( Origin gFrontEnd )
				)
				( attribute "TOLERANCE" "1%"
					( Origin gFrontEnd )
				)
				( attribute "VALUE" "100.0"
					( Origin gFrontEnd )
				)
				( attribute "VER" "2"
					( Origin gFrontEnd )
				)
				( attribute "WATTAGE" "1/16W"
					( Origin gFrontEnd )
				)
				( attribute "XY" "(13325,3925)"
					( Origin gFrontEnd )
				)
				( attribute "CHIPS_PART_NAME" "RES"
					( Origin gPackager )
				)
				( attribute "CDS_PART_NAME" "RES_0402-100.0,1%,1/16W,CHIP,GA"
					( Origin gPackager )
				)
				( objectStatus "R9N2" )
			)
			( gate "@baseboard_fab2_lib.baseboard_fab2(sch_1):page55_i19"
				( attribute "BOM_COST" "PROC_SOCKET"
					( Origin gFrontEnd )
				)
				( attribute "CDS_LIB" "mstr_discrete"
					( Origin gPackager )
				)
				( attribute "CDS_LOCATION" "R3B2"
					( Origin gPackager )
				)
				( attribute "CDS_SEC" "1"
					( Origin gPackager )
				)
				( attribute "LOCATION" "R3B2"
					( Origin gFrontEnd )
				)
				( attribute "MATERIAL" "CHIP"
					( Origin gFrontEnd )
				)
				( attribute "PACK_TYPE" "0402"
					( Origin gFrontEnd )
				)
				( attribute "PART_NUMBER" "G21796-047"
					( Origin gFrontEnd )
				)
				( attribute "PHYS_PAGE" "55"
					( Origin gFrontEnd )
				)
				( attribute "ROOM" "CPU1"
					( Origin gFrontEnd )
				)
				( attribute "ROT" "0"
					( Origin gFrontEnd )
				)
				( attribute "SEC" "1"
					( Origin gFrontEnd )
				)
				( attribute "SEC_TYPE" "0402"
					( Origin gFrontEnd )
				)
				( attribute "TOLERANCE" "1%"
					( Origin gFrontEnd )
				)
				( attribute "VALUE" "49.9"
					( Origin gFrontEnd )
				)
				( attribute "VER" "2"
					( Origin gFrontEnd )
				)
				( attribute "WATTAGE" "1/16W"
					( Origin gFrontEnd )
				)
				( attribute "XY" "(13600,3200)"
					( Origin gFrontEnd )
				)
				( attribute "CHIPS_PART_NAME" "RES"
					( Origin gPackager )
				)
				( attribute "CDS_PART_NAME" "RES_0402-49.9,1%,1/16W,CHIP,G2A"
					( Origin gPackager )
				)
				( objectStatus "R3B2" )
			)
			( gate "@baseboard_fab2_lib.baseboard_fab2(sch_1):page55_i21"
				( attribute "BOM_COST" "PROC_SOCKET"
					( Origin gFrontEnd )
				)
				( attribute "CDS_LIB" "mstr_discrete"
					( Origin gPackager )
				)
				( attribute "CDS_LOCATION" "R3B4"
					( Origin gPackager )
				)
				( attribute "CDS_SEC" "1"
					( Origin gPackager )
				)
				( attribute "LOCATION" "R3B4"
					( Origin gFrontEnd )
				)
				( attribute "MATERIAL" "CHIP"
					( Origin gFrontEnd )
				)
				( attribute "PACK_TYPE" "0402"
					( Origin gFrontEnd )
				)
				( attribute "PART_NUMBER" "G21796-017"
					( Origin gFrontEnd )
				)
				( attribute "PHYS_PAGE" "55"
					( Origin gFrontEnd )
				)
				( attribute "ROOM" "CPU1"
					( Origin gFrontEnd )
				)
				( attribute "ROT" "0"
					( Origin gFrontEnd )
				)
				( attribute "SEC" "1"
					( Origin gFrontEnd )
				)
				( attribute "SEC_TYPE" "0402"
					( Origin gFrontEnd )
				)
				( attribute "TOLERANCE" "1%"
					( Origin gFrontEnd )
				)
				( attribute "VALUE" "100.0"
					( Origin gFrontEnd )
				)
				( attribute "VER" "2"
					( Origin gFrontEnd )
				)
				( attribute "WATTAGE" "1/16W"
					( Origin gFrontEnd )
				)
				( attribute "XY" "(13325,3200)"
					( Origin gFrontEnd )
				)
				( attribute "CHIPS_PART_NAME" "RES"
					( Origin gPackager )
				)
				( attribute "CDS_PART_NAME" "RES_0402-100.0,1%,1/16W,CHIP,GA"
					( Origin gPackager )
				)
				( objectStatus "R3B4" )
			)
			( gate "@baseboard_fab2_lib.baseboard_fab2(sch_1):page55_i24"
				( attribute "BOM_COST" "PROC_SOCKET"
					( Origin gFrontEnd )
				)
				( attribute "CDS_LIB" "mstr_discrete"
					( Origin gPackager )
				)
				( attribute "CDS_LOCATION" "R1C2"
					( Origin gPackager )
				)
				( attribute "CDS_SEC" "1"
					( Origin gPackager )
				)
				( attribute "LOCATION" "R1C2"
					( Origin gFrontEnd )
				)
				( attribute "MATERIAL" "CHIP"
					( Origin gFrontEnd )
				)
				( attribute "PACK_TYPE" "0402"
					( Origin gFrontEnd )
				)
				( attribute "PART_NUMBER" "G21497-005"
					( Origin gFrontEnd )
				)
				( attribute "PHYS_PAGE" "55"
					( Origin gFrontEnd )
				)
				( attribute "ROOM" "CPU1"
					( Origin gFrontEnd )
				)
				( attribute "ROT" "0"
					( Origin gFrontEnd )
				)
				( attribute "SEC" "1"
					( Origin gPackager )
				)
				( attribute "TOLERANCE" "5%"
					( Origin gFrontEnd )
				)
				( attribute "VALUE" "0.0"
					( Origin gFrontEnd )
				)
				( attribute "VER" "1"
					( Origin gFrontEnd )
				)
				( attribute "WATTAGE" "1/16W"
					( Origin gFrontEnd )
				)
				( attribute "XY" "(12250,3650)"
					( Origin gFrontEnd )
				)
				( attribute "CHIPS_PART_NAME" "RES"
					( Origin gPackager )
				)
				( attribute "CDS_PART_NAME" "RES_0402-0.0,5%,1/16W,CHIP,G21A"
					( Origin gPackager )
				)
				( objectStatus "R1C2" )
			)
			( gate "@baseboard_fab2_lib.baseboard_fab2(sch_1):page55_i25"
				( attribute "BOM_COST" "PROC_SOCKET"
					( Origin gFrontEnd )
				)
				( attribute "CDS_LIB" "mstr_discrete"
					( Origin gPackager )
				)
				( attribute "CDS_LOCATION" "R1C3"
					( Origin gPackager )
				)
				( attribute "CDS_SEC" "1"
					( Origin gPackager )
				)
				( attribute "LOCATION" "R1C3"
					( Origin gFrontEnd )
				)
				( attribute "MATERIAL" "CHIP"
					( Origin gFrontEnd )
				)
				( attribute "PACK_TYPE" "0402"
					( Origin gFrontEnd )
				)
				( attribute "PART_NUMBER" "G21497-005"
					( Origin gFrontEnd )
				)
				( attribute "PHYS_PAGE" "55"
					( Origin gFrontEnd )
				)
				( attribute "ROOM" "CPU1"
					( Origin gFrontEnd )
				)
				( attribute "ROT" "0"
					( Origin gFrontEnd )
				)
				( attribute "SEC" "1"
					( Origin gPackager )
				)
				( attribute "TOLERANCE" "5%"
					( Origin gFrontEnd )
				)
				( attribute "VALUE" "0.0"
					( Origin gFrontEnd )
				)
				( attribute "VER" "1"
					( Origin gFrontEnd )
				)
				( attribute "WATTAGE" "1/16W"
					( Origin gFrontEnd )
				)
				( attribute "XY" "(12250,3600)"
					( Origin gFrontEnd )
				)
				( attribute "CHIPS_PART_NAME" "RES"
					( Origin gPackager )
				)
				( attribute "CDS_PART_NAME" "RES_0402-0.0,5%,1/16W,CHIP,G21A"
					( Origin gPackager )
				)
				( objectStatus "R1C3" )
			)
			( gate "@baseboard_fab2_lib.baseboard_fab2(sch_1):page55_i26"
				( attribute "BOM_COST" "PROC_SOCKET"
					( Origin gFrontEnd )
				)
				( attribute "CDS_LIB" "mstr_discrete"
					( Origin gPackager )
				)
				( attribute "CDS_LOCATION" "R1C1"
					( Origin gPackager )
				)
				( attribute "CDS_SEC" "1"
					( Origin gPackager )
				)
				( attribute "LOCATION" "R1C1"
					( Origin gFrontEnd )
				)
				( attribute "MATERIAL" "CHIP"
					( Origin gFrontEnd )
				)
				( attribute "PACK_TYPE" "0402"
					( Origin gFrontEnd )
				)
				( attribute "PART_NUMBER" "G21796-271"
					( Origin gFrontEnd )
				)
				( attribute "PHYS_PAGE" "55"
					( Origin gFrontEnd )
				)
				( attribute "ROOM" "CPU1"
					( Origin gFrontEnd )
				)
				( attribute "ROT" "0"
					( Origin gFrontEnd )
				)
				( attribute "SEC" "1"
					( Origin gPackager )
				)
				( attribute "TOLERANCE" "1.0%"
					( Origin gFrontEnd )
				)
				( attribute "VALUE" "221"
					( Origin gFrontEnd )
				)
				( attribute "VER" "1"
					( Origin gFrontEnd )
				)
				( attribute "WATTAGE" "1/16W"
					( Origin gFrontEnd )
				)
				( attribute "XY" "(12250,3550)"
					( Origin gFrontEnd )
				)
				( attribute "CHIPS_PART_NAME" "RES"
					( Origin gPackager )
				)
				( attribute "CDS_PART_NAME" "RES_0402-221,1.0%,1/16W,CHIP,GA"
					( Origin gPackager )
				)
				( objectStatus "R1C1" )
			)
			( gate "@baseboard_fab2_lib.baseboard_fab2(sch_1):page55_i27"
				( attribute "BOM_COST" "PROC_SOCKET"
					( Origin gFrontEnd )
				)
				( attribute "CDS_LIB" "mstr_discrete"
					( Origin gPackager )
				)
				( attribute "CDS_LOCATION" "R3B1"
					( Origin gPackager )
				)
				( attribute "CDS_SEC" "1"
					( Origin gPackager )
				)
				( attribute "LOCATION" "R3B1"
					( Origin gFrontEnd )
				)
				( attribute "MATERIAL" "CHIP"
					( Origin gFrontEnd )
				)
				( attribute "PACK_TYPE" "0402"
					( Origin gFrontEnd )
				)
				( attribute "PART_NUMBER" "G21796-271"
					( Origin gFrontEnd )
				)
				( attribute "PHYS_PAGE" "55"
					( Origin gFrontEnd )
				)
				( attribute "ROOM" "CPU1"
					( Origin gFrontEnd )
				)
				( attribute "ROT" "0"
					( Origin gFrontEnd )
				)
				( attribute "SEC" "1"
					( Origin gPackager )
				)
				( attribute "TOLERANCE" "1.0%"
					( Origin gFrontEnd )
				)
				( attribute "VALUE" "221"
					( Origin gFrontEnd )
				)
				( attribute "VER" "1"
					( Origin gFrontEnd )
				)
				( attribute "WATTAGE" "1/16W"
					( Origin gFrontEnd )
				)
				( attribute "XY" "(12250,3400)"
					( Origin gFrontEnd )
				)
				( attribute "CHIPS_PART_NAME" "RES"
					( Origin gPackager )
				)
				( attribute "CDS_PART_NAME" "RES_0402-221,1.0%,1/16W,CHIP,GA"
					( Origin gPackager )
				)
				( objectStatus "R3B1" )
			)
			( gate "@baseboard_fab2_lib.baseboard_fab2(sch_1):page55_i28"
				( attribute "BOM_COST" "PROC_SOCKET"
					( Origin gFrontEnd )
				)
				( attribute "CDS_LIB" "mstr_discrete"
					( Origin gPackager )
				)
				( attribute "CDS_LOCATION" "R3B5"
					( Origin gPackager )
				)
				( attribute "CDS_SEC" "1"
					( Origin gPackager )
				)
				( attribute "LOCATION" "R3B5"
					( Origin gFrontEnd )
				)
				( attribute "MATERIAL" "CHIP"
					( Origin gFrontEnd )
				)
				( attribute "PACK_TYPE" "0402"
					( Origin gFrontEnd )
				)
				( attribute "PART_NUMBER" "G21497-005"
					( Origin gFrontEnd )
				)
				( attribute "PHYS_PAGE" "55"
					( Origin gFrontEnd )
				)
				( attribute "ROOM" "CPU1"
					( Origin gFrontEnd )
				)
				( attribute "ROT" "0"
					( Origin gFrontEnd )
				)
				( attribute "SEC" "1"
					( Origin gPackager )
				)
				( attribute "TOLERANCE" "5%"
					( Origin gFrontEnd )
				)
				( attribute "VALUE" "0.0"
					( Origin gFrontEnd )
				)
				( attribute "VER" "1"
					( Origin gFrontEnd )
				)
				( attribute "WATTAGE" "1/16W"
					( Origin gFrontEnd )
				)
				( attribute "XY" "(12250,3450)"
					( Origin gFrontEnd )
				)
				( attribute "CHIPS_PART_NAME" "RES"
					( Origin gPackager )
				)
				( attribute "CDS_PART_NAME" "RES_0402-0.0,5%,1/16W,CHIP,G21A"
					( Origin gPackager )
				)
				( objectStatus "R3B5" )
			)
			( gate "@baseboard_fab2_lib.baseboard_fab2(sch_1):page55_i29"
				( attribute "BOM_COST" "PROC_SOCKET"
					( Origin gFrontEnd )
				)
				( attribute "CDS_LIB" "mstr_discrete"
					( Origin gPackager )
				)
				( attribute "CDS_LOCATION" "R3B3"
					( Origin gPackager )
				)
				( attribute "CDS_SEC" "1"
					( Origin gPackager )
				)
				( attribute "LOCATION" "R3B3"
					( Origin gFrontEnd )
				)
				( attribute "MATERIAL" "CHIP"
					( Origin gFrontEnd )
				)
				( attribute "PACK_TYPE" "0402"
					( Origin gFrontEnd )
				)
				( attribute "PART_NUMBER" "G21497-005"
					( Origin gFrontEnd )
				)
				( attribute "PHYS_PAGE" "55"
					( Origin gFrontEnd )
				)
				( attribute "ROOM" "CPU1"
					( Origin gFrontEnd )
				)
				( attribute "ROT" "0"
					( Origin gFrontEnd )
				)
				( attribute "SEC" "1"
					( Origin gPackager )
				)
				( attribute "TOLERANCE" "5%"
					( Origin gFrontEnd )
				)
				( attribute "VALUE" "0.0"
					( Origin gFrontEnd )
				)
				( attribute "VER" "1"
					( Origin gFrontEnd )
				)
				( attribute "WATTAGE" "1/16W"
					( Origin gFrontEnd )
				)
				( attribute "XY" "(12250,3500)"
					( Origin gFrontEnd )
				)
				( attribute "CHIPS_PART_NAME" "RES"
					( Origin gPackager )
				)
				( attribute "CDS_PART_NAME" "RES_0402-0.0,5%,1/16W,CHIP,G21A"
					( Origin gPackager )
				)
				( objectStatus "R3B3" )
			)
			( gate "@baseboard_fab2_lib.baseboard_fab2(sch_1):page55_i115"
				( attribute "BOM_COST" "PROC_SOCKET"
					( Origin gFrontEnd )
				)
				( attribute "CDS_LIB" "mstr_discrete"
					( Origin gPackager )
				)
				( attribute "CDS_LOCATION" "R7P19"
					( Origin gPackager )
				)
				( attribute "CDS_SEC" "1"
					( Origin gPackager )
				)
				( attribute "LOCATION" "R7P19"
					( Origin gFrontEnd )
				)
				( attribute "MATERIAL" "CHIP"
					( Origin gFrontEnd )
				)
				( attribute "PACK_TYPE" "0402"
					( Origin gFrontEnd )
				)
				( attribute "PART_NUMBER" "G21796-017"
					( Origin gFrontEnd )
				)
				( attribute "PHYS_PAGE" "55"
					( Origin gFrontEnd )
				)
				( attribute "ROOM" "CPU1"
					( Origin gFrontEnd )
				)
				( attribute "ROT" "2"
					( Origin gFrontEnd )
				)
				( attribute "SEC" "1"
					( Origin gFrontEnd )
				)
				( attribute "SEC_TYPE" "0402"
					( Origin gFrontEnd )
				)
				( attribute "TOLERANCE" "1%"
					( Origin gFrontEnd )
				)
				( attribute "VALUE" "100.0"
					( Origin gFrontEnd )
				)
				( attribute "VER" "2"
					( Origin gFrontEnd )
				)
				( attribute "WATTAGE" "1/16W"
					( Origin gFrontEnd )
				)
				( attribute "XY" "(6575,2725)"
					( Origin gFrontEnd )
				)
				( attribute "CHIPS_PART_NAME" "RES"
					( Origin gPackager )
				)
				( attribute "CDS_PART_NAME" "RES_0402-100.0,1%,1/16W,CHIP,GA"
					( Origin gPackager )
				)
				( objectStatus "R7P19" )
			)
			( gate "@baseboard_fab2_lib.baseboard_fab2(sch_1):page55_i116"
				( attribute "BOM_COST" "PROC_SOCKET"
					( Origin gFrontEnd )
				)
				( attribute "CDS_LIB" "mstr_discrete"
					( Origin gPackager )
				)
				( attribute "CDS_LOCATION" "R3D1"
					( Origin gPackager )
				)
				( attribute "CDS_SEC" "1"
					( Origin gPackager )
				)
				( attribute "LOCATION" "R3D1"
					( Origin gFrontEnd )
				)
				( attribute "MATERIAL" "CHIP"
					( Origin gFrontEnd )
				)
				( attribute "PACK_TYPE" "0402"
					( Origin gFrontEnd )
				)
				( attribute "PART_NUMBER" "G21796-365"
					( Origin gFrontEnd )
				)
				( attribute "PHYS_PAGE" "55"
					( Origin gFrontEnd )
				)
				( attribute "ROOM" "CPU1"
					( Origin gFrontEnd )
				)
				( attribute "ROT" "2"
					( Origin gFrontEnd )
				)
				( attribute "SEC" "1"
					( Origin gFrontEnd )
				)
				( attribute "SEC_TYPE" "0402"
					( Origin gFrontEnd )
				)
				( attribute "TOLERANCE" "1%"
					( Origin gFrontEnd )
				)
				( attribute "VALUE" "90.9"
					( Origin gFrontEnd )
				)
				( attribute "VER" "2"
					( Origin gFrontEnd )
				)
				( attribute "WATTAGE" "1/16W"
					( Origin gFrontEnd )
				)
				( attribute "XY" "(7700,2525)"
					( Origin gFrontEnd )
				)
				( attribute "CHIPS_PART_NAME" "RES"
					( Origin gPackager )
				)
				( attribute "CDS_PART_NAME" "RES_0402-90.9,1%,1/16W,CHIP,G2A"
					( Origin gPackager )
				)
				( objectStatus "R3D1" )
			)
			( gate "@baseboard_fab2_lib.baseboard_fab2(sch_1):page55_i117"
				( attribute "BOM_COST" "PROC_SOCKET"
					( Origin gFrontEnd )
				)
				( attribute "CDS_LIB" "mstr_discrete"
					( Origin gPackager )
				)
				( attribute "CDS_LOCATION" "R3D2"
					( Origin gPackager )
				)
				( attribute "CDS_SEC" "1"
					( Origin gPackager )
				)
				( attribute "LOCATION" "R3D2"
					( Origin gFrontEnd )
				)
				( attribute "MATERIAL" "CHIP"
					( Origin gFrontEnd )
				)
				( attribute "PACK_TYPE" "0402"
					( Origin gFrontEnd )
				)
				( attribute "PART_NUMBER" "G21796-365"
					( Origin gFrontEnd )
				)
				( attribute "PHYS_PAGE" "55"
					( Origin gFrontEnd )
				)
				( attribute "ROOM" "CPU1"
					( Origin gFrontEnd )
				)
				( attribute "ROT" "2"
					( Origin gFrontEnd )
				)
				( attribute "SEC" "1"
					( Origin gFrontEnd )
				)
				( attribute "SEC_TYPE" "0402"
					( Origin gFrontEnd )
				)
				( attribute "TOLERANCE" "1%"
					( Origin gFrontEnd )
				)
				( attribute "VALUE" "90.9"
					( Origin gFrontEnd )
				)
				( attribute "VER" "2"
					( Origin gFrontEnd )
				)
				( attribute "WATTAGE" "1/16W"
					( Origin gFrontEnd )
				)
				( attribute "XY" "(7475,2525)"
					( Origin gFrontEnd )
				)
				( attribute "CHIPS_PART_NAME" "RES"
					( Origin gPackager )
				)
				( attribute "CDS_PART_NAME" "RES_0402-90.9,1%,1/16W,CHIP,G2A"
					( Origin gPackager )
				)
				( objectStatus "R3D2" )
			)
			( gate "@baseboard_fab2_lib.baseboard_fab2(sch_1):page55_i118"
				( attribute "BOM_COST" "PROC_SOCKET"
					( Origin gFrontEnd )
				)
				( attribute "CDS_LIB" "mstr_discrete"
					( Origin gPackager )
				)
				( attribute "CDS_LOCATION" "R3D3"
					( Origin gPackager )
				)
				( attribute "CDS_SEC" "1"
					( Origin gPackager )
				)
				( attribute "LOCATION" "R3D3"
					( Origin gFrontEnd )
				)
				( attribute "MATERIAL" "CHIP"
					( Origin gFrontEnd )
				)
				( attribute "PACK_TYPE" "0402"
					( Origin gFrontEnd )
				)
				( attribute "PART_NUMBER" "G21796-017"
					( Origin gFrontEnd )
				)
				( attribute "PHYS_PAGE" "55"
					( Origin gFrontEnd )
				)
				( attribute "ROOM" "CPU1"
					( Origin gFrontEnd )
				)
				( attribute "ROT" "2"
					( Origin gFrontEnd )
				)
				( attribute "SEC" "1"
					( Origin gFrontEnd )
				)
				( attribute "SEC_TYPE" "0402"
					( Origin gFrontEnd )
				)
				( attribute "TOLERANCE" "1%"
					( Origin gFrontEnd )
				)
				( attribute "VALUE" "100.0"
					( Origin gFrontEnd )
				)
				( attribute "VER" "2"
					( Origin gFrontEnd )
				)
				( attribute "WATTAGE" "1/16W"
					( Origin gFrontEnd )
				)
				( attribute "XY" "(7250,2525)"
					( Origin gFrontEnd )
				)
				( attribute "CHIPS_PART_NAME" "RES"
					( Origin gPackager )
				)
				( attribute "CDS_PART_NAME" "RES_0402-100.0,1%,1/16W,CHIP,GA"
					( Origin gPackager )
				)
				( objectStatus "R3D3" )
			)
			( gate "@baseboard_fab2_lib.baseboard_fab2(sch_1):page55_i119"
				( attribute "BOM_COST" "PROC_SOCKET"
					( Origin gFrontEnd )
				)
				( attribute "CDS_LIB" "mstr_discrete"
					( Origin gPackager )
				)
				( attribute "CDS_LOCATION" "R7P16"
					( Origin gPackager )
				)
				( attribute "CDS_SEC" "1"
					( Origin gPackager )
				)
				( attribute "LOCATION" "R7P16"
					( Origin gFrontEnd )
				)
				( attribute "MATERIAL" "CHIP"
					( Origin gFrontEnd )
				)
				( attribute "PACK_TYPE" "0402"
					( Origin gFrontEnd )
				)
				( attribute "PART_NUMBER" "G21796-365"
					( Origin gFrontEnd )
				)
				( attribute "PHYS_PAGE" "55"
					( Origin gFrontEnd )
				)
				( attribute "ROOM" "CPU1"
					( Origin gFrontEnd )
				)
				( attribute "ROT" "2"
					( Origin gFrontEnd )
				)
				( attribute "SEC" "1"
					( Origin gFrontEnd )
				)
				( attribute "SEC_TYPE" "0402"
					( Origin gFrontEnd )
				)
				( attribute "TOLERANCE" "1%"
					( Origin gFrontEnd )
				)
				( attribute "VALUE" "90.9"
					( Origin gFrontEnd )
				)
				( attribute "VER" "2"
					( Origin gFrontEnd )
				)
				( attribute "WATTAGE" "1/16W"
					( Origin gFrontEnd )
				)
				( attribute "XY" "(7025,2600)"
					( Origin gFrontEnd )
				)
				( attribute "CHIPS_PART_NAME" "RES"
					( Origin gPackager )
				)
				( attribute "CDS_PART_NAME" "RES_0402-90.9,1%,1/16W,CHIP,G2A"
					( Origin gPackager )
				)
				( objectStatus "R7P16" )
			)
			( gate "@baseboard_fab2_lib.baseboard_fab2(sch_1):page55_i123"
				( attribute "BOM_COST" "PROC_SOCKET"
					( Origin gFrontEnd )
				)
				( attribute "CDS_LIB" "mstr_discrete"
					( Origin gPackager )
				)
				( attribute "CDS_LOCATION" "R7P8"
					( Origin gPackager )
				)
				( attribute "CDS_SEC" "1"
					( Origin gPackager )
				)
				( attribute "LOCATION" "R7P8"
					( Origin gFrontEnd )
				)
				( attribute "MATERIAL" "CHIP"
					( Origin gFrontEnd )
				)
				( attribute "PACK_TYPE" "0402"
					( Origin gFrontEnd )
				)
				( attribute "PART_NUMBER" "G21796-047"
					( Origin gFrontEnd )
				)
				( attribute "PHYS_PAGE" "55"
					( Origin gFrontEnd )
				)
				( attribute "ROOM" "CPU1"
					( Origin gFrontEnd )
				)
				( attribute "ROT" "2"
					( Origin gFrontEnd )
				)
				( attribute "SEC" "1"
					( Origin gFrontEnd )
				)
				( attribute "SEC_TYPE" "0402"
					( Origin gFrontEnd )
				)
				( attribute "TOLERANCE" "1%"
					( Origin gFrontEnd )
				)
				( attribute "VALUE" "49.9"
					( Origin gFrontEnd )
				)
				( attribute "VER" "2"
					( Origin gFrontEnd )
				)
				( attribute "WATTAGE" "1/16W"
					( Origin gFrontEnd )
				)
				( attribute "XY" "(6600,1425)"
					( Origin gFrontEnd )
				)
				( attribute "CHIPS_PART_NAME" "RES"
					( Origin gPackager )
				)
				( attribute "CDS_PART_NAME" "RES_0402-49.9,1%,1/16W,CHIP,G2A"
					( Origin gPackager )
				)
				( objectStatus "R7P8" )
			)
			( gate "@baseboard_fab2_lib.baseboard_fab2(sch_1):page55_i124"
				( attribute "BOM_COST" "PROC_SOCKET"
					( Origin gFrontEnd )
				)
				( attribute "CDS_LIB" "mstr_discrete"
					( Origin gPackager )
				)
				( attribute "CDS_LOCATION" "R7P10"
					( Origin gPackager )
				)
				( attribute "CDS_SEC" "1"
					( Origin gPackager )
				)
				( attribute "LOCATION" "R7P10"
					( Origin gFrontEnd )
				)
				( attribute "MATERIAL" "CHIP"
					( Origin gFrontEnd )
				)
				( attribute "PACK_TYPE" "0402"
					( Origin gFrontEnd )
				)
				( attribute "PART_NUMBER" "G21796-047"
					( Origin gFrontEnd )
				)
				( attribute "PHYS_PAGE" "55"
					( Origin gFrontEnd )
				)
				( attribute "ROOM" "CPU1"
					( Origin gFrontEnd )
				)
				( attribute "ROT" "2"
					( Origin gFrontEnd )
				)
				( attribute "SEC" "1"
					( Origin gFrontEnd )
				)
				( attribute "SEC_TYPE" "0402"
					( Origin gFrontEnd )
				)
				( attribute "TOLERANCE" "1%"
					( Origin gFrontEnd )
				)
				( attribute "VALUE" "49.9"
					( Origin gFrontEnd )
				)
				( attribute "VER" "2"
					( Origin gFrontEnd )
				)
				( attribute "WATTAGE" "1/16W"
					( Origin gFrontEnd )
				)
				( attribute "XY" "(6825,1425)"
					( Origin gFrontEnd )
				)
				( attribute "CHIPS_PART_NAME" "RES"
					( Origin gPackager )
				)
				( attribute "CDS_PART_NAME" "RES_0402-49.9,1%,1/16W,CHIP,G2A"
					( Origin gPackager )
				)
				( objectStatus "R7P10" )
			)
			( gate "@baseboard_fab2_lib.baseboard_fab2(sch_1):page55_i125"
				( attribute "BOM_COST" "PROC_SOCKET"
					( Origin gFrontEnd )
				)
				( attribute "CDS_LIB" "mstr_discrete"
					( Origin gPackager )
				)
				( attribute "CDS_LOCATION" "R3D19"
					( Origin gPackager )
				)
				( attribute "CDS_SEC" "1"
					( Origin gPackager )
				)
				( attribute "LOCATION" "R3D19"
					( Origin gFrontEnd )
				)
				( attribute "MATERIAL" "CHIP"
					( Origin gFrontEnd )
				)
				( attribute "PACK_TYPE" "0402"
					( Origin gFrontEnd )
				)
				( attribute "PART_NUMBER" "G21796-047"
					( Origin gFrontEnd )
				)
				( attribute "PHYS_PAGE" "55"
					( Origin gFrontEnd )
				)
				( attribute "ROOM" "CPU1"
					( Origin gFrontEnd )
				)
				( attribute "ROT" "2"
					( Origin gFrontEnd )
				)
				( attribute "SEC" "1"
					( Origin gFrontEnd )
				)
				( attribute "SEC_TYPE" "0402"
					( Origin gFrontEnd )
				)
				( attribute "TOLERANCE" "1%"
					( Origin gFrontEnd )
				)
				( attribute "VALUE" "49.9"
					( Origin gFrontEnd )
				)
				( attribute "VER" "2"
					( Origin gFrontEnd )
				)
				( attribute "WATTAGE" "1/16W"
					( Origin gFrontEnd )
				)
				( attribute "XY" "(7050,1425)"
					( Origin gFrontEnd )
				)
				( attribute "CHIPS_PART_NAME" "RES"
					( Origin gPackager )
				)
				( attribute "CDS_PART_NAME" "RES_0402-49.9,1%,1/16W,CHIP,G2A"
					( Origin gPackager )
				)
				( objectStatus "R3D19" )
			)
			( gate "@baseboard_fab2_lib.baseboard_fab2(sch_1):page55_i126"
				( attribute "BOM_COST" "PROC_SOCKET"
					( Origin gFrontEnd )
				)
				( attribute "CDS_LIB" "mstr_discrete"
					( Origin gPackager )
				)
				( attribute "CDS_LOCATION" "R7P11"
					( Origin gPackager )
				)
				( attribute "CDS_SEC" "1"
					( Origin gPackager )
				)
				( attribute "LOCATION" "R7P11"
					( Origin gFrontEnd )
				)
				( attribute "MATERIAL" "CHIP"
					( Origin gFrontEnd )
				)
				( attribute "PACK_TYPE" "0402"
					( Origin gFrontEnd )
				)
				( attribute "PART_NUMBER" "G21796-047"
					( Origin gFrontEnd )
				)
				( attribute "PHYS_PAGE" "55"
					( Origin gFrontEnd )
				)
				( attribute "ROOM" "CPU1"
					( Origin gFrontEnd )
				)
				( attribute "ROT" "2"
					( Origin gFrontEnd )
				)
				( attribute "SEC" "1"
					( Origin gFrontEnd )
				)
				( attribute "SEC_TYPE" "0402"
					( Origin gFrontEnd )
				)
				( attribute "TOLERANCE" "1%"
					( Origin gFrontEnd )
				)
				( attribute "VALUE" "49.9"
					( Origin gFrontEnd )
				)
				( attribute "VER" "2"
					( Origin gFrontEnd )
				)
				( attribute "WATTAGE" "1/16W"
					( Origin gFrontEnd )
				)
				( attribute "XY" "(7275,1425)"
					( Origin gFrontEnd )
				)
				( attribute "CHIPS_PART_NAME" "RES"
					( Origin gPackager )
				)
				( attribute "CDS_PART_NAME" "RES_0402-49.9,1%,1/16W,CHIP,G2A"
					( Origin gPackager )
				)
				( objectStatus "R7P11" )
			)
			( gate "@baseboard_fab2_lib.baseboard_fab2(sch_1):page55_i140"
				( attribute "BOM_COST" "PROC_SOCKET"
					( Origin gFrontEnd )
				)
				( attribute "CDS_LIB" "mstr_discrete"
					( Origin gPackager )
				)
				( attribute "CDS_LOCATION" "R7P17"
					( Origin gPackager )
				)
				( attribute "CDS_SEC" "1"
					( Origin gPackager )
				)
				( attribute "LOCATION" "R7P17"
					( Origin gFrontEnd )
				)
				( attribute "MATERIAL" "CHIP"
					( Origin gFrontEnd )
				)
				( attribute "PACK_TYPE" "0402"
					( Origin gFrontEnd )
				)
				( attribute "PART_NUMBER" "G21796-365"
					( Origin gFrontEnd )
				)
				( attribute "PHYS_PAGE" "55"
					( Origin gFrontEnd )
				)
				( attribute "ROOM" "CPU1"
					( Origin gFrontEnd )
				)
				( attribute "ROT" "2"
					( Origin gFrontEnd )
				)
				( attribute "SEC" "1"
					( Origin gFrontEnd )
				)
				( attribute "SEC_TYPE" "0402"
					( Origin gFrontEnd )
				)
				( attribute "TOLERANCE" "1%"
					( Origin gFrontEnd )
				)
				( attribute "VALUE" "90.9"
					( Origin gFrontEnd )
				)
				( attribute "VER" "2"
					( Origin gFrontEnd )
				)
				( attribute "WATTAGE" "1/16W"
					( Origin gFrontEnd )
				)
				( attribute "XY" "(6800,2650)"
					( Origin gFrontEnd )
				)
				( attribute "CHIPS_PART_NAME" "RES"
					( Origin gPackager )
				)
				( attribute "CDS_PART_NAME" "RES_0402-90.9,1%,1/16W,CHIP,G2A"
					( Origin gPackager )
				)
				( objectStatus "R7P17" )
			)
			( gate "@baseboard_fab2_lib.baseboard_fab2(sch_1):page55_i152"
				( attribute "BOM_COST" "PROC_SOCKET"
					( Origin gFrontEnd )
				)
				( attribute "CDS_LIB" "chpset_lib"
					( Origin gPackager )
				)
				( attribute "CDS_LOCATION" "XRU2"
					( Origin gPackager )
				)
				( attribute "LOCATION" "XRU2"
					( Origin gFrontEnd )
				)
				( attribute "MATERIAL" "PLASTIC"
					( Origin gFrontEnd )
				)
				( attribute "PACK_TYPE" "RIGHT"
					( Origin gFrontEnd )
				)
				( attribute "PART_NUMBER" "H37604-101"
					( Origin gFrontEnd )
				)
				( attribute "PHYS_PAGE" "55"
					( Origin gFrontEnd )
				)
				( attribute "ROOM" "CPU1"
					( Origin gFrontEnd )
				)
				( attribute "ROT" "0"
					( Origin gFrontEnd )
				)
				( attribute "SKT_NUMBER" "P0"
					( Origin gFrontEnd )
				)
				( attribute "VER" "1"
					( Origin gFrontEnd )
				)
				( attribute "XY" "(6875,4000)"
					( Origin gFrontEnd )
				)
				( attribute "CHIPS_PART_NAME" "SOCKET_P_MECH_A"
					( Origin gPackager )
				)
				( attribute "CDS_PART_NAME" "SOCKET_P_MECH_A_RIGHT-P0,PLASTA"
					( Origin gPackager )
				)
				( objectStatus "XRU2" )
			)
			( gate "@baseboard_fab2_lib.baseboard_fab2(sch_1):page55_i153"
				( attribute "BOM_COST" "PROC_SOCKET"
					( Origin gFrontEnd )
				)
				( attribute "CDS_LIB" "chpset_lib"
					( Origin gPackager )
				)
				( attribute "CDS_LOCATION" "XLU2"
					( Origin gPackager )
				)
				( attribute "LOCATION" "XLU2"
					( Origin gFrontEnd )
				)
				( attribute "MATERIAL" "PLASTIC"
					( Origin gFrontEnd )
				)
				( attribute "PACK_TYPE" "LEFT"
					( Origin gFrontEnd )
				)
				( attribute "PART_NUMBER" "H37604-201"
					( Origin gFrontEnd )
				)
				( attribute "PHYS_PAGE" "55"
					( Origin gFrontEnd )
				)
				( attribute "ROOM" "CPU1"
					( Origin gFrontEnd )
				)
				( attribute "ROT" "0"
					( Origin gFrontEnd )
				)
				( attribute "SKT_NUMBER" "P0"
					( Origin gFrontEnd )
				)
				( attribute "VER" "1"
					( Origin gFrontEnd )
				)
				( attribute "XY" "(6875,3725)"
					( Origin gFrontEnd )
				)
				( attribute "CHIPS_PART_NAME" "SOCKET_P_MECH_A"
					( Origin gPackager )
				)
				( attribute "CDS_PART_NAME" "SOCKET_P_MECH_A_LEFT-P0,PLASTIA"
					( Origin gPackager )
				)
				( objectStatus "XLU2" )
			)
			( gate "@baseboard_fab2_lib.baseboard_fab2(sch_1):page55_i155"
				( attribute "BOM_COST" "PROC_SOCKET"
					( Origin gFrontEnd )
				)
				( attribute "CDS_LIB" "mstr_discrete"
					( Origin gPackager )
				)
				( attribute "CDS_LOCATION" "R3D4"
					( Origin gPackager )
				)
				( attribute "CDS_SEC" "1"
					( Origin gPackager )
				)
				( attribute "LOCATION" "R3D4"
					( Origin gFrontEnd )
				)
				( attribute "MATERIAL" "CHIP"
					( Origin gFrontEnd )
				)
				( attribute "PACK_TYPE" "0402"
					( Origin gFrontEnd )
				)
				( attribute "PART_NUMBER" "G21796-047"
					( Origin gFrontEnd )
				)
				( attribute "PHYS_PAGE" "55"
					( Origin gFrontEnd )
				)
				( attribute "ROOM" "CPU1"
					( Origin gFrontEnd )
				)
				( attribute "ROT" "2"
					( Origin gFrontEnd )
				)
				( attribute "SEC" "1"
					( Origin gFrontEnd )
				)
				( attribute "SEC_TYPE" "0402"
					( Origin gFrontEnd )
				)
				( attribute "TOLERANCE" "1%"
					( Origin gFrontEnd )
				)
				( attribute "VALUE" "49.9"
					( Origin gFrontEnd )
				)
				( attribute "VER" "2"
					( Origin gFrontEnd )
				)
				( attribute "WATTAGE" "1/16W"
					( Origin gFrontEnd )
				)
				( attribute "XY" "(7500,1425)"
					( Origin gFrontEnd )
				)
				( attribute "CHIPS_PART_NAME" "RES"
					( Origin gPackager )
				)
				( attribute "CDS_PART_NAME" "RES_0402-49.9,1%,1/16W,CHIP,G2A"
					( Origin gPackager )
				)
				( objectStatus "R3D4" )
			)
			( gate "@baseboard_fab2_lib.baseboard_fab2(sch_1):page55_i156"
				( attribute "BOM_COST" "PROC_SOCKET"
					( Origin gFrontEnd )
				)
				( attribute "CDS_LIB" "mstr_discrete"
					( Origin gPackager )
				)
				( attribute "CDS_LOCATION" "R7P26"
					( Origin gPackager )
				)
				( attribute "CDS_SEC" "1"
					( Origin gPackager )
				)
				( attribute "LOCATION" "R7P26"
					( Origin gFrontEnd )
				)
				( attribute "MATERIAL" "CHIP"
					( Origin gFrontEnd )
				)
				( attribute "PACK_TYPE" "0402"
					( Origin gFrontEnd )
				)
				( attribute "PART_NUMBER" "G21796-047"
					( Origin gFrontEnd )
				)
				( attribute "PHYS_PAGE" "55"
					( Origin gFrontEnd )
				)
				( attribute "ROOM" "CPU1"
					( Origin gFrontEnd )
				)
				( attribute "ROT" "0"
					( Origin gFrontEnd )
				)
				( attribute "SEC" "1"
					( Origin gFrontEnd )
				)
				( attribute "SEC_TYPE" "0402"
					( Origin gFrontEnd )
				)
				( attribute "TOLERANCE" "1%"
					( Origin gFrontEnd )
				)
				( attribute "VALUE" "49.9"
					( Origin gFrontEnd )
				)
				( attribute "VER" "1"
					( Origin gFrontEnd )
				)
				( attribute "WATTAGE" "1/16W"
					( Origin gFrontEnd )
				)
				( attribute "XY" "(12100,3850)"
					( Origin gFrontEnd )
				)
				( attribute "CHIPS_PART_NAME" "RES"
					( Origin gPackager )
				)
				( attribute "CDS_PART_NAME" "RES_0402-49.9,1%,1/16W,CHIP,G2A"
					( Origin gPackager )
				)
				( objectStatus "R7P26" )
			)
			( gate "@baseboard_fab2_lib.baseboard_fab2(sch_1):page55_i157"
				( attribute "BOM_COST" "PROC_SOCKET"
					( Origin gFrontEnd )
				)
				( attribute "CDS_LIB" "mstr_discrete"
					( Origin gPackager )
				)
				( attribute "CDS_LOCATION" "R8N1"
					( Origin gPackager )
				)
				( attribute "CDS_SEC" "1"
					( Origin gPackager )
				)
				( attribute "LOCATION" "R8N1"
					( Origin gFrontEnd )
				)
				( attribute "MATERIAL" "CHIP"
					( Origin gFrontEnd )
				)
				( attribute "PACK_TYPE" "0402"
					( Origin gFrontEnd )
				)
				( attribute "PART_NUMBER" "G21796-336"
					( Origin gFrontEnd )
				)
				( attribute "PHYS_PAGE" "55"
					( Origin gFrontEnd )
				)
				( attribute "ROOM" "CPU1"
					( Origin gFrontEnd )
				)
				( attribute "ROT" "0"
					( Origin gFrontEnd )
				)
				( attribute "SEC" "1"
					( Origin gFrontEnd )
				)
				( attribute "SEC_TYPE" "0402"
					( Origin gFrontEnd )
				)
				( attribute "TOLERANCE" "1%"
					( Origin gFrontEnd )
				)
				( attribute "VALUE" "1.8K"
					( Origin gFrontEnd )
				)
				( attribute "VER" "2"
					( Origin gFrontEnd )
				)
				( attribute "WATTAGE" "1/16W"
					( Origin gFrontEnd )
				)
				( attribute "XY" "(12600,2300)"
					( Origin gFrontEnd )
				)
				( attribute "CHIPS_PART_NAME" "RES"
					( Origin gPackager )
				)
				( attribute "CDS_PART_NAME" "RES_0402-1.8K,1%,1/16W,CHIP,G2A"
					( Origin gPackager )
				)
				( objectStatus "R8N1" )
			)
			( gate "@baseboard_fab2_lib.baseboard_fab2(sch_1):page55_i158"
				( attribute "BOM_COST" "PROC_SOCKET"
					( Origin gFrontEnd )
				)
				( attribute "CDS_LIB" "mstr_discrete"
					( Origin gPackager )
				)
				( attribute "CDS_LOCATION" "R8N4"
					( Origin gPackager )
				)
				( attribute "CDS_SEC" "1"
					( Origin gPackager )
				)
				( attribute "LOCATION" "R8N4"
					( Origin gFrontEnd )
				)
				( attribute "MATERIAL" "CHIP"
					( Origin gFrontEnd )
				)
				( attribute "PACK_TYPE" "0402"
					( Origin gFrontEnd )
				)
				( attribute "PART_NUMBER" "G21796-336"
					( Origin gFrontEnd )
				)
				( attribute "PHYS_PAGE" "55"
					( Origin gFrontEnd )
				)
				( attribute "ROOM" "CPU1"
					( Origin gFrontEnd )
				)
				( attribute "ROT" "0"
					( Origin gFrontEnd )
				)
				( attribute "SEC" "1"
					( Origin gFrontEnd )
				)
				( attribute "SEC_TYPE" "0402"
					( Origin gFrontEnd )
				)
				( attribute "TOLERANCE" "1%"
					( Origin gFrontEnd )
				)
				( attribute "VALUE" "1.8K"
					( Origin gFrontEnd )
				)
				( attribute "VER" "2"
					( Origin gFrontEnd )
				)
				( attribute "WATTAGE" "1/16W"
					( Origin gFrontEnd )
				)
				( attribute "XY" "(12850,2300)"
					( Origin gFrontEnd )
				)
				( attribute "CHIPS_PART_NAME" "RES"
					( Origin gPackager )
				)
				( attribute "CDS_PART_NAME" "RES_0402-1.8K,1%,1/16W,CHIP,G2A"
					( Origin gPackager )
				)
				( objectStatus "R8N4" )
			)
			( gate "@baseboard_fab2_lib.baseboard_fab2(sch_1):page55_i159"
				( attribute "BOM_COST" "PROC_SOCKET"
					( Origin gFrontEnd )
				)
				( attribute "CDS_LIB" "mstr_discrete"
					( Origin gPackager )
				)
				( attribute "CDS_LOCATION" "R8N3"
					( Origin gPackager )
				)
				( attribute "CDS_SEC" "1"
					( Origin gPackager )
				)
				( attribute "LOCATION" "R8N3"
					( Origin gFrontEnd )
				)
				( attribute "MATERIAL" "CHIP"
					( Origin gFrontEnd )
				)
				( attribute "PACK_TYPE" "0402"
					( Origin gFrontEnd )
				)
				( attribute "PART_NUMBER" "G21796-016"
					( Origin gFrontEnd )
				)
				( attribute "PHYS_PAGE" "55"
					( Origin gFrontEnd )
				)
				( attribute "ROOM" "CPU1"
					( Origin gFrontEnd )
				)
				( attribute "ROT" "0"
					( Origin gFrontEnd )
				)
				( attribute "SEC" "1"
					( Origin gFrontEnd )
				)
				( attribute "SEC_TYPE" "0402"
					( Origin gFrontEnd )
				)
				( attribute "TOLERANCE" "1%"
					( Origin gFrontEnd )
				)
				( attribute "VALUE" "10.0K"
					( Origin gFrontEnd )
				)
				( attribute "VER" "2"
					( Origin gFrontEnd )
				)
				( attribute "WATTAGE" "1/16W"
					( Origin gFrontEnd )
				)
				( attribute "XY" "(13100,2300)"
					( Origin gFrontEnd )
				)
				( attribute "CHIPS_PART_NAME" "RES"
					( Origin gPackager )
				)
				( attribute "CDS_PART_NAME" "RES_0402-10.0K,1%,1/16W,CHIP,GA"
					( Origin gPackager )
				)
				( objectStatus "R8N3" )
			)
			( gate "@baseboard_fab2_lib.baseboard_fab2(sch_1):page55_i160"
				( attribute "BOM_COST" "PROC_SOCKET"
					( Origin gFrontEnd )
				)
				( attribute "CDS_LIB" "mstr_discrete"
					( Origin gPackager )
				)
				( attribute "CDS_LOCATION" "R8N5"
					( Origin gPackager )
				)
				( attribute "CDS_SEC" "1"
					( Origin gPackager )
				)
				( attribute "LOCATION" "R8N5"
					( Origin gFrontEnd )
				)
				( attribute "MATERIAL" "CHIP"
					( Origin gFrontEnd )
				)
				( attribute "PACK_TYPE" "0402"
					( Origin gFrontEnd )
				)
				( attribute "PART_NUMBER" "G21796-016"
					( Origin gFrontEnd )
				)
				( attribute "PHYS_PAGE" "55"
					( Origin gFrontEnd )
				)
				( attribute "ROOM" "CPU1"
					( Origin gFrontEnd )
				)
				( attribute "ROT" "0"
					( Origin gFrontEnd )
				)
				( attribute "SEC" "1"
					( Origin gFrontEnd )
				)
				( attribute "SEC_TYPE" "0402"
					( Origin gFrontEnd )
				)
				( attribute "TOLERANCE" "1%"
					( Origin gFrontEnd )
				)
				( attribute "VALUE" "10.0K"
					( Origin gFrontEnd )
				)
				( attribute "VER" "2"
					( Origin gFrontEnd )
				)
				( attribute "WATTAGE" "1/16W"
					( Origin gFrontEnd )
				)
				( attribute "XY" "(13350,2300)"
					( Origin gFrontEnd )
				)
				( attribute "CHIPS_PART_NAME" "RES"
					( Origin gPackager )
				)
				( attribute "CDS_PART_NAME" "RES_0402-10.0K,1%,1/16W,CHIP,GA"
					( Origin gPackager )
				)
				( objectStatus "R8N5" )
			)
			( gate "@baseboard_fab2_lib.baseboard_fab2(sch_1):page55_i161"
				( attribute "BOM_COST" "PROC_SOCKET"
					( Origin gFrontEnd )
				)
				( attribute "CDS_LIB" "mstr_discrete"
					( Origin gPackager )
				)
				( attribute "CDS_LOCATION" "R8N2"
					( Origin gPackager )
				)
				( attribute "CDS_SEC" "1"
					( Origin gPackager )
				)
				( attribute "LOCATION" "R8N2"
					( Origin gFrontEnd )
				)
				( attribute "MATERIAL" "CHIP"
					( Origin gFrontEnd )
				)
				( attribute "PACK_TYPE" "0402"
					( Origin gFrontEnd )
				)
				( attribute "PART_NUMBER" "G21796-016"
					( Origin gFrontEnd )
				)
				( attribute "PHYS_PAGE" "55"
					( Origin gFrontEnd )
				)
				( attribute "ROOM" "CPU1"
					( Origin gFrontEnd )
				)
				( attribute "ROT" "0"
					( Origin gFrontEnd )
				)
				( attribute "SEC" "1"
					( Origin gFrontEnd )
				)
				( attribute "SEC_TYPE" "0402"
					( Origin gFrontEnd )
				)
				( attribute "TOLERANCE" "1%"
					( Origin gFrontEnd )
				)
				( attribute "VALUE" "10.0K"
					( Origin gFrontEnd )
				)
				( attribute "VER" "2"
					( Origin gFrontEnd )
				)
				( attribute "WATTAGE" "1/16W"
					( Origin gFrontEnd )
				)
				( attribute "XY" "(13600,2300)"
					( Origin gFrontEnd )
				)
				( attribute "CHIPS_PART_NAME" "RES"
					( Origin gPackager )
				)
				( attribute "CDS_PART_NAME" "RES_0402-10.0K,1%,1/16W,CHIP,GA"
					( Origin gPackager )
				)
				( objectStatus "R8N2" )
			)
			( gate "@baseboard_fab2_lib.baseboard_fab2(sch_1):page55_i170"
				( attribute "BOM_COST" "PROC_SOCKET"
					( Origin gFrontEnd )
				)
				( attribute "CDS_LIB" "mstr_discrete"
					( Origin gPackager )
				)
				( attribute "CDS_LOCATION" "R7P25"
					( Origin gPackager )
				)
				( attribute "CDS_SEC" "1"
					( Origin gPackager )
				)
				( attribute "LOCATION" "R7P25"
					( Origin gFrontEnd )
				)
				( attribute "MATERIAL" "CHIP"
					( Origin gFrontEnd )
				)
				( attribute "PACK_TYPE" "0402"
					( Origin gFrontEnd )
				)
				( attribute "PART_NUMBER" "G21796-047"
					( Origin gFrontEnd )
				)
				( attribute "PHYS_PAGE" "55"
					( Origin gFrontEnd )
				)
				( attribute "ROOM" "CPU1"
					( Origin gFrontEnd )
				)
				( attribute "ROT" "0"
					( Origin gFrontEnd )
				)
				( attribute "SEC" "1"
					( Origin gFrontEnd )
				)
				( attribute "SEC_TYPE" "0402"
					( Origin gFrontEnd )
				)
				( attribute "TOLERANCE" "1%"
					( Origin gFrontEnd )
				)
				( attribute "VALUE" "49.9"
					( Origin gFrontEnd )
				)
				( attribute "VER" "1"
					( Origin gFrontEnd )
				)
				( attribute "WATTAGE" "1/16W"
					( Origin gFrontEnd )
				)
				( attribute "XY" "(12100,3900)"
					( Origin gFrontEnd )
				)
				( attribute "CHIPS_PART_NAME" "RES"
					( Origin gPackager )
				)
				( attribute "CDS_PART_NAME" "RES_0402-49.9,1%,1/16W,CHIP,G2A"
					( Origin gPackager )
				)
				( objectStatus "R7P25" )
			)
			( gate "@baseboard_fab2_lib.baseboard_fab2(sch_1):page55_i172"
				( attribute "CDS_LIB" "chpset_lib"
					( Origin gPackager )
				)
				( attribute "CDS_LOCATION" "U2D1"
					( Origin gPackager )
				)
				( attribute "CDS_SEC" "1"
					( Origin gPackager )
				)
				( attribute "LOCATION" "U2D1"
					( Origin gFrontEnd )
				)
				( attribute "MATERIAL" "IC"
					( Origin gFrontEnd )
				)
				( attribute "PACK_TYPE" "BGA1"
					( Origin gFrontEnd )
				)
				( attribute "PART_NUMBER" "TBD"
					( Origin gFrontEnd )
				)
				( attribute "PHYS_PAGE" "55"
					( Origin gFrontEnd )
				)
				( attribute "ROOM" "CPU1"
					( Origin gFrontEnd )
				)
				( attribute "ROT" "0"
					( Origin gFrontEnd )
				)
				( attribute "SEC" "1"
					( Origin gFrontEnd )
				)
				( attribute "SEC_TYPE" "BGA1"
					( Origin gFrontEnd )
				)
				( attribute "VER" "1"
					( Origin gFrontEnd )
				)
				( attribute "XY" "(10225,2500)"
					( Origin gFrontEnd )
				)
				( attribute "CHIPS_PART_NAME" "SKX_EXT_B"
					( Origin gPackager )
				)
				( attribute "CDS_PART_NAME" "SKX_EXT_B_BGA1-IC,TBD"
					( Origin gPackager )
				)
				( objectStatus "U2D1" )
			)
			( gate "@baseboard_fab2_lib.baseboard_fab2(sch_1):page55_i181"
				( attribute "CDS_LIB" "mstr_discrete"
					( Origin gPackager )
				)
				( attribute "CDS_LOCATION" "R6P39"
					( Origin gPackager )
				)
				( attribute "CDS_SEC" "1"
					( Origin gPackager )
				)
				( attribute "LOCATION" "R6P39"
					( Origin gFrontEnd )
				)
				( attribute "MATERIAL" "CHIP"
					( Origin gFrontEnd )
				)
				( attribute "PACK_TYPE" "0402"
					( Origin gFrontEnd )
				)
				( attribute "PART_NUMBER" "G21796-072"
					( Origin gFrontEnd )
				)
				( attribute "PHYS_PAGE" "55"
					( Origin gFrontEnd )
				)
				( attribute "ROOM" "CPU1"
					( Origin gFrontEnd )
				)
				( attribute "ROT" "0"
					( Origin gFrontEnd )
				)
				( attribute "SEC" "1"
					( Origin gFrontEnd )
				)
				( attribute "SEC_TYPE" "0402"
					( Origin gFrontEnd )
				)
				( attribute "TOLERANCE" "1%"
					( Origin gFrontEnd )
				)
				( attribute "VALUE" "4.75K"
					( Origin gFrontEnd )
				)
				( attribute "VER" "2"
					( Origin gFrontEnd )
				)
				( attribute "WATTAGE" "1/16W"
					( Origin gFrontEnd )
				)
				( attribute "XY" "(13275,1100)"
					( Origin gFrontEnd )
				)
				( attribute "CHIPS_PART_NAME" "RES"
					( Origin gPackager )
				)
				( attribute "CDS_PART_NAME" "RES_0402-4.75K,1%,1/16W,CHIP,GA"
					( Origin gPackager )
				)
				( objectStatus "R6P39" )
			)
			( gate "@baseboard_fab2_lib.baseboard_fab2(sch_1):page56_i169"
				( attribute "CDS_LIB" "chpset_lib"
					( Origin gPackager )
				)
				( attribute "CDS_LOCATION" "U2D1"
					( Origin gPackager )
				)
				( attribute "CDS_SEC" "2"
					( Origin gPackager )
				)
				( attribute "LOCATION" "U2D1"
					( Origin gFrontEnd )
				)
				( attribute "MATERIAL" "IC"
					( Origin gFrontEnd )
				)
				( attribute "PACK_TYPE" "BGA1"
					( Origin gFrontEnd )
				)
				( attribute "PART_NUMBER" "TBD"
					( Origin gFrontEnd )
				)
				( attribute "PHYS_PAGE" "56"
					( Origin gFrontEnd )
				)
				( attribute "ROT" "0"
					( Origin gFrontEnd )
				)
				( attribute "SEC" "2"
					( Origin gFrontEnd )
				)
				( attribute "SEC_TYPE" "BGA1"
					( Origin gFrontEnd )
				)
				( attribute "VER" "2"
					( Origin gFrontEnd )
				)
				( attribute "XY" "(-4025,2550)"
					( Origin gFrontEnd )
				)
				( attribute "CHIPS_PART_NAME" "SKX_EXT_B"
					( Origin gPackager )
				)
				( attribute "CDS_PART_NAME" "SKX_EXT_B_BGA1-IC,TBD"
					( Origin gPackager )
				)
				( objectStatus "U2D1" )
			)
			( gate "@baseboard_fab2_lib.baseboard_fab2(sch_1):page56_i173"
				( attribute "CDS_LIB" "mstr_discrete"
					( Origin gPackager )
				)
				( attribute "CDS_LOCATION" "R8P3"
					( Origin gPackager )
				)
				( attribute "CDS_SEC" "1"
					( Origin gPackager )
				)
				( attribute "LOCATION" "R8P3"
					( Origin gFrontEnd )
				)
				( attribute "MATERIAL" "CHIP"
					( Origin gFrontEnd )
				)
				( attribute "PACK_TYPE" "0402"
					( Origin gFrontEnd )
				)
				( attribute "PART_NUMBER" "G21796-047"
					( Origin gFrontEnd )
				)
				( attribute "PHYS_PAGE" "56"
					( Origin gFrontEnd )
				)
				( attribute "ROOM" "CPU1"
					( Origin gFrontEnd )
				)
				( attribute "ROT" "0"
					( Origin gFrontEnd )
				)
				( attribute "SEC" "1"
					( Origin gFrontEnd )
				)
				( attribute "SEC_TYPE" "0402"
					( Origin gFrontEnd )
				)
				( attribute "TOLERANCE" "1%"
					( Origin gFrontEnd )
				)
				( attribute "VALUE" "49.9"
					( Origin gFrontEnd )
				)
				( attribute "VER" "2"
					( Origin gFrontEnd )
				)
				( attribute "WATTAGE" "1/16W"
					( Origin gFrontEnd )
				)
				( attribute "XY" "(-650,2750)"
					( Origin gFrontEnd )
				)
				( attribute "CHIPS_PART_NAME" "RES"
					( Origin gPackager )
				)
				( attribute "CDS_PART_NAME" "RES_0402-49.9,1%,1/16W,CHIP,G2A"
					( Origin gPackager )
				)
				( objectStatus "R8P3" )
			)
			( gate "@baseboard_fab2_lib.baseboard_fab2(sch_1):page56_i174"
				( attribute "CDS_LIB" "mstr_discrete"
					( Origin gPackager )
				)
				( attribute "CDS_LOCATION" "R8R1"
					( Origin gPackager )
				)
				( attribute "CDS_SEC" "1"
					( Origin gPackager )
				)
				( attribute "LOCATION" "R8R1"
					( Origin gFrontEnd )
				)
				( attribute "MATERIAL" "CHIP"
					( Origin gFrontEnd )
				)
				( attribute "PACK_TYPE" "0402"
					( Origin gFrontEnd )
				)
				( attribute "PART_NUMBER" "G21796-047"
					( Origin gFrontEnd )
				)
				( attribute "PHYS_PAGE" "56"
					( Origin gFrontEnd )
				)
				( attribute "ROOM" "CPU1"
					( Origin gFrontEnd )
				)
				( attribute "ROT" "0"
					( Origin gFrontEnd )
				)
				( attribute "SEC" "1"
					( Origin gFrontEnd )
				)
				( attribute "SEC_TYPE" "0402"
					( Origin gFrontEnd )
				)
				( attribute "TOLERANCE" "1%"
					( Origin gFrontEnd )
				)
				( attribute "VALUE" "49.9"
					( Origin gFrontEnd )
				)
				( attribute "VER" "2"
					( Origin gFrontEnd )
				)
				( attribute "WATTAGE" "1/16W"
					( Origin gFrontEnd )
				)
				( attribute "XY" "(-375,2750)"
					( Origin gFrontEnd )
				)
				( attribute "CHIPS_PART_NAME" "RES"
					( Origin gPackager )
				)
				( attribute "CDS_PART_NAME" "RES_0402-49.9,1%,1/16W,CHIP,G2A"
					( Origin gPackager )
				)
				( objectStatus "R8R1" )
			)
			( gate "@baseboard_fab2_lib.baseboard_fab2(sch_1):page57_i172"
				( attribute "CDS_LIB" "chpset_lib"
					( Origin gPackager )
				)
				( attribute "CDS_LOCATION" "U2D1"
					( Origin gPackager )
				)
				( attribute "CDS_SEC" "3"
					( Origin gPackager )
				)
				( attribute "LOCATION" "U2D1"
					( Origin gFrontEnd )
				)
				( attribute "MATERIAL" "IC"
					( Origin gFrontEnd )
				)
				( attribute "PACK_TYPE" "BGA1"
					( Origin gFrontEnd )
				)
				( attribute "PART_NUMBER" "TBD"
					( Origin gFrontEnd )
				)
				( attribute "PHYS_PAGE" "57"
					( Origin gFrontEnd )
				)
				( attribute "ROT" "0"
					( Origin gFrontEnd )
				)
				( attribute "SEC" "3"
					( Origin gFrontEnd )
				)
				( attribute "SEC_TYPE" "BGA1"
					( Origin gFrontEnd )
				)
				( attribute "VER" "3"
					( Origin gFrontEnd )
				)
				( attribute "XY" "(-4175,2575)"
					( Origin gFrontEnd )
				)
				( attribute "CHIPS_PART_NAME" "SKX_EXT_B"
					( Origin gPackager )
				)
				( attribute "CDS_PART_NAME" "SKX_EXT_B_BGA1-IC,TBD"
					( Origin gPackager )
				)
				( objectStatus "U2D1" )
			)
			( gate "@baseboard_fab2_lib.baseboard_fab2(sch_1):page58_i172"
				( attribute "CDS_LIB" "chpset_lib"
					( Origin gPackager )
				)
				( attribute "CDS_LOCATION" "U2D1"
					( Origin gPackager )
				)
				( attribute "CDS_SEC" "4"
					( Origin gPackager )
				)
				( attribute "LOCATION" "U2D1"
					( Origin gFrontEnd )
				)
				( attribute "MATERIAL" "IC"
					( Origin gFrontEnd )
				)
				( attribute "PACK_TYPE" "BGA1"
					( Origin gFrontEnd )
				)
				( attribute "PART_NUMBER" "TBD"
					( Origin gFrontEnd )
				)
				( attribute "PHYS_PAGE" "58"
					( Origin gFrontEnd )
				)
				( attribute "ROT" "0"
					( Origin gFrontEnd )
				)
				( attribute "SEC" "4"
					( Origin gFrontEnd )
				)
				( attribute "SEC_TYPE" "BGA1"
					( Origin gFrontEnd )
				)
				( attribute "VER" "4"
					( Origin gFrontEnd )
				)
				( attribute "XY" "(-4200,2575)"
					( Origin gFrontEnd )
				)
				( attribute "CHIPS_PART_NAME" "SKX_EXT_B"
					( Origin gPackager )
				)
				( attribute "CDS_PART_NAME" "SKX_EXT_B_BGA1-IC,TBD"
					( Origin gPackager )
				)
				( objectStatus "U2D1" )
			)
			( gate "@baseboard_fab2_lib.baseboard_fab2(sch_1):page59_i172"
				( attribute "CDS_LIB" "chpset_lib"
					( Origin gPackager )
				)
				( attribute "CDS_LOCATION" "U2D1"
					( Origin gPackager )
				)
				( attribute "CDS_SEC" "5"
					( Origin gPackager )
				)
				( attribute "LOCATION" "U2D1"
					( Origin gFrontEnd )
				)
				( attribute "MATERIAL" "IC"
					( Origin gFrontEnd )
				)
				( attribute "PACK_TYPE" "BGA1"
					( Origin gFrontEnd )
				)
				( attribute "PART_NUMBER" "TBD"
					( Origin gFrontEnd )
				)
				( attribute "PHYS_PAGE" "59"
					( Origin gFrontEnd )
				)
				( attribute "ROT" "0"
					( Origin gFrontEnd )
				)
				( attribute "SEC" "5"
					( Origin gFrontEnd )
				)
				( attribute "SEC_TYPE" "BGA1"
					( Origin gFrontEnd )
				)
				( attribute "VER" "5"
					( Origin gFrontEnd )
				)
				( attribute "XY" "(-4175,2550)"
					( Origin gFrontEnd )
				)
				( attribute "CHIPS_PART_NAME" "SKX_EXT_B"
					( Origin gPackager )
				)
				( attribute "CDS_PART_NAME" "SKX_EXT_B_BGA1-IC,TBD"
					( Origin gPackager )
				)
				( objectStatus "U2D1" )
			)
			( gate "@baseboard_fab2_lib.baseboard_fab2(sch_1):page60_i172"
				( attribute "CDS_LIB" "chpset_lib"
					( Origin gPackager )
				)
				( attribute "CDS_LOCATION" "U2D1"
					( Origin gPackager )
				)
				( attribute "CDS_SEC" "6"
					( Origin gPackager )
				)
				( attribute "LOCATION" "U2D1"
					( Origin gFrontEnd )
				)
				( attribute "MATERIAL" "IC"
					( Origin gFrontEnd )
				)
				( attribute "PACK_TYPE" "BGA1"
					( Origin gFrontEnd )
				)
				( attribute "PART_NUMBER" "TBD"
					( Origin gFrontEnd )
				)
				( attribute "PHYS_PAGE" "60"
					( Origin gFrontEnd )
				)
				( attribute "ROT" "0"
					( Origin gFrontEnd )
				)
				( attribute "SEC" "6"
					( Origin gFrontEnd )
				)
				( attribute "SEC_TYPE" "BGA1"
					( Origin gFrontEnd )
				)
				( attribute "VER" "6"
					( Origin gFrontEnd )
				)
				( attribute "XY" "(-4175,2575)"
					( Origin gFrontEnd )
				)
				( attribute "CHIPS_PART_NAME" "SKX_EXT_B"
					( Origin gPackager )
				)
				( attribute "CDS_PART_NAME" "SKX_EXT_B_BGA1-IC,TBD"
					( Origin gPackager )
				)
				( objectStatus "U2D1" )
			)
			( gate "@baseboard_fab2_lib.baseboard_fab2(sch_1):page61_i172"
				( attribute "CDS_LIB" "chpset_lib"
					( Origin gPackager )
				)
				( attribute "CDS_LOCATION" "U2D1"
					( Origin gPackager )
				)
				( attribute "CDS_SEC" "7"
					( Origin gPackager )
				)
				( attribute "LOCATION" "U2D1"
					( Origin gFrontEnd )
				)
				( attribute "MATERIAL" "IC"
					( Origin gFrontEnd )
				)
				( attribute "PACK_TYPE" "BGA1"
					( Origin gFrontEnd )
				)
				( attribute "PART_NUMBER" "TBD"
					( Origin gFrontEnd )
				)
				( attribute "PHYS_PAGE" "61"
					( Origin gFrontEnd )
				)
				( attribute "ROT" "0"
					( Origin gFrontEnd )
				)
				( attribute "SEC" "7"
					( Origin gFrontEnd )
				)
				( attribute "SEC_TYPE" "BGA1"
					( Origin gFrontEnd )
				)
				( attribute "VER" "7"
					( Origin gFrontEnd )
				)
				( attribute "XY" "(-4175,2575)"
					( Origin gFrontEnd )
				)
				( attribute "CHIPS_PART_NAME" "SKX_EXT_B"
					( Origin gPackager )
				)
				( attribute "CDS_PART_NAME" "SKX_EXT_B_BGA1-IC,TBD"
					( Origin gPackager )
				)
				( objectStatus "U2D1" )
			)
			( gate "@baseboard_fab2_lib.baseboard_fab2(sch_1):page62_i172"
				( attribute "CDS_LIB" "chpset_lib"
					( Origin gPackager )
				)
				( attribute "CDS_LOCATION" "U2D1"
					( Origin gPackager )
				)
				( attribute "CDS_SEC" "8"
					( Origin gPackager )
				)
				( attribute "LOCATION" "U2D1"
					( Origin gFrontEnd )
				)
				( attribute "MATERIAL" "IC"
					( Origin gFrontEnd )
				)
				( attribute "PACK_TYPE" "BGA1"
					( Origin gFrontEnd )
				)
				( attribute "PART_NUMBER" "TBD"
					( Origin gFrontEnd )
				)
				( attribute "PHYS_PAGE" "62"
					( Origin gFrontEnd )
				)
				( attribute "ROT" "0"
					( Origin gFrontEnd )
				)
				( attribute "SEC" "8"
					( Origin gFrontEnd )
				)
				( attribute "SEC_TYPE" "BGA1"
					( Origin gFrontEnd )
				)
				( attribute "VER" "8"
					( Origin gFrontEnd )
				)
				( attribute "XY" "(-4200,2550)"
					( Origin gFrontEnd )
				)
				( attribute "CHIPS_PART_NAME" "SKX_EXT_B"
					( Origin gPackager )
				)
				( attribute "CDS_PART_NAME" "SKX_EXT_B_BGA1-IC,TBD"
					( Origin gPackager )
				)
				( objectStatus "U2D1" )
			)
			( gate "@baseboard_fab2_lib.baseboard_fab2(sch_1):page63_i23"
				( attribute "CDS_LIB" "chpset_lib"
					( Origin gPackager )
				)
				( attribute "CDS_LOCATION" "U2D1"
					( Origin gPackager )
				)
				( attribute "CDS_SEC" "9"
					( Origin gPackager )
				)
				( attribute "LOCATION" "U2D1"
					( Origin gFrontEnd )
				)
				( attribute "MATERIAL" "IC"
					( Origin gFrontEnd )
				)
				( attribute "PACK_TYPE" "BGA1"
					( Origin gFrontEnd )
				)
				( attribute "PART_NUMBER" "TBD"
					( Origin gFrontEnd )
				)
				( attribute "PHYS_PAGE" "63"
					( Origin gFrontEnd )
				)
				( attribute "ROT" "0"
					( Origin gFrontEnd )
				)
				( attribute "SEC" "9"
					( Origin gFrontEnd )
				)
				( attribute "SEC_TYPE" "BGA1"
					( Origin gFrontEnd )
				)
				( attribute "VER" "9"
					( Origin gFrontEnd )
				)
				( attribute "XY" "(-4075,2500)"
					( Origin gFrontEnd )
				)
				( attribute "CHIPS_PART_NAME" "SKX_EXT_B"
					( Origin gPackager )
				)
				( attribute "CDS_PART_NAME" "SKX_EXT_B_BGA1-IC,TBD"
					( Origin gPackager )
				)
				( objectStatus "U2D1" )
			)
			( gate "@baseboard_fab2_lib.baseboard_fab2(sch_1):page64_i68"
				( attribute "CDS_LIB" "chpset_lib"
					( Origin gPackager )
				)
				( attribute "CDS_LOCATION" "U2D1"
					( Origin gPackager )
				)
				( attribute "CDS_SEC" "10"
					( Origin gPackager )
				)
				( attribute "LOCATION" "U2D1"
					( Origin gFrontEnd )
				)
				( attribute "MATERIAL" "IC"
					( Origin gFrontEnd )
				)
				( attribute "PACK_TYPE" "BGA1"
					( Origin gFrontEnd )
				)
				( attribute "PART_NUMBER" "TBD"
					( Origin gFrontEnd )
				)
				( attribute "PHYS_PAGE" "64"
					( Origin gFrontEnd )
				)
				( attribute "ROT" "0"
					( Origin gFrontEnd )
				)
				( attribute "SEC" "10"
					( Origin gFrontEnd )
				)
				( attribute "SEC_TYPE" "BGA1"
					( Origin gFrontEnd )
				)
				( attribute "VER" "10"
					( Origin gFrontEnd )
				)
				( attribute "XY" "(-4075,2575)"
					( Origin gFrontEnd )
				)
				( attribute "CHIPS_PART_NAME" "SKX_EXT_B"
					( Origin gPackager )
				)
				( attribute "CDS_PART_NAME" "SKX_EXT_B_BGA1-IC,TBD"
					( Origin gPackager )
				)
				( objectStatus "U2D1" )
			)
			( gate "@baseboard_fab2_lib.baseboard_fab2(sch_1):page65_i68"
				( attribute "CDS_LIB" "chpset_lib"
					( Origin gPackager )
				)
				( attribute "CDS_LOCATION" "U2D1"
					( Origin gPackager )
				)
				( attribute "CDS_SEC" "11"
					( Origin gPackager )
				)
				( attribute "LOCATION" "U2D1"
					( Origin gFrontEnd )
				)
				( attribute "MATERIAL" "IC"
					( Origin gFrontEnd )
				)
				( attribute "PACK_TYPE" "BGA1"
					( Origin gFrontEnd )
				)
				( attribute "PART_NUMBER" "TBD"
					( Origin gFrontEnd )
				)
				( attribute "PHYS_PAGE" "65"
					( Origin gFrontEnd )
				)
				( attribute "ROT" "0"
					( Origin gFrontEnd )
				)
				( attribute "SEC" "11"
					( Origin gFrontEnd )
				)
				( attribute "SEC_TYPE" "BGA1"
					( Origin gFrontEnd )
				)
				( attribute "VER" "11"
					( Origin gFrontEnd )
				)
				( attribute "XY" "(-4150,2575)"
					( Origin gFrontEnd )
				)
				( attribute "CHIPS_PART_NAME" "SKX_EXT_B"
					( Origin gPackager )
				)
				( attribute "CDS_PART_NAME" "SKX_EXT_B_BGA1-IC,TBD"
					( Origin gPackager )
				)
				( objectStatus "U2D1" )
			)
			( gate "@baseboard_fab2_lib.baseboard_fab2(sch_1):page66_i84"
				( attribute "CDS_LIB" "chpset_lib"
					( Origin gPackager )
				)
				( attribute "CDS_LOCATION" "U2D1"
					( Origin gPackager )
				)
				( attribute "CDS_SEC" "12"
					( Origin gPackager )
				)
				( attribute "LOCATION" "U2D1"
					( Origin gFrontEnd )
				)
				( attribute "MATERIAL" "IC"
					( Origin gFrontEnd )
				)
				( attribute "PACK_TYPE" "BGA1"
					( Origin gFrontEnd )
				)
				( attribute "PART_NUMBER" "TBD"
					( Origin gFrontEnd )
				)
				( attribute "PHYS_PAGE" "66"
					( Origin gFrontEnd )
				)
				( attribute "ROT" "0"
					( Origin gFrontEnd )
				)
				( attribute "SEC" "12"
					( Origin gFrontEnd )
				)
				( attribute "SEC_TYPE" "BGA1"
					( Origin gFrontEnd )
				)
				( attribute "VER" "12"
					( Origin gFrontEnd )
				)
				( attribute "XY" "(-4125,2575)"
					( Origin gFrontEnd )
				)
				( attribute "CHIPS_PART_NAME" "SKX_EXT_B"
					( Origin gPackager )
				)
				( attribute "CDS_PART_NAME" "SKX_EXT_B_BGA1-IC,TBD"
					( Origin gPackager )
				)
				( objectStatus "U2D1" )
			)
			( gate "@baseboard_fab2_lib.baseboard_fab2(sch_1):page67_i132"
				( attribute "CDS_LIB" "chpset_lib"
					( Origin gPackager )
				)
				( attribute "CDS_LOCATION" "U2D1"
					( Origin gPackager )
				)
				( attribute "CDS_SEC" "13"
					( Origin gPackager )
				)
				( attribute "LOCATION" "U2D1"
					( Origin gFrontEnd )
				)
				( attribute "MATERIAL" "IC"
					( Origin gFrontEnd )
				)
				( attribute "PACK_TYPE" "BGA1"
					( Origin gFrontEnd )
				)
				( attribute "PART_NUMBER" "TBD"
					( Origin gFrontEnd )
				)
				( attribute "PHYS_PAGE" "67"
					( Origin gFrontEnd )
				)
				( attribute "ROT" "0"
					( Origin gFrontEnd )
				)
				( attribute "SEC" "13"
					( Origin gFrontEnd )
				)
				( attribute "SEC_TYPE" "BGA1"
					( Origin gFrontEnd )
				)
				( attribute "VER" "13"
					( Origin gFrontEnd )
				)
				( attribute "XY" "(-4050,2575)"
					( Origin gFrontEnd )
				)
				( attribute "CHIPS_PART_NAME" "SKX_EXT_B"
					( Origin gPackager )
				)
				( attribute "CDS_PART_NAME" "SKX_EXT_B_BGA1-IC,TBD"
					( Origin gPackager )
				)
				( objectStatus "U2D1" )
			)
			( gate "@baseboard_fab2_lib.baseboard_fab2(sch_1):page68_i125"
				( attribute "CDS_LIB" "chpset_lib"
					( Origin gPackager )
				)
				( attribute "CDS_LOCATION" "U2D1"
					( Origin gPackager )
				)
				( attribute "CDS_SEC" "14"
					( Origin gPackager )
				)
				( attribute "LOCATION" "U2D1"
					( Origin gFrontEnd )
				)
				( attribute "MATERIAL" "IC"
					( Origin gFrontEnd )
				)
				( attribute "PACK_TYPE" "BGA1"
					( Origin gFrontEnd )
				)
				( attribute "PART_NUMBER" "TBD"
					( Origin gFrontEnd )
				)
				( attribute "PHYS_PAGE" "68"
					( Origin gFrontEnd )
				)
				( attribute "ROT" "0"
					( Origin gFrontEnd )
				)
				( attribute "SEC" "14"
					( Origin gFrontEnd )
				)
				( attribute "SEC_TYPE" "BGA1"
					( Origin gFrontEnd )
				)
				( attribute "VER" "14"
					( Origin gFrontEnd )
				)
				( attribute "XY" "(-4100,2650)"
					( Origin gFrontEnd )
				)
				( attribute "CHIPS_PART_NAME" "SKX_EXT_B"
					( Origin gPackager )
				)
				( attribute "CDS_PART_NAME" "SKX_EXT_B_BGA1-IC,TBD"
					( Origin gPackager )
				)
				( objectStatus "U2D1" )
			)
			( gate "@baseboard_fab2_lib.baseboard_fab2(sch_1):page69_i1"
				( attribute "CDS_LIB" "chpset_lib"
					( Origin gPackager )
				)
				( attribute "CDS_LOCATION" "U2D1"
					( Origin gPackager )
				)
				( attribute "CDS_SEC" "15"
					( Origin gPackager )
				)
				( attribute "LOCATION" "U2D1"
					( Origin gFrontEnd )
				)
				( attribute "MATERIAL" "IC"
					( Origin gFrontEnd )
				)
				( attribute "PACK_TYPE" "BGA1"
					( Origin gFrontEnd )
				)
				( attribute "PART_NUMBER" "TBD"
					( Origin gFrontEnd )
				)
				( attribute "PHYS_PAGE" "69"
					( Origin gFrontEnd )
				)
				( attribute "ROT" "0"
					( Origin gFrontEnd )
				)
				( attribute "SEC" "15"
					( Origin gFrontEnd )
				)
				( attribute "SEC_TYPE" "BGA1"
					( Origin gFrontEnd )
				)
				( attribute "VER" "15"
					( Origin gFrontEnd )
				)
				( attribute "XY" "(-4275,2700)"
					( Origin gFrontEnd )
				)
				( attribute "CHIPS_PART_NAME" "SKX_EXT_B"
					( Origin gPackager )
				)
				( attribute "CDS_PART_NAME" "SKX_EXT_B_BGA1-IC,TBD"
					( Origin gPackager )
				)
				( objectStatus "U2D1" )
			)
			( gate "@baseboard_fab2_lib.baseboard_fab2(sch_1):page70_i9"
				( attribute "CDS_LIB" "chpset_lib"
					( Origin gPackager )
				)
				( attribute "CDS_LOCATION" "U2D1"
					( Origin gPackager )
				)
				( attribute "CDS_SEC" "16"
					( Origin gPackager )
				)
				( attribute "LOCATION" "U2D1"
					( Origin gFrontEnd )
				)
				( attribute "MATERIAL" "IC"
					( Origin gFrontEnd )
				)
				( attribute "PACK_TYPE" "BGA1"
					( Origin gFrontEnd )
				)
				( attribute "PART_NUMBER" "TBD"
					( Origin gFrontEnd )
				)
				( attribute "PHYS_PAGE" "70"
					( Origin gFrontEnd )
				)
				( attribute "ROT" "0"
					( Origin gFrontEnd )
				)
				( attribute "SEC" "16"
					( Origin gFrontEnd )
				)
				( attribute "SEC_TYPE" "BGA1"
					( Origin gFrontEnd )
				)
				( attribute "VER" "16"
					( Origin gFrontEnd )
				)
				( attribute "XY" "(-5450,2550)"
					( Origin gFrontEnd )
				)
				( attribute "CHIPS_PART_NAME" "SKX_EXT_B"
					( Origin gPackager )
				)
				( attribute "CDS_PART_NAME" "SKX_EXT_B_BGA1-IC,TBD"
					( Origin gPackager )
				)
				( objectStatus "U2D1" )
			)
			( gate "@baseboard_fab2_lib.baseboard_fab2(sch_1):page70_i10"
				( attribute "CDS_LIB" "chpset_lib"
					( Origin gPackager )
				)
				( attribute "CDS_LOCATION" "U2D1"
					( Origin gPackager )
				)
				( attribute "CDS_SEC" "17"
					( Origin gPackager )
				)
				( attribute "LOCATION" "U2D1"
					( Origin gFrontEnd )
				)
				( attribute "MATERIAL" "IC"
					( Origin gFrontEnd )
				)
				( attribute "PACK_TYPE" "BGA1"
					( Origin gFrontEnd )
				)
				( attribute "PART_NUMBER" "TBD"
					( Origin gFrontEnd )
				)
				( attribute "PHYS_PAGE" "70"
					( Origin gFrontEnd )
				)
				( attribute "ROT" "0"
					( Origin gFrontEnd )
				)
				( attribute "SEC" "17"
					( Origin gFrontEnd )
				)
				( attribute "SEC_TYPE" "BGA1"
					( Origin gFrontEnd )
				)
				( attribute "VER" "17"
					( Origin gFrontEnd )
				)
				( attribute "XY" "(-2925,2575)"
					( Origin gFrontEnd )
				)
				( attribute "CHIPS_PART_NAME" "SKX_EXT_B"
					( Origin gPackager )
				)
				( attribute "CDS_PART_NAME" "SKX_EXT_B_BGA1-IC,TBD"
					( Origin gPackager )
				)
				( objectStatus "U2D1" )
			)
			( gate "@baseboard_fab2_lib.baseboard_fab2(sch_1):page71_i43"
				( attribute "BOM_COST" "PROC_SOCKET"
					( Origin gFrontEnd )
				)
				( attribute "CDS_LIB" "mstr_discrete"
					( Origin gPackager )
				)
				( attribute "CDS_LOCATION" "R3D27"
					( Origin gPackager )
				)
				( attribute "CDS_SEC" "1"
					( Origin gPackager )
				)
				( attribute "LOCATION" "R3D27"
					( Origin gFrontEnd )
				)
				( attribute "MATERIAL" "CHIP"
					( Origin gFrontEnd )
				)
				( attribute "PACK_TYPE" "0402"
					( Origin gFrontEnd )
				)
				( attribute "PART_NUMBER" "G85996-031"
					( Origin gFrontEnd )
				)
				( attribute "PHYS_PAGE" "71"
					( Origin gFrontEnd )
				)
				( attribute "ROOM" "CPU1"
					( Origin gFrontEnd )
				)
				( attribute "ROT" "0"
					( Origin gFrontEnd )
				)
				( attribute "SEC" "1"
					( Origin gFrontEnd )
				)
				( attribute "SEC_TYPE" "0402"
					( Origin gFrontEnd )
				)
				( attribute "TOLERANCE" "0.1%"
					( Origin gFrontEnd )
				)
				( attribute "VALUE" "249"
					( Origin gFrontEnd )
				)
				( attribute "VER" "2"
					( Origin gFrontEnd )
				)
				( attribute "WATTAGE" "1/16W"
					( Origin gFrontEnd )
				)
				( attribute "XY" "(-500,750)"
					( Origin gFrontEnd )
				)
				( attribute "CHIPS_PART_NAME" "RES"
					( Origin gPackager )
				)
				( attribute "CDS_PART_NAME" "RES_0402-249,0.1%,1/16W,CHIP,GA"
					( Origin gPackager )
				)
				( objectStatus "R3D27" )
			)
			( gate "@baseboard_fab2_lib.baseboard_fab2(sch_1):page71_i49"
				( attribute "BOM_COST" "PROC_SOCKET"
					( Origin gFrontEnd )
				)
				( attribute "CDS_LIB" "mstr_discrete"
					( Origin gPackager )
				)
				( attribute "CDS_LOCATION" "RT8P1"
					( Origin gPackager )
				)
				( attribute "CDS_SEC" "1"
					( Origin gPackager )
				)
				( attribute "LOCATION" "RT8P1"
					( Origin gFrontEnd )
				)
				( attribute "MATERIAL" "CHIP"
					( Origin gFrontEnd )
				)
				( attribute "PACK_TYPE" "0603"
					( Origin gFrontEnd )
				)
				( attribute "PART_NUMBER" "G22026-050"
					( Origin gFrontEnd )
				)
				( attribute "PHYS_PAGE" "71"
					( Origin gFrontEnd )
				)
				( attribute "ROOM" "CPU1"
					( Origin gFrontEnd )
				)
				( attribute "ROT" "0"
					( Origin gFrontEnd )
				)
				( attribute "SEC" "1"
					( Origin gFrontEnd )
				)
				( attribute "SEC_TYPE" "0603"
					( Origin gFrontEnd )
				)
				( attribute "TOLERANCE" "1%"
					( Origin gFrontEnd )
				)
				( attribute "VALUE" "100.0K"
					( Origin gFrontEnd )
				)
				( attribute "VER" "2"
					( Origin gFrontEnd )
				)
				( attribute "WATTAGE" "1/10W"
					( Origin gFrontEnd )
				)
				( attribute "XY" "(-1100,1400)"
					( Origin gFrontEnd )
				)
				( attribute "CHIPS_PART_NAME" "RES"
					( Origin gPackager )
				)
				( attribute "CDS_PART_NAME" "RES_0603-100.0K,1%,1/10W,CHIP,A"
					( Origin gPackager )
				)
				( objectStatus "RT8P1" )
			)
			( gate "@baseboard_fab2_lib.baseboard_fab2(sch_1):page71_i50"
				( attribute "CDS_LIB" "chpset_lib"
					( Origin gPackager )
				)
				( attribute "CDS_LOCATION" "U2D1"
					( Origin gPackager )
				)
				( attribute "CDS_SEC" "18"
					( Origin gPackager )
				)
				( attribute "LOCATION" "U2D1"
					( Origin gFrontEnd )
				)
				( attribute "MATERIAL" "IC"
					( Origin gFrontEnd )
				)
				( attribute "PACK_TYPE" "BGA1"
					( Origin gFrontEnd )
				)
				( attribute "PART_NUMBER" "TBD"
					( Origin gFrontEnd )
				)
				( attribute "PHYS_PAGE" "71"
					( Origin gFrontEnd )
				)
				( attribute "ROT" "0"
					( Origin gFrontEnd )
				)
				( attribute "SEC" "18"
					( Origin gFrontEnd )
				)
				( attribute "SEC_TYPE" "BGA1"
					( Origin gFrontEnd )
				)
				( attribute "VER" "18"
					( Origin gFrontEnd )
				)
				( attribute "XY" "(-6375,2525)"
					( Origin gFrontEnd )
				)
				( attribute "CHIPS_PART_NAME" "SKX_EXT_B"
					( Origin gPackager )
				)
				( attribute "CDS_PART_NAME" "SKX_EXT_B_BGA1-IC,TBD"
					( Origin gPackager )
				)
				( objectStatus "U2D1" )
			)
			( gate "@baseboard_fab2_lib.baseboard_fab2(sch_1):page71_i51"
				( attribute "CDS_LIB" "chpset_lib"
					( Origin gPackager )
				)
				( attribute "CDS_LOCATION" "U2D1"
					( Origin gPackager )
				)
				( attribute "CDS_SEC" "19"
					( Origin gPackager )
				)
				( attribute "LOCATION" "U2D1"
					( Origin gFrontEnd )
				)
				( attribute "MATERIAL" "IC"
					( Origin gFrontEnd )
				)
				( attribute "PACK_TYPE" "BGA1"
					( Origin gFrontEnd )
				)
				( attribute "PART_NUMBER" "TBD"
					( Origin gFrontEnd )
				)
				( attribute "PHYS_PAGE" "71"
					( Origin gFrontEnd )
				)
				( attribute "ROT" "0"
					( Origin gFrontEnd )
				)
				( attribute "SEC" "19"
					( Origin gFrontEnd )
				)
				( attribute "SEC_TYPE" "BGA1"
					( Origin gFrontEnd )
				)
				( attribute "VER" "19"
					( Origin gFrontEnd )
				)
				( attribute "XY" "(-2675,2525)"
					( Origin gFrontEnd )
				)
				( attribute "CHIPS_PART_NAME" "SKX_EXT_B"
					( Origin gPackager )
				)
				( attribute "CDS_PART_NAME" "SKX_EXT_B_BGA1-IC,TBD"
					( Origin gPackager )
				)
				( objectStatus "U2D1" )
			)
			( gate "@baseboard_fab2_lib.baseboard_fab2(sch_1):page71_i53"
				( attribute "CDS_LIB" "mstr_discrete"
					( Origin gPackager )
				)
				( attribute "CDS_LOCATION" "R3D32"
					( Origin gPackager )
				)
				( attribute "CDS_SEC" "1"
					( Origin gPackager )
				)
				( attribute "LOCATION" "R3D32"
					( Origin gFrontEnd )
				)
				( attribute "MATERIAL" "EMPTY"
					( Origin gFrontEnd )
				)
				( attribute "PACK_TYPE" "0402"
					( Origin gFrontEnd )
				)
				( attribute "PART_NUMBER" "G21796-066"
					( Origin gFrontEnd )
				)
				( attribute "PHYS_PAGE" "71"
					( Origin gFrontEnd )
				)
				( attribute "ROOM" "CPU1"
					( Origin gFrontEnd )
				)
				( attribute "ROT" "0"
					( Origin gFrontEnd )
				)
				( attribute "SEC" "1"
					( Origin gFrontEnd )
				)
				( attribute "SEC_TYPE" "0402"
					( Origin gFrontEnd )
				)
				( attribute "TOLERANCE" "1%"
					( Origin gFrontEnd )
				)
				( attribute "VALUE" "10.0"
					( Origin gFrontEnd )
				)
				( attribute "VER" "2"
					( Origin gFrontEnd )
				)
				( attribute "WATTAGE" "1/16W"
					( Origin gFrontEnd )
				)
				( attribute "XY" "(-500,1200)"
					( Origin gFrontEnd )
				)
				( attribute "CHIPS_PART_NAME" "RES"
					( Origin gPackager )
				)
				( attribute "CDS_PART_NAME" "RES_0402-10.0,1%,1/16W,EMPTY,GA"
					( Origin gPackager )
				)
				( objectStatus "R3D32" )
			)
			( gate "@baseboard_fab2_lib.baseboard_fab2(sch_1):page72_i25"
				( attribute "BOM_COST" "PROC_SOCKET"
					( Origin gFrontEnd )
				)
				( attribute "CDS_LIB" "mstr_discrete"
					( Origin gPackager )
				)
				( attribute "CDS_LOCATION" "C3D3"
					( Origin gPackager )
				)
				( attribute "CDS_SEC" "1"
					( Origin gPackager )
				)
				( attribute "LOCATION" "C3D3"
					( Origin gFrontEnd )
				)
				( attribute "MATERIAL" "X6S"
					( Origin gFrontEnd )
				)
				( attribute "PACK_TYPE" "0603LF"
					( Origin gFrontEnd )
				)
				( attribute "PART_NUMBER" "E15431-001"
					( Origin gFrontEnd )
				)
				( attribute "PHYS_PAGE" "72"
					( Origin gFrontEnd )
				)
				( attribute "ROOM" "CPU1"
					( Origin gFrontEnd )
				)
				( attribute "ROT" "0"
					( Origin gFrontEnd )
				)
				( attribute "SEC" "1"
					( Origin gPackager )
				)
				( attribute "TOLERANCE" "20%"
					( Origin gFrontEnd )
				)
				( attribute "VALUE" "10UF"
					( Origin gFrontEnd )
				)
				( attribute "VER" "1"
					( Origin gFrontEnd )
				)
				( attribute "VOLTAGE" "4V"
					( Units "uVoltage" "V" 1.000000)
					( Origin gFrontEnd )
				)
				( attribute "XY" "(-700,1175)"
					( Origin gFrontEnd )
				)
				( attribute "CHIPS_PART_NAME" "CAP"
					( Origin gPackager )
				)
				( attribute "CDS_PART_NAME" "CAP_0603LF-10UF,4V,20%,X6S,E15A"
					( Origin gPackager )
				)
				( attribute "GROUP" "PWR_MCP_CAP"
					( Origin gFrontEnd )
				)
				( objectStatus "C3D3" )
			)
			( gate "@baseboard_fab2_lib.baseboard_fab2(sch_1):page72_i32"
				( attribute "CDS_LIB" "chpset_lib"
					( Origin gPackager )
				)
				( attribute "CDS_LOCATION" "U2D1"
					( Origin gPackager )
				)
				( attribute "CDS_SEC" "20"
					( Origin gPackager )
				)
				( attribute "LOCATION" "U2D1"
					( Origin gFrontEnd )
				)
				( attribute "MATERIAL" "IC"
					( Origin gFrontEnd )
				)
				( attribute "PACK_TYPE" "BGA1"
					( Origin gFrontEnd )
				)
				( attribute "PART_NUMBER" "TBD"
					( Origin gFrontEnd )
				)
				( attribute "PHYS_PAGE" "72"
					( Origin gFrontEnd )
				)
				( attribute "ROT" "0"
					( Origin gFrontEnd )
				)
				( attribute "SEC" "20"
					( Origin gFrontEnd )
				)
				( attribute "SEC_TYPE" "BGA1"
					( Origin gFrontEnd )
				)
				( attribute "VER" "20"
					( Origin gFrontEnd )
				)
				( attribute "XY" "(-6200,2550)"
					( Origin gFrontEnd )
				)
				( attribute "CHIPS_PART_NAME" "SKX_EXT_B"
					( Origin gPackager )
				)
				( attribute "CDS_PART_NAME" "SKX_EXT_B_BGA1-IC,TBD"
					( Origin gPackager )
				)
				( objectStatus "U2D1" )
			)
			( gate "@baseboard_fab2_lib.baseboard_fab2(sch_1):page72_i33"
				( attribute "CDS_LIB" "chpset_lib"
					( Origin gPackager )
				)
				( attribute "CDS_LOCATION" "U2D1"
					( Origin gPackager )
				)
				( attribute "CDS_SEC" "21"
					( Origin gPackager )
				)
				( attribute "LOCATION" "U2D1"
					( Origin gFrontEnd )
				)
				( attribute "MATERIAL" "IC"
					( Origin gFrontEnd )
				)
				( attribute "PACK_TYPE" "BGA1"
					( Origin gFrontEnd )
				)
				( attribute "PART_NUMBER" "TBD"
					( Origin gFrontEnd )
				)
				( attribute "PHYS_PAGE" "72"
					( Origin gFrontEnd )
				)
				( attribute "ROT" "0"
					( Origin gFrontEnd )
				)
				( attribute "SEC" "21"
					( Origin gFrontEnd )
				)
				( attribute "SEC_TYPE" "BGA1"
					( Origin gFrontEnd )
				)
				( attribute "VER" "21"
					( Origin gFrontEnd )
				)
				( attribute "XY" "(-2700,2575)"
					( Origin gFrontEnd )
				)
				( attribute "CHIPS_PART_NAME" "SKX_EXT_B"
					( Origin gPackager )
				)
				( attribute "CDS_PART_NAME" "SKX_EXT_B_BGA1-IC,TBD"
					( Origin gPackager )
				)
				( objectStatus "U2D1" )
			)
			( gate "@baseboard_fab2_lib.baseboard_fab2(sch_1):page73_i107"
				( attribute "CDS_LIB" "chpset_lib"
					( Origin gPackager )
				)
				( attribute "CDS_LOCATION" "U2D1"
					( Origin gPackager )
				)
				( attribute "CDS_SEC" "22"
					( Origin gPackager )
				)
				( attribute "LOCATION" "U2D1"
					( Origin gFrontEnd )
				)
				( attribute "MATERIAL" "IC"
					( Origin gFrontEnd )
				)
				( attribute "PACK_TYPE" "BGA1"
					( Origin gFrontEnd )
				)
				( attribute "PART_NUMBER" "TBD"
					( Origin gFrontEnd )
				)
				( attribute "PHYS_PAGE" "73"
					( Origin gFrontEnd )
				)
				( attribute "ROT" "0"
					( Origin gFrontEnd )
				)
				( attribute "SEC" "22"
					( Origin gFrontEnd )
				)
				( attribute "SEC_TYPE" "BGA1"
					( Origin gFrontEnd )
				)
				( attribute "VER" "22"
					( Origin gFrontEnd )
				)
				( attribute "XY" "(-4000,2550)"
					( Origin gFrontEnd )
				)
				( attribute "CHIPS_PART_NAME" "SKX_EXT_B"
					( Origin gPackager )
				)
				( attribute "CDS_PART_NAME" "SKX_EXT_B_BGA1-IC,TBD"
					( Origin gPackager )
				)
				( objectStatus "U2D1" )
			)
			( gate "@baseboard_fab2_lib.baseboard_fab2(sch_1):page74_i20"
				( attribute "CDS_LIB" "chpset_lib"
					( Origin gPackager )
				)
				( attribute "CDS_LOCATION" "U2D1"
					( Origin gPackager )
				)
				( attribute "CDS_SEC" "23"
					( Origin gPackager )
				)
				( attribute "LOCATION" "U2D1"
					( Origin gFrontEnd )
				)
				( attribute "MATERIAL" "IC"
					( Origin gFrontEnd )
				)
				( attribute "PACK_TYPE" "BGA1"
					( Origin gFrontEnd )
				)
				( attribute "PART_NUMBER" "TBD"
					( Origin gFrontEnd )
				)
				( attribute "PHYS_PAGE" "74"
					( Origin gFrontEnd )
				)
				( attribute "ROT" "0"
					( Origin gFrontEnd )
				)
				( attribute "SEC" "23"
					( Origin gFrontEnd )
				)
				( attribute "SEC_TYPE" "BGA1"
					( Origin gFrontEnd )
				)
				( attribute "VER" "23"
					( Origin gFrontEnd )
				)
				( attribute "XY" "(-6875,2600)"
					( Origin gFrontEnd )
				)
				( attribute "CHIPS_PART_NAME" "SKX_EXT_B"
					( Origin gPackager )
				)
				( attribute "CDS_PART_NAME" "SKX_EXT_B_BGA1-IC,TBD"
					( Origin gPackager )
				)
				( objectStatus "U2D1" )
			)
			( gate "@baseboard_fab2_lib.baseboard_fab2(sch_1):page74_i21"
				( attribute "CDS_LIB" "chpset_lib"
					( Origin gPackager )
				)
				( attribute "CDS_LOCATION" "U2D1"
					( Origin gPackager )
				)
				( attribute "CDS_SEC" "24"
					( Origin gPackager )
				)
				( attribute "LOCATION" "U2D1"
					( Origin gFrontEnd )
				)
				( attribute "MATERIAL" "IC"
					( Origin gFrontEnd )
				)
				( attribute "PACK_TYPE" "BGA1"
					( Origin gFrontEnd )
				)
				( attribute "PART_NUMBER" "TBD"
					( Origin gFrontEnd )
				)
				( attribute "PHYS_PAGE" "74"
					( Origin gFrontEnd )
				)
				( attribute "ROT" "0"
					( Origin gFrontEnd )
				)
				( attribute "SEC" "24"
					( Origin gFrontEnd )
				)
				( attribute "SEC_TYPE" "BGA1"
					( Origin gFrontEnd )
				)
				( attribute "VER" "24"
					( Origin gFrontEnd )
				)
				( attribute "XY" "(-5025,2625)"
					( Origin gFrontEnd )
				)
				( attribute "CHIPS_PART_NAME" "SKX_EXT_B"
					( Origin gPackager )
				)
				( attribute "CDS_PART_NAME" "SKX_EXT_B_BGA1-IC,TBD"
					( Origin gPackager )
				)
				( objectStatus "U2D1" )
			)
			( gate "@baseboard_fab2_lib.baseboard_fab2(sch_1):page74_i22"
				( attribute "CDS_LIB" "chpset_lib"
					( Origin gPackager )
				)
				( attribute "CDS_LOCATION" "U2D1"
					( Origin gPackager )
				)
				( attribute "CDS_SEC" "25"
					( Origin gPackager )
				)
				( attribute "LOCATION" "U2D1"
					( Origin gFrontEnd )
				)
				( attribute "MATERIAL" "IC"
					( Origin gFrontEnd )
				)
				( attribute "PACK_TYPE" "BGA1"
					( Origin gFrontEnd )
				)
				( attribute "PART_NUMBER" "TBD"
					( Origin gFrontEnd )
				)
				( attribute "PHYS_PAGE" "74"
					( Origin gFrontEnd )
				)
				( attribute "ROT" "0"
					( Origin gFrontEnd )
				)
				( attribute "SEC" "25"
					( Origin gFrontEnd )
				)
				( attribute "SEC_TYPE" "BGA1"
					( Origin gFrontEnd )
				)
				( attribute "VER" "25"
					( Origin gFrontEnd )
				)
				( attribute "XY" "(-3200,2625)"
					( Origin gFrontEnd )
				)
				( attribute "CHIPS_PART_NAME" "SKX_EXT_B"
					( Origin gPackager )
				)
				( attribute "CDS_PART_NAME" "SKX_EXT_B_BGA1-IC,TBD"
					( Origin gPackager )
				)
				( objectStatus "U2D1" )
			)
			( gate "@baseboard_fab2_lib.baseboard_fab2(sch_1):page74_i23"
				( attribute "CDS_LIB" "chpset_lib"
					( Origin gPackager )
				)
				( attribute "CDS_LOCATION" "U2D1"
					( Origin gPackager )
				)
				( attribute "CDS_SEC" "26"
					( Origin gPackager )
				)
				( attribute "LOCATION" "U2D1"
					( Origin gFrontEnd )
				)
				( attribute "MATERIAL" "IC"
					( Origin gFrontEnd )
				)
				( attribute "PACK_TYPE" "BGA1"
					( Origin gFrontEnd )
				)
				( attribute "PART_NUMBER" "TBD"
					( Origin gFrontEnd )
				)
				( attribute "PHYS_PAGE" "74"
					( Origin gFrontEnd )
				)
				( attribute "ROT" "0"
					( Origin gFrontEnd )
				)
				( attribute "SEC" "26"
					( Origin gFrontEnd )
				)
				( attribute "SEC_TYPE" "BGA1"
					( Origin gFrontEnd )
				)
				( attribute "VER" "26"
					( Origin gFrontEnd )
				)
				( attribute "XY" "(-1275,2600)"
					( Origin gFrontEnd )
				)
				( attribute "CHIPS_PART_NAME" "SKX_EXT_B"
					( Origin gPackager )
				)
				( attribute "CDS_PART_NAME" "SKX_EXT_B_BGA1-IC,TBD"
					( Origin gPackager )
				)
				( objectStatus "U2D1" )
			)
			( gate "@baseboard_fab2_lib.baseboard_fab2(sch_1):page75_i17"
				( attribute "CDS_LIB" "chpset_lib"
					( Origin gPackager )
				)
				( attribute "CDS_LOCATION" "U2D1"
					( Origin gPackager )
				)
				( attribute "CDS_SEC" "27"
					( Origin gPackager )
				)
				( attribute "LOCATION" "U2D1"
					( Origin gFrontEnd )
				)
				( attribute "MATERIAL" "IC"
					( Origin gFrontEnd )
				)
				( attribute "PACK_TYPE" "BGA1"
					( Origin gFrontEnd )
				)
				( attribute "PART_NUMBER" "TBD"
					( Origin gFrontEnd )
				)
				( attribute "PHYS_PAGE" "75"
					( Origin gFrontEnd )
				)
				( attribute "ROT" "0"
					( Origin gFrontEnd )
				)
				( attribute "SEC" "27"
					( Origin gFrontEnd )
				)
				( attribute "SEC_TYPE" "BGA1"
					( Origin gFrontEnd )
				)
				( attribute "VER" "27"
					( Origin gFrontEnd )
				)
				( attribute "XY" "(-6725,2525)"
					( Origin gFrontEnd )
				)
				( attribute "CHIPS_PART_NAME" "SKX_EXT_B"
					( Origin gPackager )
				)
				( attribute "CDS_PART_NAME" "SKX_EXT_B_BGA1-IC,TBD"
					( Origin gPackager )
				)
				( objectStatus "U2D1" )
			)
			( gate "@baseboard_fab2_lib.baseboard_fab2(sch_1):page75_i18"
				( attribute "CDS_LIB" "chpset_lib"
					( Origin gPackager )
				)
				( attribute "CDS_LOCATION" "U2D1"
					( Origin gPackager )
				)
				( attribute "CDS_SEC" "28"
					( Origin gPackager )
				)
				( attribute "LOCATION" "U2D1"
					( Origin gFrontEnd )
				)
				( attribute "MATERIAL" "IC"
					( Origin gFrontEnd )
				)
				( attribute "PACK_TYPE" "BGA1"
					( Origin gFrontEnd )
				)
				( attribute "PART_NUMBER" "TBD"
					( Origin gFrontEnd )
				)
				( attribute "PHYS_PAGE" "75"
					( Origin gFrontEnd )
				)
				( attribute "ROT" "0"
					( Origin gFrontEnd )
				)
				( attribute "SEC" "28"
					( Origin gFrontEnd )
				)
				( attribute "SEC_TYPE" "BGA1"
					( Origin gFrontEnd )
				)
				( attribute "VER" "28"
					( Origin gFrontEnd )
				)
				( attribute "XY" "(-4925,2525)"
					( Origin gFrontEnd )
				)
				( attribute "CHIPS_PART_NAME" "SKX_EXT_B"
					( Origin gPackager )
				)
				( attribute "CDS_PART_NAME" "SKX_EXT_B_BGA1-IC,TBD"
					( Origin gPackager )
				)
				( objectStatus "U2D1" )
			)
			( gate "@baseboard_fab2_lib.baseboard_fab2(sch_1):page75_i19"
				( attribute "CDS_LIB" "chpset_lib"
					( Origin gPackager )
				)
				( attribute "CDS_LOCATION" "U2D1"
					( Origin gPackager )
				)
				( attribute "CDS_SEC" "29"
					( Origin gPackager )
				)
				( attribute "LOCATION" "U2D1"
					( Origin gFrontEnd )
				)
				( attribute "MATERIAL" "IC"
					( Origin gFrontEnd )
				)
				( attribute "PACK_TYPE" "BGA1"
					( Origin gFrontEnd )
				)
				( attribute "PART_NUMBER" "TBD"
					( Origin gFrontEnd )
				)
				( attribute "PHYS_PAGE" "75"
					( Origin gFrontEnd )
				)
				( attribute "ROT" "0"
					( Origin gFrontEnd )
				)
				( attribute "SEC" "29"
					( Origin gFrontEnd )
				)
				( attribute "SEC_TYPE" "BGA1"
					( Origin gFrontEnd )
				)
				( attribute "VER" "29"
					( Origin gFrontEnd )
				)
				( attribute "XY" "(-3050,2525)"
					( Origin gFrontEnd )
				)
				( attribute "CHIPS_PART_NAME" "SKX_EXT_B"
					( Origin gPackager )
				)
				( attribute "CDS_PART_NAME" "SKX_EXT_B_BGA1-IC,TBD"
					( Origin gPackager )
				)
				( objectStatus "U2D1" )
			)
			( gate "@baseboard_fab2_lib.baseboard_fab2(sch_1):page75_i20"
				( attribute "CDS_LIB" "chpset_lib"
					( Origin gPackager )
				)
				( attribute "CDS_LOCATION" "U2D1"
					( Origin gPackager )
				)
				( attribute "CDS_SEC" "30"
					( Origin gPackager )
				)
				( attribute "LOCATION" "U2D1"
					( Origin gFrontEnd )
				)
				( attribute "MATERIAL" "IC"
					( Origin gFrontEnd )
				)
				( attribute "PACK_TYPE" "BGA1"
					( Origin gFrontEnd )
				)
				( attribute "PART_NUMBER" "TBD"
					( Origin gFrontEnd )
				)
				( attribute "PHYS_PAGE" "75"
					( Origin gFrontEnd )
				)
				( attribute "ROT" "0"
					( Origin gFrontEnd )
				)
				( attribute "SEC" "30"
					( Origin gFrontEnd )
				)
				( attribute "SEC_TYPE" "BGA1"
					( Origin gFrontEnd )
				)
				( attribute "VER" "30"
					( Origin gFrontEnd )
				)
				( attribute "XY" "(-1225,2550)"
					( Origin gFrontEnd )
				)
				( attribute "CHIPS_PART_NAME" "SKX_EXT_B"
					( Origin gPackager )
				)
				( attribute "CDS_PART_NAME" "SKX_EXT_B_BGA1-IC,TBD"
					( Origin gPackager )
				)
				( objectStatus "U2D1" )
			)
			( gate "@baseboard_fab2_lib.baseboard_fab2(sch_1):page76_i1"
				( attribute "BOM_COST" "PROC"
					( Origin gFrontEnd )
				)
				( attribute "CDS_LIB" "dev_discrete"
					( Origin gPackager )
				)
				( attribute "CDS_LOCATION" "C3D21"
					( Origin gPackager )
				)
				( attribute "CDS_SEC" "1"
					( Origin gPackager )
				)
				( attribute "LOCATION" "C3D21"
					( Origin gFrontEnd )
				)
				( attribute "MATERIAL" "X6S"
					( Origin gFrontEnd )
				)
				( attribute "PACK_TYPE" "0603V"
					( Origin gFrontEnd )
				)
				( attribute "PART_NUMBER" "E15431-004"
					( Origin gFrontEnd )
				)
				( attribute "PHYS_PAGE" "76"
					( Origin gFrontEnd )
				)
				( attribute "ROOM" "PVCCIN_CPU1_DECAP_VR"
					( Origin gFrontEnd )
				)
				( attribute "ROT" "0"
					( Origin gFrontEnd )
				)
				( attribute "SEC" "1"
					( Origin gPackager )
				)
				( attribute "TOLERANCE" "20%"
					( Origin gFrontEnd )
				)
				( attribute "VALUE" "22.0UF"
					( Origin gFrontEnd )
				)
				( attribute "VER" "1"
					( Origin gFrontEnd )
				)
				( attribute "VOLTAGE" "4V"
					( Units "uVoltage" "V" 1.000000)
					( Origin gFrontEnd )
				)
				( attribute "XY" "(-1275,4450)"
					( Origin gFrontEnd )
				)
				( attribute "CHIPS_PART_NAME" "CAP_A"
					( Origin gPackager )
				)
				( attribute "CDS_PART_NAME" "CAP_A_0603V-22.0UF,4V,20%,X6S,A"
					( Origin gPackager )
				)
				( attribute "GROUP" "PWR_MCP_CAP"
					( Origin gFrontEnd )
				)
				( objectStatus "C3D21" )
			)
			( gate "@baseboard_fab2_lib.baseboard_fab2(sch_1):page76_i3"
				( attribute "BOM_COST" "PROC"
					( Origin gFrontEnd )
				)
				( attribute "CDS_LIB" "dev_discrete"
					( Origin gPackager )
				)
				( attribute "CDS_LOCATION" "C3D5"
					( Origin gPackager )
				)
				( attribute "CDS_SEC" "1"
					( Origin gPackager )
				)
				( attribute "LOCATION" "C3D5"
					( Origin gFrontEnd )
				)
				( attribute "MATERIAL" "X6S"
					( Origin gFrontEnd )
				)
				( attribute "PACK_TYPE" "0603V"
					( Origin gFrontEnd )
				)
				( attribute "PART_NUMBER" "E15431-004"
					( Origin gFrontEnd )
				)
				( attribute "PHYS_PAGE" "76"
					( Origin gFrontEnd )
				)
				( attribute "ROOM" "PVCCIN_CPU1_DECAP_VR"
					( Origin gFrontEnd )
				)
				( attribute "ROT" "0"
					( Origin gFrontEnd )
				)
				( attribute "SEC" "1"
					( Origin gPackager )
				)
				( attribute "TOLERANCE" "20%"
					( Origin gFrontEnd )
				)
				( attribute "VALUE" "22.0UF"
					( Origin gFrontEnd )
				)
				( attribute "VER" "1"
					( Origin gFrontEnd )
				)
				( attribute "VOLTAGE" "4V"
					( Units "uVoltage" "V" 1.000000)
					( Origin gFrontEnd )
				)
				( attribute "XY" "(-1600,4450)"
					( Origin gFrontEnd )
				)
				( attribute "CHIPS_PART_NAME" "CAP_A"
					( Origin gPackager )
				)
				( attribute "CDS_PART_NAME" "CAP_A_0603V-22.0UF,4V,20%,X6S,A"
					( Origin gPackager )
				)
				( attribute "GROUP" "PWR_MCP_CAP"
					( Origin gFrontEnd )
				)
				( objectStatus "C3D5" )
			)
			( gate "@baseboard_fab2_lib.baseboard_fab2(sch_1):page76_i4"
				( attribute "BOM_COST" "PROC"
					( Origin gFrontEnd )
				)
				( attribute "CDS_LIB" "dev_discrete"
					( Origin gPackager )
				)
				( attribute "CDS_LOCATION" "C3D12"
					( Origin gPackager )
				)
				( attribute "CDS_SEC" "1"
					( Origin gPackager )
				)
				( attribute "LOCATION" "C3D12"
					( Origin gFrontEnd )
				)
				( attribute "MATERIAL" "X6S"
					( Origin gFrontEnd )
				)
				( attribute "PACK_TYPE" "0603V"
					( Origin gFrontEnd )
				)
				( attribute "PART_NUMBER" "E15431-004"
					( Origin gFrontEnd )
				)
				( attribute "PHYS_PAGE" "76"
					( Origin gFrontEnd )
				)
				( attribute "ROOM" "PVCCIN_CPU1_DECAP_VR"
					( Origin gFrontEnd )
				)
				( attribute "ROT" "0"
					( Origin gFrontEnd )
				)
				( attribute "SEC" "1"
					( Origin gPackager )
				)
				( attribute "TOLERANCE" "20%"
					( Origin gFrontEnd )
				)
				( attribute "VALUE" "22.0UF"
					( Origin gFrontEnd )
				)
				( attribute "VER" "1"
					( Origin gFrontEnd )
				)
				( attribute "VOLTAGE" "4V"
					( Units "uVoltage" "V" 1.000000)
					( Origin gFrontEnd )
				)
				( attribute "XY" "(-1875,4450)"
					( Origin gFrontEnd )
				)
				( attribute "CHIPS_PART_NAME" "CAP_A"
					( Origin gPackager )
				)
				( attribute "CDS_PART_NAME" "CAP_A_0603V-22.0UF,4V,20%,X6S,A"
					( Origin gPackager )
				)
				( attribute "GROUP" "PWR_MCP_CAP"
					( Origin gFrontEnd )
				)
				( objectStatus "C3D12" )
			)
			( gate "@baseboard_fab2_lib.baseboard_fab2(sch_1):page76_i5"
				( attribute "BOM_COST" "PROC"
					( Origin gFrontEnd )
				)
				( attribute "CDS_LIB" "dev_discrete"
					( Origin gPackager )
				)
				( attribute "CDS_LOCATION" "C3D4"
					( Origin gPackager )
				)
				( attribute "CDS_SEC" "1"
					( Origin gPackager )
				)
				( attribute "LOCATION" "C3D4"
					( Origin gFrontEnd )
				)
				( attribute "MATERIAL" "X6S"
					( Origin gFrontEnd )
				)
				( attribute "PACK_TYPE" "0603V"
					( Origin gFrontEnd )
				)
				( attribute "PART_NUMBER" "E15431-004"
					( Origin gFrontEnd )
				)
				( attribute "PHYS_PAGE" "76"
					( Origin gFrontEnd )
				)
				( attribute "ROOM" "PVCCIN_CPU1_DECAP_VR"
					( Origin gFrontEnd )
				)
				( attribute "ROT" "0"
					( Origin gFrontEnd )
				)
				( attribute "SEC" "1"
					( Origin gPackager )
				)
				( attribute "TOLERANCE" "20%"
					( Origin gFrontEnd )
				)
				( attribute "VALUE" "22.0UF"
					( Origin gFrontEnd )
				)
				( attribute "VER" "1"
					( Origin gFrontEnd )
				)
				( attribute "VOLTAGE" "4V"
					( Units "uVoltage" "V" 1.000000)
					( Origin gFrontEnd )
				)
				( attribute "XY" "(-2175,4450)"
					( Origin gFrontEnd )
				)
				( attribute "CHIPS_PART_NAME" "CAP_A"
					( Origin gPackager )
				)
				( attribute "CDS_PART_NAME" "CAP_A_0603V-22.0UF,4V,20%,X6S,A"
					( Origin gPackager )
				)
				( attribute "GROUP" "PWR_MCP_CAP"
					( Origin gFrontEnd )
				)
				( objectStatus "C3D4" )
			)
			( gate "@baseboard_fab2_lib.baseboard_fab2(sch_1):page76_i7"
				( attribute "BOM_COST" "PROC"
					( Origin gFrontEnd )
				)
				( attribute "CDS_LIB" "dev_discrete"
					( Origin gPackager )
				)
				( attribute "CDS_LOCATION" "C3D11"
					( Origin gPackager )
				)
				( attribute "CDS_SEC" "1"
					( Origin gPackager )
				)
				( attribute "LOCATION" "C3D11"
					( Origin gFrontEnd )
				)
				( attribute "MATERIAL" "X6S"
					( Origin gFrontEnd )
				)
				( attribute "PACK_TYPE" "0603V"
					( Origin gFrontEnd )
				)
				( attribute "PART_NUMBER" "E15431-004"
					( Origin gFrontEnd )
				)
				( attribute "PHYS_PAGE" "76"
					( Origin gFrontEnd )
				)
				( attribute "ROOM" "PVCCIN_CPU1_DECAP_VR"
					( Origin gFrontEnd )
				)
				( attribute "ROT" "0"
					( Origin gFrontEnd )
				)
				( attribute "SEC" "1"
					( Origin gPackager )
				)
				( attribute "TOLERANCE" "20%"
					( Origin gFrontEnd )
				)
				( attribute "VALUE" "22.0UF"
					( Origin gFrontEnd )
				)
				( attribute "VER" "1"
					( Origin gFrontEnd )
				)
				( attribute "VOLTAGE" "4V"
					( Units "uVoltage" "V" 1.000000)
					( Origin gFrontEnd )
				)
				( attribute "XY" "(-2450,4450)"
					( Origin gFrontEnd )
				)
				( attribute "CHIPS_PART_NAME" "CAP_A"
					( Origin gPackager )
				)
				( attribute "CDS_PART_NAME" "CAP_A_0603V-22.0UF,4V,20%,X6S,A"
					( Origin gPackager )
				)
				( attribute "GROUP" "PWR_MCP_CAP"
					( Origin gFrontEnd )
				)
				( objectStatus "C3D11" )
			)
			( gate "@baseboard_fab2_lib.baseboard_fab2(sch_1):page76_i8"
				( attribute "BOM_COST" "PROC"
					( Origin gFrontEnd )
				)
				( attribute "CDS_LIB" "dev_discrete"
					( Origin gPackager )
				)
				( attribute "CDS_LOCATION" "C3D13"
					( Origin gPackager )
				)
				( attribute "CDS_SEC" "1"
					( Origin gPackager )
				)
				( attribute "LOCATION" "C3D13"
					( Origin gFrontEnd )
				)
				( attribute "MATERIAL" "X6S"
					( Origin gFrontEnd )
				)
				( attribute "PACK_TYPE" "0603V"
					( Origin gFrontEnd )
				)
				( attribute "PART_NUMBER" "E15431-004"
					( Origin gFrontEnd )
				)
				( attribute "PHYS_PAGE" "76"
					( Origin gFrontEnd )
				)
				( attribute "ROOM" "PVCCIN_CPU1_DECAP_VR"
					( Origin gFrontEnd )
				)
				( attribute "ROT" "0"
					( Origin gFrontEnd )
				)
				( attribute "SEC" "1"
					( Origin gPackager )
				)
				( attribute "TOLERANCE" "20%"
					( Origin gFrontEnd )
				)
				( attribute "VALUE" "22.0UF"
					( Origin gFrontEnd )
				)
				( attribute "VER" "1"
					( Origin gFrontEnd )
				)
				( attribute "VOLTAGE" "4V"
					( Units "uVoltage" "V" 1.000000)
					( Origin gFrontEnd )
				)
				( attribute "XY" "(-2975,4450)"
					( Origin gFrontEnd )
				)
				( attribute "CHIPS_PART_NAME" "CAP_A"
					( Origin gPackager )
				)
				( attribute "CDS_PART_NAME" "CAP_A_0603V-22.0UF,4V,20%,X6S,A"
					( Origin gPackager )
				)
				( attribute "GROUP" "PWR_MCP_CAP"
					( Origin gFrontEnd )
				)
				( objectStatus "C3D13" )
			)
			( gate "@baseboard_fab2_lib.baseboard_fab2(sch_1):page76_i10"
				( attribute "BOM_COST" "PROC"
					( Origin gFrontEnd )
				)
				( attribute "CDS_LIB" "dev_discrete"
					( Origin gPackager )
				)
				( attribute "CDS_LOCATION" "C2D40"
					( Origin gPackager )
				)
				( attribute "CDS_SEC" "1"
					( Origin gPackager )
				)
				( attribute "LOCATION" "C2D40"
					( Origin gFrontEnd )
				)
				( attribute "MATERIAL" "X6S"
					( Origin gFrontEnd )
				)
				( attribute "PACK_TYPE" "0603V"
					( Origin gFrontEnd )
				)
				( attribute "PART_NUMBER" "E15431-004"
					( Origin gFrontEnd )
				)
				( attribute "PHYS_PAGE" "76"
					( Origin gFrontEnd )
				)
				( attribute "ROOM" "PVCCIN_CPU1_DECAP_VR"
					( Origin gFrontEnd )
				)
				( attribute "ROT" "0"
					( Origin gFrontEnd )
				)
				( attribute "SEC" "1"
					( Origin gPackager )
				)
				( attribute "TOLERANCE" "20%"
					( Origin gFrontEnd )
				)
				( attribute "VALUE" "22.0UF"
					( Origin gFrontEnd )
				)
				( attribute "VER" "1"
					( Origin gFrontEnd )
				)
				( attribute "VOLTAGE" "4V"
					( Units "uVoltage" "V" 1.000000)
					( Origin gFrontEnd )
				)
				( attribute "XY" "(-3250,4450)"
					( Origin gFrontEnd )
				)
				( attribute "CHIPS_PART_NAME" "CAP_A"
					( Origin gPackager )
				)
				( attribute "CDS_PART_NAME" "CAP_A_0603V-22.0UF,4V,20%,X6S,A"
					( Origin gPackager )
				)
				( attribute "GROUP" "PWR_MCP_CAP"
					( Origin gFrontEnd )
				)
				( objectStatus "C2D40" )
			)
			( gate "@baseboard_fab2_lib.baseboard_fab2(sch_1):page76_i15"
				( attribute "BOM_COST" "PROC"
					( Origin gFrontEnd )
				)
				( attribute "CDS_LIB" "dev_discrete"
					( Origin gPackager )
				)
				( attribute "CDS_LOCATION" "C3D9"
					( Origin gPackager )
				)
				( attribute "CDS_SEC" "1"
					( Origin gPackager )
				)
				( attribute "LOCATION" "C3D9"
					( Origin gFrontEnd )
				)
				( attribute "MATERIAL" "X6S"
					( Origin gFrontEnd )
				)
				( attribute "PACK_TYPE" "0603V"
					( Origin gFrontEnd )
				)
				( attribute "PART_NUMBER" "E15431-004"
					( Origin gFrontEnd )
				)
				( attribute "PHYS_PAGE" "76"
					( Origin gFrontEnd )
				)
				( attribute "ROOM" "PVCCIN_CPU1_DECAP_VR"
					( Origin gFrontEnd )
				)
				( attribute "ROT" "0"
					( Origin gFrontEnd )
				)
				( attribute "SEC" "1"
					( Origin gPackager )
				)
				( attribute "TOLERANCE" "20%"
					( Origin gFrontEnd )
				)
				( attribute "VALUE" "22.0UF"
					( Origin gFrontEnd )
				)
				( attribute "VER" "1"
					( Origin gFrontEnd )
				)
				( attribute "VOLTAGE" "4V"
					( Units "uVoltage" "V" 1.000000)
					( Origin gFrontEnd )
				)
				( attribute "XY" "(-2350,3750)"
					( Origin gFrontEnd )
				)
				( attribute "CHIPS_PART_NAME" "CAP_A"
					( Origin gPackager )
				)
				( attribute "CDS_PART_NAME" "CAP_A_0603V-22.0UF,4V,20%,X6S,A"
					( Origin gPackager )
				)
				( attribute "GROUP" "PWR_MLCC_CAP"
					( Origin gFrontEnd )
				)
				( objectStatus "C3D9" )
			)
			( gate "@baseboard_fab2_lib.baseboard_fab2(sch_1):page76_i18"
				( attribute "BOM_COST" "PROC"
					( Origin gFrontEnd )
				)
				( attribute "CDS_LIB" "dev_discrete"
					( Origin gPackager )
				)
				( attribute "CDS_LOCATION" "C3D8"
					( Origin gPackager )
				)
				( attribute "CDS_SEC" "1"
					( Origin gPackager )
				)
				( attribute "LOCATION" "C3D8"
					( Origin gFrontEnd )
				)
				( attribute "MATERIAL" "X6S"
					( Origin gFrontEnd )
				)
				( attribute "PACK_TYPE" "0603V"
					( Origin gFrontEnd )
				)
				( attribute "PART_NUMBER" "E15431-004"
					( Origin gFrontEnd )
				)
				( attribute "PHYS_PAGE" "76"
					( Origin gFrontEnd )
				)
				( attribute "ROOM" "PVCCIN_CPU1_DECAP_VR"
					( Origin gFrontEnd )
				)
				( attribute "ROT" "0"
					( Origin gFrontEnd )
				)
				( attribute "SEC" "1"
					( Origin gPackager )
				)
				( attribute "TOLERANCE" "20%"
					( Origin gFrontEnd )
				)
				( attribute "VALUE" "22.0UF"
					( Origin gFrontEnd )
				)
				( attribute "VER" "1"
					( Origin gFrontEnd )
				)
				( attribute "VOLTAGE" "4V"
					( Units "uVoltage" "V" 1.000000)
					( Origin gFrontEnd )
				)
				( attribute "XY" "(-2650,3750)"
					( Origin gFrontEnd )
				)
				( attribute "CHIPS_PART_NAME" "CAP_A"
					( Origin gPackager )
				)
				( attribute "CDS_PART_NAME" "CAP_A_0603V-22.0UF,4V,20%,X6S,A"
					( Origin gPackager )
				)
				( attribute "GROUP" "PWR_MLCC_CAP"
					( Origin gFrontEnd )
				)
				( objectStatus "C3D8" )
			)
			( gate "@baseboard_fab2_lib.baseboard_fab2(sch_1):page76_i271"
				( attribute "BOM_COST" "MEM_VRD_PVDDQ_CD"
					( Origin gFrontEnd )
				)
				( attribute "CDS_LIB" "mstr_discrete"
					( Origin gPackager )
				)
				( attribute "CDS_LOCATION" "C7P4"
					( Origin gPackager )
				)
				( attribute "CDS_SEC" "1"
					( Origin gPackager )
				)
				( attribute "LOCATION" "C7P4"
					( Origin gFrontEnd )
				)
				( attribute "MATERIAL" "X5R"
					( Origin gFrontEnd )
				)
				( attribute "NEW_MATERIAL" "X6S"
					( Origin gFrontEnd )
				)
				( attribute "PACK_TYPE" "0805"
					( Origin gFrontEnd )
				)
				( attribute "PART_NUMBER" "602433-112"
					( Origin gFrontEnd )
				)
				( attribute "PHYS_PAGE" "76"
					( Origin gFrontEnd )
				)
				( attribute "ROOM" "VDDQ_ABC_PWR_VR"
					( Origin gFrontEnd )
				)
				( attribute "ROT" "0"
					( Origin gFrontEnd )
				)
				( attribute "SEC" "1"
					( Origin gFrontEnd )
				)
				( attribute "SEC_TYPE" "0805"
					( Origin gFrontEnd )
				)
				( attribute "TOLERANCE" "20%"
					( Origin gFrontEnd )
				)
				( attribute "VALUE" "100UF"
					( Origin gFrontEnd )
				)
				( attribute "VER" "1"
					( Origin gFrontEnd )
				)
				( attribute "VOLTAGE" "4V"
					( Units "uVoltage" "V" 1.000000)
					( Origin gFrontEnd )
				)
				( attribute "XY" "(-1600,2200)"
					( Origin gFrontEnd )
				)
				( attribute "CHIPS_PART_NAME" "CAP"
					( Origin gPackager )
				)
				( attribute "CDS_PART_NAME" "CAP_0805-100UF,4V,20%,X5R,6024A"
					( Origin gPackager )
				)
				( attribute "NEW_PN" "078.1071T.M002"
					( Origin gFrontEnd )
				)
				( attribute "GROUP" "PWR_MCP_CAP"
					( Origin gFrontEnd )
				)
				( objectStatus "C7P4" )
			)
			( gate "@baseboard_fab2_lib.baseboard_fab2(sch_1):page76_i270"
				( attribute "BOM_COST" "MEM_VRD_PVDDQ_CD"
					( Origin gFrontEnd )
				)
				( attribute "CDS_LIB" "mstr_discrete"
					( Origin gPackager )
				)
				( attribute "CDS_LOCATION" "C8P15"
					( Origin gPackager )
				)
				( attribute "CDS_SEC" "1"
					( Origin gPackager )
				)
				( attribute "LOCATION" "C8P15"
					( Origin gFrontEnd )
				)
				( attribute "MATERIAL" "X5R"
					( Origin gFrontEnd )
				)
				( attribute "NEW_MATERIAL" "X6S"
					( Origin gFrontEnd )
				)
				( attribute "PACK_TYPE" "0805"
					( Origin gFrontEnd )
				)
				( attribute "PART_NUMBER" "602433-112"
					( Origin gFrontEnd )
				)
				( attribute "PHYS_PAGE" "76"
					( Origin gFrontEnd )
				)
				( attribute "ROOM" "VDDQ_ABC_PWR_VR"
					( Origin gFrontEnd )
				)
				( attribute "ROT" "0"
					( Origin gFrontEnd )
				)
				( attribute "SEC" "1"
					( Origin gFrontEnd )
				)
				( attribute "SEC_TYPE" "0805"
					( Origin gFrontEnd )
				)
				( attribute "TOLERANCE" "20%"
					( Origin gFrontEnd )
				)
				( attribute "VALUE" "100UF"
					( Origin gFrontEnd )
				)
				( attribute "VER" "1"
					( Origin gFrontEnd )
				)
				( attribute "VOLTAGE" "4V"
					( Units "uVoltage" "V" 1.000000)
					( Origin gFrontEnd )
				)
				( attribute "XY" "(-1350,2200)"
					( Origin gFrontEnd )
				)
				( attribute "CHIPS_PART_NAME" "CAP"
					( Origin gPackager )
				)
				( attribute "CDS_PART_NAME" "CAP_0805-100UF,4V,20%,X5R,6024A"
					( Origin gPackager )
				)
				( attribute "NEW_PN" "078.1071T.M002"
					( Origin gFrontEnd )
				)
				( attribute "GROUP" "PWR_MCP_CAP"
					( Origin gFrontEnd )
				)
				( objectStatus "C8P15" )
			)
			( gate "@baseboard_fab2_lib.baseboard_fab2(sch_1):page76_i269"
				( attribute "BOM_COST" "MEM_VRD_PVDDQ_CD"
					( Origin gFrontEnd )
				)
				( attribute "CDS_LIB" "mstr_discrete"
					( Origin gPackager )
				)
				( attribute "CDS_LOCATION" "C7P13"
					( Origin gPackager )
				)
				( attribute "CDS_SEC" "1"
					( Origin gPackager )
				)
				( attribute "LOCATION" "C7P13"
					( Origin gFrontEnd )
				)
				( attribute "MATERIAL" "X5R"
					( Origin gFrontEnd )
				)
				( attribute "NEW_MATERIAL" "X6S"
					( Origin gFrontEnd )
				)
				( attribute "PACK_TYPE" "0805"
					( Origin gFrontEnd )
				)
				( attribute "PART_NUMBER" "602433-112"
					( Origin gFrontEnd )
				)
				( attribute "PHYS_PAGE" "76"
					( Origin gFrontEnd )
				)
				( attribute "ROOM" "VDDQ_ABC_PWR_VR"
					( Origin gFrontEnd )
				)
				( attribute "ROT" "0"
					( Origin gFrontEnd )
				)
				( attribute "SEC" "1"
					( Origin gFrontEnd )
				)
				( attribute "SEC_TYPE" "0805"
					( Origin gFrontEnd )
				)
				( attribute "TOLERANCE" "20%"
					( Origin gFrontEnd )
				)
				( attribute "VALUE" "100UF"
					( Origin gFrontEnd )
				)
				( attribute "VER" "1"
					( Origin gFrontEnd )
				)
				( attribute "VOLTAGE" "4V"
					( Units "uVoltage" "V" 1.000000)
					( Origin gFrontEnd )
				)
				( attribute "XY" "(-2100,2200)"
					( Origin gFrontEnd )
				)
				( attribute "CHIPS_PART_NAME" "CAP"
					( Origin gPackager )
				)
				( attribute "CDS_PART_NAME" "CAP_0805-100UF,4V,20%,X5R,6024A"
					( Origin gPackager )
				)
				( attribute "NEW_PN" "078.1071T.M002"
					( Origin gFrontEnd )
				)
				( attribute "GROUP" "PWR_MCP_CAP"
					( Origin gFrontEnd )
				)
				( objectStatus "C7P13" )
			)
			( gate "@baseboard_fab2_lib.baseboard_fab2(sch_1):page76_i29"
				( attribute "BOM_COST" "PROC"
					( Origin gFrontEnd )
				)
				( attribute "CDS_LIB" "mstr_discrete"
					( Origin gPackager )
				)
				( attribute "CDS_LOCATION" "C7P17"
					( Origin gPackager )
				)
				( attribute "CDS_SEC" "1"
					( Origin gPackager )
				)
				( attribute "LOCATION" "C7P17"
					( Origin gFrontEnd )
				)
				( attribute "MATERIAL" "X6S"
					( Origin gFrontEnd )
				)
				( attribute "PACK_TYPE" "0805"
					( Origin gFrontEnd )
				)
				( attribute "PART_NUMBER" "C95333-006"
					( Origin gFrontEnd )
				)
				( attribute "PHYS_PAGE" "76"
					( Origin gFrontEnd )
				)
				( attribute "ROOM" "PVCCIN_CPU1_DECAP_VR"
					( Origin gFrontEnd )
				)
				( attribute "ROT" "0"
					( Origin gFrontEnd )
				)
				( attribute "SEC" "1"
					( Origin gPackager )
				)
				( attribute "TOLERANCE" "20%"
					( Origin gFrontEnd )
				)
				( attribute "VALUE" "47UF"
					( Origin gFrontEnd )
				)
				( attribute "VER" "1"
					( Origin gFrontEnd )
				)
				( attribute "VOLTAGE" "4V"
					( Units "uVoltage" "V" 1.000000)
					( Origin gFrontEnd )
				)
				( attribute "XY" "(-2700,1150)"
					( Origin gFrontEnd )
				)
				( attribute "CHIPS_PART_NAME" "CAP"
					( Origin gPackager )
				)
				( attribute "CDS_PART_NAME" "CAP_0805-47UF,4V,20%,X6S,C9533A"
					( Origin gPackager )
				)
				( attribute "GROUP" "PWR_MLCC_CAP"
					( Origin gFrontEnd )
				)
				( objectStatus "C7P17" )
			)
			( gate "@baseboard_fab2_lib.baseboard_fab2(sch_1):page76_i33"
				( attribute "BOM_COST" "PROC"
					( Origin gFrontEnd )
				)
				( attribute "CDS_LIB" "mstr_discrete"
					( Origin gPackager )
				)
				( attribute "CDS_LOCATION" "C2D8"
					( Origin gPackager )
				)
				( attribute "CDS_SEC" "1"
					( Origin gPackager )
				)
				( attribute "LOCATION" "C2D8"
					( Origin gFrontEnd )
				)
				( attribute "MATERIAL" "X6S"
					( Origin gFrontEnd )
				)
				( attribute "PACK_TYPE" "0603LF"
					( Origin gFrontEnd )
				)
				( attribute "PART_NUMBER" "E15431-001"
					( Origin gFrontEnd )
				)
				( attribute "PHYS_PAGE" "76"
					( Origin gFrontEnd )
				)
				( attribute "ROOM" "PVCCIN_CPU1_DECAP_VR"
					( Origin gFrontEnd )
				)
				( attribute "ROT" "0"
					( Origin gFrontEnd )
				)
				( attribute "SEC" "1"
					( Origin gPackager )
				)
				( attribute "TOLERANCE" "20%"
					( Origin gFrontEnd )
				)
				( attribute "VALUE" "10UF"
					( Origin gFrontEnd )
				)
				( attribute "VER" "1"
					( Origin gFrontEnd )
				)
				( attribute "VOLTAGE" "4V"
					( Units "uVoltage" "V" 1.000000)
					( Origin gFrontEnd )
				)
				( attribute "XY" "(-3050,3100)"
					( Origin gFrontEnd )
				)
				( attribute "CHIPS_PART_NAME" "CAP"
					( Origin gPackager )
				)
				( attribute "CDS_PART_NAME" "CAP_0603LF-10UF,4V,20%,X6S,E15A"
					( Origin gPackager )
				)
				( attribute "GROUP" "PWR_MLCC_CAP"
					( Origin gFrontEnd )
				)
				( objectStatus "C2D8" )
			)
			( gate "@baseboard_fab2_lib.baseboard_fab2(sch_1):page76_i37"
				( attribute "BOM_COST" "PROC"
					( Origin gFrontEnd )
				)
				( attribute "CDS_LIB" "mstr_discrete"
					( Origin gPackager )
				)
				( attribute "CDS_LOCATION" "C2D10"
					( Origin gPackager )
				)
				( attribute "CDS_SEC" "1"
					( Origin gPackager )
				)
				( attribute "LOCATION" "C2D10"
					( Origin gFrontEnd )
				)
				( attribute "MATERIAL" "X6S"
					( Origin gFrontEnd )
				)
				( attribute "PACK_TYPE" "0603LF"
					( Origin gFrontEnd )
				)
				( attribute "PART_NUMBER" "E15431-001"
					( Origin gFrontEnd )
				)
				( attribute "PHYS_PAGE" "76"
					( Origin gFrontEnd )
				)
				( attribute "ROOM" "PVCCIN_CPU1_DECAP_VR"
					( Origin gFrontEnd )
				)
				( attribute "ROT" "0"
					( Origin gFrontEnd )
				)
				( attribute "SEC" "1"
					( Origin gPackager )
				)
				( attribute "TOLERANCE" "20%"
					( Origin gFrontEnd )
				)
				( attribute "VALUE" "10UF"
					( Origin gFrontEnd )
				)
				( attribute "VER" "1"
					( Origin gFrontEnd )
				)
				( attribute "VOLTAGE" "4V"
					( Units "uVoltage" "V" 1.000000)
					( Origin gFrontEnd )
				)
				( attribute "XY" "(-3350,3100)"
					( Origin gFrontEnd )
				)
				( attribute "CHIPS_PART_NAME" "CAP"
					( Origin gPackager )
				)
				( attribute "CDS_PART_NAME" "CAP_0603LF-10UF,4V,20%,X6S,E15A"
					( Origin gPackager )
				)
				( attribute "GROUP" "PWR_MLCC_CAP"
					( Origin gFrontEnd )
				)
				( objectStatus "C2D10" )
			)
			( gate "@baseboard_fab2_lib.baseboard_fab2(sch_1):page76_i42"
				( attribute "BOM_COST" "PROC"
					( Origin gFrontEnd )
				)
				( attribute "CDS_LIB" "mstr_discrete"
					( Origin gPackager )
				)
				( attribute "CDS_LOCATION" "C2D11"
					( Origin gPackager )
				)
				( attribute "CDS_SEC" "1"
					( Origin gPackager )
				)
				( attribute "LOCATION" "C2D11"
					( Origin gFrontEnd )
				)
				( attribute "MATERIAL" "X6S"
					( Origin gFrontEnd )
				)
				( attribute "PACK_TYPE" "0603LF"
					( Origin gFrontEnd )
				)
				( attribute "PART_NUMBER" "E15431-001"
					( Origin gFrontEnd )
				)
				( attribute "PHYS_PAGE" "76"
					( Origin gFrontEnd )
				)
				( attribute "ROOM" "PVCCIN_CPU1_DECAP_VR"
					( Origin gFrontEnd )
				)
				( attribute "ROT" "0"
					( Origin gFrontEnd )
				)
				( attribute "SEC" "1"
					( Origin gPackager )
				)
				( attribute "TOLERANCE" "20%"
					( Origin gFrontEnd )
				)
				( attribute "VALUE" "10UF"
					( Origin gFrontEnd )
				)
				( attribute "VER" "1"
					( Origin gFrontEnd )
				)
				( attribute "VOLTAGE" "4V"
					( Units "uVoltage" "V" 1.000000)
					( Origin gFrontEnd )
				)
				( attribute "XY" "(-3650,3100)"
					( Origin gFrontEnd )
				)
				( attribute "CHIPS_PART_NAME" "CAP"
					( Origin gPackager )
				)
				( attribute "CDS_PART_NAME" "CAP_0603LF-10UF,4V,20%,X6S,E15A"
					( Origin gPackager )
				)
				( attribute "GROUP" "PWR_MLCC_CAP"
					( Origin gFrontEnd )
				)
				( objectStatus "C2D11" )
			)
			( gate "@baseboard_fab2_lib.baseboard_fab2(sch_1):page76_i43"
				( attribute "BOM_COST" "PROC"
					( Origin gFrontEnd )
				)
				( attribute "CDS_LIB" "mstr_discrete"
					( Origin gPackager )
				)
				( attribute "CDS_LOCATION" "C2D9"
					( Origin gPackager )
				)
				( attribute "CDS_SEC" "1"
					( Origin gPackager )
				)
				( attribute "LOCATION" "C2D9"
					( Origin gFrontEnd )
				)
				( attribute "MATERIAL" "X6S"
					( Origin gFrontEnd )
				)
				( attribute "PACK_TYPE" "0603LF"
					( Origin gFrontEnd )
				)
				( attribute "PART_NUMBER" "E15431-001"
					( Origin gFrontEnd )
				)
				( attribute "PHYS_PAGE" "76"
					( Origin gFrontEnd )
				)
				( attribute "ROOM" "PVCCIN_CPU1_DECAP_VR"
					( Origin gFrontEnd )
				)
				( attribute "ROT" "0"
					( Origin gFrontEnd )
				)
				( attribute "SEC" "1"
					( Origin gPackager )
				)
				( attribute "TOLERANCE" "20%"
					( Origin gFrontEnd )
				)
				( attribute "VALUE" "10UF"
					( Origin gFrontEnd )
				)
				( attribute "VER" "1"
					( Origin gFrontEnd )
				)
				( attribute "VOLTAGE" "4V"
					( Units "uVoltage" "V" 1.000000)
					( Origin gFrontEnd )
				)
				( attribute "XY" "(-3950,3100)"
					( Origin gFrontEnd )
				)
				( attribute "CHIPS_PART_NAME" "CAP"
					( Origin gPackager )
				)
				( attribute "CDS_PART_NAME" "CAP_0603LF-10UF,4V,20%,X6S,E15A"
					( Origin gPackager )
				)
				( attribute "GROUP" "PWR_MLCC_CAP"
					( Origin gFrontEnd )
				)
				( objectStatus "C2D9" )
			)
			( gate "@baseboard_fab2_lib.baseboard_fab2(sch_1):page76_i265"
				( attribute "BOM_COST" "MEM_VRD_PVDDQ_CD"
					( Origin gFrontEnd )
				)
				( attribute "CDS_LIB" "mstr_discrete"
					( Origin gPackager )
				)
				( attribute "CDS_LOCATION" "C7P8"
					( Origin gPackager )
				)
				( attribute "CDS_SEC" "1"
					( Origin gPackager )
				)
				( attribute "LOCATION" "C7P8"
					( Origin gFrontEnd )
				)
				( attribute "MATERIAL" "X5R"
					( Origin gFrontEnd )
				)
				( attribute "NEW_MATERIAL" "X6S"
					( Origin gFrontEnd )
				)
				( attribute "PACK_TYPE" "0805"
					( Origin gFrontEnd )
				)
				( attribute "PART_NUMBER" "602433-112"
					( Origin gFrontEnd )
				)
				( attribute "PHYS_PAGE" "76"
					( Origin gFrontEnd )
				)
				( attribute "ROOM" "VDDQ_ABC_PWR_VR"
					( Origin gFrontEnd )
				)
				( attribute "ROT" "0"
					( Origin gFrontEnd )
				)
				( attribute "SEC" "1"
					( Origin gFrontEnd )
				)
				( attribute "SEC_TYPE" "0805"
					( Origin gFrontEnd )
				)
				( attribute "TOLERANCE" "20%"
					( Origin gFrontEnd )
				)
				( attribute "VALUE" "100UF"
					( Origin gFrontEnd )
				)
				( attribute "VER" "1"
					( Origin gFrontEnd )
				)
				( attribute "VOLTAGE" "4V"
					( Units "uVoltage" "V" 1.000000)
					( Origin gFrontEnd )
				)
				( attribute "XY" "(-3100,2200)"
					( Origin gFrontEnd )
				)
				( attribute "CHIPS_PART_NAME" "CAP"
					( Origin gPackager )
				)
				( attribute "CDS_PART_NAME" "CAP_0805-100UF,4V,20%,X5R,6024A"
					( Origin gPackager )
				)
				( attribute "NEW_PN" "078.1071T.M002"
					( Origin gFrontEnd )
				)
				( attribute "GROUP" "PWR_MCP_CAP"
					( Origin gFrontEnd )
				)
				( objectStatus "C7P8" )
			)
			( gate "@baseboard_fab2_lib.baseboard_fab2(sch_1):page76_i263"
				( attribute "BOM_COST" "MEM_VRD_PVDDQ_CD"
					( Origin gFrontEnd )
				)
				( attribute "CDS_LIB" "mstr_discrete"
					( Origin gPackager )
				)
				( attribute "CDS_LOCATION" "C7P15"
					( Origin gPackager )
				)
				( attribute "CDS_SEC" "1"
					( Origin gPackager )
				)
				( attribute "LOCATION" "C7P15"
					( Origin gFrontEnd )
				)
				( attribute "MATERIAL" "X5R"
					( Origin gFrontEnd )
				)
				( attribute "NEW_MATERIAL" "X6S"
					( Origin gFrontEnd )
				)
				( attribute "PACK_TYPE" "0805"
					( Origin gFrontEnd )
				)
				( attribute "PART_NUMBER" "602433-112"
					( Origin gFrontEnd )
				)
				( attribute "PHYS_PAGE" "76"
					( Origin gFrontEnd )
				)
				( attribute "ROOM" "VDDQ_ABC_PWR_VR"
					( Origin gFrontEnd )
				)
				( attribute "ROT" "0"
					( Origin gFrontEnd )
				)
				( attribute "SEC" "1"
					( Origin gFrontEnd )
				)
				( attribute "SEC_TYPE" "0805"
					( Origin gFrontEnd )
				)
				( attribute "TOLERANCE" "20%"
					( Origin gFrontEnd )
				)
				( attribute "VALUE" "100UF"
					( Origin gFrontEnd )
				)
				( attribute "VER" "1"
					( Origin gFrontEnd )
				)
				( attribute "VOLTAGE" "4V"
					( Units "uVoltage" "V" 1.000000)
					( Origin gFrontEnd )
				)
				( attribute "XY" "(-3600,2200)"
					( Origin gFrontEnd )
				)
				( attribute "CHIPS_PART_NAME" "CAP"
					( Origin gPackager )
				)
				( attribute "CDS_PART_NAME" "CAP_0805-100UF,4V,20%,X5R,6024A"
					( Origin gPackager )
				)
				( attribute "NEW_PN" "078.1071T.M002"
					( Origin gFrontEnd )
				)
				( attribute "GROUP" "PWR_MCP_CAP"
					( Origin gFrontEnd )
				)
				( objectStatus "C7P15" )
			)
			( gate "@baseboard_fab2_lib.baseboard_fab2(sch_1):page76_i262"
				( attribute "BOM_COST" "MEM_VRD_PVDDQ_CD"
					( Origin gFrontEnd )
				)
				( attribute "CDS_LIB" "mstr_discrete"
					( Origin gPackager )
				)
				( attribute "CDS_LOCATION" "C7P11"
					( Origin gPackager )
				)
				( attribute "CDS_SEC" "1"
					( Origin gPackager )
				)
				( attribute "LOCATION" "C7P11"
					( Origin gFrontEnd )
				)
				( attribute "MATERIAL" "X5R"
					( Origin gFrontEnd )
				)
				( attribute "NEW_MATERIAL" "X6S"
					( Origin gFrontEnd )
				)
				( attribute "PACK_TYPE" "0805"
					( Origin gFrontEnd )
				)
				( attribute "PART_NUMBER" "602433-112"
					( Origin gFrontEnd )
				)
				( attribute "PHYS_PAGE" "76"
					( Origin gFrontEnd )
				)
				( attribute "ROOM" "VDDQ_ABC_PWR_VR"
					( Origin gFrontEnd )
				)
				( attribute "ROT" "0"
					( Origin gFrontEnd )
				)
				( attribute "SEC" "1"
					( Origin gFrontEnd )
				)
				( attribute "SEC_TYPE" "0805"
					( Origin gFrontEnd )
				)
				( attribute "TOLERANCE" "20%"
					( Origin gFrontEnd )
				)
				( attribute "VALUE" "100UF"
					( Origin gFrontEnd )
				)
				( attribute "VER" "1"
					( Origin gFrontEnd )
				)
				( attribute "VOLTAGE" "4V"
					( Units "uVoltage" "V" 1.000000)
					( Origin gFrontEnd )
				)
				( attribute "XY" "(-3350,2200)"
					( Origin gFrontEnd )
				)
				( attribute "CHIPS_PART_NAME" "CAP"
					( Origin gPackager )
				)
				( attribute "CDS_PART_NAME" "CAP_0805-100UF,4V,20%,X5R,6024A"
					( Origin gPackager )
				)
				( attribute "NEW_PN" "078.1071T.M002"
					( Origin gFrontEnd )
				)
				( attribute "GROUP" "PWR_MCP_CAP"
					( Origin gFrontEnd )
				)
				( objectStatus "C7P11" )
			)
			( gate "@baseboard_fab2_lib.baseboard_fab2(sch_1):page76_i251"
				( attribute "BOM_COST" "PROC"
					( Origin gFrontEnd )
				)
				( attribute "CDS_LIB" "mstr_discrete"
					( Origin gPackager )
				)
				( attribute "CDS_LOCATION" "C8P25"
					( Origin gPackager )
				)
				( attribute "LOCATION" "C8P25"
					( Origin gFrontEnd )
				)
				( attribute "MATERIAL" "X6S"
					( Origin gFrontEnd )
				)
				( attribute "PACK_TYPE" "0805"
					( Origin gFrontEnd )
				)
				( attribute "PART_NUMBER" "C95333-006"
					( Origin gFrontEnd )
				)
				( attribute "PHYS_PAGE" "76"
					( Origin gFrontEnd )
				)
				( attribute "ROOM" "PVCCIN_CPU1_DECAP_VR"
					( Origin gFrontEnd )
				)
				( attribute "ROT" "0"
					( Origin gFrontEnd )
				)
				( attribute "SEC" "1"
					( Origin gFrontEnd )
				)
				( attribute "SEC_TYPE" "0805"
					( Origin gFrontEnd )
				)
				( attribute "TOLERANCE" "20%"
					( Origin gFrontEnd )
				)
				( attribute "VALUE" "47UF"
					( Origin gFrontEnd )
				)
				( attribute "VER" "1"
					( Origin gFrontEnd )
				)
				( attribute "VOLTAGE" "4V"
					( Units "uVoltage" "V" 1.000000)
					( Origin gFrontEnd )
				)
				( attribute "XY" "(-7150,800)"
					( Origin gFrontEnd )
				)
				( attribute "CHIPS_PART_NAME" "CAP"
					( Origin gPackager )
				)
				( attribute "CDS_PART_NAME" "CAP_0805-47UF,4V,20%,X6S,C9533A"
					( Origin gPackager )
				)
				( attribute "GROUP" "PWR_MLCC_CAP"
					( Origin gFrontEnd )
				)
				( attribute "CDS_SEC" "1"
					( Origin gPackager )
				)
				( objectStatus "C8P25" )
			)
			( gate "@baseboard_fab2_lib.baseboard_fab2(sch_1):page76_i51"
				( attribute "BOM_COST" "PROC"
					( Origin gFrontEnd )
				)
				( attribute "CDS_LIB" "mstr_discrete"
					( Origin gPackager )
				)
				( attribute "CDS_LOCATION" "C7P18"
					( Origin gPackager )
				)
				( attribute "CDS_SEC" "1"
					( Origin gPackager )
				)
				( attribute "LOCATION" "C7P18"
					( Origin gFrontEnd )
				)
				( attribute "MATERIAL" "X6S"
					( Origin gFrontEnd )
				)
				( attribute "PACK_TYPE" "0805"
					( Origin gFrontEnd )
				)
				( attribute "PART_NUMBER" "C95333-006"
					( Origin gFrontEnd )
				)
				( attribute "PHYS_PAGE" "76"
					( Origin gFrontEnd )
				)
				( attribute "ROOM" "PVCCIN_CPU1_DECAP_VR"
					( Origin gFrontEnd )
				)
				( attribute "ROT" "0"
					( Origin gFrontEnd )
				)
				( attribute "SEC" "1"
					( Origin gPackager )
				)
				( attribute "TOLERANCE" "20%"
					( Origin gFrontEnd )
				)
				( attribute "VALUE" "47UF"
					( Origin gFrontEnd )
				)
				( attribute "VER" "1"
					( Origin gFrontEnd )
				)
				( attribute "VOLTAGE" "4V"
					( Units "uVoltage" "V" 1.000000)
					( Origin gFrontEnd )
				)
				( attribute "XY" "(-3000,1150)"
					( Origin gFrontEnd )
				)
				( attribute "CHIPS_PART_NAME" "CAP"
					( Origin gPackager )
				)
				( attribute "CDS_PART_NAME" "CAP_0805-47UF,4V,20%,X6S,C9533A"
					( Origin gPackager )
				)
				( attribute "GROUP" "PWR_MLCC_CAP"
					( Origin gFrontEnd )
				)
				( objectStatus "C7P18" )
			)
			( gate "@baseboard_fab2_lib.baseboard_fab2(sch_1):page76_i52"
				( attribute "BOM_COST" "PROC"
					( Origin gFrontEnd )
				)
				( attribute "CDS_LIB" "mstr_discrete"
					( Origin gPackager )
				)
				( attribute "CDS_LOCATION" "C7P3"
					( Origin gPackager )
				)
				( attribute "CDS_SEC" "1"
					( Origin gPackager )
				)
				( attribute "LOCATION" "C7P3"
					( Origin gFrontEnd )
				)
				( attribute "MATERIAL" "X6S"
					( Origin gFrontEnd )
				)
				( attribute "PACK_TYPE" "0805"
					( Origin gFrontEnd )
				)
				( attribute "PART_NUMBER" "C95333-006"
					( Origin gFrontEnd )
				)
				( attribute "PHYS_PAGE" "76"
					( Origin gFrontEnd )
				)
				( attribute "ROOM" "PVCCIN_CPU1_DECAP_VR"
					( Origin gFrontEnd )
				)
				( attribute "ROT" "0"
					( Origin gFrontEnd )
				)
				( attribute "SEC" "1"
					( Origin gPackager )
				)
				( attribute "TOLERANCE" "20%"
					( Origin gFrontEnd )
				)
				( attribute "VALUE" "47UF"
					( Origin gFrontEnd )
				)
				( attribute "VER" "1"
					( Origin gFrontEnd )
				)
				( attribute "VOLTAGE" "4V"
					( Units "uVoltage" "V" 1.000000)
					( Origin gFrontEnd )
				)
				( attribute "XY" "(-3300,1150)"
					( Origin gFrontEnd )
				)
				( attribute "CHIPS_PART_NAME" "CAP"
					( Origin gPackager )
				)
				( attribute "CDS_PART_NAME" "CAP_0805-47UF,4V,20%,X6S,C9533A"
					( Origin gPackager )
				)
				( attribute "GROUP" "PWR_MLCC_CAP"
					( Origin gFrontEnd )
				)
				( objectStatus "C7P3" )
			)
			( gate "@baseboard_fab2_lib.baseboard_fab2(sch_1):page76_i250"
				( attribute "BOM_COST" "PROC"
					( Origin gFrontEnd )
				)
				( attribute "CDS_LIB" "mstr_discrete"
					( Origin gPackager )
				)
				( attribute "CDS_LOCATION" "C8P27"
					( Origin gPackager )
				)
				( attribute "LOCATION" "C8P27"
					( Origin gFrontEnd )
				)
				( attribute "MATERIAL" "X6S"
					( Origin gFrontEnd )
				)
				( attribute "PACK_TYPE" "0805"
					( Origin gFrontEnd )
				)
				( attribute "PART_NUMBER" "C95333-006"
					( Origin gFrontEnd )
				)
				( attribute "PHYS_PAGE" "76"
					( Origin gFrontEnd )
				)
				( attribute "ROOM" "PVCCIN_CPU1_DECAP_VR"
					( Origin gFrontEnd )
				)
				( attribute "ROT" "0"
					( Origin gFrontEnd )
				)
				( attribute "SEC" "1"
					( Origin gFrontEnd )
				)
				( attribute "SEC_TYPE" "0805"
					( Origin gFrontEnd )
				)
				( attribute "TOLERANCE" "20%"
					( Origin gFrontEnd )
				)
				( attribute "VALUE" "47UF"
					( Origin gFrontEnd )
				)
				( attribute "VER" "1"
					( Origin gFrontEnd )
				)
				( attribute "VOLTAGE" "4V"
					( Units "uVoltage" "V" 1.000000)
					( Origin gFrontEnd )
				)
				( attribute "XY" "(-7450,800)"
					( Origin gFrontEnd )
				)
				( attribute "CHIPS_PART_NAME" "CAP"
					( Origin gPackager )
				)
				( attribute "CDS_PART_NAME" "CAP_0805-47UF,4V,20%,X6S,C9533A"
					( Origin gPackager )
				)
				( attribute "GROUP" "PWR_MLCC_CAP"
					( Origin gFrontEnd )
				)
				( attribute "CDS_SEC" "1"
					( Origin gPackager )
				)
				( objectStatus "C8P27" )
			)
			( gate "@baseboard_fab2_lib.baseboard_fab2(sch_1):page76_i249"
				( attribute "BOM_COST" "PROC"
					( Origin gFrontEnd )
				)
				( attribute "CDS_LIB" "mstr_discrete"
					( Origin gPackager )
				)
				( attribute "CDS_LOCATION" "C8P21"
					( Origin gPackager )
				)
				( attribute "LOCATION" "C8P21"
					( Origin gFrontEnd )
				)
				( attribute "MATERIAL" "X6S"
					( Origin gFrontEnd )
				)
				( attribute "PACK_TYPE" "0805"
					( Origin gFrontEnd )
				)
				( attribute "PART_NUMBER" "C95333-006"
					( Origin gFrontEnd )
				)
				( attribute "PHYS_PAGE" "76"
					( Origin gFrontEnd )
				)
				( attribute "ROOM" "PVCCIN_CPU1_DECAP_VR"
					( Origin gFrontEnd )
				)
				( attribute "ROT" "0"
					( Origin gFrontEnd )
				)
				( attribute "SEC" "1"
					( Origin gFrontEnd )
				)
				( attribute "SEC_TYPE" "0805"
					( Origin gFrontEnd )
				)
				( attribute "TOLERANCE" "20%"
					( Origin gFrontEnd )
				)
				( attribute "VALUE" "47UF"
					( Origin gFrontEnd )
				)
				( attribute "VER" "1"
					( Origin gFrontEnd )
				)
				( attribute "VOLTAGE" "4V"
					( Units "uVoltage" "V" 1.000000)
					( Origin gFrontEnd )
				)
				( attribute "XY" "(-6850,800)"
					( Origin gFrontEnd )
				)
				( attribute "CHIPS_PART_NAME" "CAP"
					( Origin gPackager )
				)
				( attribute "CDS_PART_NAME" "CAP_0805-47UF,4V,20%,X6S,C9533A"
					( Origin gPackager )
				)
				( attribute "GROUP" "PWR_MLCC_CAP"
					( Origin gFrontEnd )
				)
				( attribute "CDS_SEC" "1"
					( Origin gPackager )
				)
				( objectStatus "C8P21" )
			)
			( gate "@baseboard_fab2_lib.baseboard_fab2(sch_1):page76_i59"
				( attribute "BOM_COST" "PROC"
					( Origin gFrontEnd )
				)
				( attribute "CDS_LIB" "dev_discrete"
					( Origin gPackager )
				)
				( attribute "CDS_LOCATION" "C2D12"
					( Origin gPackager )
				)
				( attribute "CDS_SEC" "1"
					( Origin gPackager )
				)
				( attribute "LOCATION" "C2D12"
					( Origin gFrontEnd )
				)
				( attribute "MATERIAL" "X6S"
					( Origin gFrontEnd )
				)
				( attribute "PACK_TYPE" "0603V"
					( Origin gFrontEnd )
				)
				( attribute "PART_NUMBER" "E15431-004"
					( Origin gFrontEnd )
				)
				( attribute "PHYS_PAGE" "76"
					( Origin gFrontEnd )
				)
				( attribute "ROOM" "PVCCIN_CPU1_DECAP_VR"
					( Origin gFrontEnd )
				)
				( attribute "ROT" "0"
					( Origin gFrontEnd )
				)
				( attribute "SEC" "1"
					( Origin gPackager )
				)
				( attribute "TOLERANCE" "20%"
					( Origin gFrontEnd )
				)
				( attribute "VALUE" "22.0UF"
					( Origin gFrontEnd )
				)
				( attribute "VER" "1"
					( Origin gFrontEnd )
				)
				( attribute "VOLTAGE" "4V"
					( Units "uVoltage" "V" 1.000000)
					( Origin gFrontEnd )
				)
				( attribute "XY" "(-4800,4450)"
					( Origin gFrontEnd )
				)
				( attribute "CHIPS_PART_NAME" "CAP_A"
					( Origin gPackager )
				)
				( attribute "CDS_PART_NAME" "CAP_A_0603V-22.0UF,4V,20%,X6S,A"
					( Origin gPackager )
				)
				( attribute "GROUP" "PWR_MLCC_CAP"
					( Origin gFrontEnd )
				)
				( objectStatus "C2D12" )
			)
			( gate "@baseboard_fab2_lib.baseboard_fab2(sch_1):page76_i61"
				( attribute "BOM_COST" "PROC"
					( Origin gFrontEnd )
				)
				( attribute "CDS_LIB" "dev_discrete"
					( Origin gPackager )
				)
				( attribute "CDS_LOCATION" "C2D22"
					( Origin gPackager )
				)
				( attribute "CDS_SEC" "1"
					( Origin gPackager )
				)
				( attribute "LOCATION" "C2D22"
					( Origin gFrontEnd )
				)
				( attribute "MATERIAL" "X6S"
					( Origin gFrontEnd )
				)
				( attribute "PACK_TYPE" "0603V"
					( Origin gFrontEnd )
				)
				( attribute "PART_NUMBER" "E15431-004"
					( Origin gFrontEnd )
				)
				( attribute "PHYS_PAGE" "76"
					( Origin gFrontEnd )
				)
				( attribute "ROOM" "PVCCIN_CPU1_DECAP_VR"
					( Origin gFrontEnd )
				)
				( attribute "ROT" "0"
					( Origin gFrontEnd )
				)
				( attribute "SEC" "1"
					( Origin gPackager )
				)
				( attribute "TOLERANCE" "20%"
					( Origin gFrontEnd )
				)
				( attribute "VALUE" "22.0UF"
					( Origin gFrontEnd )
				)
				( attribute "VER" "1"
					( Origin gFrontEnd )
				)
				( attribute "VOLTAGE" "4V"
					( Units "uVoltage" "V" 1.000000)
					( Origin gFrontEnd )
				)
				( attribute "XY" "(-5100,4450)"
					( Origin gFrontEnd )
				)
				( attribute "CHIPS_PART_NAME" "CAP_A"
					( Origin gPackager )
				)
				( attribute "CDS_PART_NAME" "CAP_A_0603V-22.0UF,4V,20%,X6S,A"
					( Origin gPackager )
				)
				( attribute "GROUP" "PWR_MLCC_CAP"
					( Origin gFrontEnd )
				)
				( objectStatus "C2D22" )
			)
			( gate "@baseboard_fab2_lib.baseboard_fab2(sch_1):page76_i63"
				( attribute "BOM_COST" "PROC"
					( Origin gFrontEnd )
				)
				( attribute "CDS_LIB" "dev_discrete"
					( Origin gPackager )
				)
				( attribute "CDS_LOCATION" "C2D31"
					( Origin gPackager )
				)
				( attribute "CDS_SEC" "1"
					( Origin gPackager )
				)
				( attribute "LOCATION" "C2D31"
					( Origin gFrontEnd )
				)
				( attribute "MATERIAL" "X6S"
					( Origin gFrontEnd )
				)
				( attribute "PACK_TYPE" "0603V"
					( Origin gFrontEnd )
				)
				( attribute "PART_NUMBER" "E15431-004"
					( Origin gFrontEnd )
				)
				( attribute "PHYS_PAGE" "76"
					( Origin gFrontEnd )
				)
				( attribute "ROOM" "PVCCIN_CPU1_DECAP_VR"
					( Origin gFrontEnd )
				)
				( attribute "ROT" "0"
					( Origin gFrontEnd )
				)
				( attribute "SEC" "1"
					( Origin gPackager )
				)
				( attribute "TOLERANCE" "20%"
					( Origin gFrontEnd )
				)
				( attribute "VALUE" "22.0UF"
					( Origin gFrontEnd )
				)
				( attribute "VER" "1"
					( Origin gFrontEnd )
				)
				( attribute "VOLTAGE" "4V"
					( Units "uVoltage" "V" 1.000000)
					( Origin gFrontEnd )
				)
				( attribute "XY" "(-5600,4450)"
					( Origin gFrontEnd )
				)
				( attribute "CHIPS_PART_NAME" "CAP_A"
					( Origin gPackager )
				)
				( attribute "CDS_PART_NAME" "CAP_A_0603V-22.0UF,4V,20%,X6S,A"
					( Origin gPackager )
				)
				( attribute "GROUP" "PWR_MLCC_CAP"
					( Origin gFrontEnd )
				)
				( objectStatus "C2D31" )
			)
			( gate "@baseboard_fab2_lib.baseboard_fab2(sch_1):page76_i65"
				( attribute "BOM_COST" "PROC"
					( Origin gFrontEnd )
				)
				( attribute "CDS_LIB" "dev_discrete"
					( Origin gPackager )
				)
				( attribute "CDS_LOCATION" "C2D21"
					( Origin gPackager )
				)
				( attribute "CDS_SEC" "1"
					( Origin gPackager )
				)
				( attribute "LOCATION" "C2D21"
					( Origin gFrontEnd )
				)
				( attribute "MATERIAL" "X6S"
					( Origin gFrontEnd )
				)
				( attribute "PACK_TYPE" "0603V"
					( Origin gFrontEnd )
				)
				( attribute "PART_NUMBER" "E15431-004"
					( Origin gFrontEnd )
				)
				( attribute "PHYS_PAGE" "76"
					( Origin gFrontEnd )
				)
				( attribute "ROOM" "PVCCIN_CPU1_DECAP_VR"
					( Origin gFrontEnd )
				)
				( attribute "ROT" "0"
					( Origin gFrontEnd )
				)
				( attribute "SEC" "1"
					( Origin gPackager )
				)
				( attribute "TOLERANCE" "20%"
					( Origin gFrontEnd )
				)
				( attribute "VALUE" "22.0UF"
					( Origin gFrontEnd )
				)
				( attribute "VER" "1"
					( Origin gFrontEnd )
				)
				( attribute "VOLTAGE" "4V"
					( Units "uVoltage" "V" 1.000000)
					( Origin gFrontEnd )
				)
				( attribute "XY" "(-5900,4450)"
					( Origin gFrontEnd )
				)
				( attribute "CHIPS_PART_NAME" "CAP_A"
					( Origin gPackager )
				)
				( attribute "CDS_PART_NAME" "CAP_A_0603V-22.0UF,4V,20%,X6S,A"
					( Origin gPackager )
				)
				( attribute "GROUP" "PWR_MLCC_CAP"
					( Origin gFrontEnd )
				)
				( objectStatus "C2D21" )
			)
			( gate "@baseboard_fab2_lib.baseboard_fab2(sch_1):page76_i66"
				( attribute "BOM_COST" "PROC"
					( Origin gFrontEnd )
				)
				( attribute "CDS_LIB" "dev_discrete"
					( Origin gPackager )
				)
				( attribute "CDS_LOCATION" "C2D27"
					( Origin gPackager )
				)
				( attribute "CDS_SEC" "1"
					( Origin gPackager )
				)
				( attribute "LOCATION" "C2D27"
					( Origin gFrontEnd )
				)
				( attribute "MATERIAL" "X6S"
					( Origin gFrontEnd )
				)
				( attribute "PACK_TYPE" "0603V"
					( Origin gFrontEnd )
				)
				( attribute "PART_NUMBER" "E15431-004"
					( Origin gFrontEnd )
				)
				( attribute "PHYS_PAGE" "76"
					( Origin gFrontEnd )
				)
				( attribute "ROOM" "PVCCIN_CPU1_DECAP_VR"
					( Origin gFrontEnd )
				)
				( attribute "ROT" "0"
					( Origin gFrontEnd )
				)
				( attribute "SEC" "1"
					( Origin gPackager )
				)
				( attribute "TOLERANCE" "20%"
					( Origin gFrontEnd )
				)
				( attribute "VALUE" "22.0UF"
					( Origin gFrontEnd )
				)
				( attribute "VER" "1"
					( Origin gFrontEnd )
				)
				( attribute "VOLTAGE" "4V"
					( Units "uVoltage" "V" 1.000000)
					( Origin gFrontEnd )
				)
				( attribute "XY" "(-6650,4450)"
					( Origin gFrontEnd )
				)
				( attribute "CHIPS_PART_NAME" "CAP_A"
					( Origin gPackager )
				)
				( attribute "CDS_PART_NAME" "CAP_A_0603V-22.0UF,4V,20%,X6S,A"
					( Origin gPackager )
				)
				( attribute "GROUP" "PWR_MLCC_CAP"
					( Origin gFrontEnd )
				)
				( objectStatus "C2D27" )
			)
			( gate "@baseboard_fab2_lib.baseboard_fab2(sch_1):page76_i69"
				( attribute "BOM_COST" "PROC"
					( Origin gFrontEnd )
				)
				( attribute "CDS_LIB" "dev_discrete"
					( Origin gPackager )
				)
				( attribute "CDS_LOCATION" "C3D2"
					( Origin gPackager )
				)
				( attribute "CDS_SEC" "1"
					( Origin gPackager )
				)
				( attribute "LOCATION" "C3D2"
					( Origin gFrontEnd )
				)
				( attribute "MATERIAL" "X6S"
					( Origin gFrontEnd )
				)
				( attribute "PACK_TYPE" "0603V"
					( Origin gFrontEnd )
				)
				( attribute "PART_NUMBER" "E15431-004"
					( Origin gFrontEnd )
				)
				( attribute "PHYS_PAGE" "76"
					( Origin gFrontEnd )
				)
				( attribute "ROOM" "PVCCIN_CPU1_DECAP_VR"
					( Origin gFrontEnd )
				)
				( attribute "ROT" "0"
					( Origin gFrontEnd )
				)
				( attribute "SEC" "1"
					( Origin gPackager )
				)
				( attribute "TOLERANCE" "20%"
					( Origin gFrontEnd )
				)
				( attribute "VALUE" "22.0UF"
					( Origin gFrontEnd )
				)
				( attribute "VER" "1"
					( Origin gFrontEnd )
				)
				( attribute "VOLTAGE" "4V"
					( Units "uVoltage" "V" 1.000000)
					( Origin gFrontEnd )
				)
				( attribute "XY" "(-7350,4450)"
					( Origin gFrontEnd )
				)
				( attribute "CHIPS_PART_NAME" "CAP_A"
					( Origin gPackager )
				)
				( attribute "CDS_PART_NAME" "CAP_A_0603V-22.0UF,4V,20%,X6S,A"
					( Origin gPackager )
				)
				( attribute "GROUP" "PWR_MLCC_CAP"
					( Origin gFrontEnd )
				)
				( objectStatus "C3D2" )
			)
			( gate "@baseboard_fab2_lib.baseboard_fab2(sch_1):page76_i70"
				( attribute "BOM_COST" "PROC"
					( Origin gFrontEnd )
				)
				( attribute "CDS_LIB" "dev_discrete"
					( Origin gPackager )
				)
				( attribute "CDS_LOCATION" "C2D36"
					( Origin gPackager )
				)
				( attribute "CDS_SEC" "1"
					( Origin gPackager )
				)
				( attribute "LOCATION" "C2D36"
					( Origin gFrontEnd )
				)
				( attribute "MATERIAL" "X6S"
					( Origin gFrontEnd )
				)
				( attribute "PACK_TYPE" "0603V"
					( Origin gFrontEnd )
				)
				( attribute "PART_NUMBER" "E15431-004"
					( Origin gFrontEnd )
				)
				( attribute "PHYS_PAGE" "76"
					( Origin gFrontEnd )
				)
				( attribute "ROOM" "PVCCIN_CPU1_DECAP_VR"
					( Origin gFrontEnd )
				)
				( attribute "ROT" "0"
					( Origin gFrontEnd )
				)
				( attribute "SEC" "1"
					( Origin gPackager )
				)
				( attribute "TOLERANCE" "20%"
					( Origin gFrontEnd )
				)
				( attribute "VALUE" "22.0UF"
					( Origin gFrontEnd )
				)
				( attribute "VER" "1"
					( Origin gFrontEnd )
				)
				( attribute "VOLTAGE" "4V"
					( Units "uVoltage" "V" 1.000000)
					( Origin gFrontEnd )
				)
				( attribute "XY" "(-7650,4450)"
					( Origin gFrontEnd )
				)
				( attribute "CHIPS_PART_NAME" "CAP_A"
					( Origin gPackager )
				)
				( attribute "CDS_PART_NAME" "CAP_A_0603V-22.0UF,4V,20%,X6S,A"
					( Origin gPackager )
				)
				( attribute "GROUP" "PWR_MLCC_CAP"
					( Origin gFrontEnd )
				)
				( objectStatus "C2D36" )
			)
			( gate "@baseboard_fab2_lib.baseboard_fab2(sch_1):page76_i73"
				( attribute "BOM_COST" "PROC"
					( Origin gFrontEnd )
				)
				( attribute "CDS_LIB" "dev_discrete"
					( Origin gPackager )
				)
				( attribute "CDS_LOCATION" "C2D13"
					( Origin gPackager )
				)
				( attribute "CDS_SEC" "1"
					( Origin gPackager )
				)
				( attribute "LOCATION" "C2D13"
					( Origin gFrontEnd )
				)
				( attribute "MATERIAL" "X6S"
					( Origin gFrontEnd )
				)
				( attribute "PACK_TYPE" "0603V"
					( Origin gFrontEnd )
				)
				( attribute "PART_NUMBER" "E15431-004"
					( Origin gFrontEnd )
				)
				( attribute "PHYS_PAGE" "76"
					( Origin gFrontEnd )
				)
				( attribute "ROOM" "PVCCIN_CPU1_DECAP_VR"
					( Origin gFrontEnd )
				)
				( attribute "ROT" "0"
					( Origin gFrontEnd )
				)
				( attribute "SEC" "1"
					( Origin gPackager )
				)
				( attribute "TOLERANCE" "20%"
					( Origin gFrontEnd )
				)
				( attribute "VALUE" "22.0UF"
					( Origin gFrontEnd )
				)
				( attribute "VER" "1"
					( Origin gFrontEnd )
				)
				( attribute "VOLTAGE" "4V"
					( Units "uVoltage" "V" 1.000000)
					( Origin gFrontEnd )
				)
				( attribute "XY" "(-4700,3750)"
					( Origin gFrontEnd )
				)
				( attribute "CHIPS_PART_NAME" "CAP_A"
					( Origin gPackager )
				)
				( attribute "CDS_PART_NAME" "CAP_A_0603V-22.0UF,4V,20%,X6S,A"
					( Origin gPackager )
				)
				( attribute "GROUP" "PWR_MLCC_CAP"
					( Origin gFrontEnd )
				)
				( objectStatus "C2D13" )
			)
			( gate "@baseboard_fab2_lib.baseboard_fab2(sch_1):page76_i75"
				( attribute "BOM_COST" "PROC"
					( Origin gFrontEnd )
				)
				( attribute "CDS_LIB" "dev_discrete"
					( Origin gPackager )
				)
				( attribute "CDS_LOCATION" "C2D19"
					( Origin gPackager )
				)
				( attribute "CDS_SEC" "1"
					( Origin gPackager )
				)
				( attribute "LOCATION" "C2D19"
					( Origin gFrontEnd )
				)
				( attribute "MATERIAL" "X6S"
					( Origin gFrontEnd )
				)
				( attribute "PACK_TYPE" "0603V"
					( Origin gFrontEnd )
				)
				( attribute "PART_NUMBER" "E15431-004"
					( Origin gFrontEnd )
				)
				( attribute "PHYS_PAGE" "76"
					( Origin gFrontEnd )
				)
				( attribute "ROOM" "PVCCIN_CPU1_DECAP_VR"
					( Origin gFrontEnd )
				)
				( attribute "ROT" "0"
					( Origin gFrontEnd )
				)
				( attribute "SEC" "1"
					( Origin gPackager )
				)
				( attribute "TOLERANCE" "20%"
					( Origin gFrontEnd )
				)
				( attribute "VALUE" "22.0UF"
					( Origin gFrontEnd )
				)
				( attribute "VER" "1"
					( Origin gFrontEnd )
				)
				( attribute "VOLTAGE" "4V"
					( Units "uVoltage" "V" 1.000000)
					( Origin gFrontEnd )
				)
				( attribute "XY" "(-5000,3750)"
					( Origin gFrontEnd )
				)
				( attribute "CHIPS_PART_NAME" "CAP_A"
					( Origin gPackager )
				)
				( attribute "CDS_PART_NAME" "CAP_A_0603V-22.0UF,4V,20%,X6S,A"
					( Origin gPackager )
				)
				( attribute "GROUP" "PWR_MLCC_CAP"
					( Origin gFrontEnd )
				)
				( objectStatus "C2D19" )
			)
			( gate "@baseboard_fab2_lib.baseboard_fab2(sch_1):page76_i76"
				( attribute "BOM_COST" "PROC"
					( Origin gFrontEnd )
				)
				( attribute "CDS_LIB" "dev_discrete"
					( Origin gPackager )
				)
				( attribute "CDS_LOCATION" "C2D14"
					( Origin gPackager )
				)
				( attribute "CDS_SEC" "1"
					( Origin gPackager )
				)
				( attribute "LOCATION" "C2D14"
					( Origin gFrontEnd )
				)
				( attribute "MATERIAL" "X6S"
					( Origin gFrontEnd )
				)
				( attribute "PACK_TYPE" "0603V"
					( Origin gFrontEnd )
				)
				( attribute "PART_NUMBER" "E15431-004"
					( Origin gFrontEnd )
				)
				( attribute "PHYS_PAGE" "76"
					( Origin gFrontEnd )
				)
				( attribute "ROOM" "PVCCIN_CPU1_DECAP_VR"
					( Origin gFrontEnd )
				)
				( attribute "ROT" "0"
					( Origin gFrontEnd )
				)
				( attribute "SEC" "1"
					( Origin gPackager )
				)
				( attribute "TOLERANCE" "20%"
					( Origin gFrontEnd )
				)
				( attribute "VALUE" "22.0UF"
					( Origin gFrontEnd )
				)
				( attribute "VER" "1"
					( Origin gFrontEnd )
				)
				( attribute "VOLTAGE" "4V"
					( Units "uVoltage" "V" 1.000000)
					( Origin gFrontEnd )
				)
				( attribute "XY" "(-4800,3050)"
					( Origin gFrontEnd )
				)
				( attribute "CHIPS_PART_NAME" "CAP_A"
					( Origin gPackager )
				)
				( attribute "CDS_PART_NAME" "CAP_A_0603V-22.0UF,4V,20%,X6S,A"
					( Origin gPackager )
				)
				( attribute "GROUP" "PWR_MLCC_CAP"
					( Origin gFrontEnd )
				)
				( objectStatus "C2D14" )
			)
			( gate "@baseboard_fab2_lib.baseboard_fab2(sch_1):page76_i79"
				( attribute "BOM_COST" "PROC"
					( Origin gFrontEnd )
				)
				( attribute "CDS_LIB" "dev_discrete"
					( Origin gPackager )
				)
				( attribute "CDS_LOCATION" "C2D20"
					( Origin gPackager )
				)
				( attribute "CDS_SEC" "1"
					( Origin gPackager )
				)
				( attribute "LOCATION" "C2D20"
					( Origin gFrontEnd )
				)
				( attribute "MATERIAL" "X6S"
					( Origin gFrontEnd )
				)
				( attribute "PACK_TYPE" "0603V"
					( Origin gFrontEnd )
				)
				( attribute "PART_NUMBER" "E15431-004"
					( Origin gFrontEnd )
				)
				( attribute "PHYS_PAGE" "76"
					( Origin gFrontEnd )
				)
				( attribute "ROOM" "PVCCIN_CPU1_DECAP_VR"
					( Origin gFrontEnd )
				)
				( attribute "ROT" "0"
					( Origin gFrontEnd )
				)
				( attribute "SEC" "1"
					( Origin gPackager )
				)
				( attribute "TOLERANCE" "20%"
					( Origin gFrontEnd )
				)
				( attribute "VALUE" "22.0UF"
					( Origin gFrontEnd )
				)
				( attribute "VER" "1"
					( Origin gFrontEnd )
				)
				( attribute "VOLTAGE" "4V"
					( Units "uVoltage" "V" 1.000000)
					( Origin gFrontEnd )
				)
				( attribute "XY" "(-5100,3050)"
					( Origin gFrontEnd )
				)
				( attribute "CHIPS_PART_NAME" "CAP_A"
					( Origin gPackager )
				)
				( attribute "CDS_PART_NAME" "CAP_A_0603V-22.0UF,4V,20%,X6S,A"
					( Origin gPackager )
				)
				( attribute "GROUP" "PWR_MLCC_CAP"
					( Origin gFrontEnd )
				)
				( objectStatus "C2D20" )
			)
			( gate "@baseboard_fab2_lib.baseboard_fab2(sch_1):page76_i80"
				( attribute "BOM_COST" "PROC"
					( Origin gFrontEnd )
				)
				( attribute "CDS_LIB" "dev_discrete"
					( Origin gPackager )
				)
				( attribute "CDS_LOCATION" "C2D24"
					( Origin gPackager )
				)
				( attribute "CDS_SEC" "1"
					( Origin gPackager )
				)
				( attribute "LOCATION" "C2D24"
					( Origin gFrontEnd )
				)
				( attribute "MATERIAL" "X6S"
					( Origin gFrontEnd )
				)
				( attribute "PACK_TYPE" "0603V"
					( Origin gFrontEnd )
				)
				( attribute "PART_NUMBER" "E15431-004"
					( Origin gFrontEnd )
				)
				( attribute "PHYS_PAGE" "76"
					( Origin gFrontEnd )
				)
				( attribute "ROOM" "PVCCIN_CPU1_DECAP_VR"
					( Origin gFrontEnd )
				)
				( attribute "ROT" "0"
					( Origin gFrontEnd )
				)
				( attribute "SEC" "1"
					( Origin gPackager )
				)
				( attribute "TOLERANCE" "20%"
					( Origin gFrontEnd )
				)
				( attribute "VALUE" "22.0UF"
					( Origin gFrontEnd )
				)
				( attribute "VER" "1"
					( Origin gFrontEnd )
				)
				( attribute "VOLTAGE" "4V"
					( Units "uVoltage" "V" 1.000000)
					( Origin gFrontEnd )
				)
				( attribute "XY" "(-5400,3050)"
					( Origin gFrontEnd )
				)
				( attribute "CHIPS_PART_NAME" "CAP_A"
					( Origin gPackager )
				)
				( attribute "CDS_PART_NAME" "CAP_A_0603V-22.0UF,4V,20%,X6S,A"
					( Origin gPackager )
				)
				( attribute "GROUP" "PWR_MLCC_CAP"
					( Origin gFrontEnd )
				)
				( objectStatus "C2D24" )
			)
			( gate "@baseboard_fab2_lib.baseboard_fab2(sch_1):page76_i82"
				( attribute "BOM_COST" "PROC"
					( Origin gFrontEnd )
				)
				( attribute "CDS_LIB" "dev_discrete"
					( Origin gPackager )
				)
				( attribute "CDS_LOCATION" "C2D25"
					( Origin gPackager )
				)
				( attribute "CDS_SEC" "1"
					( Origin gPackager )
				)
				( attribute "LOCATION" "C2D25"
					( Origin gFrontEnd )
				)
				( attribute "MATERIAL" "X6S"
					( Origin gFrontEnd )
				)
				( attribute "PACK_TYPE" "0603V"
					( Origin gFrontEnd )
				)
				( attribute "PART_NUMBER" "E15431-004"
					( Origin gFrontEnd )
				)
				( attribute "PHYS_PAGE" "76"
					( Origin gFrontEnd )
				)
				( attribute "ROOM" "PVCCIN_CPU1_DECAP_VR"
					( Origin gFrontEnd )
				)
				( attribute "ROT" "0"
					( Origin gFrontEnd )
				)
				( attribute "SEC" "1"
					( Origin gPackager )
				)
				( attribute "TOLERANCE" "20%"
					( Origin gFrontEnd )
				)
				( attribute "VALUE" "22.0UF"
					( Origin gFrontEnd )
				)
				( attribute "VER" "1"
					( Origin gFrontEnd )
				)
				( attribute "VOLTAGE" "4V"
					( Units "uVoltage" "V" 1.000000)
					( Origin gFrontEnd )
				)
				( attribute "XY" "(-5300,3750)"
					( Origin gFrontEnd )
				)
				( attribute "CHIPS_PART_NAME" "CAP_A"
					( Origin gPackager )
				)
				( attribute "CDS_PART_NAME" "CAP_A_0603V-22.0UF,4V,20%,X6S,A"
					( Origin gPackager )
				)
				( attribute "GROUP" "PWR_MLCC_CAP"
					( Origin gFrontEnd )
				)
				( objectStatus "C2D25" )
			)
			( gate "@baseboard_fab2_lib.baseboard_fab2(sch_1):page76_i83"
				( attribute "BOM_COST" "PROC"
					( Origin gFrontEnd )
				)
				( attribute "CDS_LIB" "dev_discrete"
					( Origin gPackager )
				)
				( attribute "CDS_LOCATION" "C2D30"
					( Origin gPackager )
				)
				( attribute "CDS_SEC" "1"
					( Origin gPackager )
				)
				( attribute "LOCATION" "C2D30"
					( Origin gFrontEnd )
				)
				( attribute "MATERIAL" "X6S"
					( Origin gFrontEnd )
				)
				( attribute "PACK_TYPE" "0603V"
					( Origin gFrontEnd )
				)
				( attribute "PART_NUMBER" "E15431-004"
					( Origin gFrontEnd )
				)
				( attribute "PHYS_PAGE" "76"
					( Origin gFrontEnd )
				)
				( attribute "ROOM" "PVCCIN_CPU1_DECAP_VR"
					( Origin gFrontEnd )
				)
				( attribute "ROT" "0"
					( Origin gFrontEnd )
				)
				( attribute "SEC" "1"
					( Origin gPackager )
				)
				( attribute "TOLERANCE" "20%"
					( Origin gFrontEnd )
				)
				( attribute "VALUE" "22.0UF"
					( Origin gFrontEnd )
				)
				( attribute "VER" "1"
					( Origin gFrontEnd )
				)
				( attribute "VOLTAGE" "4V"
					( Units "uVoltage" "V" 1.000000)
					( Origin gFrontEnd )
				)
				( attribute "XY" "(-5600,3750)"
					( Origin gFrontEnd )
				)
				( attribute "CHIPS_PART_NAME" "CAP_A"
					( Origin gPackager )
				)
				( attribute "CDS_PART_NAME" "CAP_A_0603V-22.0UF,4V,20%,X6S,A"
					( Origin gPackager )
				)
				( attribute "GROUP" "PWR_MLCC_CAP"
					( Origin gFrontEnd )
				)
				( objectStatus "C2D30" )
			)
			( gate "@baseboard_fab2_lib.baseboard_fab2(sch_1):page76_i85"
				( attribute "BOM_COST" "PROC"
					( Origin gFrontEnd )
				)
				( attribute "CDS_LIB" "dev_discrete"
					( Origin gPackager )
				)
				( attribute "CDS_LOCATION" "C2D33"
					( Origin gPackager )
				)
				( attribute "CDS_SEC" "1"
					( Origin gPackager )
				)
				( attribute "LOCATION" "C2D33"
					( Origin gFrontEnd )
				)
				( attribute "MATERIAL" "X6S"
					( Origin gFrontEnd )
				)
				( attribute "PACK_TYPE" "0603V"
					( Origin gFrontEnd )
				)
				( attribute "PART_NUMBER" "E15431-004"
					( Origin gFrontEnd )
				)
				( attribute "PHYS_PAGE" "76"
					( Origin gFrontEnd )
				)
				( attribute "ROOM" "PVCCIN_CPU1_DECAP_VR"
					( Origin gFrontEnd )
				)
				( attribute "ROT" "0"
					( Origin gFrontEnd )
				)
				( attribute "SEC" "1"
					( Origin gPackager )
				)
				( attribute "TOLERANCE" "20%"
					( Origin gFrontEnd )
				)
				( attribute "VALUE" "22.0UF"
					( Origin gFrontEnd )
				)
				( attribute "VER" "1"
					( Origin gFrontEnd )
				)
				( attribute "VOLTAGE" "4V"
					( Units "uVoltage" "V" 1.000000)
					( Origin gFrontEnd )
				)
				( attribute "XY" "(-5900,3750)"
					( Origin gFrontEnd )
				)
				( attribute "CHIPS_PART_NAME" "CAP_A"
					( Origin gPackager )
				)
				( attribute "CDS_PART_NAME" "CAP_A_0603V-22.0UF,4V,20%,X6S,A"
					( Origin gPackager )
				)
				( attribute "GROUP" "PWR_MLCC_CAP"
					( Origin gFrontEnd )
				)
				( objectStatus "C2D33" )
			)
			( gate "@baseboard_fab2_lib.baseboard_fab2(sch_1):page76_i89"
				( attribute "BOM_COST" "PROC"
					( Origin gFrontEnd )
				)
				( attribute "CDS_LIB" "mstr_discrete"
					( Origin gPackager )
				)
				( attribute "CDS_LOCATION" "C8P20"
					( Origin gPackager )
				)
				( attribute "CDS_SEC" "1"
					( Origin gPackager )
				)
				( attribute "LOCATION" "C8P20"
					( Origin gFrontEnd )
				)
				( attribute "MATERIAL" "X6S"
					( Origin gFrontEnd )
				)
				( attribute "PACK_TYPE" "0805"
					( Origin gFrontEnd )
				)
				( attribute "PART_NUMBER" "C95333-006"
					( Origin gFrontEnd )
				)
				( attribute "PHYS_PAGE" "76"
					( Origin gFrontEnd )
				)
				( attribute "ROOM" "PVCCIN_CPU1_DECAP_VR"
					( Origin gFrontEnd )
				)
				( attribute "ROT" "0"
					( Origin gFrontEnd )
				)
				( attribute "SEC" "1"
					( Origin gPackager )
				)
				( attribute "TOLERANCE" "20%"
					( Origin gFrontEnd )
				)
				( attribute "VALUE" "47UF"
					( Origin gFrontEnd )
				)
				( attribute "VER" "1"
					( Origin gFrontEnd )
				)
				( attribute "VOLTAGE" "4V"
					( Units "uVoltage" "V" 1.000000)
					( Origin gFrontEnd )
				)
				( attribute "XY" "(-5650,2200)"
					( Origin gFrontEnd )
				)
				( attribute "CHIPS_PART_NAME" "CAP"
					( Origin gPackager )
				)
				( attribute "CDS_PART_NAME" "CAP_0805-47UF,4V,20%,X6S,C9533A"
					( Origin gPackager )
				)
				( attribute "GROUP" "PWR_MLCC_CAP"
					( Origin gFrontEnd )
				)
				( objectStatus "C8P20" )
			)
			( gate "@baseboard_fab2_lib.baseboard_fab2(sch_1):page76_i90"
				( attribute "BOM_COST" "PROC"
					( Origin gFrontEnd )
				)
				( attribute "CDS_LIB" "dev_discrete"
					( Origin gPackager )
				)
				( attribute "CDS_LOCATION" "C2D32"
					( Origin gPackager )
				)
				( attribute "CDS_SEC" "1"
					( Origin gPackager )
				)
				( attribute "LOCATION" "C2D32"
					( Origin gFrontEnd )
				)
				( attribute "MATERIAL" "X6S"
					( Origin gFrontEnd )
				)
				( attribute "PACK_TYPE" "0603V"
					( Origin gFrontEnd )
				)
				( attribute "PART_NUMBER" "E15431-004"
					( Origin gFrontEnd )
				)
				( attribute "PHYS_PAGE" "76"
					( Origin gFrontEnd )
				)
				( attribute "ROOM" "PVCCIN_CPU1_DECAP_VR"
					( Origin gFrontEnd )
				)
				( attribute "ROT" "0"
					( Origin gFrontEnd )
				)
				( attribute "SEC" "1"
					( Origin gPackager )
				)
				( attribute "TOLERANCE" "20%"
					( Origin gFrontEnd )
				)
				( attribute "VALUE" "22.0UF"
					( Origin gFrontEnd )
				)
				( attribute "VER" "1"
					( Origin gFrontEnd )
				)
				( attribute "VOLTAGE" "4V"
					( Units "uVoltage" "V" 1.000000)
					( Origin gFrontEnd )
				)
				( attribute "XY" "(-5900,3050)"
					( Origin gFrontEnd )
				)
				( attribute "CHIPS_PART_NAME" "CAP_A"
					( Origin gPackager )
				)
				( attribute "CDS_PART_NAME" "CAP_A_0603V-22.0UF,4V,20%,X6S,A"
					( Origin gPackager )
				)
				( attribute "GROUP" "PWR_MLCC_CAP"
					( Origin gFrontEnd )
				)
				( objectStatus "C2D32" )
			)
			( gate "@baseboard_fab2_lib.baseboard_fab2(sch_1):page76_i92"
				( attribute "BOM_COST" "PROC"
					( Origin gFrontEnd )
				)
				( attribute "CDS_LIB" "mstr_discrete"
					( Origin gPackager )
				)
				( attribute "CDS_LOCATION" "C8P18"
					( Origin gPackager )
				)
				( attribute "CDS_SEC" "1"
					( Origin gPackager )
				)
				( attribute "LOCATION" "C8P18"
					( Origin gFrontEnd )
				)
				( attribute "MATERIAL" "X6S"
					( Origin gFrontEnd )
				)
				( attribute "PACK_TYPE" "0805"
					( Origin gFrontEnd )
				)
				( attribute "PART_NUMBER" "C95333-006"
					( Origin gFrontEnd )
				)
				( attribute "PHYS_PAGE" "76"
					( Origin gFrontEnd )
				)
				( attribute "ROOM" "PVCCIN_CPU1_DECAP_VR"
					( Origin gFrontEnd )
				)
				( attribute "ROT" "0"
					( Origin gFrontEnd )
				)
				( attribute "SEC" "1"
					( Origin gPackager )
				)
				( attribute "TOLERANCE" "20%"
					( Origin gFrontEnd )
				)
				( attribute "VALUE" "47UF"
					( Origin gFrontEnd )
				)
				( attribute "VER" "1"
					( Origin gFrontEnd )
				)
				( attribute "VOLTAGE" "4V"
					( Units "uVoltage" "V" 1.000000)
					( Origin gFrontEnd )
				)
				( attribute "XY" "(-5950,2200)"
					( Origin gFrontEnd )
				)
				( attribute "CHIPS_PART_NAME" "CAP"
					( Origin gPackager )
				)
				( attribute "CDS_PART_NAME" "CAP_0805-47UF,4V,20%,X6S,C9533A"
					( Origin gPackager )
				)
				( attribute "GROUP" "PWR_MLCC_CAP"
					( Origin gFrontEnd )
				)
				( objectStatus "C8P18" )
			)
			( gate "@baseboard_fab2_lib.baseboard_fab2(sch_1):page76_i103"
				( attribute "BOM_COST" "PROC"
					( Origin gFrontEnd )
				)
				( attribute "CDS_LIB" "mstr_discrete"
					( Origin gPackager )
				)
				( attribute "CDS_LOCATION" "C8P19"
					( Origin gPackager )
				)
				( attribute "CDS_SEC" "1"
					( Origin gPackager )
				)
				( attribute "LOCATION" "C8P19"
					( Origin gFrontEnd )
				)
				( attribute "MATERIAL" "X6S"
					( Origin gFrontEnd )
				)
				( attribute "PACK_TYPE" "0805"
					( Origin gFrontEnd )
				)
				( attribute "PART_NUMBER" "C95333-006"
					( Origin gFrontEnd )
				)
				( attribute "PHYS_PAGE" "76"
					( Origin gFrontEnd )
				)
				( attribute "ROOM" "PVCCIN_CPU1_DECAP_VR"
					( Origin gFrontEnd )
				)
				( attribute "ROT" "0"
					( Origin gFrontEnd )
				)
				( attribute "SEC" "1"
					( Origin gPackager )
				)
				( attribute "TOLERANCE" "20%"
					( Origin gFrontEnd )
				)
				( attribute "VALUE" "47UF"
					( Origin gFrontEnd )
				)
				( attribute "VER" "1"
					( Origin gFrontEnd )
				)
				( attribute "VOLTAGE" "4V"
					( Units "uVoltage" "V" 1.000000)
					( Origin gFrontEnd )
				)
				( attribute "XY" "(-5950,1500)"
					( Origin gFrontEnd )
				)
				( attribute "CHIPS_PART_NAME" "CAP"
					( Origin gPackager )
				)
				( attribute "CDS_PART_NAME" "CAP_0805-47UF,4V,20%,X6S,C9533A"
					( Origin gPackager )
				)
				( attribute "GROUP" "PWR_MLCC_CAP"
					( Origin gFrontEnd )
				)
				( objectStatus "C8P19" )
			)
			( gate "@baseboard_fab2_lib.baseboard_fab2(sch_1):page166_i34"
				( attribute "CDS_LIB" "w_hdl"
					( Origin gPackager )
				)
				( attribute "CDS_LMAN_SYM_OUTLINE" "-150,150,150,-150"
					( Origin gPackager )
				)
				( attribute "LOCATION" "U7W1"
					( Origin gFrontEnd )
				)
				( attribute "PACK_TYPE" "DISCRET-GC2"
					( Origin gFrontEnd )
				)
				( attribute "PART_NUMBER" "073.53157.000J"
					( Origin gFrontEnd )
				)
				( attribute "PHYS_PAGE" "166"
					( Origin gFrontEnd )
				)
				( attribute "ROT" "0"
					( Origin gFrontEnd )
				)
				( attribute "SEC" "1"
					( Origin gFrontEnd )
				)
				( attribute "SEC_TYPE" "DISCRET-GC2"
					( Origin gFrontEnd )
				)
				( attribute "VALUE" "PI5A3157BC6E-GP"
					( Origin gFrontEnd )
				)
				( attribute "VER" "1"
					( Origin gFrontEnd )
				)
				( attribute "XY" "(-3400,2825)"
					( Origin gFrontEnd )
				)
				( attribute "CHIPS_PART_NAME" "PI5A3157BC6E-GP"
					( Origin gPackager )
				)
				( attribute "CDS_PART_NAME" "PI5A3157BC6E-GP_DISCRET-GC2-PIA"
					( Origin gPackager )
				)
				( attribute "CDS_LOCATION" "U7W1"
					( Origin gPackager )
				)
				( attribute "CDS_SEC" "1"
					( Origin gPackager )
				)
				( objectStatus "U7W1" )
			)
			( gate "@baseboard_fab2_lib.baseboard_fab2(sch_1):page76_i107"
				( attribute "BOM_COST" "PROC"
					( Origin gFrontEnd )
				)
				( attribute "CDS_LIB" "mstr_discrete"
					( Origin gPackager )
				)
				( attribute "CDS_LOCATION" "C8P12"
					( Origin gPackager )
				)
				( attribute "CDS_SEC" "1"
					( Origin gPackager )
				)
				( attribute "LOCATION" "C8P12"
					( Origin gFrontEnd )
				)
				( attribute "MATERIAL" "X6S"
					( Origin gFrontEnd )
				)
				( attribute "PACK_TYPE" "0805"
					( Origin gFrontEnd )
				)
				( attribute "PART_NUMBER" "C95333-006"
					( Origin gFrontEnd )
				)
				( attribute "PHYS_PAGE" "76"
					( Origin gFrontEnd )
				)
				( attribute "ROOM" "PVCCIN_CPU1_DECAP_VR"
					( Origin gFrontEnd )
				)
				( attribute "ROT" "0"
					( Origin gFrontEnd )
				)
				( attribute "SEC" "1"
					( Origin gPackager )
				)
				( attribute "TOLERANCE" "20%"
					( Origin gFrontEnd )
				)
				( attribute "VALUE" "47UF"
					( Origin gFrontEnd )
				)
				( attribute "VER" "1"
					( Origin gFrontEnd )
				)
				( attribute "VOLTAGE" "4V"
					( Units "uVoltage" "V" 1.000000)
					( Origin gFrontEnd )
				)
				( attribute "XY" "(-5950,800)"
					( Origin gFrontEnd )
				)
				( attribute "CHIPS_PART_NAME" "CAP"
					( Origin gPackager )
				)
				( attribute "CDS_PART_NAME" "CAP_0805-47UF,4V,20%,X6S,C9533A"
					( Origin gPackager )
				)
				( attribute "GROUP" "PWR_MLCC_CAP"
					( Origin gFrontEnd )
				)
				( objectStatus "C8P12" )
			)
			( gate "@baseboard_fab2_lib.baseboard_fab2(sch_1):page76_i108"
				( attribute "BOM_COST" "PROC"
					( Origin gFrontEnd )
				)
				( attribute "CDS_LIB" "dev_discrete"
					( Origin gPackager )
				)
				( attribute "CDS_LOCATION" "C2D26"
					( Origin gPackager )
				)
				( attribute "CDS_SEC" "1"
					( Origin gPackager )
				)
				( attribute "LOCATION" "C2D26"
					( Origin gFrontEnd )
				)
				( attribute "MATERIAL" "X6S"
					( Origin gFrontEnd )
				)
				( attribute "PACK_TYPE" "0603V"
					( Origin gFrontEnd )
				)
				( attribute "PART_NUMBER" "E15431-004"
					( Origin gFrontEnd )
				)
				( attribute "PHYS_PAGE" "76"
					( Origin gFrontEnd )
				)
				( attribute "ROOM" "PVCCIN_CPU1_DECAP_VR"
					( Origin gFrontEnd )
				)
				( attribute "ROT" "0"
					( Origin gFrontEnd )
				)
				( attribute "SEC" "1"
					( Origin gPackager )
				)
				( attribute "TOLERANCE" "20%"
					( Origin gFrontEnd )
				)
				( attribute "VALUE" "22.0UF"
					( Origin gFrontEnd )
				)
				( attribute "VER" "1"
					( Origin gFrontEnd )
				)
				( attribute "VOLTAGE" "4V"
					( Units "uVoltage" "V" 1.000000)
					( Origin gFrontEnd )
				)
				( attribute "XY" "(-6750,3750)"
					( Origin gFrontEnd )
				)
				( attribute "CHIPS_PART_NAME" "CAP_A"
					( Origin gPackager )
				)
				( attribute "CDS_PART_NAME" "CAP_A_0603V-22.0UF,4V,20%,X6S,A"
					( Origin gPackager )
				)
				( attribute "GROUP" "PWR_MLCC_CAP"
					( Origin gFrontEnd )
				)
				( objectStatus "C2D26" )
			)
			( gate "@baseboard_fab2_lib.baseboard_fab2(sch_1):page76_i112"
				( attribute "BOM_COST" "PROC"
					( Origin gFrontEnd )
				)
				( attribute "CDS_LIB" "dev_discrete"
					( Origin gPackager )
				)
				( attribute "CDS_LOCATION" "C2D23"
					( Origin gPackager )
				)
				( attribute "CDS_SEC" "1"
					( Origin gPackager )
				)
				( attribute "LOCATION" "C2D23"
					( Origin gFrontEnd )
				)
				( attribute "MATERIAL" "X6S"
					( Origin gFrontEnd )
				)
				( attribute "PACK_TYPE" "0603V"
					( Origin gFrontEnd )
				)
				( attribute "PART_NUMBER" "E15431-004"
					( Origin gFrontEnd )
				)
				( attribute "PHYS_PAGE" "76"
					( Origin gFrontEnd )
				)
				( attribute "ROOM" "PVCCIN_CPU1_DECAP_VR"
					( Origin gFrontEnd )
				)
				( attribute "ROT" "0"
					( Origin gFrontEnd )
				)
				( attribute "SEC" "1"
					( Origin gPackager )
				)
				( attribute "TOLERANCE" "20%"
					( Origin gFrontEnd )
				)
				( attribute "VALUE" "22.0UF"
					( Origin gFrontEnd )
				)
				( attribute "VER" "1"
					( Origin gFrontEnd )
				)
				( attribute "VOLTAGE" "4V"
					( Units "uVoltage" "V" 1.000000)
					( Origin gFrontEnd )
				)
				( attribute "XY" "(-6750,3050)"
					( Origin gFrontEnd )
				)
				( attribute "CHIPS_PART_NAME" "CAP_A"
					( Origin gPackager )
				)
				( attribute "CDS_PART_NAME" "CAP_A_0603V-22.0UF,4V,20%,X6S,A"
					( Origin gPackager )
				)
				( attribute "GROUP" "PWR_MLCC_CAP"
					( Origin gFrontEnd )
				)
				( objectStatus "C2D23" )
			)
			( gate "@baseboard_fab2_lib.baseboard_fab2(sch_1):page76_i114"
				( attribute "BOM_COST" "PROC"
					( Origin gFrontEnd )
				)
				( attribute "CDS_LIB" "dev_discrete"
					( Origin gPackager )
				)
				( attribute "CDS_LOCATION" "C2D17"
					( Origin gPackager )
				)
				( attribute "CDS_SEC" "1"
					( Origin gPackager )
				)
				( attribute "LOCATION" "C2D17"
					( Origin gFrontEnd )
				)
				( attribute "MATERIAL" "X6S"
					( Origin gFrontEnd )
				)
				( attribute "PACK_TYPE" "0603V"
					( Origin gFrontEnd )
				)
				( attribute "PART_NUMBER" "E15431-004"
					( Origin gFrontEnd )
				)
				( attribute "PHYS_PAGE" "76"
					( Origin gFrontEnd )
				)
				( attribute "ROOM" "PVCCIN_CPU1_DECAP_VR"
					( Origin gFrontEnd )
				)
				( attribute "ROT" "0"
					( Origin gFrontEnd )
				)
				( attribute "SEC" "1"
					( Origin gPackager )
				)
				( attribute "TOLERANCE" "20%"
					( Origin gFrontEnd )
				)
				( attribute "VALUE" "22.0UF"
					( Origin gFrontEnd )
				)
				( attribute "VER" "1"
					( Origin gFrontEnd )
				)
				( attribute "VOLTAGE" "4V"
					( Units "uVoltage" "V" 1.000000)
					( Origin gFrontEnd )
				)
				( attribute "XY" "(-7050,3050)"
					( Origin gFrontEnd )
				)
				( attribute "CHIPS_PART_NAME" "CAP_A"
					( Origin gPackager )
				)
				( attribute "CDS_PART_NAME" "CAP_A_0603V-22.0UF,4V,20%,X6S,A"
					( Origin gPackager )
				)
				( attribute "GROUP" "PWR_MLCC_CAP"
					( Origin gFrontEnd )
				)
				( objectStatus "C2D17" )
			)
			( gate "@baseboard_fab2_lib.baseboard_fab2(sch_1):page228_i257"
				( attribute "BOM_COST" "PROC"
					( Origin gFrontEnd )
				)
				( attribute "CDS_LIB" "dev_discrete"
					( Origin gPackager )
				)
				( attribute "CDS_LOCATION" "C2D2"
					( Origin gPackager )
				)
				( attribute "LOCATION" "C2D2"
					( Origin gFrontEnd )
				)
				( attribute "MATERIAL" "X6S"
					( Origin gFrontEnd )
				)
				( attribute "PACK_TYPE" "0603V"
					( Origin gFrontEnd )
				)
				( attribute "PART_NUMBER" "E15431-004"
					( Origin gFrontEnd )
				)
				( attribute "PHYS_PAGE" "228"
					( Origin gFrontEnd )
				)
				( attribute "ROOM" "PVCCIN_CPU1_DECAP_VR"
					( Origin gFrontEnd )
				)
				( attribute "ROT" "0"
					( Origin gFrontEnd )
				)
				( attribute "SEC" "1"
					( Origin gFrontEnd )
				)
				( attribute "SEC_TYPE" "0603V"
					( Origin gFrontEnd )
				)
				( attribute "TOLERANCE" "20%"
					( Origin gFrontEnd )
				)
				( attribute "VALUE" "22.0UF"
					( Origin gFrontEnd )
				)
				( attribute "VER" "1"
					( Origin gFrontEnd )
				)
				( attribute "VOLTAGE" "4V"
					( Units "uVoltage" "V" 1.000000)
					( Origin gFrontEnd )
				)
				( attribute "XY" "(950,1800)"
					( Origin gFrontEnd )
				)
				( attribute "CHIPS_PART_NAME" "CAP_A"
					( Origin gPackager )
				)
				( attribute "CDS_PART_NAME" "CAP_A_0603V-22.0UF,4V,20%,X6S,A"
					( Origin gPackager )
				)
				( attribute "CDS_SEC" "1"
					( Origin gPackager )
				)
				( attribute "GROUP" "PWR_MLCC_CAP"
					( Origin gFrontEnd )
				)
				( objectStatus "C2D2" )
			)
			( gate "@baseboard_fab2_lib.baseboard_fab2(sch_1):page76_i118"
				( attribute "BOM_COST" "PROC"
					( Origin gFrontEnd )
				)
				( attribute "CDS_LIB" "mstr_discrete"
					( Origin gPackager )
				)
				( attribute "CDS_LOCATION" "C8P26"
					( Origin gPackager )
				)
				( attribute "CDS_SEC" "1"
					( Origin gPackager )
				)
				( attribute "LOCATION" "C8P26"
					( Origin gFrontEnd )
				)
				( attribute "MATERIAL" "X6S"
					( Origin gFrontEnd )
				)
				( attribute "PACK_TYPE" "0805"
					( Origin gFrontEnd )
				)
				( attribute "PART_NUMBER" "C95333-006"
					( Origin gFrontEnd )
				)
				( attribute "PHYS_PAGE" "76"
					( Origin gFrontEnd )
				)
				( attribute "ROOM" "PVCCIN_CPU1_DECAP_VR"
					( Origin gFrontEnd )
				)
				( attribute "ROT" "0"
					( Origin gFrontEnd )
				)
				( attribute "SEC" "1"
					( Origin gPackager )
				)
				( attribute "TOLERANCE" "20%"
					( Origin gFrontEnd )
				)
				( attribute "VALUE" "47UF"
					( Origin gFrontEnd )
				)
				( attribute "VER" "1"
					( Origin gFrontEnd )
				)
				( attribute "VOLTAGE" "4V"
					( Units "uVoltage" "V" 1.000000)
					( Origin gFrontEnd )
				)
				( attribute "XY" "(-7150,2200)"
					( Origin gFrontEnd )
				)
				( attribute "CHIPS_PART_NAME" "CAP"
					( Origin gPackager )
				)
				( attribute "CDS_PART_NAME" "CAP_0805-47UF,4V,20%,X6S,C9533A"
					( Origin gPackager )
				)
				( attribute "GROUP" "PWR_MLCC_CAP"
					( Origin gFrontEnd )
				)
				( objectStatus "C8P26" )
			)
			( gate "@baseboard_fab2_lib.baseboard_fab2(sch_1):page76_i119"
				( attribute "BOM_COST" "PROC"
					( Origin gFrontEnd )
				)
				( attribute "CDS_LIB" "dev_discrete"
					( Origin gPackager )
				)
				( attribute "CDS_LOCATION" "C2D37"
					( Origin gPackager )
				)
				( attribute "CDS_SEC" "1"
					( Origin gPackager )
				)
				( attribute "LOCATION" "C2D37"
					( Origin gFrontEnd )
				)
				( attribute "MATERIAL" "X6S"
					( Origin gFrontEnd )
				)
				( attribute "PACK_TYPE" "0603V"
					( Origin gFrontEnd )
				)
				( attribute "PART_NUMBER" "E15431-004"
					( Origin gFrontEnd )
				)
				( attribute "PHYS_PAGE" "76"
					( Origin gFrontEnd )
				)
				( attribute "ROOM" "PVCCIN_CPU1_DECAP_VR"
					( Origin gFrontEnd )
				)
				( attribute "ROT" "0"
					( Origin gFrontEnd )
				)
				( attribute "SEC" "1"
					( Origin gPackager )
				)
				( attribute "TOLERANCE" "20%"
					( Origin gFrontEnd )
				)
				( attribute "VALUE" "22.0UF"
					( Origin gFrontEnd )
				)
				( attribute "VER" "1"
					( Origin gFrontEnd )
				)
				( attribute "VOLTAGE" "4V"
					( Units "uVoltage" "V" 1.000000)
					( Origin gFrontEnd )
				)
				( attribute "XY" "(-7450,3750)"
					( Origin gFrontEnd )
				)
				( attribute "CHIPS_PART_NAME" "CAP_A"
					( Origin gPackager )
				)
				( attribute "CDS_PART_NAME" "CAP_A_0603V-22.0UF,4V,20%,X6S,A"
					( Origin gPackager )
				)
				( attribute "GROUP" "PWR_MLCC_CAP"
					( Origin gFrontEnd )
				)
				( objectStatus "C2D37" )
			)
			( gate "@baseboard_fab2_lib.baseboard_fab2(sch_1):page76_i122"
				( attribute "BOM_COST" "PROC"
					( Origin gFrontEnd )
				)
				( attribute "CDS_LIB" "dev_discrete"
					( Origin gPackager )
				)
				( attribute "CDS_LOCATION" "C2D34"
					( Origin gPackager )
				)
				( attribute "CDS_SEC" "1"
					( Origin gPackager )
				)
				( attribute "LOCATION" "C2D34"
					( Origin gFrontEnd )
				)
				( attribute "MATERIAL" "X6S"
					( Origin gFrontEnd )
				)
				( attribute "PACK_TYPE" "0603V"
					( Origin gFrontEnd )
				)
				( attribute "PART_NUMBER" "E15431-004"
					( Origin gFrontEnd )
				)
				( attribute "PHYS_PAGE" "76"
					( Origin gFrontEnd )
				)
				( attribute "ROOM" "PVCCIN_CPU1_DECAP_VR"
					( Origin gFrontEnd )
				)
				( attribute "ROT" "0"
					( Origin gFrontEnd )
				)
				( attribute "SEC" "1"
					( Origin gPackager )
				)
				( attribute "TOLERANCE" "20%"
					( Origin gFrontEnd )
				)
				( attribute "VALUE" "22.0UF"
					( Origin gFrontEnd )
				)
				( attribute "VER" "1"
					( Origin gFrontEnd )
				)
				( attribute "VOLTAGE" "4V"
					( Units "uVoltage" "V" 1.000000)
					( Origin gFrontEnd )
				)
				( attribute "XY" "(-7750,3750)"
					( Origin gFrontEnd )
				)
				( attribute "CHIPS_PART_NAME" "CAP_A"
					( Origin gPackager )
				)
				( attribute "CDS_PART_NAME" "CAP_A_0603V-22.0UF,4V,20%,X6S,A"
					( Origin gPackager )
				)
				( attribute "GROUP" "PWR_MLCC_CAP"
					( Origin gFrontEnd )
				)
				( objectStatus "C2D34" )
			)
			( gate "@baseboard_fab2_lib.baseboard_fab2(sch_1):page228_i258"
				( attribute "BOM_COST" "PROC"
					( Origin gFrontEnd )
				)
				( attribute "CDS_LIB" "dev_discrete"
					( Origin gPackager )
				)
				( attribute "CDS_LOCATION" "C2D1"
					( Origin gPackager )
				)
				( attribute "CDS_SEC" "1"
					( Origin gPackager )
				)
				( attribute "LOCATION" "C2D1"
					( Origin gFrontEnd )
				)
				( attribute "MATERIAL" "X6S"
					( Origin gFrontEnd )
				)
				( attribute "PACK_TYPE" "0603V"
					( Origin gFrontEnd )
				)
				( attribute "PART_NUMBER" "E15431-004"
					( Origin gFrontEnd )
				)
				( attribute "PHYS_PAGE" "228"
					( Origin gFrontEnd )
				)
				( attribute "ROOM" "PVCCIN_CPU1_DECAP_VR"
					( Origin gFrontEnd )
				)
				( attribute "ROT" "0"
					( Origin gFrontEnd )
				)
				( attribute "SEC" "1"
					( Origin gPackager )
				)
				( attribute "TOLERANCE" "20%"
					( Origin gFrontEnd )
				)
				( attribute "VALUE" "22.0UF"
					( Origin gFrontEnd )
				)
				( attribute "VER" "1"
					( Origin gFrontEnd )
				)
				( attribute "VOLTAGE" "4V"
					( Units "uVoltage" "V" 1.000000)
					( Origin gFrontEnd )
				)
				( attribute "XY" "(600,1800)"
					( Origin gFrontEnd )
				)
				( attribute "CHIPS_PART_NAME" "CAP_A"
					( Origin gPackager )
				)
				( attribute "CDS_PART_NAME" "CAP_A_0603V-22.0UF,4V,20%,X6S,A"
					( Origin gPackager )
				)
				( attribute "GROUP" "PWR_MLCC_CAP"
					( Origin gFrontEnd )
				)
				( objectStatus "C2D1" )
			)
			( gate "@baseboard_fab2_lib.baseboard_fab2(sch_1):page76_i124"
				( attribute "BOM_COST" "PROC"
					( Origin gFrontEnd )
				)
				( attribute "CDS_LIB" "dev_discrete"
					( Origin gPackager )
				)
				( attribute "CDS_LOCATION" "C2D16"
					( Origin gPackager )
				)
				( attribute "CDS_SEC" "1"
					( Origin gPackager )
				)
				( attribute "LOCATION" "C2D16"
					( Origin gFrontEnd )
				)
				( attribute "MATERIAL" "X6S"
					( Origin gFrontEnd )
				)
				( attribute "PACK_TYPE" "0603V"
					( Origin gFrontEnd )
				)
				( attribute "PART_NUMBER" "E15431-004"
					( Origin gFrontEnd )
				)
				( attribute "PHYS_PAGE" "76"
					( Origin gFrontEnd )
				)
				( attribute "ROOM" "PVCCIN_CPU1_DECAP_VR"
					( Origin gFrontEnd )
				)
				( attribute "ROT" "0"
					( Origin gFrontEnd )
				)
				( attribute "SEC" "1"
					( Origin gPackager )
				)
				( attribute "TOLERANCE" "20%"
					( Origin gFrontEnd )
				)
				( attribute "VALUE" "22.0UF"
					( Origin gFrontEnd )
				)
				( attribute "VER" "1"
					( Origin gFrontEnd )
				)
				( attribute "VOLTAGE" "4V"
					( Units "uVoltage" "V" 1.000000)
					( Origin gFrontEnd )
				)
				( attribute "XY" "(-7750,3050)"
					( Origin gFrontEnd )
				)
				( attribute "CHIPS_PART_NAME" "CAP_A"
					( Origin gPackager )
				)
				( attribute "CDS_PART_NAME" "CAP_A_0603V-22.0UF,4V,20%,X6S,A"
					( Origin gPackager )
				)
				( attribute "GROUP" "PWR_MLCC_CAP"
					( Origin gFrontEnd )
				)
				( objectStatus "C2D16" )
			)
			( gate "@baseboard_fab2_lib.baseboard_fab2(sch_1):page76_i125"
				( attribute "BOM_COST" "PROC"
					( Origin gFrontEnd )
				)
				( attribute "CDS_LIB" "mstr_discrete"
					( Origin gPackager )
				)
				( attribute "CDS_LOCATION" "C8P29"
					( Origin gPackager )
				)
				( attribute "CDS_SEC" "1"
					( Origin gPackager )
				)
				( attribute "LOCATION" "C8P29"
					( Origin gFrontEnd )
				)
				( attribute "MATERIAL" "X6S"
					( Origin gFrontEnd )
				)
				( attribute "PACK_TYPE" "0805"
					( Origin gFrontEnd )
				)
				( attribute "PART_NUMBER" "C95333-006"
					( Origin gFrontEnd )
				)
				( attribute "PHYS_PAGE" "76"
					( Origin gFrontEnd )
				)
				( attribute "ROOM" "PVCCIN_CPU1_DECAP_VR"
					( Origin gFrontEnd )
				)
				( attribute "ROT" "0"
					( Origin gFrontEnd )
				)
				( attribute "SEC" "1"
					( Origin gPackager )
				)
				( attribute "TOLERANCE" "20%"
					( Origin gFrontEnd )
				)
				( attribute "VALUE" "47UF"
					( Origin gFrontEnd )
				)
				( attribute "VER" "1"
					( Origin gFrontEnd )
				)
				( attribute "VOLTAGE" "4V"
					( Units "uVoltage" "V" 1.000000)
					( Origin gFrontEnd )
				)
				( attribute "XY" "(-7450,2200)"
					( Origin gFrontEnd )
				)
				( attribute "CHIPS_PART_NAME" "CAP"
					( Origin gPackager )
				)
				( attribute "CDS_PART_NAME" "CAP_0805-47UF,4V,20%,X6S,C9533A"
					( Origin gPackager )
				)
				( attribute "GROUP" "PWR_MLCC_CAP"
					( Origin gFrontEnd )
				)
				( objectStatus "C8P29" )
			)
			( gate "@baseboard_fab2_lib.baseboard_fab2(sch_1):page76_i127"
				( attribute "BOM_COST" "PROC"
					( Origin gFrontEnd )
				)
				( attribute "CDS_LIB" "mstr_discrete"
					( Origin gPackager )
				)
				( attribute "CDS_LOCATION" "C8P10"
					( Origin gPackager )
				)
				( attribute "CDS_SEC" "1"
					( Origin gPackager )
				)
				( attribute "LOCATION" "C8P10"
					( Origin gFrontEnd )
				)
				( attribute "MATERIAL" "X6S"
					( Origin gFrontEnd )
				)
				( attribute "PACK_TYPE" "0805"
					( Origin gFrontEnd )
				)
				( attribute "PART_NUMBER" "C95333-006"
					( Origin gFrontEnd )
				)
				( attribute "PHYS_PAGE" "76"
					( Origin gFrontEnd )
				)
				( attribute "ROOM" "PVCCIN_CPU1_DECAP_VR"
					( Origin gFrontEnd )
				)
				( attribute "ROT" "0"
					( Origin gFrontEnd )
				)
				( attribute "SEC" "1"
					( Origin gPackager )
				)
				( attribute "TOLERANCE" "20%"
					( Origin gFrontEnd )
				)
				( attribute "VALUE" "47UF"
					( Origin gFrontEnd )
				)
				( attribute "VER" "1"
					( Origin gFrontEnd )
				)
				( attribute "VOLTAGE" "4V"
					( Units "uVoltage" "V" 1.000000)
					( Origin gFrontEnd )
				)
				( attribute "XY" "(-7750,2200)"
					( Origin gFrontEnd )
				)
				( attribute "CHIPS_PART_NAME" "CAP"
					( Origin gPackager )
				)
				( attribute "CDS_PART_NAME" "CAP_0805-47UF,4V,20%,X6S,C9533A"
					( Origin gPackager )
				)
				( attribute "GROUP" "PWR_MLCC_CAP"
					( Origin gFrontEnd )
				)
				( objectStatus "C8P10" )
			)
			( gate "@baseboard_fab2_lib.baseboard_fab2(sch_1):page76_i129"
				( attribute "BOM_COST" "PROC"
					( Origin gFrontEnd )
				)
				( attribute "CDS_LIB" "mstr_discrete"
					( Origin gPackager )
				)
				( attribute "CDS_LOCATION" "C8P16"
					( Origin gPackager )
				)
				( attribute "CDS_SEC" "1"
					( Origin gPackager )
				)
				( attribute "LOCATION" "C8P16"
					( Origin gFrontEnd )
				)
				( attribute "MATERIAL" "X6S"
					( Origin gFrontEnd )
				)
				( attribute "PACK_TYPE" "0805"
					( Origin gFrontEnd )
				)
				( attribute "PART_NUMBER" "C95333-006"
					( Origin gFrontEnd )
				)
				( attribute "PHYS_PAGE" "76"
					( Origin gFrontEnd )
				)
				( attribute "ROOM" "PVCCIN_CPU1_DECAP_VR"
					( Origin gFrontEnd )
				)
				( attribute "ROT" "0"
					( Origin gFrontEnd )
				)
				( attribute "SEC" "1"
					( Origin gPackager )
				)
				( attribute "TOLERANCE" "20%"
					( Origin gFrontEnd )
				)
				( attribute "VALUE" "47UF"
					( Origin gFrontEnd )
				)
				( attribute "VER" "1"
					( Origin gFrontEnd )
				)
				( attribute "VOLTAGE" "4V"
					( Units "uVoltage" "V" 1.000000)
					( Origin gFrontEnd )
				)
				( attribute "XY" "(-6550,1500)"
					( Origin gFrontEnd )
				)
				( attribute "CHIPS_PART_NAME" "CAP"
					( Origin gPackager )
				)
				( attribute "CDS_PART_NAME" "CAP_0805-47UF,4V,20%,X6S,C9533A"
					( Origin gPackager )
				)
				( attribute "GROUP" "PWR_MLCC_CAP"
					( Origin gFrontEnd )
				)
				( objectStatus "C8P16" )
			)
			( gate "@baseboard_fab2_lib.baseboard_fab2(sch_1):page166_i36"
				( attribute "BOM_COST" "PROC_SIDEBAND"
					( Origin gFrontEnd )
				)
				( attribute "CDS_LIB" "dev_discrete"
					( Origin gPackager )
				)
				( attribute "CDS_LOCATION" "C7W1"
					( Origin gPackager )
				)
				( attribute "CDS_SEC" "1"
					( Origin gPackager )
				)
				( attribute "LOCATION" "C7W1"
					( Origin gFrontEnd )
				)
				( attribute "MATERIAL" "X7R"
					( Origin gFrontEnd )
				)
				( attribute "PACK_TYPE" "0402V"
					( Origin gFrontEnd )
				)
				( attribute "PART_NUMBER" "A36096-030"
					( Origin gFrontEnd )
				)
				( attribute "PHYS_PAGE" "166"
					( Origin gFrontEnd )
				)
				( attribute "ROOM" "PROC_SIDEBAND"
					( Origin gFrontEnd )
				)
				( attribute "ROT" "0"
					( Origin gFrontEnd )
				)
				( attribute "SEC" "1"
					( Origin gFrontEnd )
				)
				( attribute "SEC_TYPE" "0402V"
					( Origin gFrontEnd )
				)
				( attribute "TOLERANCE" "10%"
					( Origin gFrontEnd )
				)
				( attribute "VALUE" "0.1UF"
					( Origin gFrontEnd )
				)
				( attribute "VER" "1"
					( Origin gFrontEnd )
				)
				( attribute "VOLTAGE" "16V"
					( Units "uVoltage" "V" 1.000000)
					( Origin gFrontEnd )
				)
				( attribute "XY" "(-2725,3225)"
					( Origin gFrontEnd )
				)
				( attribute "CHIPS_PART_NAME" "CAP_A"
					( Origin gPackager )
				)
				( attribute "CDS_PART_NAME" "CAP_A_0402V-0.1UF,16V,10%,X7R,A"
					( Origin gPackager )
				)
				( objectStatus "C7W1" )
			)
			( gate "@baseboard_fab2_lib.baseboard_fab2(sch_1):page76_i132"
				( attribute "BOM_COST" "PROC"
					( Origin gFrontEnd )
				)
				( attribute "CDS_LIB" "mstr_discrete"
					( Origin gPackager )
				)
				( attribute "CDS_LOCATION" "C8P13"
					( Origin gPackager )
				)
				( attribute "CDS_SEC" "1"
					( Origin gPackager )
				)
				( attribute "LOCATION" "C8P13"
					( Origin gFrontEnd )
				)
				( attribute "MATERIAL" "X6S"
					( Origin gFrontEnd )
				)
				( attribute "PACK_TYPE" "0805"
					( Origin gFrontEnd )
				)
				( attribute "PART_NUMBER" "C95333-006"
					( Origin gFrontEnd )
				)
				( attribute "PHYS_PAGE" "76"
					( Origin gFrontEnd )
				)
				( attribute "ROOM" "PVCCIN_CPU1_DECAP_VR"
					( Origin gFrontEnd )
				)
				( attribute "ROT" "0"
					( Origin gFrontEnd )
				)
				( attribute "SEC" "1"
					( Origin gPackager )
				)
				( attribute "TOLERANCE" "20%"
					( Origin gFrontEnd )
				)
				( attribute "VALUE" "47UF"
					( Origin gFrontEnd )
				)
				( attribute "VER" "1"
					( Origin gFrontEnd )
				)
				( attribute "VOLTAGE" "4V"
					( Units "uVoltage" "V" 1.000000)
					( Origin gFrontEnd )
				)
				( attribute "XY" "(-7150,1500)"
					( Origin gFrontEnd )
				)
				( attribute "CHIPS_PART_NAME" "CAP"
					( Origin gPackager )
				)
				( attribute "CDS_PART_NAME" "CAP_0805-47UF,4V,20%,X6S,C9533A"
					( Origin gPackager )
				)
				( attribute "GROUP" "PWR_MLCC_CAP"
					( Origin gFrontEnd )
				)
				( objectStatus "C8P13" )
			)
			( gate "@baseboard_fab2_lib.baseboard_fab2(sch_1):page76_i137"
				( attribute "BOM_COST" "PROC"
					( Origin gFrontEnd )
				)
				( attribute "CDS_LIB" "mstr_discrete"
					( Origin gPackager )
				)
				( attribute "CDS_LOCATION" "C8P28"
					( Origin gPackager )
				)
				( attribute "CDS_SEC" "1"
					( Origin gPackager )
				)
				( attribute "LOCATION" "C8P28"
					( Origin gFrontEnd )
				)
				( attribute "MATERIAL" "X6S"
					( Origin gFrontEnd )
				)
				( attribute "PACK_TYPE" "0805"
					( Origin gFrontEnd )
				)
				( attribute "PART_NUMBER" "C95333-006"
					( Origin gFrontEnd )
				)
				( attribute "PHYS_PAGE" "76"
					( Origin gFrontEnd )
				)
				( attribute "ROOM" "PVCCIN_CPU1_DECAP_VR"
					( Origin gFrontEnd )
				)
				( attribute "ROT" "0"
					( Origin gFrontEnd )
				)
				( attribute "SEC" "1"
					( Origin gPackager )
				)
				( attribute "TOLERANCE" "20%"
					( Origin gFrontEnd )
				)
				( attribute "VALUE" "47UF"
					( Origin gFrontEnd )
				)
				( attribute "VER" "1"
					( Origin gFrontEnd )
				)
				( attribute "VOLTAGE" "4V"
					( Units "uVoltage" "V" 1.000000)
					( Origin gFrontEnd )
				)
				( attribute "XY" "(-7450,1500)"
					( Origin gFrontEnd )
				)
				( attribute "CHIPS_PART_NAME" "CAP"
					( Origin gPackager )
				)
				( attribute "CDS_PART_NAME" "CAP_0805-47UF,4V,20%,X6S,C9533A"
					( Origin gPackager )
				)
				( attribute "GROUP" "PWR_MLCC_CAP"
					( Origin gFrontEnd )
				)
				( objectStatus "C8P28" )
			)
			( gate "@baseboard_fab2_lib.baseboard_fab2(sch_1):page76_i139"
				( attribute "BOM_COST" "PROC"
					( Origin gFrontEnd )
				)
				( attribute "CDS_LIB" "mstr_discrete"
					( Origin gPackager )
				)
				( attribute "CDS_LOCATION" "C8P11"
					( Origin gPackager )
				)
				( attribute "CDS_SEC" "1"
					( Origin gPackager )
				)
				( attribute "LOCATION" "C8P11"
					( Origin gFrontEnd )
				)
				( attribute "MATERIAL" "X6S"
					( Origin gFrontEnd )
				)
				( attribute "PACK_TYPE" "0805"
					( Origin gFrontEnd )
				)
				( attribute "PART_NUMBER" "C95333-006"
					( Origin gFrontEnd )
				)
				( attribute "PHYS_PAGE" "76"
					( Origin gFrontEnd )
				)
				( attribute "ROOM" "PVCCIN_CPU1_DECAP_VR"
					( Origin gFrontEnd )
				)
				( attribute "ROT" "0"
					( Origin gFrontEnd )
				)
				( attribute "SEC" "1"
					( Origin gPackager )
				)
				( attribute "TOLERANCE" "20%"
					( Origin gFrontEnd )
				)
				( attribute "VALUE" "47UF"
					( Origin gFrontEnd )
				)
				( attribute "VER" "1"
					( Origin gFrontEnd )
				)
				( attribute "VOLTAGE" "4V"
					( Units "uVoltage" "V" 1.000000)
					( Origin gFrontEnd )
				)
				( attribute "XY" "(-7750,1500)"
					( Origin gFrontEnd )
				)
				( attribute "CHIPS_PART_NAME" "CAP"
					( Origin gPackager )
				)
				( attribute "CDS_PART_NAME" "CAP_0805-47UF,4V,20%,X6S,C9533A"
					( Origin gPackager )
				)
				( attribute "GROUP" "PWR_MLCC_CAP"
					( Origin gFrontEnd )
				)
				( objectStatus "C8P11" )
			)
			( gate "@baseboard_fab2_lib.baseboard_fab2(sch_1):page196_i130"
				( attribute "BOM_COST" "SB"
					( Origin gFrontEnd )
				)
				( attribute "CDS_LIB" "mstr_discrete"
					( Origin gPackager )
				)
				( attribute "CDS_LOCATION" "R8D40"
					( Origin gPackager )
				)
				( attribute "CDS_SEC" "1"
					( Origin gPackager )
				)
				( attribute "LOCATION" "R8D40"
					( Origin gFrontEnd )
				)
				( attribute "MATERIAL" "CHIP"
					( Origin gFrontEnd )
				)
				( attribute "PACK_TYPE" "0402"
					( Origin gFrontEnd )
				)
				( attribute "PART_NUMBER" "G21796-040"
					( Origin gFrontEnd )
				)
				( attribute "PHYS_PAGE" "196"
					( Origin gFrontEnd )
				)
				( attribute "ROOM" "SB"
					( Origin gFrontEnd )
				)
				( attribute "ROT" "0"
					( Origin gFrontEnd )
				)
				( attribute "SEC" "1"
					( Origin gFrontEnd )
				)
				( attribute "SEC_TYPE" "0402"
					( Origin gFrontEnd )
				)
				( attribute "TOLERANCE" "1%"
					( Origin gFrontEnd )
				)
				( attribute "VALUE" "20.0K"
					( Origin gFrontEnd )
				)
				( attribute "VER" "2"
					( Origin gFrontEnd )
				)
				( attribute "WATTAGE" "1/16W"
					( Origin gFrontEnd )
				)
				( attribute "XY" "(-1750,2400)"
					( Origin gFrontEnd )
				)
				( attribute "CHIPS_PART_NAME" "RES"
					( Origin gPackager )
				)
				( attribute "CDS_PART_NAME" "RES_0402-20.0K,1%,1/16W,CHIP,GA"
					( Origin gPackager )
				)
				( objectStatus "R8D40" )
			)
			( gate "@baseboard_fab2_lib.baseboard_fab2(sch_1):page76_i159"
				( attribute "BOM_COST" "PROC"
					( Origin gFrontEnd )
				)
				( attribute "CDS_LIB" "dev_discrete"
					( Origin gPackager )
				)
				( attribute "CDS_LOCATION" "C2D15"
					( Origin gPackager )
				)
				( attribute "CDS_SEC" "1"
					( Origin gPackager )
				)
				( attribute "LOCATION" "C2D15"
					( Origin gFrontEnd )
				)
				( attribute "MATERIAL" "X6S"
					( Origin gFrontEnd )
				)
				( attribute "PACK_TYPE" "0603V"
					( Origin gFrontEnd )
				)
				( attribute "PART_NUMBER" "E15431-004"
					( Origin gFrontEnd )
				)
				( attribute "PHYS_PAGE" "76"
					( Origin gFrontEnd )
				)
				( attribute "ROOM" "PVCCIN_CPU1_DECAP_VR"
					( Origin gFrontEnd )
				)
				( attribute "ROT" "0"
					( Origin gFrontEnd )
				)
				( attribute "SEC" "1"
					( Origin gPackager )
				)
				( attribute "TOLERANCE" "20%"
					( Origin gFrontEnd )
				)
				( attribute "VALUE" "22.0UF"
					( Origin gFrontEnd )
				)
				( attribute "VER" "1"
					( Origin gFrontEnd )
				)
				( attribute "VOLTAGE" "4V"
					( Units "uVoltage" "V" 1.000000)
					( Origin gFrontEnd )
				)
				( attribute "XY" "(-4500,4450)"
					( Origin gFrontEnd )
				)
				( attribute "CHIPS_PART_NAME" "CAP_A"
					( Origin gPackager )
				)
				( attribute "CDS_PART_NAME" "CAP_A_0603V-22.0UF,4V,20%,X6S,A"
					( Origin gPackager )
				)
				( attribute "GROUP" "PWR_MLCC_CAP"
					( Origin gFrontEnd )
				)
				( objectStatus "C2D15" )
			)
			( gate "@baseboard_fab2_lib.baseboard_fab2(sch_1):page76_i160"
				( attribute "BOM_COST" "PROC"
					( Origin gFrontEnd )
				)
				( attribute "CDS_LIB" "dev_discrete"
					( Origin gPackager )
				)
				( attribute "CDS_LOCATION" "C2D38"
					( Origin gPackager )
				)
				( attribute "CDS_SEC" "1"
					( Origin gPackager )
				)
				( attribute "LOCATION" "C2D38"
					( Origin gFrontEnd )
				)
				( attribute "MATERIAL" "X6S"
					( Origin gFrontEnd )
				)
				( attribute "PACK_TYPE" "0603V"
					( Origin gFrontEnd )
				)
				( attribute "PART_NUMBER" "E15431-004"
					( Origin gFrontEnd )
				)
				( attribute "PHYS_PAGE" "76"
					( Origin gFrontEnd )
				)
				( attribute "ROOM" "PVCCIN_CPU1_DECAP_VR"
					( Origin gFrontEnd )
				)
				( attribute "ROT" "0"
					( Origin gFrontEnd )
				)
				( attribute "SEC" "1"
					( Origin gPackager )
				)
				( attribute "TOLERANCE" "20%"
					( Origin gFrontEnd )
				)
				( attribute "VALUE" "22.0UF"
					( Origin gFrontEnd )
				)
				( attribute "VER" "1"
					( Origin gFrontEnd )
				)
				( attribute "VOLTAGE" "4V"
					( Units "uVoltage" "V" 1.000000)
					( Origin gFrontEnd )
				)
				( attribute "XY" "(-4400,3750)"
					( Origin gFrontEnd )
				)
				( attribute "CHIPS_PART_NAME" "CAP_A"
					( Origin gPackager )
				)
				( attribute "CDS_PART_NAME" "CAP_A_0603V-22.0UF,4V,20%,X6S,A"
					( Origin gPackager )
				)
				( attribute "GROUP" "PWR_MLCC_CAP"
					( Origin gFrontEnd )
				)
				( objectStatus "C2D38" )
			)
			( gate "@baseboard_fab2_lib.baseboard_fab2(sch_1):page76_i161"
				( attribute "BOM_COST" "PROC"
					( Origin gFrontEnd )
				)
				( attribute "CDS_LIB" "dev_discrete"
					( Origin gPackager )
				)
				( attribute "CDS_LOCATION" "C2D35"
					( Origin gPackager )
				)
				( attribute "CDS_SEC" "1"
					( Origin gPackager )
				)
				( attribute "LOCATION" "C2D35"
					( Origin gFrontEnd )
				)
				( attribute "MATERIAL" "X6S"
					( Origin gFrontEnd )
				)
				( attribute "PACK_TYPE" "0603V"
					( Origin gFrontEnd )
				)
				( attribute "PART_NUMBER" "E15431-004"
					( Origin gFrontEnd )
				)
				( attribute "PHYS_PAGE" "76"
					( Origin gFrontEnd )
				)
				( attribute "ROOM" "PVCCIN_CPU1_DECAP_VR"
					( Origin gFrontEnd )
				)
				( attribute "ROT" "0"
					( Origin gFrontEnd )
				)
				( attribute "SEC" "1"
					( Origin gPackager )
				)
				( attribute "TOLERANCE" "20%"
					( Origin gFrontEnd )
				)
				( attribute "VALUE" "22.0UF"
					( Origin gFrontEnd )
				)
				( attribute "VER" "1"
					( Origin gFrontEnd )
				)
				( attribute "VOLTAGE" "4V"
					( Units "uVoltage" "V" 1.000000)
					( Origin gFrontEnd )
				)
				( attribute "XY" "(-4500,3050)"
					( Origin gFrontEnd )
				)
				( attribute "CHIPS_PART_NAME" "CAP_A"
					( Origin gPackager )
				)
				( attribute "CDS_PART_NAME" "CAP_A_0603V-22.0UF,4V,20%,X6S,A"
					( Origin gPackager )
				)
				( attribute "GROUP" "PWR_MLCC_CAP"
					( Origin gFrontEnd )
				)
				( objectStatus "C2D35" )
			)
			( gate "@baseboard_fab2_lib.baseboard_fab2(sch_1):page76_i164"
				( attribute "CDS_LIB" "dev_discrete"
					( Origin gPackager )
				)
				( attribute "CDS_LOCATION" "C3D7"
					( Origin gPackager )
				)
				( attribute "CDS_SEC" "1"
					( Origin gPackager )
				)
				( attribute "LOCATION" "C3D7"
					( Origin gFrontEnd )
				)
				( attribute "MATERIAL" "X6S"
					( Origin gFrontEnd )
				)
				( attribute "PACK_TYPE" "0603V"
					( Origin gFrontEnd )
				)
				( attribute "PART_NUMBER" "E15431-004"
					( Origin gFrontEnd )
				)
				( attribute "PHYS_PAGE" "76"
					( Origin gFrontEnd )
				)
				( attribute "ROOM" "PVCCIN_CPU1_DECAP_VR"
					( Origin gFrontEnd )
				)
				( attribute "ROT" "0"
					( Origin gFrontEnd )
				)
				( attribute "SEC" "1"
					( Origin gPackager )
				)
				( attribute "TOLERANCE" "20%"
					( Origin gFrontEnd )
				)
				( attribute "VALUE" "22.0UF"
					( Origin gFrontEnd )
				)
				( attribute "VER" "1"
					( Origin gFrontEnd )
				)
				( attribute "VOLTAGE" "4V"
					( Units "uVoltage" "V" 1.000000)
					( Origin gFrontEnd )
				)
				( attribute "XY" "(-4000,4450)"
					( Origin gFrontEnd )
				)
				( attribute "CHIPS_PART_NAME" "CAP_A"
					( Origin gPackager )
				)
				( attribute "CDS_PART_NAME" "CAP_A_0603V-22.0UF,4V,20%,X6S,A"
					( Origin gPackager )
				)
				( attribute "GROUP" "PWR_MCP_CAP"
					( Origin gFrontEnd )
				)
				( objectStatus "C3D7" )
			)
			( gate "@baseboard_fab2_lib.baseboard_fab2(sch_1):page76_i165"
				( attribute "BOM_COST" "PROC"
					( Origin gFrontEnd )
				)
				( attribute "CDS_LIB" "dev_discrete"
					( Origin gPackager )
				)
				( attribute "CDS_LOCATION" "C2D39"
					( Origin gPackager )
				)
				( attribute "CDS_SEC" "1"
					( Origin gPackager )
				)
				( attribute "LOCATION" "C2D39"
					( Origin gFrontEnd )
				)
				( attribute "MATERIAL" "X6S"
					( Origin gFrontEnd )
				)
				( attribute "PACK_TYPE" "0603V"
					( Origin gFrontEnd )
				)
				( attribute "PART_NUMBER" "E15431-004"
					( Origin gFrontEnd )
				)
				( attribute "PHYS_PAGE" "76"
					( Origin gFrontEnd )
				)
				( attribute "ROOM" "PVCCIN_CPU1_DECAP_VR"
					( Origin gFrontEnd )
				)
				( attribute "ROT" "0"
					( Origin gFrontEnd )
				)
				( attribute "SEC" "1"
					( Origin gPackager )
				)
				( attribute "TOLERANCE" "20%"
					( Origin gFrontEnd )
				)
				( attribute "VALUE" "22.0UF"
					( Origin gFrontEnd )
				)
				( attribute "VER" "1"
					( Origin gFrontEnd )
				)
				( attribute "VOLTAGE" "4V"
					( Units "uVoltage" "V" 1.000000)
					( Origin gFrontEnd )
				)
				( attribute "XY" "(-3750,4450)"
					( Origin gFrontEnd )
				)
				( attribute "CHIPS_PART_NAME" "CAP_A"
					( Origin gPackager )
				)
				( attribute "CDS_PART_NAME" "CAP_A_0603V-22.0UF,4V,20%,X6S,A"
					( Origin gPackager )
				)
				( attribute "GROUP" "PWR_MCP_CAP"
					( Origin gFrontEnd )
				)
				( objectStatus "C2D39" )
			)
			( gate "@baseboard_fab2_lib.baseboard_fab2(sch_1):page76_i166"
				( attribute "BOM_COST" "PROC"
					( Origin gFrontEnd )
				)
				( attribute "CDS_LIB" "dev_discrete"
					( Origin gPackager )
				)
				( attribute "CDS_LOCATION" "C3D17"
					( Origin gPackager )
				)
				( attribute "CDS_SEC" "1"
					( Origin gPackager )
				)
				( attribute "LOCATION" "C3D17"
					( Origin gFrontEnd )
				)
				( attribute "MATERIAL" "X6S"
					( Origin gFrontEnd )
				)
				( attribute "PACK_TYPE" "0603V"
					( Origin gFrontEnd )
				)
				( attribute "PART_NUMBER" "E15431-004"
					( Origin gFrontEnd )
				)
				( attribute "PHYS_PAGE" "76"
					( Origin gFrontEnd )
				)
				( attribute "ROOM" "PVCCIN_CPU1_DECAP_VR"
					( Origin gFrontEnd )
				)
				( attribute "ROT" "0"
					( Origin gFrontEnd )
				)
				( attribute "SEC" "1"
					( Origin gPackager )
				)
				( attribute "TOLERANCE" "20%"
					( Origin gFrontEnd )
				)
				( attribute "VALUE" "22.0UF"
					( Origin gFrontEnd )
				)
				( attribute "VER" "1"
					( Origin gFrontEnd )
				)
				( attribute "VOLTAGE" "4V"
					( Units "uVoltage" "V" 1.000000)
					( Origin gFrontEnd )
				)
				( attribute "XY" "(-3500,4450)"
					( Origin gFrontEnd )
				)
				( attribute "CHIPS_PART_NAME" "CAP_A"
					( Origin gPackager )
				)
				( attribute "CDS_PART_NAME" "CAP_A_0603V-22.0UF,4V,20%,X6S,A"
					( Origin gPackager )
				)
				( attribute "GROUP" "PWR_MCP_CAP"
					( Origin gFrontEnd )
				)
				( objectStatus "C3D17" )
			)
			( gate "@baseboard_fab2_lib.baseboard_fab2(sch_1):page76_i169"
				( attribute "BOM_COST" "PROC"
					( Origin gFrontEnd )
				)
				( attribute "CDS_LIB" "dev_discrete"
					( Origin gPackager )
				)
				( attribute "CDS_LOCATION" "C3D18"
					( Origin gPackager )
				)
				( attribute "CDS_SEC" "1"
					( Origin gPackager )
				)
				( attribute "LOCATION" "C3D18"
					( Origin gFrontEnd )
				)
				( attribute "MATERIAL" "X6S"
					( Origin gFrontEnd )
				)
				( attribute "PACK_TYPE" "0603V"
					( Origin gFrontEnd )
				)
				( attribute "PART_NUMBER" "E15431-004"
					( Origin gFrontEnd )
				)
				( attribute "PHYS_PAGE" "76"
					( Origin gFrontEnd )
				)
				( attribute "ROOM" "PVCCIN_CPU1_DECAP_VR"
					( Origin gFrontEnd )
				)
				( attribute "ROT" "0"
					( Origin gFrontEnd )
				)
				( attribute "SEC" "1"
					( Origin gPackager )
				)
				( attribute "TOLERANCE" "20%"
					( Origin gFrontEnd )
				)
				( attribute "VALUE" "22.0UF"
					( Origin gFrontEnd )
				)
				( attribute "VER" "1"
					( Origin gFrontEnd )
				)
				( attribute "VOLTAGE" "4V"
					( Units "uVoltage" "V" 1.000000)
					( Origin gFrontEnd )
				)
				( attribute "XY" "(-975,4450)"
					( Origin gFrontEnd )
				)
				( attribute "CHIPS_PART_NAME" "CAP_A"
					( Origin gPackager )
				)
				( attribute "CDS_PART_NAME" "CAP_A_0603V-22.0UF,4V,20%,X6S,A"
					( Origin gPackager )
				)
				( attribute "GROUP" "PWR_MCP_CAP"
					( Origin gFrontEnd )
				)
				( objectStatus "C3D18" )
			)
			( gate "@baseboard_fab2_lib.baseboard_fab2(sch_1):page76_i170"
				( attribute "BOM_COST" "PROC"
					( Origin gFrontEnd )
				)
				( attribute "CDS_LIB" "dev_discrete"
					( Origin gPackager )
				)
				( attribute "CDS_LOCATION" "C3D6"
					( Origin gPackager )
				)
				( attribute "CDS_SEC" "1"
					( Origin gPackager )
				)
				( attribute "LOCATION" "C3D6"
					( Origin gFrontEnd )
				)
				( attribute "MATERIAL" "X6S"
					( Origin gFrontEnd )
				)
				( attribute "PACK_TYPE" "0603V"
					( Origin gFrontEnd )
				)
				( attribute "PART_NUMBER" "E15431-004"
					( Origin gFrontEnd )
				)
				( attribute "PHYS_PAGE" "76"
					( Origin gFrontEnd )
				)
				( attribute "ROOM" "PVCCIN_CPU1_DECAP_VR"
					( Origin gFrontEnd )
				)
				( attribute "ROT" "0"
					( Origin gFrontEnd )
				)
				( attribute "SEC" "1"
					( Origin gPackager )
				)
				( attribute "TOLERANCE" "20%"
					( Origin gFrontEnd )
				)
				( attribute "VALUE" "22.0UF"
					( Origin gFrontEnd )
				)
				( attribute "VER" "1"
					( Origin gFrontEnd )
				)
				( attribute "VOLTAGE" "4V"
					( Units "uVoltage" "V" 1.000000)
					( Origin gFrontEnd )
				)
				( attribute "XY" "(-725,4450)"
					( Origin gFrontEnd )
				)
				( attribute "CHIPS_PART_NAME" "CAP_A"
					( Origin gPackager )
				)
				( attribute "CDS_PART_NAME" "CAP_A_0603V-22.0UF,4V,20%,X6S,A"
					( Origin gPackager )
				)
				( attribute "GROUP" "PWR_MCP_CAP"
					( Origin gFrontEnd )
				)
				( objectStatus "C3D6" )
			)
			( gate "@baseboard_fab2_lib.baseboard_fab2(sch_1):page76_i171"
				( attribute "BOM_COST" "PROC"
					( Origin gFrontEnd )
				)
				( attribute "CDS_LIB" "dev_discrete"
					( Origin gPackager )
				)
				( attribute "CDS_LOCATION" "C3D14"
					( Origin gPackager )
				)
				( attribute "CDS_SEC" "1"
					( Origin gPackager )
				)
				( attribute "LOCATION" "C3D14"
					( Origin gFrontEnd )
				)
				( attribute "MATERIAL" "X6S"
					( Origin gFrontEnd )
				)
				( attribute "PACK_TYPE" "0603V"
					( Origin gFrontEnd )
				)
				( attribute "PART_NUMBER" "E15431-004"
					( Origin gFrontEnd )
				)
				( attribute "PHYS_PAGE" "76"
					( Origin gFrontEnd )
				)
				( attribute "ROOM" "PVCCIN_CPU1_DECAP_VR"
					( Origin gFrontEnd )
				)
				( attribute "ROT" "0"
					( Origin gFrontEnd )
				)
				( attribute "SEC" "1"
					( Origin gPackager )
				)
				( attribute "TOLERANCE" "20%"
					( Origin gFrontEnd )
				)
				( attribute "VALUE" "22.0UF"
					( Origin gFrontEnd )
				)
				( attribute "VER" "1"
					( Origin gFrontEnd )
				)
				( attribute "VOLTAGE" "4V"
					( Units "uVoltage" "V" 1.000000)
					( Origin gFrontEnd )
				)
				( attribute "XY" "(-2725,4450)"
					( Origin gFrontEnd )
				)
				( attribute "CHIPS_PART_NAME" "CAP_A"
					( Origin gPackager )
				)
				( attribute "CDS_PART_NAME" "CAP_A_0603V-22.0UF,4V,20%,X6S,A"
					( Origin gPackager )
				)
				( attribute "GROUP" "PWR_MCP_CAP"
					( Origin gFrontEnd )
				)
				( objectStatus "C3D14" )
			)
			( gate "@baseboard_fab2_lib.baseboard_fab2(sch_1):page76_i172"
				( attribute "BOM_COST" "PROC"
					( Origin gFrontEnd )
				)
				( attribute "CDS_LIB" "dev_discrete"
					( Origin gPackager )
				)
				( attribute "CDS_LOCATION" "C3D23"
					( Origin gPackager )
				)
				( attribute "CDS_SEC" "1"
					( Origin gPackager )
				)
				( attribute "LOCATION" "C3D23"
					( Origin gFrontEnd )
				)
				( attribute "MATERIAL" "X6S"
					( Origin gFrontEnd )
				)
				( attribute "PACK_TYPE" "0603V"
					( Origin gFrontEnd )
				)
				( attribute "PART_NUMBER" "E15431-004"
					( Origin gFrontEnd )
				)
				( attribute "PHYS_PAGE" "76"
					( Origin gFrontEnd )
				)
				( attribute "ROOM" "PVCCIN_CPU1_DECAP_VR"
					( Origin gFrontEnd )
				)
				( attribute "ROT" "0"
					( Origin gFrontEnd )
				)
				( attribute "SEC" "1"
					( Origin gPackager )
				)
				( attribute "TOLERANCE" "20%"
					( Origin gFrontEnd )
				)
				( attribute "VALUE" "22.0UF"
					( Origin gFrontEnd )
				)
				( attribute "VER" "1"
					( Origin gFrontEnd )
				)
				( attribute "VOLTAGE" "4V"
					( Units "uVoltage" "V" 1.000000)
					( Origin gFrontEnd )
				)
				( attribute "XY" "(-3850,3750)"
					( Origin gFrontEnd )
				)
				( attribute "CHIPS_PART_NAME" "CAP_A"
					( Origin gPackager )
				)
				( attribute "CDS_PART_NAME" "CAP_A_0603V-22.0UF,4V,20%,X6S,A"
					( Origin gPackager )
				)
				( attribute "GROUP" "PWR_MLCC_CAP"
					( Origin gFrontEnd )
				)
				( objectStatus "C3D23" )
			)
			( gate "@baseboard_fab2_lib.baseboard_fab2(sch_1):page76_i174"
				( attribute "BOM_COST" "PROC"
					( Origin gFrontEnd )
				)
				( attribute "CDS_LIB" "dev_discrete"
					( Origin gPackager )
				)
				( attribute "CDS_LOCATION" "C3D15"
					( Origin gPackager )
				)
				( attribute "CDS_SEC" "1"
					( Origin gPackager )
				)
				( attribute "LOCATION" "C3D15"
					( Origin gFrontEnd )
				)
				( attribute "MATERIAL" "X6S"
					( Origin gFrontEnd )
				)
				( attribute "PACK_TYPE" "0603V"
					( Origin gFrontEnd )
				)
				( attribute "PART_NUMBER" "E15431-004"
					( Origin gFrontEnd )
				)
				( attribute "PHYS_PAGE" "76"
					( Origin gFrontEnd )
				)
				( attribute "ROOM" "PVCCIN_CPU1_DECAP_VR"
					( Origin gFrontEnd )
				)
				( attribute "ROT" "0"
					( Origin gFrontEnd )
				)
				( attribute "SEC" "1"
					( Origin gPackager )
				)
				( attribute "TOLERANCE" "20%"
					( Origin gFrontEnd )
				)
				( attribute "VALUE" "22.0UF"
					( Origin gFrontEnd )
				)
				( attribute "VER" "1"
					( Origin gFrontEnd )
				)
				( attribute "VOLTAGE" "4V"
					( Units "uVoltage" "V" 1.000000)
					( Origin gFrontEnd )
				)
				( attribute "XY" "(-3550,3750)"
					( Origin gFrontEnd )
				)
				( attribute "CHIPS_PART_NAME" "CAP_A"
					( Origin gPackager )
				)
				( attribute "CDS_PART_NAME" "CAP_A_0603V-22.0UF,4V,20%,X6S,A"
					( Origin gPackager )
				)
				( attribute "GROUP" "PWR_MLCC_CAP"
					( Origin gFrontEnd )
				)
				( objectStatus "C3D15" )
			)
			( gate "@baseboard_fab2_lib.baseboard_fab2(sch_1):page76_i175"
				( attribute "BOM_COST" "PROC"
					( Origin gFrontEnd )
				)
				( attribute "CDS_LIB" "dev_discrete"
					( Origin gPackager )
				)
				( attribute "CDS_LOCATION" "C3D24"
					( Origin gPackager )
				)
				( attribute "CDS_SEC" "1"
					( Origin gPackager )
				)
				( attribute "LOCATION" "C3D24"
					( Origin gFrontEnd )
				)
				( attribute "MATERIAL" "X6S"
					( Origin gFrontEnd )
				)
				( attribute "PACK_TYPE" "0603V"
					( Origin gFrontEnd )
				)
				( attribute "PART_NUMBER" "E15431-004"
					( Origin gFrontEnd )
				)
				( attribute "PHYS_PAGE" "76"
					( Origin gFrontEnd )
				)
				( attribute "ROOM" "PVCCIN_CPU1_DECAP_VR"
					( Origin gFrontEnd )
				)
				( attribute "ROT" "0"
					( Origin gFrontEnd )
				)
				( attribute "SEC" "1"
					( Origin gPackager )
				)
				( attribute "TOLERANCE" "20%"
					( Origin gFrontEnd )
				)
				( attribute "VALUE" "22.0UF"
					( Origin gFrontEnd )
				)
				( attribute "VER" "1"
					( Origin gFrontEnd )
				)
				( attribute "VOLTAGE" "4V"
					( Units "uVoltage" "V" 1.000000)
					( Origin gFrontEnd )
				)
				( attribute "XY" "(-3250,3750)"
					( Origin gFrontEnd )
				)
				( attribute "CHIPS_PART_NAME" "CAP_A"
					( Origin gPackager )
				)
				( attribute "CDS_PART_NAME" "CAP_A_0603V-22.0UF,4V,20%,X6S,A"
					( Origin gPackager )
				)
				( attribute "GROUP" "PWR_MLCC_CAP"
					( Origin gFrontEnd )
				)
				( objectStatus "C3D24" )
			)
			( gate "@baseboard_fab2_lib.baseboard_fab2(sch_1):page76_i176"
				( attribute "BOM_COST" "PROC"
					( Origin gFrontEnd )
				)
				( attribute "CDS_LIB" "dev_discrete"
					( Origin gPackager )
				)
				( attribute "CDS_LOCATION" "C3D16"
					( Origin gPackager )
				)
				( attribute "CDS_SEC" "1"
					( Origin gPackager )
				)
				( attribute "LOCATION" "C3D16"
					( Origin gFrontEnd )
				)
				( attribute "MATERIAL" "X6S"
					( Origin gFrontEnd )
				)
				( attribute "PACK_TYPE" "0603V"
					( Origin gFrontEnd )
				)
				( attribute "PART_NUMBER" "E15431-004"
					( Origin gFrontEnd )
				)
				( attribute "PHYS_PAGE" "76"
					( Origin gFrontEnd )
				)
				( attribute "ROOM" "PVCCIN_CPU1_DECAP_VR"
					( Origin gFrontEnd )
				)
				( attribute "ROT" "0"
					( Origin gFrontEnd )
				)
				( attribute "SEC" "1"
					( Origin gPackager )
				)
				( attribute "TOLERANCE" "20%"
					( Origin gFrontEnd )
				)
				( attribute "VALUE" "22.0UF"
					( Origin gFrontEnd )
				)
				( attribute "VER" "1"
					( Origin gFrontEnd )
				)
				( attribute "VOLTAGE" "4V"
					( Units "uVoltage" "V" 1.000000)
					( Origin gFrontEnd )
				)
				( attribute "XY" "(-2950,3750)"
					( Origin gFrontEnd )
				)
				( attribute "CHIPS_PART_NAME" "CAP_A"
					( Origin gPackager )
				)
				( attribute "CDS_PART_NAME" "CAP_A_0603V-22.0UF,4V,20%,X6S,A"
					( Origin gPackager )
				)
				( attribute "GROUP" "PWR_MLCC_CAP"
					( Origin gFrontEnd )
				)
				( objectStatus "C3D16" )
			)
			( gate "@baseboard_fab2_lib.baseboard_fab2(sch_1):page76_i179"
				( attribute "BOM_COST" "PROC"
					( Origin gFrontEnd )
				)
				( attribute "CDS_LIB" "dev_discrete"
					( Origin gPackager )
				)
				( attribute "CDS_LOCATION" "C7P12"
					( Origin gPackager )
				)
				( attribute "CDS_SEC" "1"
					( Origin gPackager )
				)
				( attribute "LOCATION" "C7P12"
					( Origin gFrontEnd )
				)
				( attribute "MATERIAL" "X6S"
					( Origin gFrontEnd )
				)
				( attribute "PACK_TYPE" "0603V"
					( Origin gFrontEnd )
				)
				( attribute "PART_NUMBER" "E15431-004"
					( Origin gFrontEnd )
				)
				( attribute "PHYS_PAGE" "76"
					( Origin gFrontEnd )
				)
				( attribute "ROOM" "PVCCIN_CPU1_DECAP_VR"
					( Origin gFrontEnd )
				)
				( attribute "ROT" "0"
					( Origin gFrontEnd )
				)
				( attribute "SEC" "1"
					( Origin gPackager )
				)
				( attribute "TOLERANCE" "20%"
					( Origin gFrontEnd )
				)
				( attribute "VALUE" "22.0UF"
					( Origin gFrontEnd )
				)
				( attribute "VER" "1"
					( Origin gFrontEnd )
				)
				( attribute "VOLTAGE" "4V"
					( Units "uVoltage" "V" 1.000000)
					( Origin gFrontEnd )
				)
				( attribute "XY" "(-2400,1150)"
					( Origin gFrontEnd )
				)
				( attribute "CHIPS_PART_NAME" "CAP_A"
					( Origin gPackager )
				)
				( attribute "CDS_PART_NAME" "CAP_A_0603V-22.0UF,4V,20%,X6S,A"
					( Origin gPackager )
				)
				( attribute "GROUP" "PWR_MLCC_CAP"
					( Origin gFrontEnd )
				)
				( objectStatus "C7P12" )
			)
			( gate "@baseboard_fab2_lib.baseboard_fab2(sch_1):page76_i261"
				( attribute "BOM_COST" "MEM_VRD_PVDDQ_CD"
					( Origin gFrontEnd )
				)
				( attribute "CDS_LIB" "mstr_discrete"
					( Origin gPackager )
				)
				( attribute "CDS_LOCATION" "C7P14"
					( Origin gPackager )
				)
				( attribute "CDS_SEC" "1"
					( Origin gPackager )
				)
				( attribute "LOCATION" "C7P14"
					( Origin gFrontEnd )
				)
				( attribute "MATERIAL" "X5R"
					( Origin gFrontEnd )
				)
				( attribute "NEW_MATERIAL" "X6S"
					( Origin gFrontEnd )
				)
				( attribute "PACK_TYPE" "0805"
					( Origin gFrontEnd )
				)
				( attribute "PART_NUMBER" "602433-112"
					( Origin gFrontEnd )
				)
				( attribute "PHYS_PAGE" "76"
					( Origin gFrontEnd )
				)
				( attribute "ROOM" "VDDQ_ABC_PWR_VR"
					( Origin gFrontEnd )
				)
				( attribute "ROT" "0"
					( Origin gFrontEnd )
				)
				( attribute "SEC" "1"
					( Origin gFrontEnd )
				)
				( attribute "SEC_TYPE" "0805"
					( Origin gFrontEnd )
				)
				( attribute "TOLERANCE" "20%"
					( Origin gFrontEnd )
				)
				( attribute "VALUE" "100UF"
					( Origin gFrontEnd )
				)
				( attribute "VER" "1"
					( Origin gFrontEnd )
				)
				( attribute "VOLTAGE" "4V"
					( Units "uVoltage" "V" 1.000000)
					( Origin gFrontEnd )
				)
				( attribute "XY" "(-4100,2200)"
					( Origin gFrontEnd )
				)
				( attribute "CHIPS_PART_NAME" "CAP"
					( Origin gPackager )
				)
				( attribute "CDS_PART_NAME" "CAP_0805-100UF,4V,20%,X5R,6024A"
					( Origin gPackager )
				)
				( attribute "NEW_PN" "078.1071T.M002"
					( Origin gFrontEnd )
				)
				( attribute "GROUP" "PWR_MCP_CAP"
					( Origin gFrontEnd )
				)
				( objectStatus "C7P14" )
			)
			( gate "@baseboard_fab2_lib.baseboard_fab2(sch_1):page76_i260"
				( attribute "BOM_COST" "MEM_VRD_PVDDQ_CD"
					( Origin gFrontEnd )
				)
				( attribute "CDS_LIB" "mstr_discrete"
					( Origin gPackager )
				)
				( attribute "CDS_LOCATION" "C8P23"
					( Origin gPackager )
				)
				( attribute "CDS_SEC" "1"
					( Origin gPackager )
				)
				( attribute "LOCATION" "C8P23"
					( Origin gFrontEnd )
				)
				( attribute "MATERIAL" "X5R"
					( Origin gFrontEnd )
				)
				( attribute "NEW_MATERIAL" "X6S"
					( Origin gFrontEnd )
				)
				( attribute "PACK_TYPE" "0805"
					( Origin gFrontEnd )
				)
				( attribute "PART_NUMBER" "602433-112"
					( Origin gFrontEnd )
				)
				( attribute "PHYS_PAGE" "76"
					( Origin gFrontEnd )
				)
				( attribute "ROOM" "VDDQ_ABC_PWR_VR"
					( Origin gFrontEnd )
				)
				( attribute "ROT" "0"
					( Origin gFrontEnd )
				)
				( attribute "SEC" "1"
					( Origin gFrontEnd )
				)
				( attribute "SEC_TYPE" "0805"
					( Origin gFrontEnd )
				)
				( attribute "TOLERANCE" "20%"
					( Origin gFrontEnd )
				)
				( attribute "VALUE" "100UF"
					( Origin gFrontEnd )
				)
				( attribute "VER" "1"
					( Origin gFrontEnd )
				)
				( attribute "VOLTAGE" "4V"
					( Units "uVoltage" "V" 1.000000)
					( Origin gFrontEnd )
				)
				( attribute "XY" "(-3850,2200)"
					( Origin gFrontEnd )
				)
				( attribute "CHIPS_PART_NAME" "CAP"
					( Origin gPackager )
				)
				( attribute "CDS_PART_NAME" "CAP_0805-100UF,4V,20%,X5R,6024A"
					( Origin gPackager )
				)
				( attribute "NEW_PN" "078.1071T.M002"
					( Origin gFrontEnd )
				)
				( attribute "GROUP" "PWR_MCP_CAP"
					( Origin gFrontEnd )
				)
				( objectStatus "C8P23" )
			)
			( gate "@baseboard_fab2_lib.baseboard_fab2(sch_1):page76_i264"
				( attribute "BOM_COST" "MEM_VRD_PVDDQ_CD"
					( Origin gFrontEnd )
				)
				( attribute "CDS_LIB" "mstr_discrete"
					( Origin gPackager )
				)
				( attribute "CDS_LOCATION" "C8P22"
					( Origin gPackager )
				)
				( attribute "CDS_SEC" "1"
					( Origin gPackager )
				)
				( attribute "LOCATION" "C8P22"
					( Origin gFrontEnd )
				)
				( attribute "MATERIAL" "X5R"
					( Origin gFrontEnd )
				)
				( attribute "NEW_MATERIAL" "X6S"
					( Origin gFrontEnd )
				)
				( attribute "PACK_TYPE" "0805"
					( Origin gFrontEnd )
				)
				( attribute "PART_NUMBER" "602433-112"
					( Origin gFrontEnd )
				)
				( attribute "PHYS_PAGE" "76"
					( Origin gFrontEnd )
				)
				( attribute "ROOM" "VDDQ_ABC_PWR_VR"
					( Origin gFrontEnd )
				)
				( attribute "ROT" "0"
					( Origin gFrontEnd )
				)
				( attribute "SEC" "1"
					( Origin gFrontEnd )
				)
				( attribute "SEC_TYPE" "0805"
					( Origin gFrontEnd )
				)
				( attribute "TOLERANCE" "20%"
					( Origin gFrontEnd )
				)
				( attribute "VALUE" "100UF"
					( Origin gFrontEnd )
				)
				( attribute "VER" "1"
					( Origin gFrontEnd )
				)
				( attribute "VOLTAGE" "4V"
					( Units "uVoltage" "V" 1.000000)
					( Origin gFrontEnd )
				)
				( attribute "XY" "(-2850,2200)"
					( Origin gFrontEnd )
				)
				( attribute "CHIPS_PART_NAME" "CAP"
					( Origin gPackager )
				)
				( attribute "CDS_PART_NAME" "CAP_0805-100UF,4V,20%,X5R,6024A"
					( Origin gPackager )
				)
				( attribute "NEW_PN" "078.1071T.M002"
					( Origin gFrontEnd )
				)
				( attribute "GROUP" "PWR_MCP_CAP"
					( Origin gFrontEnd )
				)
				( objectStatus "C8P22" )
			)
			( gate "@baseboard_fab2_lib.baseboard_fab2(sch_1):page76_i268"
				( attribute "BOM_COST" "MEM_VRD_PVDDQ_CD"
					( Origin gFrontEnd )
				)
				( attribute "CDS_LIB" "mstr_discrete"
					( Origin gPackager )
				)
				( attribute "CDS_LOCATION" "C7P6"
					( Origin gPackager )
				)
				( attribute "CDS_SEC" "1"
					( Origin gPackager )
				)
				( attribute "LOCATION" "C7P6"
					( Origin gFrontEnd )
				)
				( attribute "MATERIAL" "X5R"
					( Origin gFrontEnd )
				)
				( attribute "NEW_MATERIAL" "X6S"
					( Origin gFrontEnd )
				)
				( attribute "PACK_TYPE" "0805"
					( Origin gFrontEnd )
				)
				( attribute "PART_NUMBER" "602433-112"
					( Origin gFrontEnd )
				)
				( attribute "PHYS_PAGE" "76"
					( Origin gFrontEnd )
				)
				( attribute "ROOM" "VDDQ_ABC_PWR_VR"
					( Origin gFrontEnd )
				)
				( attribute "ROT" "0"
					( Origin gFrontEnd )
				)
				( attribute "SEC" "1"
					( Origin gFrontEnd )
				)
				( attribute "SEC_TYPE" "0805"
					( Origin gFrontEnd )
				)
				( attribute "TOLERANCE" "20%"
					( Origin gFrontEnd )
				)
				( attribute "VALUE" "100UF"
					( Origin gFrontEnd )
				)
				( attribute "VER" "1"
					( Origin gFrontEnd )
				)
				( attribute "VOLTAGE" "4V"
					( Units "uVoltage" "V" 1.000000)
					( Origin gFrontEnd )
				)
				( attribute "XY" "(-1850,2200)"
					( Origin gFrontEnd )
				)
				( attribute "CHIPS_PART_NAME" "CAP"
					( Origin gPackager )
				)
				( attribute "CDS_PART_NAME" "CAP_0805-100UF,4V,20%,X5R,6024A"
					( Origin gPackager )
				)
				( attribute "NEW_PN" "078.1071T.M002"
					( Origin gFrontEnd )
				)
				( attribute "GROUP" "PWR_MCP_CAP"
					( Origin gFrontEnd )
				)
				( objectStatus "C7P6" )
			)
			( gate "@baseboard_fab2_lib.baseboard_fab2(sch_1):page76_i196"
				( attribute "BOM_COST" "PROC"
					( Origin gFrontEnd )
				)
				( attribute "CDS_LIB" "dev_discrete"
					( Origin gPackager )
				)
				( attribute "CDS_LOCATION" "C3D10"
					( Origin gPackager )
				)
				( attribute "CDS_SEC" "1"
					( Origin gPackager )
				)
				( attribute "LOCATION" "C3D10"
					( Origin gFrontEnd )
				)
				( attribute "MATERIAL" "X6S"
					( Origin gFrontEnd )
				)
				( attribute "PACK_TYPE" "0603V"
					( Origin gFrontEnd )
				)
				( attribute "PART_NUMBER" "E15431-004"
					( Origin gFrontEnd )
				)
				( attribute "PHYS_PAGE" "76"
					( Origin gFrontEnd )
				)
				( attribute "ROOM" "PVCCIN_CPU1_DECAP_VR"
					( Origin gFrontEnd )
				)
				( attribute "ROT" "0"
					( Origin gFrontEnd )
				)
				( attribute "SEC" "1"
					( Origin gPackager )
				)
				( attribute "TOLERANCE" "20%"
					( Origin gFrontEnd )
				)
				( attribute "VALUE" "22.0UF"
					( Origin gFrontEnd )
				)
				( attribute "VER" "1"
					( Origin gFrontEnd )
				)
				( attribute "VOLTAGE" "4V"
					( Units "uVoltage" "V" 1.000000)
					( Origin gFrontEnd )
				)
				( attribute "XY" "(-1975,3775)"
					( Origin gFrontEnd )
				)
				( attribute "CHIPS_PART_NAME" "CAP_A"
					( Origin gPackager )
				)
				( attribute "CDS_PART_NAME" "CAP_A_0603V-22.0UF,4V,20%,X6S,A"
					( Origin gPackager )
				)
				( attribute "GROUP" "PWR_MCP_CAP"
					( Origin gFrontEnd )
				)
				( objectStatus "C3D10" )
			)
			( gate "@baseboard_fab2_lib.baseboard_fab2(sch_1):page76_i197"
				( attribute "BOM_COST" "PROC"
					( Origin gFrontEnd )
				)
				( attribute "CDS_LIB" "dev_discrete"
					( Origin gPackager )
				)
				( attribute "CDS_LOCATION" "C2D18"
					( Origin gPackager )
				)
				( attribute "CDS_SEC" "1"
					( Origin gPackager )
				)
				( attribute "LOCATION" "C2D18"
					( Origin gFrontEnd )
				)
				( attribute "MATERIAL" "X6S"
					( Origin gFrontEnd )
				)
				( attribute "PACK_TYPE" "0603V"
					( Origin gFrontEnd )
				)
				( attribute "PART_NUMBER" "E15431-004"
					( Origin gFrontEnd )
				)
				( attribute "PHYS_PAGE" "76"
					( Origin gFrontEnd )
				)
				( attribute "ROOM" "PVCCIN_CPU1_DECAP_VR"
					( Origin gFrontEnd )
				)
				( attribute "ROT" "0"
					( Origin gFrontEnd )
				)
				( attribute "SEC" "1"
					( Origin gPackager )
				)
				( attribute "TOLERANCE" "20%"
					( Origin gFrontEnd )
				)
				( attribute "VALUE" "22.0UF"
					( Origin gFrontEnd )
				)
				( attribute "VER" "1"
					( Origin gFrontEnd )
				)
				( attribute "VOLTAGE" "4V"
					( Units "uVoltage" "V" 1.000000)
					( Origin gFrontEnd )
				)
				( attribute "XY" "(-1725,3775)"
					( Origin gFrontEnd )
				)
				( attribute "CHIPS_PART_NAME" "CAP_A"
					( Origin gPackager )
				)
				( attribute "CDS_PART_NAME" "CAP_A_0603V-22.0UF,4V,20%,X6S,A"
					( Origin gPackager )
				)
				( attribute "GROUP" "PWR_MCP_CAP"
					( Origin gFrontEnd )
				)
				( objectStatus "C2D18" )
			)
			( gate "@baseboard_fab2_lib.baseboard_fab2(sch_1):page76_i198"
				( attribute "BOM_COST" "PROC"
					( Origin gFrontEnd )
				)
				( attribute "CDS_LIB" "dev_discrete"
					( Origin gPackager )
				)
				( attribute "CDS_LOCATION" "C2D28"
					( Origin gPackager )
				)
				( attribute "CDS_SEC" "1"
					( Origin gPackager )
				)
				( attribute "LOCATION" "C2D28"
					( Origin gFrontEnd )
				)
				( attribute "MATERIAL" "X6S"
					( Origin gFrontEnd )
				)
				( attribute "PACK_TYPE" "0603V"
					( Origin gFrontEnd )
				)
				( attribute "PART_NUMBER" "E15431-004"
					( Origin gFrontEnd )
				)
				( attribute "PHYS_PAGE" "76"
					( Origin gFrontEnd )
				)
				( attribute "ROOM" "PVCCIN_CPU1_DECAP_VR"
					( Origin gFrontEnd )
				)
				( attribute "ROT" "0"
					( Origin gFrontEnd )
				)
				( attribute "SEC" "1"
					( Origin gPackager )
				)
				( attribute "TOLERANCE" "20%"
					( Origin gFrontEnd )
				)
				( attribute "VALUE" "22.0UF"
					( Origin gFrontEnd )
				)
				( attribute "VER" "1"
					( Origin gFrontEnd )
				)
				( attribute "VOLTAGE" "4V"
					( Units "uVoltage" "V" 1.000000)
					( Origin gFrontEnd )
				)
				( attribute "XY" "(-1475,3775)"
					( Origin gFrontEnd )
				)
				( attribute "CHIPS_PART_NAME" "CAP_A"
					( Origin gPackager )
				)
				( attribute "CDS_PART_NAME" "CAP_A_0603V-22.0UF,4V,20%,X6S,A"
					( Origin gPackager )
				)
				( attribute "GROUP" "PWR_MCP_CAP"
					( Origin gFrontEnd )
				)
				( objectStatus "C2D28" )
			)
			( gate "@baseboard_fab2_lib.baseboard_fab2(sch_1):page76_i199"
				( attribute "BOM_COST" "PROC"
					( Origin gFrontEnd )
				)
				( attribute "CDS_LIB" "dev_discrete"
					( Origin gPackager )
				)
				( attribute "CDS_LOCATION" "C2D29"
					( Origin gPackager )
				)
				( attribute "CDS_SEC" "1"
					( Origin gPackager )
				)
				( attribute "LOCATION" "C2D29"
					( Origin gFrontEnd )
				)
				( attribute "MATERIAL" "X6S"
					( Origin gFrontEnd )
				)
				( attribute "PACK_TYPE" "0603V"
					( Origin gFrontEnd )
				)
				( attribute "PART_NUMBER" "E15431-004"
					( Origin gFrontEnd )
				)
				( attribute "PHYS_PAGE" "76"
					( Origin gFrontEnd )
				)
				( attribute "ROOM" "PVCCIN_CPU1_DECAP_VR"
					( Origin gFrontEnd )
				)
				( attribute "ROT" "0"
					( Origin gFrontEnd )
				)
				( attribute "SEC" "1"
					( Origin gPackager )
				)
				( attribute "TOLERANCE" "20%"
					( Origin gFrontEnd )
				)
				( attribute "VALUE" "22.0UF"
					( Origin gFrontEnd )
				)
				( attribute "VER" "1"
					( Origin gFrontEnd )
				)
				( attribute "VOLTAGE" "4V"
					( Units "uVoltage" "V" 1.000000)
					( Origin gFrontEnd )
				)
				( attribute "XY" "(-1225,3775)"
					( Origin gFrontEnd )
				)
				( attribute "CHIPS_PART_NAME" "CAP_A"
					( Origin gPackager )
				)
				( attribute "CDS_PART_NAME" "CAP_A_0603V-22.0UF,4V,20%,X6S,A"
					( Origin gPackager )
				)
				( attribute "GROUP" "PWR_MCP_CAP"
					( Origin gFrontEnd )
				)
				( objectStatus "C2D29" )
			)
			( gate "@baseboard_fab2_lib.baseboard_fab2(sch_1):page42_i211"
				( attribute "BOM_COST" "MEM_VRD_PVDDQ_CD"
					( Origin gFrontEnd )
				)
				( attribute "CDS_LIB" "mstr_discrete"
					( Origin gPackager )
				)
				( attribute "CDS_LOCATION" "C8W3"
					( Origin gPackager )
				)
				( attribute "CDS_SEC" "1"
					( Origin gPackager )
				)
				( attribute "LOCATION" "C8W3"
					( Origin gFrontEnd )
				)
				( attribute "MATERIAL" "X5R"
					( Origin gFrontEnd )
				)
				( attribute "PACK_TYPE" "0805"
					( Origin gFrontEnd )
				)
				( attribute "PART_NUMBER" "602433-112"
					( Origin gFrontEnd )
				)
				( attribute "PHYS_PAGE" "42"
					( Origin gFrontEnd )
				)
				( attribute "ROOM" "VDDQ_ABC_PWR_VR"
					( Origin gFrontEnd )
				)
				( attribute "ROT" "0"
					( Origin gFrontEnd )
				)
				( attribute "SEC" "1"
					( Origin gFrontEnd )
				)
				( attribute "SEC_TYPE" "0805"
					( Origin gFrontEnd )
				)
				( attribute "TOLERANCE" "20%"
					( Origin gFrontEnd )
				)
				( attribute "VALUE" "100UF"
					( Origin gFrontEnd )
				)
				( attribute "VER" "1"
					( Origin gFrontEnd )
				)
				( attribute "VOLTAGE" "4V"
					( Units "uVoltage" "V" 1.000000)
					( Origin gFrontEnd )
				)
				( attribute "XY" "(-1150,1250)"
					( Origin gFrontEnd )
				)
				( attribute "CHIPS_PART_NAME" "CAP"
					( Origin gPackager )
				)
				( attribute "CDS_PART_NAME" "CAP_0805-100UF,4V,20%,X5R,6024A"
					( Origin gPackager )
				)
				( attribute "NEW_MATERIAL" "X6S"
					( Origin gFrontEnd )
				)
				( attribute "GROUP" "PWR_MLCC_CAP"
					( Origin gFrontEnd )
				)
				( attribute "NEW_PN" "078.1071T.M002"
					( Origin gFrontEnd )
				)
				( objectStatus "C8W3" )
			)
			( gate "@baseboard_fab2_lib.baseboard_fab2(sch_1):page217_i316"
				( attribute "BOM_COST" "MEM_VRD_PVDDQ_CD"
					( Origin gFrontEnd )
				)
				( attribute "CDS_LIB" "mstr_discrete"
					( Origin gPackager )
				)
				( attribute "CDS_LOCATION" "C5U1"
					( Origin gPackager )
				)
				( attribute "CDS_SEC" "1"
					( Origin gPackager )
				)
				( attribute "LOCATION" "C5U1"
					( Origin gFrontEnd )
				)
				( attribute "MATERIAL" "X5R"
					( Origin gFrontEnd )
				)
				( attribute "NEW_MATERIAL" "X6S"
					( Origin gFrontEnd )
				)
				( attribute "PACK_TYPE" "0805"
					( Origin gFrontEnd )
				)
				( attribute "PART_NUMBER" "602433-112"
					( Origin gFrontEnd )
				)
				( attribute "PHYS_PAGE" "217"
					( Origin gFrontEnd )
				)
				( attribute "ROOM" "VDDQ_ABC_PWR_VR"
					( Origin gFrontEnd )
				)
				( attribute "ROT" "0"
					( Origin gFrontEnd )
				)
				( attribute "SEC" "1"
					( Origin gFrontEnd )
				)
				( attribute "SEC_TYPE" "0805"
					( Origin gFrontEnd )
				)
				( attribute "TOLERANCE" "20%"
					( Origin gFrontEnd )
				)
				( attribute "VALUE" "100UF"
					( Origin gFrontEnd )
				)
				( attribute "VER" "1"
					( Origin gFrontEnd )
				)
				( attribute "VOLTAGE" "4V"
					( Units "uVoltage" "V" 1.000000)
					( Origin gFrontEnd )
				)
				( attribute "XY" "(4725,2850)"
					( Origin gFrontEnd )
				)
				( attribute "CHIPS_PART_NAME" "CAP"
					( Origin gPackager )
				)
				( attribute "CDS_PART_NAME" "CAP_0805-100UF,4V,20%,X5R,6024A"
					( Origin gPackager )
				)
				( attribute "GROUP" "PWR_MLCC_CAP"
					( Origin gFrontEnd )
				)
				( attribute "NEW_PN" "078.1071T.M002"
					( Origin gFrontEnd )
				)
				( attribute "BOM_SS" "NOPOP"
					( Origin gFrontEnd )
				)
				( objectStatus "C5U1" )
			)
			( gate "@baseboard_fab2_lib.baseboard_fab2(sch_1):page225_i264"
				( attribute "BOM_COST" "PROC"
					( Origin gFrontEnd )
				)
				( attribute "CDS_LIB" "dev_discrete"
					( Origin gPackager )
				)
				( attribute "CDS_LOCATION" "C2D46"
					( Origin gPackager )
				)
				( attribute "LOCATION" "C2D46"
					( Origin gFrontEnd )
				)
				( attribute "MATERIAL" "X6S"
					( Origin gFrontEnd )
				)
				( attribute "PACK_TYPE" "0603V"
					( Origin gFrontEnd )
				)
				( attribute "PART_NUMBER" "E15431-004"
					( Origin gFrontEnd )
				)
				( attribute "PHYS_PAGE" "225"
					( Origin gFrontEnd )
				)
				( attribute "ROOM" "PVCCIN_CPU1_DECAP_VR"
					( Origin gFrontEnd )
				)
				( attribute "ROT" "0"
					( Origin gFrontEnd )
				)
				( attribute "SEC" "1"
					( Origin gFrontEnd )
				)
				( attribute "SEC_TYPE" "0603V"
					( Origin gFrontEnd )
				)
				( attribute "TOLERANCE" "20%"
					( Origin gFrontEnd )
				)
				( attribute "VALUE" "22.0UF"
					( Origin gFrontEnd )
				)
				( attribute "VER" "1"
					( Origin gFrontEnd )
				)
				( attribute "VOLTAGE" "4V"
					( Units "uVoltage" "V" 1.000000)
					( Origin gFrontEnd )
				)
				( attribute "XY" "(1000,2100)"
					( Origin gFrontEnd )
				)
				( attribute "CHIPS_PART_NAME" "CAP_A"
					( Origin gPackager )
				)
				( attribute "CDS_PART_NAME" "CAP_A_0603V-22.0UF,4V,20%,X6S,A"
					( Origin gPackager )
				)
				( attribute "CDS_SEC" "1"
					( Origin gPackager )
				)
				( attribute "GROUP" "PWR_MLCC_CAP"
					( Origin gFrontEnd )
				)
				( objectStatus "C2D46" )
			)
			( gate "@baseboard_fab2_lib.baseboard_fab2(sch_1):page225_i263"
				( attribute "BOM_COST" "PROC"
					( Origin gFrontEnd )
				)
				( attribute "CDS_LIB" "dev_discrete"
					( Origin gPackager )
				)
				( attribute "CDS_LOCATION" "C2D47"
					( Origin gPackager )
				)
				( attribute "LOCATION" "C2D47"
					( Origin gFrontEnd )
				)
				( attribute "MATERIAL" "X6S"
					( Origin gFrontEnd )
				)
				( attribute "PACK_TYPE" "0603V"
					( Origin gFrontEnd )
				)
				( attribute "PART_NUMBER" "E15431-004"
					( Origin gFrontEnd )
				)
				( attribute "PHYS_PAGE" "225"
					( Origin gFrontEnd )
				)
				( attribute "ROOM" "PVCCIN_CPU1_DECAP_VR"
					( Origin gFrontEnd )
				)
				( attribute "ROT" "0"
					( Origin gFrontEnd )
				)
				( attribute "SEC" "1"
					( Origin gFrontEnd )
				)
				( attribute "SEC_TYPE" "0603V"
					( Origin gFrontEnd )
				)
				( attribute "TOLERANCE" "20%"
					( Origin gFrontEnd )
				)
				( attribute "VALUE" "22.0UF"
					( Origin gFrontEnd )
				)
				( attribute "VER" "1"
					( Origin gFrontEnd )
				)
				( attribute "VOLTAGE" "4V"
					( Units "uVoltage" "V" 1.000000)
					( Origin gFrontEnd )
				)
				( attribute "XY" "(1300,2100)"
					( Origin gFrontEnd )
				)
				( attribute "CHIPS_PART_NAME" "CAP_A"
					( Origin gPackager )
				)
				( attribute "CDS_PART_NAME" "CAP_A_0603V-22.0UF,4V,20%,X6S,A"
					( Origin gPackager )
				)
				( attribute "CDS_SEC" "1"
					( Origin gPackager )
				)
				( attribute "GROUP" "PWR_MLCC_CAP"
					( Origin gFrontEnd )
				)
				( objectStatus "C2D47" )
			)
			( gate "@baseboard_fab2_lib.baseboard_fab2(sch_1):page225_i262"
				( attribute "BOM_COST" "PROC"
					( Origin gFrontEnd )
				)
				( attribute "CDS_LIB" "dev_discrete"
					( Origin gPackager )
				)
				( attribute "CDS_LOCATION" "C3D25"
					( Origin gPackager )
				)
				( attribute "LOCATION" "C3D25"
					( Origin gFrontEnd )
				)
				( attribute "MATERIAL" "X6S"
					( Origin gFrontEnd )
				)
				( attribute "PACK_TYPE" "0603V"
					( Origin gFrontEnd )
				)
				( attribute "PART_NUMBER" "E15431-004"
					( Origin gFrontEnd )
				)
				( attribute "PHYS_PAGE" "225"
					( Origin gFrontEnd )
				)
				( attribute "ROOM" "PVCCIN_CPU1_DECAP_VR"
					( Origin gFrontEnd )
				)
				( attribute "ROT" "0"
					( Origin gFrontEnd )
				)
				( attribute "SEC" "1"
					( Origin gFrontEnd )
				)
				( attribute "SEC_TYPE" "0603V"
					( Origin gFrontEnd )
				)
				( attribute "TOLERANCE" "20%"
					( Origin gFrontEnd )
				)
				( attribute "VALUE" "22.0UF"
					( Origin gFrontEnd )
				)
				( attribute "VER" "1"
					( Origin gFrontEnd )
				)
				( attribute "VOLTAGE" "4V"
					( Units "uVoltage" "V" 1.000000)
					( Origin gFrontEnd )
				)
				( attribute "XY" "(1600,2100)"
					( Origin gFrontEnd )
				)
				( attribute "CHIPS_PART_NAME" "CAP_A"
					( Origin gPackager )
				)
				( attribute "CDS_PART_NAME" "CAP_A_0603V-22.0UF,4V,20%,X6S,A"
					( Origin gPackager )
				)
				( attribute "CDS_SEC" "1"
					( Origin gPackager )
				)
				( attribute "GROUP" "PWR_MLCC_CAP"
					( Origin gFrontEnd )
				)
				( objectStatus "C3D25" )
			)
			( gate "@baseboard_fab2_lib.baseboard_fab2(sch_1):page76_i206"
				( attribute "BOM_COST" "PROC"
					( Origin gFrontEnd )
				)
				( attribute "CDS_LIB" "dev_discrete"
					( Origin gPackager )
				)
				( attribute "CDS_LOCATION" "C7P16"
					( Origin gPackager )
				)
				( attribute "CDS_SEC" "1"
					( Origin gPackager )
				)
				( attribute "LOCATION" "C7P16"
					( Origin gFrontEnd )
				)
				( attribute "MATERIAL" "X6S"
					( Origin gFrontEnd )
				)
				( attribute "PACK_TYPE" "0603V"
					( Origin gFrontEnd )
				)
				( attribute "PART_NUMBER" "E15431-004"
					( Origin gFrontEnd )
				)
				( attribute "PHYS_PAGE" "76"
					( Origin gFrontEnd )
				)
				( attribute "ROOM" "PVCCIN_CPU1_DECAP_VR"
					( Origin gFrontEnd )
				)
				( attribute "ROT" "0"
					( Origin gFrontEnd )
				)
				( attribute "SEC" "1"
					( Origin gPackager )
				)
				( attribute "TOLERANCE" "20%"
					( Origin gFrontEnd )
				)
				( attribute "VALUE" "22.0UF"
					( Origin gFrontEnd )
				)
				( attribute "VER" "1"
					( Origin gFrontEnd )
				)
				( attribute "VOLTAGE" "4V"
					( Units "uVoltage" "V" 1.000000)
					( Origin gFrontEnd )
				)
				( attribute "XY" "(-2100,1150)"
					( Origin gFrontEnd )
				)
				( attribute "CHIPS_PART_NAME" "CAP_A"
					( Origin gPackager )
				)
				( attribute "CDS_PART_NAME" "CAP_A_0603V-22.0UF,4V,20%,X6S,A"
					( Origin gPackager )
				)
				( attribute "GROUP" "PWR_MLCC_CAP"
					( Origin gFrontEnd )
				)
				( objectStatus "C7P16" )
			)
			( gate "@baseboard_fab2_lib.baseboard_fab2(sch_1):page76_i207"
				( attribute "BOM_COST" "PROC"
					( Origin gFrontEnd )
				)
				( attribute "CDS_LIB" "dev_discrete"
					( Origin gPackager )
				)
				( attribute "CDS_LOCATION" "C3D20"
					( Origin gPackager )
				)
				( attribute "CDS_SEC" "1"
					( Origin gPackager )
				)
				( attribute "LOCATION" "C3D20"
					( Origin gFrontEnd )
				)
				( attribute "MATERIAL" "X6S"
					( Origin gFrontEnd )
				)
				( attribute "PACK_TYPE" "0603V"
					( Origin gFrontEnd )
				)
				( attribute "PART_NUMBER" "E15431-004"
					( Origin gFrontEnd )
				)
				( attribute "PHYS_PAGE" "76"
					( Origin gFrontEnd )
				)
				( attribute "ROOM" "PVCCIN_CPU1_DECAP_VR"
					( Origin gFrontEnd )
				)
				( attribute "ROT" "0"
					( Origin gFrontEnd )
				)
				( attribute "SEC" "1"
					( Origin gPackager )
				)
				( attribute "TOLERANCE" "20%"
					( Origin gFrontEnd )
				)
				( attribute "VALUE" "22.0UF"
					( Origin gFrontEnd )
				)
				( attribute "VER" "1"
					( Origin gFrontEnd )
				)
				( attribute "VOLTAGE" "4V"
					( Units "uVoltage" "V" 1.000000)
					( Origin gFrontEnd )
				)
				( attribute "XY" "(-750,3775)"
					( Origin gFrontEnd )
				)
				( attribute "CHIPS_PART_NAME" "CAP_A"
					( Origin gPackager )
				)
				( attribute "CDS_PART_NAME" "CAP_A_0603V-22.0UF,4V,20%,X6S,A"
					( Origin gPackager )
				)
				( attribute "GROUP" "PWR_MCP_CAP"
					( Origin gFrontEnd )
				)
				( objectStatus "C3D20" )
			)
			( gate "@baseboard_fab2_lib.baseboard_fab2(sch_1):page76_i208"
				( attribute "BOM_COST" "PROC"
					( Origin gFrontEnd )
				)
				( attribute "CDS_LIB" "dev_discrete"
					( Origin gPackager )
				)
				( attribute "CDS_LOCATION" "C3D19"
					( Origin gPackager )
				)
				( attribute "CDS_SEC" "1"
					( Origin gPackager )
				)
				( attribute "LOCATION" "C3D19"
					( Origin gFrontEnd )
				)
				( attribute "MATERIAL" "X6S"
					( Origin gFrontEnd )
				)
				( attribute "PACK_TYPE" "0603V"
					( Origin gFrontEnd )
				)
				( attribute "PART_NUMBER" "E15431-004"
					( Origin gFrontEnd )
				)
				( attribute "PHYS_PAGE" "76"
					( Origin gFrontEnd )
				)
				( attribute "ROOM" "PVCCIN_CPU1_DECAP_VR"
					( Origin gFrontEnd )
				)
				( attribute "ROT" "0"
					( Origin gFrontEnd )
				)
				( attribute "SEC" "1"
					( Origin gPackager )
				)
				( attribute "TOLERANCE" "20%"
					( Origin gFrontEnd )
				)
				( attribute "VALUE" "22.0UF"
					( Origin gFrontEnd )
				)
				( attribute "VER" "1"
					( Origin gFrontEnd )
				)
				( attribute "VOLTAGE" "4V"
					( Units "uVoltage" "V" 1.000000)
					( Origin gFrontEnd )
				)
				( attribute "XY" "(-975,3775)"
					( Origin gFrontEnd )
				)
				( attribute "CHIPS_PART_NAME" "CAP_A"
					( Origin gPackager )
				)
				( attribute "CDS_PART_NAME" "CAP_A_0603V-22.0UF,4V,20%,X6S,A"
					( Origin gPackager )
				)
				( attribute "GROUP" "PWR_MCP_CAP"
					( Origin gFrontEnd )
				)
				( objectStatus "C3D19" )
			)
			( gate "@baseboard_fab2_lib.baseboard_fab2(sch_1):page76_i215"
				( attribute "BOM_COST" "PROC"
					( Origin gFrontEnd )
				)
				( attribute "CDS_LIB" "mstr_discrete"
					( Origin gPackager )
				)
				( attribute "CDS_LOCATION" "C7P19"
					( Origin gPackager )
				)
				( attribute "LOCATION" "C7P19"
					( Origin gFrontEnd )
				)
				( attribute "MATERIAL" "X6S"
					( Origin gFrontEnd )
				)
				( attribute "PACK_TYPE" "0805"
					( Origin gFrontEnd )
				)
				( attribute "PART_NUMBER" "C95333-006"
					( Origin gFrontEnd )
				)
				( attribute "PHYS_PAGE" "76"
					( Origin gFrontEnd )
				)
				( attribute "ROOM" "PVCCIN_CPU1_DECAP_VR"
					( Origin gFrontEnd )
				)
				( attribute "ROT" "0"
					( Origin gFrontEnd )
				)
				( attribute "SEC" "1"
					( Origin gFrontEnd )
				)
				( attribute "TOLERANCE" "20%"
					( Origin gFrontEnd )
				)
				( attribute "VALUE" "47UF"
					( Origin gFrontEnd )
				)
				( attribute "VER" "1"
					( Origin gFrontEnd )
				)
				( attribute "VOLTAGE" "4V"
					( Units "uVoltage" "V" 1.000000)
					( Origin gFrontEnd )
				)
				( attribute "XY" "(-6850,2200)"
					( Origin gFrontEnd )
				)
				( attribute "CHIPS_PART_NAME" "CAP"
					( Origin gPackager )
				)
				( attribute "CDS_PART_NAME" "CAP_0805-47UF,4V,20%,X6S,C9533A"
					( Origin gPackager )
				)
				( attribute "SEC_TYPE" "0805"
					( Origin gFrontEnd )
				)
				( attribute "GROUP" "PWR_MLCC_CAP"
					( Origin gFrontEnd )
				)
				( attribute "CDS_SEC" "1"
					( Origin gPackager )
				)
				( objectStatus "C7P19" )
			)
			( gate "@baseboard_fab2_lib.baseboard_fab2(sch_1):page76_i217"
				( attribute "BOM_COST" "PROC"
					( Origin gFrontEnd )
				)
				( attribute "CDS_LIB" "mstr_discrete"
					( Origin gPackager )
				)
				( attribute "CDS_LOCATION" "C8P24"
					( Origin gPackager )
				)
				( attribute "LOCATION" "C8P24"
					( Origin gFrontEnd )
				)
				( attribute "MATERIAL" "X6S"
					( Origin gFrontEnd )
				)
				( attribute "PACK_TYPE" "0805"
					( Origin gFrontEnd )
				)
				( attribute "PART_NUMBER" "C95333-006"
					( Origin gFrontEnd )
				)
				( attribute "PHYS_PAGE" "76"
					( Origin gFrontEnd )
				)
				( attribute "ROOM" "PVCCIN_CPU1_DECAP_VR"
					( Origin gFrontEnd )
				)
				( attribute "ROT" "0"
					( Origin gFrontEnd )
				)
				( attribute "SEC" "1"
					( Origin gFrontEnd )
				)
				( attribute "TOLERANCE" "20%"
					( Origin gFrontEnd )
				)
				( attribute "VALUE" "47UF"
					( Origin gFrontEnd )
				)
				( attribute "VER" "1"
					( Origin gFrontEnd )
				)
				( attribute "VOLTAGE" "4V"
					( Units "uVoltage" "V" 1.000000)
					( Origin gFrontEnd )
				)
				( attribute "XY" "(-7750,800)"
					( Origin gFrontEnd )
				)
				( attribute "CHIPS_PART_NAME" "CAP"
					( Origin gPackager )
				)
				( attribute "CDS_PART_NAME" "CAP_0805-47UF,4V,20%,X6S,C9533A"
					( Origin gPackager )
				)
				( attribute "SEC_TYPE" "0805"
					( Origin gFrontEnd )
				)
				( attribute "CDS_SEC" "1"
					( Origin gPackager )
				)
				( attribute "GROUP" "PWR_MLCC_CAP"
					( Origin gFrontEnd )
				)
				( objectStatus "C8P24" )
			)
			( gate "@baseboard_fab2_lib.baseboard_fab2(sch_1):page77_i43"
				( attribute "BOM_COST" "MEM"
					( Origin gFrontEnd )
				)
				( attribute "CDS_LIB" "mstr_sconn"
					( Origin gPackager )
				)
				( attribute "CDS_LOCATION" "J1G1"
					( Origin gPackager )
				)
				( attribute "CDS_SEC" "3"
					( Origin gPackager )
				)
				( attribute "LOCATION" "J1G1"
					( Origin gFrontEnd )
				)
				( attribute "MATERIAL" "SCONN"
					( Origin gFrontEnd )
				)
				( attribute "PACK_TYPE" "PIP"
					( Origin gFrontEnd )
				)
				( attribute "PART_NUMBER" "H44441-004"
					( Origin gFrontEnd )
				)
				( attribute "PHYS_PAGE" "77"
					( Origin gFrontEnd )
				)
				( attribute "ROOM" "DDR4_CH_G"
					( Origin gFrontEnd )
				)
				( attribute "ROT" "0"
					( Origin gFrontEnd )
				)
				( attribute "SEC" "3"
					( Origin gFrontEnd )
				)
				( attribute "SEC_TYPE" "PIP"
					( Origin gFrontEnd )
				)
				( attribute "VER" "3"
					( Origin gFrontEnd )
				)
				( attribute "XY" "(1800,2200)"
					( Origin gFrontEnd )
				)
				( attribute "CHIPS_PART_NAME" "SCONN288_H44441004"
					( Origin gPackager )
				)
				( attribute "CDS_PART_NAME" "SCONN288_H44441004_PIP-SCONN,HA"
					( Origin gPackager )
				)
				( objectStatus "J1G1" )
			)
			( gate "@baseboard_fab2_lib.baseboard_fab2(sch_1):page77_i66"
				( attribute "BOM_COST" "MEM"
					( Origin gFrontEnd )
				)
				( attribute "CDS_LIB" "mstr_sconn"
					( Origin gPackager )
				)
				( attribute "CDS_LOCATION" "J1G1"
					( Origin gPackager )
				)
				( attribute "CDS_SEC" "2"
					( Origin gPackager )
				)
				( attribute "LOCATION" "J1G1"
					( Origin gFrontEnd )
				)
				( attribute "MATERIAL" "SCONN"
					( Origin gFrontEnd )
				)
				( attribute "PACK_TYPE" "PIP"
					( Origin gFrontEnd )
				)
				( attribute "PART_NUMBER" "H44441-004"
					( Origin gFrontEnd )
				)
				( attribute "PHYS_PAGE" "77"
					( Origin gFrontEnd )
				)
				( attribute "ROOM" "DDR4_CH_G"
					( Origin gFrontEnd )
				)
				( attribute "ROT" "0"
					( Origin gFrontEnd )
				)
				( attribute "SEC" "2"
					( Origin gFrontEnd )
				)
				( attribute "SEC_TYPE" "PIP"
					( Origin gFrontEnd )
				)
				( attribute "VER" "2"
					( Origin gFrontEnd )
				)
				( attribute "XY" "(0,4200)"
					( Origin gFrontEnd )
				)
				( attribute "CHIPS_PART_NAME" "SCONN288_H44441004"
					( Origin gPackager )
				)
				( attribute "CDS_PART_NAME" "SCONN288_H44441004_PIP-SCONN,HA"
					( Origin gPackager )
				)
				( objectStatus "J1G1" )
			)
			( gate "@baseboard_fab2_lib.baseboard_fab2(sch_1):page77_i111"
				( attribute "BOM_COST" "MEM"
					( Origin gFrontEnd )
				)
				( attribute "CDS_LIB" "mstr_sconn"
					( Origin gPackager )
				)
				( attribute "CDS_LOCATION" "J1G1"
					( Origin gPackager )
				)
				( attribute "CDS_SEC" "1"
					( Origin gPackager )
				)
				( attribute "LOCATION" "J1G1"
					( Origin gFrontEnd )
				)
				( attribute "MATERIAL" "SCONN"
					( Origin gFrontEnd )
				)
				( attribute "PACK_TYPE" "PIP"
					( Origin gFrontEnd )
				)
				( attribute "PART_NUMBER" "H44441-004"
					( Origin gFrontEnd )
				)
				( attribute "PHYS_PAGE" "77"
					( Origin gFrontEnd )
				)
				( attribute "ROOM" "DDR4_CH_G"
					( Origin gFrontEnd )
				)
				( attribute "ROT" "0"
					( Origin gFrontEnd )
				)
				( attribute "SEC" "1"
					( Origin gFrontEnd )
				)
				( attribute "SEC_TYPE" "PIP"
					( Origin gFrontEnd )
				)
				( attribute "VER" "1"
					( Origin gFrontEnd )
				)
				( attribute "XY" "(-2375,2775)"
					( Origin gFrontEnd )
				)
				( attribute "CHIPS_PART_NAME" "SCONN288_H44441004"
					( Origin gPackager )
				)
				( attribute "CDS_PART_NAME" "SCONN288_H44441004_PIP-SCONN,HA"
					( Origin gPackager )
				)
				( objectStatus "J1G1" )
			)
			( gate "@baseboard_fab2_lib.baseboard_fab2(sch_1):page77_i171"
				( attribute "BOM_COST" "MEM"
					( Origin gFrontEnd )
				)
				( attribute "CDS_LIB" "mstr_sconn"
					( Origin gPackager )
				)
				( attribute "CDS_LOCATION" "J1G1"
					( Origin gPackager )
				)
				( attribute "CDS_SEC" "4"
					( Origin gPackager )
				)
				( attribute "LOCATION" "J1G1"
					( Origin gFrontEnd )
				)
				( attribute "MATERIAL" "SCONN"
					( Origin gFrontEnd )
				)
				( attribute "PACK_TYPE" "PIP"
					( Origin gFrontEnd )
				)
				( attribute "PART_NUMBER" "H44441-004"
					( Origin gFrontEnd )
				)
				( attribute "PHYS_PAGE" "77"
					( Origin gFrontEnd )
				)
				( attribute "ROOM" "DDR4_CH_G"
					( Origin gFrontEnd )
				)
				( attribute "ROT" "0"
					( Origin gFrontEnd )
				)
				( attribute "SEC" "4"
					( Origin gFrontEnd )
				)
				( attribute "SEC_TYPE" "PIP"
					( Origin gFrontEnd )
				)
				( attribute "VER" "4"
					( Origin gFrontEnd )
				)
				( attribute "XY" "(-300,1950)"
					( Origin gFrontEnd )
				)
				( attribute "CHIPS_PART_NAME" "SCONN288_H44441004"
					( Origin gPackager )
				)
				( attribute "CDS_PART_NAME" "SCONN288_H44441004_PIP-SCONN,HA"
					( Origin gPackager )
				)
				( objectStatus "J1G1" )
			)
			( gate "@baseboard_fab2_lib.baseboard_fab2(sch_1):page77_i181"
				( attribute "BOM_COST" "MEM"
					( Origin gFrontEnd )
				)
				( attribute "CDS_LIB" "dev_discrete"
					( Origin gPackager )
				)
				( attribute "CDS_LOCATION" "C1F22"
					( Origin gPackager )
				)
				( attribute "CDS_SEC" "1"
					( Origin gPackager )
				)
				( attribute "LOCATION" "C1F22"
					( Origin gFrontEnd )
				)
				( attribute "MATERIAL" "X7R"
					( Origin gFrontEnd )
				)
				( attribute "PACK_TYPE" "0402V"
					( Origin gFrontEnd )
				)
				( attribute "PART_NUMBER" "A36096-045"
					( Origin gFrontEnd )
				)
				( attribute "PHYS_PAGE" "77"
					( Origin gFrontEnd )
				)
				( attribute "ROOM" "DDR4_CH_G"
					( Origin gFrontEnd )
				)
				( attribute "ROT" "2"
					( Origin gFrontEnd )
				)
				( attribute "SEC" "1"
					( Origin gPackager )
				)
				( attribute "TOLERANCE" "10%"
					( Origin gFrontEnd )
				)
				( attribute "VALUE" "0.01UF"
					( Origin gFrontEnd )
				)
				( attribute "VER" "1"
					( Origin gFrontEnd )
				)
				( attribute "VOLTAGE" "25V"
					( Units "uVoltage" "V" 1.000000)
					( Origin gFrontEnd )
				)
				( attribute "XY" "(-4425,1075)"
					( Origin gFrontEnd )
				)
				( attribute "CHIPS_PART_NAME" "CAP_A"
					( Origin gPackager )
				)
				( attribute "CDS_PART_NAME" "CAP_A_0402V-0.01UF,25V,10%,X7RA"
					( Origin gPackager )
				)
				( objectStatus "C1F22" )
			)
			( gate "@baseboard_fab2_lib.baseboard_fab2(sch_1):page78_i2"
				( attribute "BOM_COST" "MEM"
					( Origin gFrontEnd )
				)
				( attribute "CDS_LIB" "dev_discrete"
					( Origin gPackager )
				)
				( attribute "CDS_LOCATION" "C9T7"
					( Origin gPackager )
				)
				( attribute "CDS_SEC" "1"
					( Origin gPackager )
				)
				( attribute "LOCATION" "C9T7"
					( Origin gFrontEnd )
				)
				( attribute "MATERIAL" "X7R"
					( Origin gFrontEnd )
				)
				( attribute "PACK_TYPE" "0402V"
					( Origin gFrontEnd )
				)
				( attribute "PART_NUMBER" "A36096-045"
					( Origin gFrontEnd )
				)
				( attribute "PHYS_PAGE" "78"
					( Origin gFrontEnd )
				)
				( attribute "ROOM" "DDR4_GH_G"
					( Origin gFrontEnd )
				)
				( attribute "ROT" "2"
					( Origin gFrontEnd )
				)
				( attribute "SEC" "1"
					( Origin gPackager )
				)
				( attribute "TOLERANCE" "10%"
					( Origin gFrontEnd )
				)
				( attribute "VALUE" "0.01UF"
					( Origin gFrontEnd )
				)
				( attribute "VER" "1"
					( Origin gFrontEnd )
				)
				( attribute "VOLTAGE" "25V"
					( Units "uVoltage" "V" 1.000000)
					( Origin gFrontEnd )
				)
				( attribute "XY" "(-2675,875)"
					( Origin gFrontEnd )
				)
				( attribute "CHIPS_PART_NAME" "CAP_A"
					( Origin gPackager )
				)
				( attribute "CDS_PART_NAME" "CAP_A_0402V-0.01UF,25V,10%,X7RA"
					( Origin gPackager )
				)
				( objectStatus "C9T7" )
			)
			( gate "@baseboard_fab2_lib.baseboard_fab2(sch_1):page78_i13"
				( attribute "BOM_COST" "MEM"
					( Origin gFrontEnd )
				)
				( attribute "CDS_LIB" "mstr_sconn"
					( Origin gPackager )
				)
				( attribute "CDS_LOCATION" "J9T1"
					( Origin gPackager )
				)
				( attribute "CDS_SEC" "1"
					( Origin gPackager )
				)
				( attribute "LOCATION" "J9T1"
					( Origin gFrontEnd )
				)
				( attribute "MATERIAL" "SCONN"
					( Origin gFrontEnd )
				)
				( attribute "PACK_TYPE" "PIP"
					( Origin gFrontEnd )
				)
				( attribute "PART_NUMBER" "H44441-003"
					( Origin gFrontEnd )
				)
				( attribute "PHYS_PAGE" "78"
					( Origin gFrontEnd )
				)
				( attribute "ROOM" "DDR4_GH_G"
					( Origin gFrontEnd )
				)
				( attribute "ROT" "0"
					( Origin gFrontEnd )
				)
				( attribute "SEC" "1"
					( Origin gFrontEnd )
				)
				( attribute "SEC_TYPE" "PIP"
					( Origin gFrontEnd )
				)
				( attribute "VER" "1"
					( Origin gFrontEnd )
				)
				( attribute "XY" "(-625,2575)"
					( Origin gFrontEnd )
				)
				( attribute "CHIPS_PART_NAME" "SCONN288_H44441003"
					( Origin gPackager )
				)
				( attribute "CDS_PART_NAME" "SCONN288_H44441003_PIP-SCONN,HA"
					( Origin gPackager )
				)
				( attribute "BOM_SS" "NOPOP"
					( Origin gFrontEnd )
				)
				( objectStatus "J9T1" )
			)
			( gate "@baseboard_fab2_lib.baseboard_fab2(sch_1):page78_i75"
				( attribute "BOM_COST" "MEM"
					( Origin gFrontEnd )
				)
				( attribute "CDS_LIB" "mstr_sconn"
					( Origin gPackager )
				)
				( attribute "CDS_LOCATION" "J9T1"
					( Origin gPackager )
				)
				( attribute "CDS_SEC" "4"
					( Origin gPackager )
				)
				( attribute "LOCATION" "J9T1"
					( Origin gFrontEnd )
				)
				( attribute "MATERIAL" "SCONN"
					( Origin gFrontEnd )
				)
				( attribute "PACK_TYPE" "PIP"
					( Origin gFrontEnd )
				)
				( attribute "PART_NUMBER" "H44441-003"
					( Origin gFrontEnd )
				)
				( attribute "PHYS_PAGE" "78"
					( Origin gFrontEnd )
				)
				( attribute "ROOM" "DDR4_GH_G"
					( Origin gFrontEnd )
				)
				( attribute "ROT" "0"
					( Origin gFrontEnd )
				)
				( attribute "SEC" "4"
					( Origin gFrontEnd )
				)
				( attribute "SEC_TYPE" "PIP"
					( Origin gFrontEnd )
				)
				( attribute "VER" "4"
					( Origin gFrontEnd )
				)
				( attribute "XY" "(1450,1750)"
					( Origin gFrontEnd )
				)
				( attribute "CHIPS_PART_NAME" "SCONN288_H44441003"
					( Origin gPackager )
				)
				( attribute "CDS_PART_NAME" "SCONN288_H44441003_PIP-SCONN,HA"
					( Origin gPackager )
				)
				( attribute "BOM_SS" "NOPOP"
					( Origin gFrontEnd )
				)
				( objectStatus "J9T1" )
			)
			( gate "@baseboard_fab2_lib.baseboard_fab2(sch_1):page78_i120"
				( attribute "BOM_COST" "MEM"
					( Origin gFrontEnd )
				)
				( attribute "CDS_LIB" "mstr_sconn"
					( Origin gPackager )
				)
				( attribute "CDS_LOCATION" "J9T1"
					( Origin gPackager )
				)
				( attribute "CDS_SEC" "2"
					( Origin gPackager )
				)
				( attribute "LOCATION" "J9T1"
					( Origin gFrontEnd )
				)
				( attribute "MATERIAL" "SCONN"
					( Origin gFrontEnd )
				)
				( attribute "PACK_TYPE" "PIP"
					( Origin gFrontEnd )
				)
				( attribute "PART_NUMBER" "H44441-003"
					( Origin gFrontEnd )
				)
				( attribute "PHYS_PAGE" "78"
					( Origin gFrontEnd )
				)
				( attribute "ROOM" "DDR4_GH_G"
					( Origin gFrontEnd )
				)
				( attribute "ROT" "0"
					( Origin gFrontEnd )
				)
				( attribute "SEC" "2"
					( Origin gFrontEnd )
				)
				( attribute "SEC_TYPE" "PIP"
					( Origin gFrontEnd )
				)
				( attribute "VER" "2"
					( Origin gFrontEnd )
				)
				( attribute "XY" "(1750,4000)"
					( Origin gFrontEnd )
				)
				( attribute "CHIPS_PART_NAME" "SCONN288_H44441003"
					( Origin gPackager )
				)
				( attribute "CDS_PART_NAME" "SCONN288_H44441003_PIP-SCONN,HA"
					( Origin gPackager )
				)
				( attribute "BOM_SS" "NOPOP"
					( Origin gFrontEnd )
				)
				( objectStatus "J9T1" )
			)
			( gate "@baseboard_fab2_lib.baseboard_fab2(sch_1):page78_i144"
				( attribute "BOM_COST" "MEM"
					( Origin gFrontEnd )
				)
				( attribute "CDS_LIB" "mstr_sconn"
					( Origin gPackager )
				)
				( attribute "CDS_LOCATION" "J9T1"
					( Origin gPackager )
				)
				( attribute "CDS_SEC" "3"
					( Origin gPackager )
				)
				( attribute "LOCATION" "J9T1"
					( Origin gFrontEnd )
				)
				( attribute "MATERIAL" "SCONN"
					( Origin gFrontEnd )
				)
				( attribute "PACK_TYPE" "PIP"
					( Origin gFrontEnd )
				)
				( attribute "PART_NUMBER" "H44441-003"
					( Origin gFrontEnd )
				)
				( attribute "PHYS_PAGE" "78"
					( Origin gFrontEnd )
				)
				( attribute "ROOM" "DDR4_GH_G"
					( Origin gFrontEnd )
				)
				( attribute "ROT" "0"
					( Origin gFrontEnd )
				)
				( attribute "SEC" "3"
					( Origin gFrontEnd )
				)
				( attribute "SEC_TYPE" "PIP"
					( Origin gFrontEnd )
				)
				( attribute "VER" "3"
					( Origin gFrontEnd )
				)
				( attribute "XY" "(3550,2000)"
					( Origin gFrontEnd )
				)
				( attribute "CHIPS_PART_NAME" "SCONN288_H44441003"
					( Origin gPackager )
				)
				( attribute "CDS_PART_NAME" "SCONN288_H44441003_PIP-SCONN,HA"
					( Origin gPackager )
				)
				( attribute "BOM_SS" "NOPOP"
					( Origin gFrontEnd )
				)
				( objectStatus "J9T1" )
			)
			( gate "@baseboard_fab2_lib.baseboard_fab2(sch_1):page79_i43"
				( attribute "BOM_COST" "MEM"
					( Origin gFrontEnd )
				)
				( attribute "CDS_LIB" "mstr_sconn"
					( Origin gPackager )
				)
				( attribute "CDS_LOCATION" "J1G2"
					( Origin gPackager )
				)
				( attribute "CDS_SEC" "3"
					( Origin gPackager )
				)
				( attribute "LOCATION" "J1G2"
					( Origin gFrontEnd )
				)
				( attribute "MATERIAL" "SCONN"
					( Origin gFrontEnd )
				)
				( attribute "PACK_TYPE" "PIP"
					( Origin gFrontEnd )
				)
				( attribute "PART_NUMBER" "H44441-004"
					( Origin gFrontEnd )
				)
				( attribute "PHYS_PAGE" "79"
					( Origin gFrontEnd )
				)
				( attribute "ROOM" "DDR4_CH_H"
					( Origin gFrontEnd )
				)
				( attribute "ROT" "0"
					( Origin gFrontEnd )
				)
				( attribute "SEC" "3"
					( Origin gFrontEnd )
				)
				( attribute "SEC_TYPE" "PIP"
					( Origin gFrontEnd )
				)
				( attribute "VER" "3"
					( Origin gFrontEnd )
				)
				( attribute "XY" "(1750,2400)"
					( Origin gFrontEnd )
				)
				( attribute "CHIPS_PART_NAME" "SCONN288_H44441004"
					( Origin gPackager )
				)
				( attribute "CDS_PART_NAME" "SCONN288_H44441004_PIP-SCONN,HA"
					( Origin gPackager )
				)
				( objectStatus "J1G2" )
			)
			( gate "@baseboard_fab2_lib.baseboard_fab2(sch_1):page79_i64"
				( attribute "BOM_COST" "MEM"
					( Origin gFrontEnd )
				)
				( attribute "CDS_LIB" "mstr_sconn"
					( Origin gPackager )
				)
				( attribute "CDS_LOCATION" "J1G2"
					( Origin gPackager )
				)
				( attribute "CDS_SEC" "2"
					( Origin gPackager )
				)
				( attribute "LOCATION" "J1G2"
					( Origin gFrontEnd )
				)
				( attribute "MATERIAL" "SCONN"
					( Origin gFrontEnd )
				)
				( attribute "PACK_TYPE" "PIP"
					( Origin gFrontEnd )
				)
				( attribute "PART_NUMBER" "H44441-004"
					( Origin gFrontEnd )
				)
				( attribute "PHYS_PAGE" "79"
					( Origin gFrontEnd )
				)
				( attribute "ROOM" "DDR4_CH_H"
					( Origin gFrontEnd )
				)
				( attribute "ROT" "0"
					( Origin gFrontEnd )
				)
				( attribute "SEC" "2"
					( Origin gFrontEnd )
				)
				( attribute "SEC_TYPE" "PIP"
					( Origin gFrontEnd )
				)
				( attribute "VER" "2"
					( Origin gFrontEnd )
				)
				( attribute "XY" "(-50,4300)"
					( Origin gFrontEnd )
				)
				( attribute "CHIPS_PART_NAME" "SCONN288_H44441004"
					( Origin gPackager )
				)
				( attribute "CDS_PART_NAME" "SCONN288_H44441004_PIP-SCONN,HA"
					( Origin gPackager )
				)
				( objectStatus "J1G2" )
			)
			( gate "@baseboard_fab2_lib.baseboard_fab2(sch_1):page79_i111"
				( attribute "BOM_COST" "MEM"
					( Origin gFrontEnd )
				)
				( attribute "CDS_LIB" "mstr_sconn"
					( Origin gPackager )
				)
				( attribute "CDS_LOCATION" "J1G2"
					( Origin gPackager )
				)
				( attribute "CDS_SEC" "1"
					( Origin gPackager )
				)
				( attribute "LOCATION" "J1G2"
					( Origin gFrontEnd )
				)
				( attribute "MATERIAL" "SCONN"
					( Origin gFrontEnd )
				)
				( attribute "PACK_TYPE" "PIP"
					( Origin gFrontEnd )
				)
				( attribute "PART_NUMBER" "H44441-004"
					( Origin gFrontEnd )
				)
				( attribute "PHYS_PAGE" "79"
					( Origin gFrontEnd )
				)
				( attribute "ROOM" "DDR4_CH_H"
					( Origin gFrontEnd )
				)
				( attribute "ROT" "0"
					( Origin gFrontEnd )
				)
				( attribute "SEC" "1"
					( Origin gFrontEnd )
				)
				( attribute "SEC_TYPE" "PIP"
					( Origin gFrontEnd )
				)
				( attribute "VER" "1"
					( Origin gFrontEnd )
				)
				( attribute "XY" "(-2600,3250)"
					( Origin gFrontEnd )
				)
				( attribute "CHIPS_PART_NAME" "SCONN288_H44441004"
					( Origin gPackager )
				)
				( attribute "CDS_PART_NAME" "SCONN288_H44441004_PIP-SCONN,HA"
					( Origin gPackager )
				)
				( objectStatus "J1G2" )
			)
			( gate "@baseboard_fab2_lib.baseboard_fab2(sch_1):page79_i169"
				( attribute "BOM_COST" "MEM"
					( Origin gFrontEnd )
				)
				( attribute "CDS_LIB" "mstr_sconn"
					( Origin gPackager )
				)
				( attribute "CDS_LOCATION" "J1G2"
					( Origin gPackager )
				)
				( attribute "CDS_SEC" "4"
					( Origin gPackager )
				)
				( attribute "LOCATION" "J1G2"
					( Origin gFrontEnd )
				)
				( attribute "MATERIAL" "SCONN"
					( Origin gFrontEnd )
				)
				( attribute "PACK_TYPE" "PIP"
					( Origin gFrontEnd )
				)
				( attribute "PART_NUMBER" "H44441-004"
					( Origin gFrontEnd )
				)
				( attribute "PHYS_PAGE" "79"
					( Origin gFrontEnd )
				)
				( attribute "ROOM" "DDR4_CH_H"
					( Origin gFrontEnd )
				)
				( attribute "ROT" "0"
					( Origin gFrontEnd )
				)
				( attribute "SEC" "4"
					( Origin gFrontEnd )
				)
				( attribute "SEC_TYPE" "PIP"
					( Origin gFrontEnd )
				)
				( attribute "VER" "4"
					( Origin gFrontEnd )
				)
				( attribute "XY" "(-450,2000)"
					( Origin gFrontEnd )
				)
				( attribute "CHIPS_PART_NAME" "SCONN288_H44441004"
					( Origin gPackager )
				)
				( attribute "CDS_PART_NAME" "SCONN288_H44441004_PIP-SCONN,HA"
					( Origin gPackager )
				)
				( objectStatus "J1G2" )
			)
			( gate "@baseboard_fab2_lib.baseboard_fab2(sch_1):page79_i178"
				( attribute "BOM_COST" "MEM"
					( Origin gFrontEnd )
				)
				( attribute "CDS_LIB" "dev_discrete"
					( Origin gPackager )
				)
				( attribute "CDS_LOCATION" "C9U7"
					( Origin gPackager )
				)
				( attribute "CDS_SEC" "1"
					( Origin gPackager )
				)
				( attribute "LOCATION" "C9U7"
					( Origin gFrontEnd )
				)
				( attribute "MATERIAL" "X7R"
					( Origin gFrontEnd )
				)
				( attribute "PACK_TYPE" "0402V"
					( Origin gFrontEnd )
				)
				( attribute "PART_NUMBER" "A36096-045"
					( Origin gFrontEnd )
				)
				( attribute "PHYS_PAGE" "79"
					( Origin gFrontEnd )
				)
				( attribute "ROOM" "DDR4_CH_J"
					( Origin gFrontEnd )
				)
				( attribute "ROT" "2"
					( Origin gFrontEnd )
				)
				( attribute "SEC" "1"
					( Origin gPackager )
				)
				( attribute "TOLERANCE" "10%"
					( Origin gFrontEnd )
				)
				( attribute "VALUE" "0.01UF"
					( Origin gFrontEnd )
				)
				( attribute "VER" "1"
					( Origin gFrontEnd )
				)
				( attribute "VOLTAGE" "25V"
					( Units "uVoltage" "V" 1.000000)
					( Origin gFrontEnd )
				)
				( attribute "XY" "(-4600,1550)"
					( Origin gFrontEnd )
				)
				( attribute "CHIPS_PART_NAME" "CAP_A"
					( Origin gPackager )
				)
				( attribute "CDS_PART_NAME" "CAP_A_0402V-0.01UF,25V,10%,X7RA"
					( Origin gPackager )
				)
				( objectStatus "C9U7" )
			)
			( gate "@baseboard_fab2_lib.baseboard_fab2(sch_1):page80_i3"
				( attribute "BOM_COST" "MEM"
					( Origin gFrontEnd )
				)
				( attribute "CDS_LIB" "dev_discrete"
					( Origin gPackager )
				)
				( attribute "CDS_LOCATION" "C1G10"
					( Origin gPackager )
				)
				( attribute "CDS_SEC" "1"
					( Origin gPackager )
				)
				( attribute "LOCATION" "C1G10"
					( Origin gFrontEnd )
				)
				( attribute "MATERIAL" "X7R"
					( Origin gFrontEnd )
				)
				( attribute "PACK_TYPE" "0402V"
					( Origin gFrontEnd )
				)
				( attribute "PART_NUMBER" "A36096-045"
					( Origin gFrontEnd )
				)
				( attribute "PHYS_PAGE" "80"
					( Origin gFrontEnd )
				)
				( attribute "ROOM" "DDR4_GH_G"
					( Origin gFrontEnd )
				)
				( attribute "ROT" "2"
					( Origin gFrontEnd )
				)
				( attribute "SEC" "1"
					( Origin gPackager )
				)
				( attribute "TOLERANCE" "10%"
					( Origin gFrontEnd )
				)
				( attribute "VALUE" "0.01UF"
					( Origin gFrontEnd )
				)
				( attribute "VER" "1"
					( Origin gFrontEnd )
				)
				( attribute "VOLTAGE" "25V"
					( Units "uVoltage" "V" 1.000000)
					( Origin gFrontEnd )
				)
				( attribute "XY" "(-7225,1000)"
					( Origin gFrontEnd )
				)
				( attribute "CHIPS_PART_NAME" "CAP_A"
					( Origin gPackager )
				)
				( attribute "CDS_PART_NAME" "CAP_A_0402V-0.01UF,25V,10%,X7RA"
					( Origin gPackager )
				)
				( objectStatus "C1G10" )
			)
			( gate "@baseboard_fab2_lib.baseboard_fab2(sch_1):page80_i24"
				( attribute "BOM_COST" "MEM"
					( Origin gFrontEnd )
				)
				( attribute "CDS_LIB" "mstr_sconn"
					( Origin gPackager )
				)
				( attribute "CDS_LOCATION" "J9U1"
					( Origin gPackager )
				)
				( attribute "CDS_SEC" "1"
					( Origin gPackager )
				)
				( attribute "LOCATION" "J9U1"
					( Origin gFrontEnd )
				)
				( attribute "MATERIAL" "SCONN"
					( Origin gFrontEnd )
				)
				( attribute "PACK_TYPE" "PIP"
					( Origin gFrontEnd )
				)
				( attribute "PART_NUMBER" "H44441-003"
					( Origin gFrontEnd )
				)
				( attribute "PHYS_PAGE" "80"
					( Origin gFrontEnd )
				)
				( attribute "ROOM" "DDR4_GH_H"
					( Origin gFrontEnd )
				)
				( attribute "ROT" "0"
					( Origin gFrontEnd )
				)
				( attribute "SEC" "1"
					( Origin gFrontEnd )
				)
				( attribute "SEC_TYPE" "PIP"
					( Origin gFrontEnd )
				)
				( attribute "VER" "1"
					( Origin gFrontEnd )
				)
				( attribute "XY" "(-5225,2700)"
					( Origin gFrontEnd )
				)
				( attribute "CHIPS_PART_NAME" "SCONN288_H44441003"
					( Origin gPackager )
				)
				( attribute "CDS_PART_NAME" "SCONN288_H44441003_PIP-SCONN,HA"
					( Origin gPackager )
				)
				( attribute "BOM_SS" "NOPOP"
					( Origin gFrontEnd )
				)
				( objectStatus "J9U1" )
			)
			( gate "@baseboard_fab2_lib.baseboard_fab2(sch_1):page80_i56"
				( attribute "BOM_COST" "MEM"
					( Origin gFrontEnd )
				)
				( attribute "CDS_LIB" "mstr_sconn"
					( Origin gPackager )
				)
				( attribute "CDS_LOCATION" "J9U1"
					( Origin gPackager )
				)
				( attribute "CDS_SEC" "4"
					( Origin gPackager )
				)
				( attribute "LOCATION" "J9U1"
					( Origin gFrontEnd )
				)
				( attribute "MATERIAL" "SCONN"
					( Origin gFrontEnd )
				)
				( attribute "PACK_TYPE" "PIP"
					( Origin gFrontEnd )
				)
				( attribute "PART_NUMBER" "H44441-003"
					( Origin gFrontEnd )
				)
				( attribute "PHYS_PAGE" "80"
					( Origin gFrontEnd )
				)
				( attribute "ROOM" "DDR4_GH_H"
					( Origin gFrontEnd )
				)
				( attribute "ROT" "0"
					( Origin gFrontEnd )
				)
				( attribute "SEC" "4"
					( Origin gFrontEnd )
				)
				( attribute "SEC_TYPE" "PIP"
					( Origin gFrontEnd )
				)
				( attribute "VER" "4"
					( Origin gFrontEnd )
				)
				( attribute "XY" "(-3075,1450)"
					( Origin gFrontEnd )
				)
				( attribute "CHIPS_PART_NAME" "SCONN288_H44441003"
					( Origin gPackager )
				)
				( attribute "CDS_PART_NAME" "SCONN288_H44441003_PIP-SCONN,HA"
					( Origin gPackager )
				)
				( attribute "BOM_SS" "NOPOP"
					( Origin gFrontEnd )
				)
				( objectStatus "J9U1" )
			)
			( gate "@baseboard_fab2_lib.baseboard_fab2(sch_1):page80_i101"
				( attribute "BOM_COST" "MEM"
					( Origin gFrontEnd )
				)
				( attribute "CDS_LIB" "mstr_sconn"
					( Origin gPackager )
				)
				( attribute "CDS_LOCATION" "J9U1"
					( Origin gPackager )
				)
				( attribute "CDS_SEC" "2"
					( Origin gPackager )
				)
				( attribute "LOCATION" "J9U1"
					( Origin gFrontEnd )
				)
				( attribute "MATERIAL" "SCONN"
					( Origin gFrontEnd )
				)
				( attribute "PACK_TYPE" "PIP"
					( Origin gFrontEnd )
				)
				( attribute "PART_NUMBER" "H44441-003"
					( Origin gFrontEnd )
				)
				( attribute "PHYS_PAGE" "80"
					( Origin gFrontEnd )
				)
				( attribute "ROOM" "DDR4_GH_H"
					( Origin gFrontEnd )
				)
				( attribute "ROT" "0"
					( Origin gFrontEnd )
				)
				( attribute "SEC" "2"
					( Origin gFrontEnd )
				)
				( attribute "SEC_TYPE" "PIP"
					( Origin gFrontEnd )
				)
				( attribute "VER" "2"
					( Origin gFrontEnd )
				)
				( attribute "XY" "(-2675,3750)"
					( Origin gFrontEnd )
				)
				( attribute "CHIPS_PART_NAME" "SCONN288_H44441003"
					( Origin gPackager )
				)
				( attribute "CDS_PART_NAME" "SCONN288_H44441003_PIP-SCONN,HA"
					( Origin gPackager )
				)
				( attribute "BOM_SS" "NOPOP"
					( Origin gFrontEnd )
				)
				( objectStatus "J9U1" )
			)
			( gate "@baseboard_fab2_lib.baseboard_fab2(sch_1):page80_i138"
				( attribute "BOM_COST" "MEM"
					( Origin gFrontEnd )
				)
				( attribute "CDS_LIB" "mstr_sconn"
					( Origin gPackager )
				)
				( attribute "CDS_LOCATION" "J9U1"
					( Origin gPackager )
				)
				( attribute "CDS_SEC" "3"
					( Origin gPackager )
				)
				( attribute "LOCATION" "J9U1"
					( Origin gFrontEnd )
				)
				( attribute "MATERIAL" "SCONN"
					( Origin gFrontEnd )
				)
				( attribute "PACK_TYPE" "PIP"
					( Origin gFrontEnd )
				)
				( attribute "PART_NUMBER" "H44441-003"
					( Origin gFrontEnd )
				)
				( attribute "PHYS_PAGE" "80"
					( Origin gFrontEnd )
				)
				( attribute "ROOM" "DDR4_GH_H"
					( Origin gFrontEnd )
				)
				( attribute "ROT" "0"
					( Origin gFrontEnd )
				)
				( attribute "SEC" "3"
					( Origin gFrontEnd )
				)
				( attribute "SEC_TYPE" "PIP"
					( Origin gFrontEnd )
				)
				( attribute "VER" "3"
					( Origin gFrontEnd )
				)
				( attribute "XY" "(-875,1850)"
					( Origin gFrontEnd )
				)
				( attribute "CHIPS_PART_NAME" "SCONN288_H44441003"
					( Origin gPackager )
				)
				( attribute "CDS_PART_NAME" "SCONN288_H44441003_PIP-SCONN,HA"
					( Origin gPackager )
				)
				( attribute "BOM_SS" "NOPOP"
					( Origin gFrontEnd )
				)
				( objectStatus "J9U1" )
			)
			( gate "@baseboard_fab2_lib.baseboard_fab2(sch_1):page81_i67"
				( attribute "BOM_COST" "MEM"
					( Origin gFrontEnd )
				)
				( attribute "CDS_LIB" "mstr_sconn"
					( Origin gPackager )
				)
				( attribute "CDS_LOCATION" "J1G3"
					( Origin gPackager )
				)
				( attribute "CDS_SEC" "2"
					( Origin gPackager )
				)
				( attribute "LOCATION" "J1G3"
					( Origin gFrontEnd )
				)
				( attribute "MATERIAL" "SCONN"
					( Origin gFrontEnd )
				)
				( attribute "PACK_TYPE" "PIP"
					( Origin gFrontEnd )
				)
				( attribute "PART_NUMBER" "H44441-004"
					( Origin gFrontEnd )
				)
				( attribute "PHYS_PAGE" "81"
					( Origin gFrontEnd )
				)
				( attribute "ROOM" "DDR4_CH_J"
					( Origin gFrontEnd )
				)
				( attribute "ROT" "0"
					( Origin gFrontEnd )
				)
				( attribute "SEC" "2"
					( Origin gFrontEnd )
				)
				( attribute "SEC_TYPE" "PIP"
					( Origin gFrontEnd )
				)
				( attribute "VER" "2"
					( Origin gFrontEnd )
				)
				( attribute "XY" "(-50,4300)"
					( Origin gFrontEnd )
				)
				( attribute "CHIPS_PART_NAME" "SCONN288_H44441004"
					( Origin gPackager )
				)
				( attribute "CDS_PART_NAME" "SCONN288_H44441004_PIP-SCONN,HA"
					( Origin gPackager )
				)
				( objectStatus "J1G3" )
			)
			( gate "@baseboard_fab2_lib.baseboard_fab2(sch_1):page81_i169"
				( attribute "BOM_COST" "MEM"
					( Origin gFrontEnd )
				)
				( attribute "CDS_LIB" "mstr_sconn"
					( Origin gPackager )
				)
				( attribute "CDS_LOCATION" "J1G3"
					( Origin gPackager )
				)
				( attribute "CDS_SEC" "4"
					( Origin gPackager )
				)
				( attribute "LOCATION" "J1G3"
					( Origin gFrontEnd )
				)
				( attribute "MATERIAL" "SCONN"
					( Origin gFrontEnd )
				)
				( attribute "PACK_TYPE" "PIP"
					( Origin gFrontEnd )
				)
				( attribute "PART_NUMBER" "H44441-004"
					( Origin gFrontEnd )
				)
				( attribute "PHYS_PAGE" "81"
					( Origin gFrontEnd )
				)
				( attribute "ROOM" "DDR4_CH_J"
					( Origin gFrontEnd )
				)
				( attribute "ROT" "0"
					( Origin gFrontEnd )
				)
				( attribute "SEC" "4"
					( Origin gFrontEnd )
				)
				( attribute "SEC_TYPE" "PIP"
					( Origin gFrontEnd )
				)
				( attribute "VER" "4"
					( Origin gFrontEnd )
				)
				( attribute "XY" "(-350,2000)"
					( Origin gFrontEnd )
				)
				( attribute "CHIPS_PART_NAME" "SCONN288_H44441004"
					( Origin gPackager )
				)
				( attribute "CDS_PART_NAME" "SCONN288_H44441004_PIP-SCONN,HA"
					( Origin gPackager )
				)
				( objectStatus "J1G3" )
			)
			( gate "@baseboard_fab2_lib.baseboard_fab2(sch_1):page81_i178"
				( attribute "BOM_COST" "MEM"
					( Origin gFrontEnd )
				)
				( attribute "CDS_LIB" "dev_discrete"
					( Origin gPackager )
				)
				( attribute "CDS_LOCATION" "C9U10"
					( Origin gPackager )
				)
				( attribute "CDS_SEC" "1"
					( Origin gPackager )
				)
				( attribute "LOCATION" "C9U10"
					( Origin gFrontEnd )
				)
				( attribute "MATERIAL" "X7R"
					( Origin gFrontEnd )
				)
				( attribute "PACK_TYPE" "0402V"
					( Origin gFrontEnd )
				)
				( attribute "PART_NUMBER" "A36096-045"
					( Origin gFrontEnd )
				)
				( attribute "PHYS_PAGE" "81"
					( Origin gFrontEnd )
				)
				( attribute "ROOM" "DDR4_CH_J"
					( Origin gFrontEnd )
				)
				( attribute "ROT" "2"
					( Origin gFrontEnd )
				)
				( attribute "SEC" "1"
					( Origin gPackager )
				)
				( attribute "TOLERANCE" "10%"
					( Origin gFrontEnd )
				)
				( attribute "VALUE" "0.01UF"
					( Origin gFrontEnd )
				)
				( attribute "VER" "1"
					( Origin gFrontEnd )
				)
				( attribute "VOLTAGE" "25V"
					( Units "uVoltage" "V" 1.000000)
					( Origin gFrontEnd )
				)
				( attribute "XY" "(-4550,1450)"
					( Origin gFrontEnd )
				)
				( attribute "CHIPS_PART_NAME" "CAP_A"
					( Origin gPackager )
				)
				( attribute "CDS_PART_NAME" "CAP_A_0402V-0.01UF,25V,10%,X7RA"
					( Origin gPackager )
				)
				( objectStatus "C9U10" )
			)
			( gate "@baseboard_fab2_lib.baseboard_fab2(sch_1):page81_i185"
				( attribute "BOM_COST" "MEM"
					( Origin gFrontEnd )
				)
				( attribute "CDS_LIB" "mstr_sconn"
					( Origin gPackager )
				)
				( attribute "CDS_LOCATION" "J1G3"
					( Origin gPackager )
				)
				( attribute "CDS_SEC" "3"
					( Origin gPackager )
				)
				( attribute "LOCATION" "J1G3"
					( Origin gFrontEnd )
				)
				( attribute "MATERIAL" "SCONN"
					( Origin gFrontEnd )
				)
				( attribute "PACK_TYPE" "PIP"
					( Origin gFrontEnd )
				)
				( attribute "PART_NUMBER" "H44441-004"
					( Origin gFrontEnd )
				)
				( attribute "PHYS_PAGE" "81"
					( Origin gFrontEnd )
				)
				( attribute "ROOM" "DDR4_CH_J"
					( Origin gFrontEnd )
				)
				( attribute "ROT" "0"
					( Origin gFrontEnd )
				)
				( attribute "SEC" "3"
					( Origin gFrontEnd )
				)
				( attribute "SEC_TYPE" "PIP"
					( Origin gFrontEnd )
				)
				( attribute "VER" "3"
					( Origin gFrontEnd )
				)
				( attribute "XY" "(1750,2400)"
					( Origin gFrontEnd )
				)
				( attribute "CHIPS_PART_NAME" "SCONN288_H44441004"
					( Origin gPackager )
				)
				( attribute "CDS_PART_NAME" "SCONN288_H44441004_PIP-SCONN,HA"
					( Origin gPackager )
				)
				( objectStatus "J1G3" )
			)
			( gate "@baseboard_fab2_lib.baseboard_fab2(sch_1):page81_i186"
				( attribute "BOM_COST" "MEM"
					( Origin gFrontEnd )
				)
				( attribute "CDS_LIB" "mstr_sconn"
					( Origin gPackager )
				)
				( attribute "CDS_LOCATION" "J1G3"
					( Origin gPackager )
				)
				( attribute "CDS_SEC" "1"
					( Origin gPackager )
				)
				( attribute "LOCATION" "J1G3"
					( Origin gFrontEnd )
				)
				( attribute "MATERIAL" "SCONN"
					( Origin gFrontEnd )
				)
				( attribute "PACK_TYPE" "PIP"
					( Origin gFrontEnd )
				)
				( attribute "PART_NUMBER" "H44441-004"
					( Origin gFrontEnd )
				)
				( attribute "PHYS_PAGE" "81"
					( Origin gFrontEnd )
				)
				( attribute "ROOM" "DDR4_CH_J"
					( Origin gFrontEnd )
				)
				( attribute "ROT" "0"
					( Origin gFrontEnd )
				)
				( attribute "SEC" "1"
					( Origin gFrontEnd )
				)
				( attribute "SEC_TYPE" "PIP"
					( Origin gFrontEnd )
				)
				( attribute "VER" "1"
					( Origin gFrontEnd )
				)
				( attribute "XY" "(-2550,3150)"
					( Origin gFrontEnd )
				)
				( attribute "CHIPS_PART_NAME" "SCONN288_H44441004"
					( Origin gPackager )
				)
				( attribute "CDS_PART_NAME" "SCONN288_H44441004_PIP-SCONN,HA"
					( Origin gPackager )
				)
				( objectStatus "J1G3" )
			)
			( gate "@baseboard_fab2_lib.baseboard_fab2(sch_1):page82_i64"
				( attribute "BOM_COST" "MEM"
					( Origin gFrontEnd )
				)
				( attribute "CDS_LIB" "mstr_sconn"
					( Origin gPackager )
				)
				( attribute "CDS_LOCATION" "J9U2"
					( Origin gPackager )
				)
				( attribute "CDS_SEC" "2"
					( Origin gPackager )
				)
				( attribute "LOCATION" "J9U2"
					( Origin gFrontEnd )
				)
				( attribute "MATERIAL" "SCONN"
					( Origin gFrontEnd )
				)
				( attribute "PACK_TYPE" "PIP"
					( Origin gFrontEnd )
				)
				( attribute "PART_NUMBER" "H44441-003"
					( Origin gFrontEnd )
				)
				( attribute "PHYS_PAGE" "82"
					( Origin gFrontEnd )
				)
				( attribute "ROOM" "DDR4_CH_J"
					( Origin gFrontEnd )
				)
				( attribute "ROT" "0"
					( Origin gFrontEnd )
				)
				( attribute "SEC" "2"
					( Origin gFrontEnd )
				)
				( attribute "SEC_TYPE" "PIP"
					( Origin gFrontEnd )
				)
				( attribute "VER" "2"
					( Origin gFrontEnd )
				)
				( attribute "XY" "(-50,4300)"
					( Origin gFrontEnd )
				)
				( attribute "CHIPS_PART_NAME" "SCONN288_H44441003"
					( Origin gPackager )
				)
				( attribute "CDS_PART_NAME" "SCONN288_H44441003_PIP-SCONN,HA"
					( Origin gPackager )
				)
				( attribute "BOM_SS" "NOPOP"
					( Origin gFrontEnd )
				)
				( objectStatus "J9U2" )
			)
			( gate "@baseboard_fab2_lib.baseboard_fab2(sch_1):page82_i171"
				( attribute "BOM_COST" "MEM"
					( Origin gFrontEnd )
				)
				( attribute "CDS_LIB" "mstr_sconn"
					( Origin gPackager )
				)
				( attribute "CDS_LOCATION" "J9U2"
					( Origin gPackager )
				)
				( attribute "CDS_SEC" "4"
					( Origin gPackager )
				)
				( attribute "LOCATION" "J9U2"
					( Origin gFrontEnd )
				)
				( attribute "MATERIAL" "SCONN"
					( Origin gFrontEnd )
				)
				( attribute "PACK_TYPE" "PIP"
					( Origin gFrontEnd )
				)
				( attribute "PART_NUMBER" "H44441-003"
					( Origin gFrontEnd )
				)
				( attribute "PHYS_PAGE" "82"
					( Origin gFrontEnd )
				)
				( attribute "ROOM" "DDR4_CH_J"
					( Origin gFrontEnd )
				)
				( attribute "ROT" "0"
					( Origin gFrontEnd )
				)
				( attribute "SEC" "4"
					( Origin gFrontEnd )
				)
				( attribute "SEC_TYPE" "PIP"
					( Origin gFrontEnd )
				)
				( attribute "VER" "4"
					( Origin gFrontEnd )
				)
				( attribute "XY" "(-350,2050)"
					( Origin gFrontEnd )
				)
				( attribute "CHIPS_PART_NAME" "SCONN288_H44441003"
					( Origin gPackager )
				)
				( attribute "CDS_PART_NAME" "SCONN288_H44441003_PIP-SCONN,HA"
					( Origin gPackager )
				)
				( attribute "BOM_SS" "NOPOP"
					( Origin gFrontEnd )
				)
				( objectStatus "J9U2" )
			)
			( gate "@baseboard_fab2_lib.baseboard_fab2(sch_1):page82_i180"
				( attribute "BOM_COST" "MEM"
					( Origin gFrontEnd )
				)
				( attribute "CDS_LIB" "dev_discrete"
					( Origin gPackager )
				)
				( attribute "CDS_LOCATION" "C1G19"
					( Origin gPackager )
				)
				( attribute "CDS_SEC" "1"
					( Origin gPackager )
				)
				( attribute "LOCATION" "C1G19"
					( Origin gFrontEnd )
				)
				( attribute "MATERIAL" "X7R"
					( Origin gFrontEnd )
				)
				( attribute "PACK_TYPE" "0402V"
					( Origin gFrontEnd )
				)
				( attribute "PART_NUMBER" "A36096-045"
					( Origin gFrontEnd )
				)
				( attribute "PHYS_PAGE" "82"
					( Origin gFrontEnd )
				)
				( attribute "ROOM" "DDR4_CH_J"
					( Origin gFrontEnd )
				)
				( attribute "ROT" "2"
					( Origin gFrontEnd )
				)
				( attribute "SEC" "1"
					( Origin gPackager )
				)
				( attribute "TOLERANCE" "10%"
					( Origin gFrontEnd )
				)
				( attribute "VALUE" "0.01UF"
					( Origin gFrontEnd )
				)
				( attribute "VER" "1"
					( Origin gFrontEnd )
				)
				( attribute "VOLTAGE" "25V"
					( Units "uVoltage" "V" 1.000000)
					( Origin gFrontEnd )
				)
				( attribute "XY" "(-4500,1450)"
					( Origin gFrontEnd )
				)
				( attribute "CHIPS_PART_NAME" "CAP_A"
					( Origin gPackager )
				)
				( attribute "CDS_PART_NAME" "CAP_A_0402V-0.01UF,25V,10%,X7RA"
					( Origin gPackager )
				)
				( objectStatus "C1G19" )
			)
			( gate "@baseboard_fab2_lib.baseboard_fab2(sch_1):page82_i187"
				( attribute "BOM_COST" "MEM"
					( Origin gFrontEnd )
				)
				( attribute "CDS_LIB" "mstr_sconn"
					( Origin gPackager )
				)
				( attribute "CDS_LOCATION" "J9U2"
					( Origin gPackager )
				)
				( attribute "CDS_SEC" "1"
					( Origin gPackager )
				)
				( attribute "LOCATION" "J9U2"
					( Origin gFrontEnd )
				)
				( attribute "MATERIAL" "SCONN"
					( Origin gFrontEnd )
				)
				( attribute "PACK_TYPE" "PIP"
					( Origin gFrontEnd )
				)
				( attribute "PART_NUMBER" "H44441-003"
					( Origin gFrontEnd )
				)
				( attribute "PHYS_PAGE" "82"
					( Origin gFrontEnd )
				)
				( attribute "ROOM" "DDR4_CH_J"
					( Origin gFrontEnd )
				)
				( attribute "ROT" "0"
					( Origin gFrontEnd )
				)
				( attribute "SEC" "1"
					( Origin gFrontEnd )
				)
				( attribute "SEC_TYPE" "PIP"
					( Origin gFrontEnd )
				)
				( attribute "VER" "1"
					( Origin gFrontEnd )
				)
				( attribute "XY" "(-2500,3150)"
					( Origin gFrontEnd )
				)
				( attribute "CHIPS_PART_NAME" "SCONN288_H44441003"
					( Origin gPackager )
				)
				( attribute "CDS_PART_NAME" "SCONN288_H44441003_PIP-SCONN,HA"
					( Origin gPackager )
				)
				( attribute "BOM_SS" "NOPOP"
					( Origin gFrontEnd )
				)
				( objectStatus "J9U2" )
			)
			( gate "@baseboard_fab2_lib.baseboard_fab2(sch_1):page82_i188"
				( attribute "BOM_COST" "MEM"
					( Origin gFrontEnd )
				)
				( attribute "CDS_LIB" "mstr_sconn"
					( Origin gPackager )
				)
				( attribute "CDS_LOCATION" "J9U2"
					( Origin gPackager )
				)
				( attribute "CDS_SEC" "3"
					( Origin gPackager )
				)
				( attribute "LOCATION" "J9U2"
					( Origin gFrontEnd )
				)
				( attribute "MATERIAL" "SCONN"
					( Origin gFrontEnd )
				)
				( attribute "PACK_TYPE" "PIP"
					( Origin gFrontEnd )
				)
				( attribute "PART_NUMBER" "H44441-003"
					( Origin gFrontEnd )
				)
				( attribute "PHYS_PAGE" "82"
					( Origin gFrontEnd )
				)
				( attribute "ROOM" "DDR4_CH_J"
					( Origin gFrontEnd )
				)
				( attribute "ROT" "0"
					( Origin gFrontEnd )
				)
				( attribute "SEC" "3"
					( Origin gFrontEnd )
				)
				( attribute "SEC_TYPE" "PIP"
					( Origin gFrontEnd )
				)
				( attribute "VER" "3"
					( Origin gFrontEnd )
				)
				( attribute "XY" "(1750,2350)"
					( Origin gFrontEnd )
				)
				( attribute "CHIPS_PART_NAME" "SCONN288_H44441003"
					( Origin gPackager )
				)
				( attribute "CDS_PART_NAME" "SCONN288_H44441003_PIP-SCONN,HA"
					( Origin gPackager )
				)
				( attribute "BOM_SS" "NOPOP"
					( Origin gFrontEnd )
				)
				( objectStatus "J9U2" )
			)
			( gate "@baseboard_fab2_lib.baseboard_fab2(sch_1):page83_i43"
				( attribute "BOM_COST" "MEM"
					( Origin gFrontEnd )
				)
				( attribute "CDS_LIB" "mstr_sconn"
					( Origin gPackager )
				)
				( attribute "CDS_LOCATION" "J1B1"
					( Origin gPackager )
				)
				( attribute "CDS_SEC" "3"
					( Origin gPackager )
				)
				( attribute "LOCATION" "J1B1"
					( Origin gFrontEnd )
				)
				( attribute "MATERIAL" "SCONN"
					( Origin gFrontEnd )
				)
				( attribute "PACK_TYPE" "PIP"
					( Origin gFrontEnd )
				)
				( attribute "PART_NUMBER" "H44441-004"
					( Origin gFrontEnd )
				)
				( attribute "PHYS_PAGE" "83"
					( Origin gFrontEnd )
				)
				( attribute "ROOM" "DDR4_CH_K"
					( Origin gFrontEnd )
				)
				( attribute "ROT" "0"
					( Origin gFrontEnd )
				)
				( attribute "SEC" "3"
					( Origin gFrontEnd )
				)
				( attribute "SEC_TYPE" "PIP"
					( Origin gFrontEnd )
				)
				( attribute "VER" "3"
					( Origin gFrontEnd )
				)
				( attribute "XY" "(1800,2400)"
					( Origin gFrontEnd )
				)
				( attribute "CHIPS_PART_NAME" "SCONN288_H44441004"
					( Origin gPackager )
				)
				( attribute "CDS_PART_NAME" "SCONN288_H44441004_PIP-SCONN,HA"
					( Origin gPackager )
				)
				( objectStatus "J1B1" )
			)
			( gate "@baseboard_fab2_lib.baseboard_fab2(sch_1):page83_i66"
				( attribute "BOM_COST" "MEM"
					( Origin gFrontEnd )
				)
				( attribute "CDS_LIB" "mstr_sconn"
					( Origin gPackager )
				)
				( attribute "CDS_LOCATION" "J1B1"
					( Origin gPackager )
				)
				( attribute "CDS_SEC" "2"
					( Origin gPackager )
				)
				( attribute "LOCATION" "J1B1"
					( Origin gFrontEnd )
				)
				( attribute "MATERIAL" "SCONN"
					( Origin gFrontEnd )
				)
				( attribute "PACK_TYPE" "PIP"
					( Origin gFrontEnd )
				)
				( attribute "PART_NUMBER" "H44441-004"
					( Origin gFrontEnd )
				)
				( attribute "PHYS_PAGE" "83"
					( Origin gFrontEnd )
				)
				( attribute "ROOM" "DDR4_CH_K"
					( Origin gFrontEnd )
				)
				( attribute "ROT" "0"
					( Origin gFrontEnd )
				)
				( attribute "SEC" "2"
					( Origin gFrontEnd )
				)
				( attribute "SEC_TYPE" "PIP"
					( Origin gFrontEnd )
				)
				( attribute "VER" "2"
					( Origin gFrontEnd )
				)
				( attribute "XY" "(0,4350)"
					( Origin gFrontEnd )
				)
				( attribute "CHIPS_PART_NAME" "SCONN288_H44441004"
					( Origin gPackager )
				)
				( attribute "CDS_PART_NAME" "SCONN288_H44441004_PIP-SCONN,HA"
					( Origin gPackager )
				)
				( objectStatus "J1B1" )
			)
			( gate "@baseboard_fab2_lib.baseboard_fab2(sch_1):page83_i111"
				( attribute "BOM_COST" "MEM"
					( Origin gFrontEnd )
				)
				( attribute "CDS_LIB" "mstr_sconn"
					( Origin gPackager )
				)
				( attribute "CDS_LOCATION" "J1B1"
					( Origin gPackager )
				)
				( attribute "CDS_SEC" "1"
					( Origin gPackager )
				)
				( attribute "LOCATION" "J1B1"
					( Origin gFrontEnd )
				)
				( attribute "MATERIAL" "SCONN"
					( Origin gFrontEnd )
				)
				( attribute "PACK_TYPE" "PIP"
					( Origin gFrontEnd )
				)
				( attribute "PART_NUMBER" "H44441-004"
					( Origin gFrontEnd )
				)
				( attribute "PHYS_PAGE" "83"
					( Origin gFrontEnd )
				)
				( attribute "ROOM" "DDR4_CH_K"
					( Origin gFrontEnd )
				)
				( attribute "ROT" "0"
					( Origin gFrontEnd )
				)
				( attribute "SEC" "1"
					( Origin gFrontEnd )
				)
				( attribute "SEC_TYPE" "PIP"
					( Origin gFrontEnd )
				)
				( attribute "VER" "1"
					( Origin gFrontEnd )
				)
				( attribute "XY" "(-2450,3200)"
					( Origin gFrontEnd )
				)
				( attribute "CHIPS_PART_NAME" "SCONN288_H44441004"
					( Origin gPackager )
				)
				( attribute "CDS_PART_NAME" "SCONN288_H44441004_PIP-SCONN,HA"
					( Origin gPackager )
				)
				( objectStatus "J1B1" )
			)
			( gate "@baseboard_fab2_lib.baseboard_fab2(sch_1):page83_i167"
				( attribute "BOM_COST" "MEM"
					( Origin gFrontEnd )
				)
				( attribute "CDS_LIB" "mstr_sconn"
					( Origin gPackager )
				)
				( attribute "CDS_LOCATION" "J1B1"
					( Origin gPackager )
				)
				( attribute "CDS_SEC" "4"
					( Origin gPackager )
				)
				( attribute "LOCATION" "J1B1"
					( Origin gFrontEnd )
				)
				( attribute "MATERIAL" "SCONN"
					( Origin gFrontEnd )
				)
				( attribute "PACK_TYPE" "PIP"
					( Origin gFrontEnd )
				)
				( attribute "PART_NUMBER" "H44441-004"
					( Origin gFrontEnd )
				)
				( attribute "PHYS_PAGE" "83"
					( Origin gFrontEnd )
				)
				( attribute "ROOM" "DDR4_CH_K"
					( Origin gFrontEnd )
				)
				( attribute "ROT" "0"
					( Origin gFrontEnd )
				)
				( attribute "SEC" "4"
					( Origin gFrontEnd )
				)
				( attribute "SEC_TYPE" "PIP"
					( Origin gFrontEnd )
				)
				( attribute "VER" "4"
					( Origin gFrontEnd )
				)
				( attribute "XY" "(-150,2100)"
					( Origin gFrontEnd )
				)
				( attribute "CHIPS_PART_NAME" "SCONN288_H44441004"
					( Origin gPackager )
				)
				( attribute "CDS_PART_NAME" "SCONN288_H44441004_PIP-SCONN,HA"
					( Origin gPackager )
				)
				( objectStatus "J1B1" )
			)
			( gate "@baseboard_fab2_lib.baseboard_fab2(sch_1):page83_i176"
				( attribute "BOM_COST" "MEM"
					( Origin gFrontEnd )
				)
				( attribute "CDS_LIB" "dev_discrete"
					( Origin gPackager )
				)
				( attribute "CDS_LOCATION" "C1B9"
					( Origin gPackager )
				)
				( attribute "CDS_SEC" "1"
					( Origin gPackager )
				)
				( attribute "LOCATION" "C1B9"
					( Origin gFrontEnd )
				)
				( attribute "MATERIAL" "X7R"
					( Origin gFrontEnd )
				)
				( attribute "PACK_TYPE" "0402V"
					( Origin gFrontEnd )
				)
				( attribute "PART_NUMBER" "A36096-045"
					( Origin gFrontEnd )
				)
				( attribute "PHYS_PAGE" "83"
					( Origin gFrontEnd )
				)
				( attribute "ROOM" "DDR4_CH_K"
					( Origin gFrontEnd )
				)
				( attribute "ROT" "2"
					( Origin gFrontEnd )
				)
				( attribute "SEC" "1"
					( Origin gPackager )
				)
				( attribute "TOLERANCE" "10%"
					( Origin gFrontEnd )
				)
				( attribute "VALUE" "0.01UF"
					( Origin gFrontEnd )
				)
				( attribute "VER" "1"
					( Origin gFrontEnd )
				)
				( attribute "VOLTAGE" "25V"
					( Units "uVoltage" "V" 1.000000)
					( Origin gFrontEnd )
				)
				( attribute "XY" "(-4600,1500)"
					( Origin gFrontEnd )
				)
				( attribute "CHIPS_PART_NAME" "CAP_A"
					( Origin gPackager )
				)
				( attribute "CDS_PART_NAME" "CAP_A_0402V-0.01UF,25V,10%,X7RA"
					( Origin gPackager )
				)
				( objectStatus "C1B9" )
			)
			( gate "@baseboard_fab2_lib.baseboard_fab2(sch_1):page84_i4"
				( attribute "BOM_COST" "MEM"
					( Origin gFrontEnd )
				)
				( attribute "CDS_LIB" "dev_discrete"
					( Origin gPackager )
				)
				( attribute "CDS_LOCATION" "C9M1"
					( Origin gPackager )
				)
				( attribute "CDS_SEC" "1"
					( Origin gPackager )
				)
				( attribute "LOCATION" "C9M1"
					( Origin gFrontEnd )
				)
				( attribute "MATERIAL" "X7R"
					( Origin gFrontEnd )
				)
				( attribute "PACK_TYPE" "0402V"
					( Origin gFrontEnd )
				)
				( attribute "PART_NUMBER" "A36096-045"
					( Origin gFrontEnd )
				)
				( attribute "PHYS_PAGE" "84"
					( Origin gFrontEnd )
				)
				( attribute "ROOM" "DDR4_CH_C"
					( Origin gFrontEnd )
				)
				( attribute "ROT" "2"
					( Origin gFrontEnd )
				)
				( attribute "SEC" "1"
					( Origin gPackager )
				)
				( attribute "TOLERANCE" "10%"
					( Origin gFrontEnd )
				)
				( attribute "VALUE" "0.01UF"
					( Origin gFrontEnd )
				)
				( attribute "VER" "1"
					( Origin gFrontEnd )
				)
				( attribute "VOLTAGE" "25V"
					( Units "uVoltage" "V" 1.000000)
					( Origin gFrontEnd )
				)
				( attribute "XY" "(-3000,1125)"
					( Origin gFrontEnd )
				)
				( attribute "CHIPS_PART_NAME" "CAP_A"
					( Origin gPackager )
				)
				( attribute "CDS_PART_NAME" "CAP_A_0402V-0.01UF,25V,10%,X7RA"
					( Origin gPackager )
				)
				( objectStatus "C9M1" )
			)
			( gate "@baseboard_fab2_lib.baseboard_fab2(sch_1):page84_i14"
				( attribute "BOM_COST" "MEM"
					( Origin gFrontEnd )
				)
				( attribute "CDS_LIB" "mstr_sconn"
					( Origin gPackager )
				)
				( attribute "CDS_LOCATION" "J9M1"
					( Origin gPackager )
				)
				( attribute "CDS_SEC" "1"
					( Origin gPackager )
				)
				( attribute "LOCATION" "J9M1"
					( Origin gFrontEnd )
				)
				( attribute "MATERIAL" "SCONN"
					( Origin gFrontEnd )
				)
				( attribute "PACK_TYPE" "PIP"
					( Origin gFrontEnd )
				)
				( attribute "PART_NUMBER" "H44441-003"
					( Origin gFrontEnd )
				)
				( attribute "PHYS_PAGE" "84"
					( Origin gFrontEnd )
				)
				( attribute "ROOM" "DDR4_CH_K"
					( Origin gFrontEnd )
				)
				( attribute "ROT" "0"
					( Origin gFrontEnd )
				)
				( attribute "SEC" "1"
					( Origin gFrontEnd )
				)
				( attribute "SEC_TYPE" "PIP"
					( Origin gFrontEnd )
				)
				( attribute "VER" "1"
					( Origin gFrontEnd )
				)
				( attribute "XY" "(-850,2825)"
					( Origin gFrontEnd )
				)
				( attribute "CHIPS_PART_NAME" "SCONN288_H44441003"
					( Origin gPackager )
				)
				( attribute "CDS_PART_NAME" "SCONN288_H44441003_PIP-SCONN,HA"
					( Origin gPackager )
				)
				( attribute "BOM_SS" "NOPOP"
					( Origin gFrontEnd )
				)
				( objectStatus "J9M1" )
			)
			( gate "@baseboard_fab2_lib.baseboard_fab2(sch_1):page84_i57"
				( attribute "BOM_COST" "MEM"
					( Origin gFrontEnd )
				)
				( attribute "CDS_LIB" "mstr_sconn"
					( Origin gPackager )
				)
				( attribute "CDS_LOCATION" "J9M1"
					( Origin gPackager )
				)
				( attribute "CDS_SEC" "4"
					( Origin gPackager )
				)
				( attribute "LOCATION" "J9M1"
					( Origin gFrontEnd )
				)
				( attribute "MATERIAL" "SCONN"
					( Origin gFrontEnd )
				)
				( attribute "PACK_TYPE" "PIP"
					( Origin gFrontEnd )
				)
				( attribute "PART_NUMBER" "H44441-003"
					( Origin gFrontEnd )
				)
				( attribute "PHYS_PAGE" "84"
					( Origin gFrontEnd )
				)
				( attribute "ROOM" "DDR4_CH_K"
					( Origin gFrontEnd )
				)
				( attribute "ROT" "0"
					( Origin gFrontEnd )
				)
				( attribute "SEC" "4"
					( Origin gFrontEnd )
				)
				( attribute "SEC_TYPE" "PIP"
					( Origin gFrontEnd )
				)
				( attribute "VER" "4"
					( Origin gFrontEnd )
				)
				( attribute "XY" "(1450,1725)"
					( Origin gFrontEnd )
				)
				( attribute "CHIPS_PART_NAME" "SCONN288_H44441003"
					( Origin gPackager )
				)
				( attribute "CDS_PART_NAME" "SCONN288_H44441003_PIP-SCONN,HA"
					( Origin gPackager )
				)
				( attribute "BOM_SS" "NOPOP"
					( Origin gFrontEnd )
				)
				( objectStatus "J9M1" )
			)
			( gate "@baseboard_fab2_lib.baseboard_fab2(sch_1):page84_i102"
				( attribute "BOM_COST" "MEM"
					( Origin gFrontEnd )
				)
				( attribute "CDS_LIB" "mstr_sconn"
					( Origin gPackager )
				)
				( attribute "CDS_LOCATION" "J9M1"
					( Origin gPackager )
				)
				( attribute "CDS_SEC" "2"
					( Origin gPackager )
				)
				( attribute "LOCATION" "J9M1"
					( Origin gFrontEnd )
				)
				( attribute "MATERIAL" "SCONN"
					( Origin gFrontEnd )
				)
				( attribute "PACK_TYPE" "PIP"
					( Origin gFrontEnd )
				)
				( attribute "PART_NUMBER" "H44441-003"
					( Origin gFrontEnd )
				)
				( attribute "PHYS_PAGE" "84"
					( Origin gFrontEnd )
				)
				( attribute "ROOM" "DDR4_CH_K"
					( Origin gFrontEnd )
				)
				( attribute "ROT" "0"
					( Origin gFrontEnd )
				)
				( attribute "SEC" "2"
					( Origin gFrontEnd )
				)
				( attribute "SEC_TYPE" "PIP"
					( Origin gFrontEnd )
				)
				( attribute "VER" "2"
					( Origin gFrontEnd )
				)
				( attribute "XY" "(1600,3975)"
					( Origin gFrontEnd )
				)
				( attribute "CHIPS_PART_NAME" "SCONN288_H44441003"
					( Origin gPackager )
				)
				( attribute "CDS_PART_NAME" "SCONN288_H44441003_PIP-SCONN,HA"
					( Origin gPackager )
				)
				( attribute "BOM_SS" "NOPOP"
					( Origin gFrontEnd )
				)
				( objectStatus "J9M1" )
			)
			( gate "@baseboard_fab2_lib.baseboard_fab2(sch_1):page84_i138"
				( attribute "BOM_COST" "MEM"
					( Origin gFrontEnd )
				)
				( attribute "CDS_LIB" "mstr_sconn"
					( Origin gPackager )
				)
				( attribute "CDS_LOCATION" "J9M1"
					( Origin gPackager )
				)
				( attribute "CDS_SEC" "3"
					( Origin gPackager )
				)
				( attribute "LOCATION" "J9M1"
					( Origin gFrontEnd )
				)
				( attribute "MATERIAL" "SCONN"
					( Origin gFrontEnd )
				)
				( attribute "PACK_TYPE" "PIP"
					( Origin gFrontEnd )
				)
				( attribute "PART_NUMBER" "H44441-003"
					( Origin gFrontEnd )
				)
				( attribute "PHYS_PAGE" "84"
					( Origin gFrontEnd )
				)
				( attribute "ROOM" "DDR4_CH_K"
					( Origin gFrontEnd )
				)
				( attribute "ROT" "0"
					( Origin gFrontEnd )
				)
				( attribute "SEC" "3"
					( Origin gFrontEnd )
				)
				( attribute "SEC_TYPE" "PIP"
					( Origin gFrontEnd )
				)
				( attribute "VER" "3"
					( Origin gFrontEnd )
				)
				( attribute "XY" "(3400,2025)"
					( Origin gFrontEnd )
				)
				( attribute "CHIPS_PART_NAME" "SCONN288_H44441003"
					( Origin gPackager )
				)
				( attribute "CDS_PART_NAME" "SCONN288_H44441003_PIP-SCONN,HA"
					( Origin gPackager )
				)
				( attribute "BOM_SS" "NOPOP"
					( Origin gFrontEnd )
				)
				( objectStatus "J9M1" )
			)
			( gate "@baseboard_fab2_lib.baseboard_fab2(sch_1):page85_i43"
				( attribute "BOM_COST" "MEM"
					( Origin gFrontEnd )
				)
				( attribute "CDS_LIB" "mstr_sconn"
					( Origin gPackager )
				)
				( attribute "CDS_LOCATION" "J1A2"
					( Origin gPackager )
				)
				( attribute "CDS_SEC" "3"
					( Origin gPackager )
				)
				( attribute "LOCATION" "J1A2"
					( Origin gFrontEnd )
				)
				( attribute "MATERIAL" "SCONN"
					( Origin gFrontEnd )
				)
				( attribute "PACK_TYPE" "PIP"
					( Origin gFrontEnd )
				)
				( attribute "PART_NUMBER" "H44441-004"
					( Origin gFrontEnd )
				)
				( attribute "PHYS_PAGE" "85"
					( Origin gFrontEnd )
				)
				( attribute "ROOM" "DDR4_CH_L"
					( Origin gFrontEnd )
				)
				( attribute "ROT" "0"
					( Origin gFrontEnd )
				)
				( attribute "SEC" "3"
					( Origin gFrontEnd )
				)
				( attribute "SEC_TYPE" "PIP"
					( Origin gFrontEnd )
				)
				( attribute "VER" "3"
					( Origin gFrontEnd )
				)
				( attribute "XY" "(1800,2400)"
					( Origin gFrontEnd )
				)
				( attribute "CHIPS_PART_NAME" "SCONN288_H44441004"
					( Origin gPackager )
				)
				( attribute "CDS_PART_NAME" "SCONN288_H44441004_PIP-SCONN,HA"
					( Origin gPackager )
				)
				( objectStatus "J1A2" )
			)
			( gate "@baseboard_fab2_lib.baseboard_fab2(sch_1):page85_i66"
				( attribute "BOM_COST" "MEM"
					( Origin gFrontEnd )
				)
				( attribute "CDS_LIB" "mstr_sconn"
					( Origin gPackager )
				)
				( attribute "CDS_LOCATION" "J1A2"
					( Origin gPackager )
				)
				( attribute "CDS_SEC" "2"
					( Origin gPackager )
				)
				( attribute "LOCATION" "J1A2"
					( Origin gFrontEnd )
				)
				( attribute "MATERIAL" "SCONN"
					( Origin gFrontEnd )
				)
				( attribute "PACK_TYPE" "PIP"
					( Origin gFrontEnd )
				)
				( attribute "PART_NUMBER" "H44441-004"
					( Origin gFrontEnd )
				)
				( attribute "PHYS_PAGE" "85"
					( Origin gFrontEnd )
				)
				( attribute "ROOM" "DDR4_CH_L"
					( Origin gFrontEnd )
				)
				( attribute "ROT" "0"
					( Origin gFrontEnd )
				)
				( attribute "SEC" "2"
					( Origin gFrontEnd )
				)
				( attribute "SEC_TYPE" "PIP"
					( Origin gFrontEnd )
				)
				( attribute "VER" "2"
					( Origin gFrontEnd )
				)
				( attribute "XY" "(0,4300)"
					( Origin gFrontEnd )
				)
				( attribute "CHIPS_PART_NAME" "SCONN288_H44441004"
					( Origin gPackager )
				)
				( attribute "CDS_PART_NAME" "SCONN288_H44441004_PIP-SCONN,HA"
					( Origin gPackager )
				)
				( objectStatus "J1A2" )
			)
			( gate "@baseboard_fab2_lib.baseboard_fab2(sch_1):page85_i111"
				( attribute "BOM_COST" "MEM"
					( Origin gFrontEnd )
				)
				( attribute "CDS_LIB" "mstr_sconn"
					( Origin gPackager )
				)
				( attribute "CDS_LOCATION" "J1A2"
					( Origin gPackager )
				)
				( attribute "CDS_SEC" "1"
					( Origin gPackager )
				)
				( attribute "LOCATION" "J1A2"
					( Origin gFrontEnd )
				)
				( attribute "MATERIAL" "SCONN"
					( Origin gFrontEnd )
				)
				( attribute "PACK_TYPE" "PIP"
					( Origin gFrontEnd )
				)
				( attribute "PART_NUMBER" "H44441-004"
					( Origin gFrontEnd )
				)
				( attribute "PHYS_PAGE" "85"
					( Origin gFrontEnd )
				)
				( attribute "ROOM" "DDR4_CH_L"
					( Origin gFrontEnd )
				)
				( attribute "ROT" "0"
					( Origin gFrontEnd )
				)
				( attribute "SEC" "1"
					( Origin gFrontEnd )
				)
				( attribute "SEC_TYPE" "PIP"
					( Origin gFrontEnd )
				)
				( attribute "VER" "1"
					( Origin gFrontEnd )
				)
				( attribute "XY" "(-2500,3250)"
					( Origin gFrontEnd )
				)
				( attribute "CHIPS_PART_NAME" "SCONN288_H44441004"
					( Origin gPackager )
				)
				( attribute "CDS_PART_NAME" "SCONN288_H44441004_PIP-SCONN,HA"
					( Origin gPackager )
				)
				( objectStatus "J1A2" )
			)
			( gate "@baseboard_fab2_lib.baseboard_fab2(sch_1):page85_i172"
				( attribute "BOM_COST" "MEM"
					( Origin gFrontEnd )
				)
				( attribute "CDS_LIB" "mstr_sconn"
					( Origin gPackager )
				)
				( attribute "CDS_LOCATION" "J1A2"
					( Origin gPackager )
				)
				( attribute "CDS_SEC" "4"
					( Origin gPackager )
				)
				( attribute "LOCATION" "J1A2"
					( Origin gFrontEnd )
				)
				( attribute "MATERIAL" "SCONN"
					( Origin gFrontEnd )
				)
				( attribute "PACK_TYPE" "PIP"
					( Origin gFrontEnd )
				)
				( attribute "PART_NUMBER" "H44441-004"
					( Origin gFrontEnd )
				)
				( attribute "PHYS_PAGE" "85"
					( Origin gFrontEnd )
				)
				( attribute "ROOM" "DDR4_CH_L"
					( Origin gFrontEnd )
				)
				( attribute "ROT" "0"
					( Origin gFrontEnd )
				)
				( attribute "SEC" "4"
					( Origin gFrontEnd )
				)
				( attribute "SEC_TYPE" "PIP"
					( Origin gFrontEnd )
				)
				( attribute "VER" "4"
					( Origin gFrontEnd )
				)
				( attribute "XY" "(-250,2050)"
					( Origin gFrontEnd )
				)
				( attribute "CHIPS_PART_NAME" "SCONN288_H44441004"
					( Origin gPackager )
				)
				( attribute "CDS_PART_NAME" "SCONN288_H44441004_PIP-SCONN,HA"
					( Origin gPackager )
				)
				( objectStatus "J1A2" )
			)
			( gate "@baseboard_fab2_lib.baseboard_fab2(sch_1):page85_i181"
				( attribute "BOM_COST" "MEM"
					( Origin gFrontEnd )
				)
				( attribute "CDS_LIB" "dev_discrete"
					( Origin gPackager )
				)
				( attribute "CDS_LOCATION" "C9L7"
					( Origin gPackager )
				)
				( attribute "CDS_SEC" "1"
					( Origin gPackager )
				)
				( attribute "LOCATION" "C9L7"
					( Origin gFrontEnd )
				)
				( attribute "MATERIAL" "X7R"
					( Origin gFrontEnd )
				)
				( attribute "PACK_TYPE" "0402V"
					( Origin gFrontEnd )
				)
				( attribute "PART_NUMBER" "A36096-045"
					( Origin gFrontEnd )
				)
				( attribute "PHYS_PAGE" "85"
					( Origin gFrontEnd )
				)
				( attribute "ROOM" "DDR4_CH_L"
					( Origin gFrontEnd )
				)
				( attribute "ROT" "2"
					( Origin gFrontEnd )
				)
				( attribute "SEC" "1"
					( Origin gPackager )
				)
				( attribute "TOLERANCE" "10%"
					( Origin gFrontEnd )
				)
				( attribute "VALUE" "0.01UF"
					( Origin gFrontEnd )
				)
				( attribute "VER" "1"
					( Origin gFrontEnd )
				)
				( attribute "VOLTAGE" "25V"
					( Units "uVoltage" "V" 1.000000)
					( Origin gFrontEnd )
				)
				( attribute "XY" "(-4650,1550)"
					( Origin gFrontEnd )
				)
				( attribute "CHIPS_PART_NAME" "CAP_A"
					( Origin gPackager )
				)
				( attribute "CDS_PART_NAME" "CAP_A_0402V-0.01UF,25V,10%,X7RA"
					( Origin gPackager )
				)
				( objectStatus "C9L7" )
			)
			( gate "@baseboard_fab2_lib.baseboard_fab2(sch_1):page86_i12"
				( attribute "BOM_COST" "MEM"
					( Origin gFrontEnd )
				)
				( attribute "CDS_LIB" "mstr_sconn"
					( Origin gPackager )
				)
				( attribute "CDS_LOCATION" "J9L2"
					( Origin gPackager )
				)
				( attribute "CDS_SEC" "1"
					( Origin gPackager )
				)
				( attribute "LOCATION" "J9L2"
					( Origin gFrontEnd )
				)
				( attribute "MATERIAL" "SCONN"
					( Origin gFrontEnd )
				)
				( attribute "PACK_TYPE" "PIP"
					( Origin gFrontEnd )
				)
				( attribute "PART_NUMBER" "H44441-003"
					( Origin gFrontEnd )
				)
				( attribute "PHYS_PAGE" "86"
					( Origin gFrontEnd )
				)
				( attribute "ROOM" "DDR4_CH_L"
					( Origin gFrontEnd )
				)
				( attribute "ROT" "0"
					( Origin gFrontEnd )
				)
				( attribute "SEC" "1"
					( Origin gFrontEnd )
				)
				( attribute "SEC_TYPE" "PIP"
					( Origin gFrontEnd )
				)
				( attribute "VER" "1"
					( Origin gFrontEnd )
				)
				( attribute "XY" "(-875,2925)"
					( Origin gFrontEnd )
				)
				( attribute "CHIPS_PART_NAME" "SCONN288_H44441003"
					( Origin gPackager )
				)
				( attribute "CDS_PART_NAME" "SCONN288_H44441003_PIP-SCONN,HA"
					( Origin gPackager )
				)
				( attribute "BOM_SS" "NOPOP"
					( Origin gFrontEnd )
				)
				( objectStatus "J9L2" )
			)
			( gate "@baseboard_fab2_lib.baseboard_fab2(sch_1):page86_i55"
				( attribute "BOM_COST" "MEM"
					( Origin gFrontEnd )
				)
				( attribute "CDS_LIB" "mstr_sconn"
					( Origin gPackager )
				)
				( attribute "CDS_LOCATION" "J9L2"
					( Origin gPackager )
				)
				( attribute "CDS_SEC" "4"
					( Origin gPackager )
				)
				( attribute "LOCATION" "J9L2"
					( Origin gFrontEnd )
				)
				( attribute "MATERIAL" "SCONN"
					( Origin gFrontEnd )
				)
				( attribute "PACK_TYPE" "PIP"
					( Origin gFrontEnd )
				)
				( attribute "PART_NUMBER" "H44441-003"
					( Origin gFrontEnd )
				)
				( attribute "PHYS_PAGE" "86"
					( Origin gFrontEnd )
				)
				( attribute "ROOM" "DDR4_CH_L"
					( Origin gFrontEnd )
				)
				( attribute "ROT" "0"
					( Origin gFrontEnd )
				)
				( attribute "SEC" "4"
					( Origin gFrontEnd )
				)
				( attribute "SEC_TYPE" "PIP"
					( Origin gFrontEnd )
				)
				( attribute "VER" "4"
					( Origin gFrontEnd )
				)
				( attribute "XY" "(1375,1725)"
					( Origin gFrontEnd )
				)
				( attribute "CHIPS_PART_NAME" "SCONN288_H44441003"
					( Origin gPackager )
				)
				( attribute "CDS_PART_NAME" "SCONN288_H44441003_PIP-SCONN,HA"
					( Origin gPackager )
				)
				( attribute "BOM_SS" "NOPOP"
					( Origin gFrontEnd )
				)
				( objectStatus "J9L2" )
			)
			( gate "@baseboard_fab2_lib.baseboard_fab2(sch_1):page86_i100"
				( attribute "BOM_COST" "MEM"
					( Origin gFrontEnd )
				)
				( attribute "CDS_LIB" "mstr_sconn"
					( Origin gPackager )
				)
				( attribute "CDS_LOCATION" "J9L2"
					( Origin gPackager )
				)
				( attribute "CDS_SEC" "2"
					( Origin gPackager )
				)
				( attribute "LOCATION" "J9L2"
					( Origin gFrontEnd )
				)
				( attribute "MATERIAL" "SCONN"
					( Origin gFrontEnd )
				)
				( attribute "PACK_TYPE" "PIP"
					( Origin gFrontEnd )
				)
				( attribute "PART_NUMBER" "H44441-003"
					( Origin gFrontEnd )
				)
				( attribute "PHYS_PAGE" "86"
					( Origin gFrontEnd )
				)
				( attribute "ROOM" "DDR4_CH_L"
					( Origin gFrontEnd )
				)
				( attribute "ROT" "0"
					( Origin gFrontEnd )
				)
				( attribute "SEC" "2"
					( Origin gFrontEnd )
				)
				( attribute "SEC_TYPE" "PIP"
					( Origin gFrontEnd )
				)
				( attribute "VER" "2"
					( Origin gFrontEnd )
				)
				( attribute "XY" "(1625,3975)"
					( Origin gFrontEnd )
				)
				( attribute "CHIPS_PART_NAME" "SCONN288_H44441003"
					( Origin gPackager )
				)
				( attribute "CDS_PART_NAME" "SCONN288_H44441003_PIP-SCONN,HA"
					( Origin gPackager )
				)
				( attribute "BOM_SS" "NOPOP"
					( Origin gFrontEnd )
				)
				( objectStatus "J9L2" )
			)
			( gate "@baseboard_fab2_lib.baseboard_fab2(sch_1):page86_i138"
				( attribute "BOM_COST" "MEM"
					( Origin gFrontEnd )
				)
				( attribute "CDS_LIB" "mstr_sconn"
					( Origin gPackager )
				)
				( attribute "CDS_LOCATION" "J9L2"
					( Origin gPackager )
				)
				( attribute "CDS_SEC" "3"
					( Origin gPackager )
				)
				( attribute "LOCATION" "J9L2"
					( Origin gFrontEnd )
				)
				( attribute "MATERIAL" "SCONN"
					( Origin gFrontEnd )
				)
				( attribute "PACK_TYPE" "PIP"
					( Origin gFrontEnd )
				)
				( attribute "PART_NUMBER" "H44441-003"
					( Origin gFrontEnd )
				)
				( attribute "PHYS_PAGE" "86"
					( Origin gFrontEnd )
				)
				( attribute "ROOM" "DDR4_CH_L"
					( Origin gFrontEnd )
				)
				( attribute "ROT" "0"
					( Origin gFrontEnd )
				)
				( attribute "SEC" "3"
					( Origin gFrontEnd )
				)
				( attribute "SEC_TYPE" "PIP"
					( Origin gFrontEnd )
				)
				( attribute "VER" "3"
					( Origin gFrontEnd )
				)
				( attribute "XY" "(3425,2075)"
					( Origin gFrontEnd )
				)
				( attribute "CHIPS_PART_NAME" "SCONN288_H44441003"
					( Origin gPackager )
				)
				( attribute "CDS_PART_NAME" "SCONN288_H44441003_PIP-SCONN,HA"
					( Origin gPackager )
				)
				( attribute "BOM_SS" "NOPOP"
					( Origin gFrontEnd )
				)
				( objectStatus "J9L2" )
			)
			( gate "@baseboard_fab2_lib.baseboard_fab2(sch_1):page86_i182"
				( attribute "BOM_COST" "MEM"
					( Origin gFrontEnd )
				)
				( attribute "CDS_LIB" "dev_discrete"
					( Origin gPackager )
				)
				( attribute "CDS_LOCATION" "C1A17"
					( Origin gPackager )
				)
				( attribute "CDS_SEC" "1"
					( Origin gPackager )
				)
				( attribute "LOCATION" "C1A17"
					( Origin gFrontEnd )
				)
				( attribute "MATERIAL" "X7R"
					( Origin gFrontEnd )
				)
				( attribute "PACK_TYPE" "0402V"
					( Origin gFrontEnd )
				)
				( attribute "PART_NUMBER" "A36096-045"
					( Origin gFrontEnd )
				)
				( attribute "PHYS_PAGE" "86"
					( Origin gFrontEnd )
				)
				( attribute "ROOM" "DDR4_CH_D"
					( Origin gFrontEnd )
				)
				( attribute "ROT" "2"
					( Origin gFrontEnd )
				)
				( attribute "SEC" "1"
					( Origin gPackager )
				)
				( attribute "TOLERANCE" "10%"
					( Origin gFrontEnd )
				)
				( attribute "VALUE" "0.01UF"
					( Origin gFrontEnd )
				)
				( attribute "VER" "1"
					( Origin gFrontEnd )
				)
				( attribute "VOLTAGE" "25V"
					( Units "uVoltage" "V" 1.000000)
					( Origin gFrontEnd )
				)
				( attribute "XY" "(-3025,1225)"
					( Origin gFrontEnd )
				)
				( attribute "CHIPS_PART_NAME" "CAP_A"
					( Origin gPackager )
				)
				( attribute "CDS_PART_NAME" "CAP_A_0402V-0.01UF,25V,10%,X7RA"
					( Origin gPackager )
				)
				( objectStatus "C1A17" )
			)
			( gate "@baseboard_fab2_lib.baseboard_fab2(sch_1):page87_i169"
				( attribute "BOM_COST" "MEM"
					( Origin gFrontEnd )
				)
				( attribute "CDS_LIB" "mstr_sconn"
					( Origin gPackager )
				)
				( attribute "CDS_LOCATION" "J1A1"
					( Origin gPackager )
				)
				( attribute "CDS_SEC" "4"
					( Origin gPackager )
				)
				( attribute "LOCATION" "J1A1"
					( Origin gFrontEnd )
				)
				( attribute "MATERIAL" "SCONN"
					( Origin gFrontEnd )
				)
				( attribute "PACK_TYPE" "PIP"
					( Origin gFrontEnd )
				)
				( attribute "PART_NUMBER" "H44441-004"
					( Origin gFrontEnd )
				)
				( attribute "PHYS_PAGE" "87"
					( Origin gFrontEnd )
				)
				( attribute "ROOM" "DDR4_CH_M"
					( Origin gFrontEnd )
				)
				( attribute "ROT" "0"
					( Origin gFrontEnd )
				)
				( attribute "SEC" "4"
					( Origin gFrontEnd )
				)
				( attribute "SEC_TYPE" "PIP"
					( Origin gFrontEnd )
				)
				( attribute "VER" "4"
					( Origin gFrontEnd )
				)
				( attribute "XY" "(-400,2050)"
					( Origin gFrontEnd )
				)
				( attribute "CHIPS_PART_NAME" "SCONN288_H44441004"
					( Origin gPackager )
				)
				( attribute "CDS_PART_NAME" "SCONN288_H44441004_PIP-SCONN,HA"
					( Origin gPackager )
				)
				( objectStatus "J1A1" )
			)
			( gate "@baseboard_fab2_lib.baseboard_fab2(sch_1):page87_i178"
				( attribute "BOM_COST" "MEM"
					( Origin gFrontEnd )
				)
				( attribute "CDS_LIB" "dev_discrete"
					( Origin gPackager )
				)
				( attribute "CDS_LOCATION" "C1A5"
					( Origin gPackager )
				)
				( attribute "CDS_SEC" "1"
					( Origin gPackager )
				)
				( attribute "LOCATION" "C1A5"
					( Origin gFrontEnd )
				)
				( attribute "MATERIAL" "X7R"
					( Origin gFrontEnd )
				)
				( attribute "PACK_TYPE" "0402V"
					( Origin gFrontEnd )
				)
				( attribute "PART_NUMBER" "A36096-045"
					( Origin gFrontEnd )
				)
				( attribute "PHYS_PAGE" "87"
					( Origin gFrontEnd )
				)
				( attribute "ROOM" "DDR4_CH_M"
					( Origin gFrontEnd )
				)
				( attribute "ROT" "2"
					( Origin gFrontEnd )
				)
				( attribute "SEC" "1"
					( Origin gFrontEnd )
				)
				( attribute "SEC_TYPE" "0402V"
					( Origin gFrontEnd )
				)
				( attribute "TOLERANCE" "10%"
					( Origin gFrontEnd )
				)
				( attribute "VALUE" "0.01UF"
					( Origin gFrontEnd )
				)
				( attribute "VER" "1"
					( Origin gFrontEnd )
				)
				( attribute "VOLTAGE" "25V"
					( Units "uVoltage" "V" 1.000000)
					( Origin gFrontEnd )
				)
				( attribute "XY" "(-4650,1550)"
					( Origin gFrontEnd )
				)
				( attribute "CHIPS_PART_NAME" "CAP_A"
					( Origin gPackager )
				)
				( attribute "CDS_PART_NAME" "CAP_A_0402V-0.01UF,25V,10%,X7RA"
					( Origin gPackager )
				)
				( objectStatus "C1A5" )
			)
			( gate "@baseboard_fab2_lib.baseboard_fab2(sch_1):page87_i185"
				( attribute "BOM_COST" "MEM"
					( Origin gFrontEnd )
				)
				( attribute "CDS_LIB" "mstr_sconn"
					( Origin gPackager )
				)
				( attribute "CDS_LOCATION" "J1A1"
					( Origin gPackager )
				)
				( attribute "CDS_SEC" "3"
					( Origin gPackager )
				)
				( attribute "LOCATION" "J1A1"
					( Origin gFrontEnd )
				)
				( attribute "MATERIAL" "SCONN"
					( Origin gFrontEnd )
				)
				( attribute "PACK_TYPE" "PIP"
					( Origin gFrontEnd )
				)
				( attribute "PART_NUMBER" "H44441-004"
					( Origin gFrontEnd )
				)
				( attribute "PHYS_PAGE" "87"
					( Origin gFrontEnd )
				)
				( attribute "ROOM" "DDR4_CH_M"
					( Origin gFrontEnd )
				)
				( attribute "ROT" "0"
					( Origin gFrontEnd )
				)
				( attribute "SEC" "3"
					( Origin gFrontEnd )
				)
				( attribute "SEC_TYPE" "PIP"
					( Origin gFrontEnd )
				)
				( attribute "VER" "3"
					( Origin gFrontEnd )
				)
				( attribute "XY" "(1800,2450)"
					( Origin gFrontEnd )
				)
				( attribute "CHIPS_PART_NAME" "SCONN288_H44441004"
					( Origin gPackager )
				)
				( attribute "CDS_PART_NAME" "SCONN288_H44441004_PIP-SCONN,HA"
					( Origin gPackager )
				)
				( objectStatus "J1A1" )
			)
			( gate "@baseboard_fab2_lib.baseboard_fab2(sch_1):page87_i186"
				( attribute "BOM_COST" "MEM"
					( Origin gFrontEnd )
				)
				( attribute "CDS_LIB" "mstr_sconn"
					( Origin gPackager )
				)
				( attribute "CDS_LOCATION" "J1A1"
					( Origin gPackager )
				)
				( attribute "CDS_SEC" "1"
					( Origin gPackager )
				)
				( attribute "LOCATION" "J1A1"
					( Origin gFrontEnd )
				)
				( attribute "MATERIAL" "SCONN"
					( Origin gFrontEnd )
				)
				( attribute "PACK_TYPE" "PIP"
					( Origin gFrontEnd )
				)
				( attribute "PART_NUMBER" "H44441-004"
					( Origin gFrontEnd )
				)
				( attribute "PHYS_PAGE" "87"
					( Origin gFrontEnd )
				)
				( attribute "ROOM" "DDR4_CH_M"
					( Origin gFrontEnd )
				)
				( attribute "ROT" "0"
					( Origin gFrontEnd )
				)
				( attribute "SEC" "1"
					( Origin gFrontEnd )
				)
				( attribute "SEC_TYPE" "PIP"
					( Origin gFrontEnd )
				)
				( attribute "VER" "1"
					( Origin gFrontEnd )
				)
				( attribute "XY" "(-2500,3250)"
					( Origin gFrontEnd )
				)
				( attribute "CHIPS_PART_NAME" "SCONN288_H44441004"
					( Origin gPackager )
				)
				( attribute "CDS_PART_NAME" "SCONN288_H44441004_PIP-SCONN,HA"
					( Origin gPackager )
				)
				( objectStatus "J1A1" )
			)
			( gate "@baseboard_fab2_lib.baseboard_fab2(sch_1):page87_i187"
				( attribute "BOM_COST" "MEM"
					( Origin gFrontEnd )
				)
				( attribute "CDS_LIB" "mstr_sconn"
					( Origin gPackager )
				)
				( attribute "CDS_LOCATION" "J1A1"
					( Origin gPackager )
				)
				( attribute "CDS_SEC" "2"
					( Origin gPackager )
				)
				( attribute "LOCATION" "J1A1"
					( Origin gFrontEnd )
				)
				( attribute "MATERIAL" "SCONN"
					( Origin gFrontEnd )
				)
				( attribute "PACK_TYPE" "PIP"
					( Origin gFrontEnd )
				)
				( attribute "PART_NUMBER" "H44441-004"
					( Origin gFrontEnd )
				)
				( attribute "PHYS_PAGE" "87"
					( Origin gFrontEnd )
				)
				( attribute "ROOM" "DDR4_CH_M"
					( Origin gFrontEnd )
				)
				( attribute "ROT" "0"
					( Origin gFrontEnd )
				)
				( attribute "SEC" "2"
					( Origin gFrontEnd )
				)
				( attribute "SEC_TYPE" "PIP"
					( Origin gFrontEnd )
				)
				( attribute "VER" "2"
					( Origin gFrontEnd )
				)
				( attribute "XY" "(0,4300)"
					( Origin gFrontEnd )
				)
				( attribute "CHIPS_PART_NAME" "SCONN288_H44441004"
					( Origin gPackager )
				)
				( attribute "CDS_PART_NAME" "SCONN288_H44441004_PIP-SCONN,HA"
					( Origin gPackager )
				)
				( objectStatus "J1A1" )
			)
			( gate "@baseboard_fab2_lib.baseboard_fab2(sch_1):page88_i25"
				( attribute "BOM_COST" "DDR4_CH_M"
					( Origin gFrontEnd )
				)
				( attribute "CDS_LIB" "mstr_sconn"
					( Origin gPackager )
				)
				( attribute "CDS_LOCATION" "J9L1"
					( Origin gPackager )
				)
				( attribute "CDS_SEC" "3"
					( Origin gPackager )
				)
				( attribute "LOCATION" "J9L1"
					( Origin gFrontEnd )
				)
				( attribute "MATERIAL" "SCONN"
					( Origin gFrontEnd )
				)
				( attribute "PACK_TYPE" "PIP"
					( Origin gFrontEnd )
				)
				( attribute "PART_NUMBER" "H44441-003"
					( Origin gFrontEnd )
				)
				( attribute "PHYS_PAGE" "88"
					( Origin gFrontEnd )
				)
				( attribute "ROOM" "DDR4_CH_M"
					( Origin gFrontEnd )
				)
				( attribute "ROT" "0"
					( Origin gFrontEnd )
				)
				( attribute "SEC" "3"
					( Origin gFrontEnd )
				)
				( attribute "SEC_TYPE" "PIP"
					( Origin gFrontEnd )
				)
				( attribute "VER" "3"
					( Origin gFrontEnd )
				)
				( attribute "XY" "(1800,2400)"
					( Origin gFrontEnd )
				)
				( attribute "CHIPS_PART_NAME" "SCONN288_H44441003"
					( Origin gPackager )
				)
				( attribute "CDS_PART_NAME" "SCONN288_H44441003_PIP-SCONN,HA"
					( Origin gPackager )
				)
				( attribute "BOM_SS" "NOPOP"
					( Origin gFrontEnd )
				)
				( objectStatus "J9L1" )
			)
			( gate "@baseboard_fab2_lib.baseboard_fab2(sch_1):page88_i87"
				( attribute "BOM_COST" "DDR4_CH_M"
					( Origin gFrontEnd )
				)
				( attribute "CDS_LIB" "mstr_sconn"
					( Origin gPackager )
				)
				( attribute "CDS_LOCATION" "J9L1"
					( Origin gPackager )
				)
				( attribute "CDS_SEC" "2"
					( Origin gPackager )
				)
				( attribute "LOCATION" "J9L1"
					( Origin gFrontEnd )
				)
				( attribute "MATERIAL" "SCONN"
					( Origin gFrontEnd )
				)
				( attribute "PACK_TYPE" "PIP"
					( Origin gFrontEnd )
				)
				( attribute "PART_NUMBER" "H44441-003"
					( Origin gFrontEnd )
				)
				( attribute "PHYS_PAGE" "88"
					( Origin gFrontEnd )
				)
				( attribute "ROOM" "DDR4_CH_M"
					( Origin gFrontEnd )
				)
				( attribute "ROT" "0"
					( Origin gFrontEnd )
				)
				( attribute "SEC" "2"
					( Origin gFrontEnd )
				)
				( attribute "SEC_TYPE" "PIP"
					( Origin gFrontEnd )
				)
				( attribute "VER" "2"
					( Origin gFrontEnd )
				)
				( attribute "XY" "(0,4300)"
					( Origin gFrontEnd )
				)
				( attribute "CHIPS_PART_NAME" "SCONN288_H44441003"
					( Origin gPackager )
				)
				( attribute "CDS_PART_NAME" "SCONN288_H44441003_PIP-SCONN,HA"
					( Origin gPackager )
				)
				( attribute "BOM_SS" "NOPOP"
					( Origin gFrontEnd )
				)
				( objectStatus "J9L1" )
			)
			( gate "@baseboard_fab2_lib.baseboard_fab2(sch_1):page88_i111"
				( attribute "BOM_COST" "DDR4_CH_M"
					( Origin gFrontEnd )
				)
				( attribute "CDS_LIB" "mstr_sconn"
					( Origin gPackager )
				)
				( attribute "CDS_LOCATION" "J9L1"
					( Origin gPackager )
				)
				( attribute "CDS_SEC" "1"
					( Origin gPackager )
				)
				( attribute "LOCATION" "J9L1"
					( Origin gFrontEnd )
				)
				( attribute "MATERIAL" "SCONN"
					( Origin gFrontEnd )
				)
				( attribute "PACK_TYPE" "PIP"
					( Origin gFrontEnd )
				)
				( attribute "PART_NUMBER" "H44441-003"
					( Origin gFrontEnd )
				)
				( attribute "PHYS_PAGE" "88"
					( Origin gFrontEnd )
				)
				( attribute "ROOM" "DDR4_CH_M"
					( Origin gFrontEnd )
				)
				( attribute "ROT" "0"
					( Origin gFrontEnd )
				)
				( attribute "SEC" "1"
					( Origin gFrontEnd )
				)
				( attribute "SEC_TYPE" "PIP"
					( Origin gFrontEnd )
				)
				( attribute "VER" "1"
					( Origin gFrontEnd )
				)
				( attribute "XY" "(-2450,3100)"
					( Origin gFrontEnd )
				)
				( attribute "CHIPS_PART_NAME" "SCONN288_H44441003"
					( Origin gPackager )
				)
				( attribute "CDS_PART_NAME" "SCONN288_H44441003_PIP-SCONN,HA"
					( Origin gPackager )
				)
				( attribute "BOM_SS" "NOPOP"
					( Origin gFrontEnd )
				)
				( objectStatus "J9L1" )
			)
			( gate "@baseboard_fab2_lib.baseboard_fab2(sch_1):page88_i168"
				( attribute "BOM_COST" "MEM"
					( Origin gFrontEnd )
				)
				( attribute "CDS_LIB" "mstr_sconn"
					( Origin gPackager )
				)
				( attribute "CDS_LOCATION" "J9L1"
					( Origin gPackager )
				)
				( attribute "CDS_SEC" "4"
					( Origin gPackager )
				)
				( attribute "LOCATION" "J9L1"
					( Origin gFrontEnd )
				)
				( attribute "MATERIAL" "SCONN"
					( Origin gFrontEnd )
				)
				( attribute "PACK_TYPE" "PIP"
					( Origin gFrontEnd )
				)
				( attribute "PART_NUMBER" "H44441-003"
					( Origin gFrontEnd )
				)
				( attribute "PHYS_PAGE" "88"
					( Origin gFrontEnd )
				)
				( attribute "ROOM" "DDR4_CH_M"
					( Origin gFrontEnd )
				)
				( attribute "ROT" "0"
					( Origin gFrontEnd )
				)
				( attribute "SEC" "4"
					( Origin gFrontEnd )
				)
				( attribute "SEC_TYPE" "PIP"
					( Origin gFrontEnd )
				)
				( attribute "VER" "4"
					( Origin gFrontEnd )
				)
				( attribute "XY" "(-300,2000)"
					( Origin gFrontEnd )
				)
				( attribute "CHIPS_PART_NAME" "SCONN288_H44441003"
					( Origin gPackager )
				)
				( attribute "CDS_PART_NAME" "SCONN288_H44441003_PIP-SCONN,HA"
					( Origin gPackager )
				)
				( attribute "BOM_SS" "NOPOP"
					( Origin gFrontEnd )
				)
				( objectStatus "J9L1" )
			)
			( gate "@baseboard_fab2_lib.baseboard_fab2(sch_1):page88_i177"
				( attribute "BOM_COST" "MEM"
					( Origin gFrontEnd )
				)
				( attribute "CDS_LIB" "dev_discrete"
					( Origin gPackager )
				)
				( attribute "CDS_LOCATION" "C9L1"
					( Origin gPackager )
				)
				( attribute "CDS_SEC" "1"
					( Origin gPackager )
				)
				( attribute "LOCATION" "C9L1"
					( Origin gFrontEnd )
				)
				( attribute "MATERIAL" "X7R"
					( Origin gFrontEnd )
				)
				( attribute "PACK_TYPE" "0402V"
					( Origin gFrontEnd )
				)
				( attribute "PART_NUMBER" "A36096-045"
					( Origin gFrontEnd )
				)
				( attribute "PHYS_PAGE" "88"
					( Origin gFrontEnd )
				)
				( attribute "ROOM" "DDR4_CH_M1"
					( Origin gFrontEnd )
				)
				( attribute "ROT" "2"
					( Origin gFrontEnd )
				)
				( attribute "SEC" "1"
					( Origin gFrontEnd )
				)
				( attribute "SEC_TYPE" "0402V"
					( Origin gFrontEnd )
				)
				( attribute "TOLERANCE" "10%"
					( Origin gFrontEnd )
				)
				( attribute "VALUE" "0.01UF"
					( Origin gFrontEnd )
				)
				( attribute "VER" "1"
					( Origin gFrontEnd )
				)
				( attribute "VOLTAGE" "25V"
					( Units "uVoltage" "V" 1.000000)
					( Origin gFrontEnd )
				)
				( attribute "XY" "(-4650,1400)"
					( Origin gFrontEnd )
				)
				( attribute "CHIPS_PART_NAME" "CAP_A"
					( Origin gPackager )
				)
				( attribute "CDS_PART_NAME" "CAP_A_0402V-0.01UF,25V,10%,X7RA"
					( Origin gPackager )
				)
				( objectStatus "C9L1" )
			)
			( gate "@baseboard_fab2_lib.baseboard_fab2(sch_1):page89_i1"
				( attribute "BOM_COST" "MEM_NV"
					( Origin gFrontEnd )
				)
				( attribute "CDS_LIB" "mstr_discrete"
					( Origin gPackager )
				)
				( attribute "CDS_LOCATION" "R4T2"
					( Origin gPackager )
				)
				( attribute "CDS_SEC" "1"
					( Origin gPackager )
				)
				( attribute "LOCATION" "R4T2"
					( Origin gFrontEnd )
				)
				( attribute "MATERIAL" "EMPTY"
					( Origin gFrontEnd )
				)
				( attribute "PACK_TYPE" "0402"
					( Origin gFrontEnd )
				)
				( attribute "PART_NUMBER" "G21497-005"
					( Origin gFrontEnd )
				)
				( attribute "PHYS_PAGE" "89"
					( Origin gFrontEnd )
				)
				( attribute "ROOM" "NV_DIMM"
					( Origin gFrontEnd )
				)
				( attribute "ROT" "0"
					( Origin gFrontEnd )
				)
				( attribute "SEC" "1"
					( Origin gFrontEnd )
				)
				( attribute "SEC_TYPE" "0402"
					( Origin gFrontEnd )
				)
				( attribute "TOLERANCE" "5%"
					( Origin gFrontEnd )
				)
				( attribute "VALUE" "0.0"
					( Origin gFrontEnd )
				)
				( attribute "VER" "1"
					( Origin gFrontEnd )
				)
				( attribute "WATTAGE" "1/16W"
					( Origin gFrontEnd )
				)
				( attribute "XY" "(-2250,3025)"
					( Origin gFrontEnd )
				)
				( attribute "CHIPS_PART_NAME" "RES"
					( Origin gPackager )
				)
				( attribute "CDS_PART_NAME" "RES_0402-0.0,5%,1/16W,EMPTY,G2A"
					( Origin gPackager )
				)
				( objectStatus "R4T2" )
			)
			( gate "@baseboard_fab2_lib.baseboard_fab2(sch_1):page89_i2"
				( attribute "BOM_COST" "MEM_NV"
					( Origin gFrontEnd )
				)
				( attribute "CDS_LIB" "mstr_discrete"
					( Origin gPackager )
				)
				( attribute "CDS_LOCATION" "R4T1"
					( Origin gPackager )
				)
				( attribute "CDS_SEC" "1"
					( Origin gPackager )
				)
				( attribute "LOCATION" "R4T1"
					( Origin gFrontEnd )
				)
				( attribute "MATERIAL" "CHIP"
					( Origin gFrontEnd )
				)
				( attribute "PACK_TYPE" "0402"
					( Origin gFrontEnd )
				)
				( attribute "PART_NUMBER" "G21497-005"
					( Origin gFrontEnd )
				)
				( attribute "PHYS_PAGE" "89"
					( Origin gFrontEnd )
				)
				( attribute "ROOM" "NV_DIMM"
					( Origin gFrontEnd )
				)
				( attribute "ROT" "0"
					( Origin gFrontEnd )
				)
				( attribute "SEC" "1"
					( Origin gFrontEnd )
				)
				( attribute "SEC_TYPE" "0402"
					( Origin gFrontEnd )
				)
				( attribute "TOLERANCE" "5%"
					( Origin gFrontEnd )
				)
				( attribute "VALUE" "0.0"
					( Origin gFrontEnd )
				)
				( attribute "VER" "1"
					( Origin gFrontEnd )
				)
				( attribute "WATTAGE" "1/16W"
					( Origin gFrontEnd )
				)
				( attribute "XY" "(-2250,2725)"
					( Origin gFrontEnd )
				)
				( attribute "CHIPS_PART_NAME" "RES"
					( Origin gPackager )
				)
				( attribute "CDS_PART_NAME" "RES_0402-0.0,5%,1/16W,CHIP,G21A"
					( Origin gPackager )
				)
				( objectStatus "R4T1" )
			)
			( gate "@baseboard_fab2_lib.baseboard_fab2(sch_1):page89_i3"
				( attribute "BOM_COST" "MEM_NV"
					( Origin gFrontEnd )
				)
				( attribute "CDS_LIB" "mstr_discrete"
					( Origin gPackager )
				)
				( attribute "CDS_LOCATION" "R6F4"
					( Origin gPackager )
				)
				( attribute "CDS_SEC" "1"
					( Origin gPackager )
				)
				( attribute "LOCATION" "R6F4"
					( Origin gFrontEnd )
				)
				( attribute "MATERIAL" "CHIP"
					( Origin gFrontEnd )
				)
				( attribute "PACK_TYPE" "0402"
					( Origin gFrontEnd )
				)
				( attribute "PART_NUMBER" "G21796-047"
					( Origin gFrontEnd )
				)
				( attribute "PHYS_PAGE" "89"
					( Origin gFrontEnd )
				)
				( attribute "ROOM" "NV_DIMM"
					( Origin gFrontEnd )
				)
				( attribute "ROT" "0"
					( Origin gFrontEnd )
				)
				( attribute "SEC" "1"
					( Origin gFrontEnd )
				)
				( attribute "SEC_TYPE" "0402"
					( Origin gFrontEnd )
				)
				( attribute "TOLERANCE" "1%"
					( Origin gFrontEnd )
				)
				( attribute "VALUE" "49.9"
					( Origin gFrontEnd )
				)
				( attribute "VER" "1"
					( Origin gFrontEnd )
				)
				( attribute "WATTAGE" "1/16W"
					( Origin gFrontEnd )
				)
				( attribute "XY" "(350,3125)"
					( Origin gFrontEnd )
				)
				( attribute "CHIPS_PART_NAME" "RES"
					( Origin gPackager )
				)
				( attribute "CDS_PART_NAME" "RES_0402-49.9,1%,1/16W,CHIP,G2A"
					( Origin gPackager )
				)
				( objectStatus "R6F4" )
			)
			( gate "@baseboard_fab2_lib.baseboard_fab2(sch_1):page89_i4"
				( attribute "BOM_COST" "MEM_NV"
					( Origin gFrontEnd )
				)
				( attribute "CDS_LIB" "mstr_discrete"
					( Origin gPackager )
				)
				( attribute "CDS_LOCATION" "R6F1"
					( Origin gPackager )
				)
				( attribute "CDS_SEC" "1"
					( Origin gPackager )
				)
				( attribute "LOCATION" "R6F1"
					( Origin gFrontEnd )
				)
				( attribute "MATERIAL" "CHIP"
					( Origin gFrontEnd )
				)
				( attribute "PACK_TYPE" "0402"
					( Origin gFrontEnd )
				)
				( attribute "PART_NUMBER" "G21796-047"
					( Origin gFrontEnd )
				)
				( attribute "PHYS_PAGE" "89"
					( Origin gFrontEnd )
				)
				( attribute "ROOM" "NV_DIMM"
					( Origin gFrontEnd )
				)
				( attribute "ROT" "0"
					( Origin gFrontEnd )
				)
				( attribute "SEC" "1"
					( Origin gFrontEnd )
				)
				( attribute "SEC_TYPE" "0402"
					( Origin gFrontEnd )
				)
				( attribute "TOLERANCE" "1%"
					( Origin gFrontEnd )
				)
				( attribute "VALUE" "49.9"
					( Origin gFrontEnd )
				)
				( attribute "VER" "1"
					( Origin gFrontEnd )
				)
				( attribute "WATTAGE" "1/16W"
					( Origin gFrontEnd )
				)
				( attribute "XY" "(350,2825)"
					( Origin gFrontEnd )
				)
				( attribute "CHIPS_PART_NAME" "RES"
					( Origin gPackager )
				)
				( attribute "CDS_PART_NAME" "RES_0402-49.9,1%,1/16W,CHIP,G2A"
					( Origin gPackager )
				)
				( objectStatus "R6F1" )
			)
			( gate "@baseboard_fab2_lib.baseboard_fab2(sch_1):page89_i5"
				( attribute "BOM_COST" "MEM_NV"
					( Origin gFrontEnd )
				)
				( attribute "CDS_LIB" "mstr_discrete"
					( Origin gPackager )
				)
				( attribute "CDS_LOCATION" "R6F5"
					( Origin gPackager )
				)
				( attribute "CDS_SEC" "1"
					( Origin gPackager )
				)
				( attribute "LOCATION" "R6F5"
					( Origin gFrontEnd )
				)
				( attribute "MATERIAL" "CHIP"
					( Origin gFrontEnd )
				)
				( attribute "PACK_TYPE" "0402"
					( Origin gFrontEnd )
				)
				( attribute "PART_NUMBER" "G21796-047"
					( Origin gFrontEnd )
				)
				( attribute "PHYS_PAGE" "89"
					( Origin gFrontEnd )
				)
				( attribute "ROOM" "NV_DIMM"
					( Origin gFrontEnd )
				)
				( attribute "ROT" "0"
					( Origin gFrontEnd )
				)
				( attribute "SEC" "1"
					( Origin gFrontEnd )
				)
				( attribute "SEC_TYPE" "0402"
					( Origin gFrontEnd )
				)
				( attribute "TOLERANCE" "1%"
					( Origin gFrontEnd )
				)
				( attribute "VALUE" "49.9"
					( Origin gFrontEnd )
				)
				( attribute "VER" "1"
					( Origin gFrontEnd )
				)
				( attribute "WATTAGE" "1/16W"
					( Origin gFrontEnd )
				)
				( attribute "XY" "(350,1950)"
					( Origin gFrontEnd )
				)
				( attribute "CHIPS_PART_NAME" "RES"
					( Origin gPackager )
				)
				( attribute "CDS_PART_NAME" "RES_0402-49.9,1%,1/16W,CHIP,G2A"
					( Origin gPackager )
				)
				( objectStatus "R6F5" )
			)
			( gate "@baseboard_fab2_lib.baseboard_fab2(sch_1):page89_i6"
				( attribute "BOM_COST" "MEM_NV"
					( Origin gFrontEnd )
				)
				( attribute "CDS_LIB" "mstr_discrete"
					( Origin gPackager )
				)
				( attribute "CDS_LOCATION" "R6F2"
					( Origin gPackager )
				)
				( attribute "CDS_SEC" "1"
					( Origin gPackager )
				)
				( attribute "LOCATION" "R6F2"
					( Origin gFrontEnd )
				)
				( attribute "MATERIAL" "CHIP"
					( Origin gFrontEnd )
				)
				( attribute "PACK_TYPE" "0402"
					( Origin gFrontEnd )
				)
				( attribute "PART_NUMBER" "G21796-047"
					( Origin gFrontEnd )
				)
				( attribute "PHYS_PAGE" "89"
					( Origin gFrontEnd )
				)
				( attribute "ROOM" "NV_DIMM"
					( Origin gFrontEnd )
				)
				( attribute "ROT" "0"
					( Origin gFrontEnd )
				)
				( attribute "SEC" "1"
					( Origin gFrontEnd )
				)
				( attribute "SEC_TYPE" "0402"
					( Origin gFrontEnd )
				)
				( attribute "TOLERANCE" "1%"
					( Origin gFrontEnd )
				)
				( attribute "VALUE" "49.9"
					( Origin gFrontEnd )
				)
				( attribute "VER" "1"
					( Origin gFrontEnd )
				)
				( attribute "WATTAGE" "1/16W"
					( Origin gFrontEnd )
				)
				( attribute "XY" "(350,1650)"
					( Origin gFrontEnd )
				)
				( attribute "CHIPS_PART_NAME" "RES"
					( Origin gPackager )
				)
				( attribute "CDS_PART_NAME" "RES_0402-49.9,1%,1/16W,CHIP,G2A"
					( Origin gPackager )
				)
				( objectStatus "R6F2" )
			)
			( gate "@baseboard_fab2_lib.baseboard_fab2(sch_1):page89_i7"
				( attribute "BOM_COST" "MEM_NV"
					( Origin gFrontEnd )
				)
				( attribute "CDS_LIB" "mstr_discrete"
					( Origin gPackager )
				)
				( attribute "CDS_LOCATION" "R6F3"
					( Origin gPackager )
				)
				( attribute "LOCATION" "R6F3"
					( Origin gFrontEnd )
				)
				( attribute "MATERIAL" "CHIP"
					( Origin gFrontEnd )
				)
				( attribute "PACK_TYPE" "0402"
					( Origin gFrontEnd )
				)
				( attribute "PART_NUMBER" "G21796-016"
					( Origin gFrontEnd )
				)
				( attribute "PHYS_PAGE" "89"
					( Origin gFrontEnd )
				)
				( attribute "ROOM" "NV_DIMM"
					( Origin gFrontEnd )
				)
				( attribute "ROT" "0"
					( Origin gFrontEnd )
				)
				( attribute "SEC" "1"
					( Origin gFrontEnd )
				)
				( attribute "SEC_TYPE" "0402"
					( Origin gFrontEnd )
				)
				( attribute "TOLERANCE" "1%"
					( Origin gFrontEnd )
				)
				( attribute "VALUE" "10.0K"
					( Origin gFrontEnd )
				)
				( attribute "VER" "2"
					( Origin gFrontEnd )
				)
				( attribute "WATTAGE" "1/16W"
					( Origin gFrontEnd )
				)
				( attribute "XY" "(-450,3325)"
					( Origin gFrontEnd )
				)
				( attribute "CHIPS_PART_NAME" "RES"
					( Origin gPackager )
				)
				( attribute "CDS_PART_NAME" "RES_0402-10.0K,1%,1/16W,CHIP,GA"
					( Origin gPackager )
				)
				( attribute "CDS_SEC" "1"
					( Origin gPackager )
				)
				( objectStatus "R6F3" )
			)
			( gate "@baseboard_fab2_lib.baseboard_fab2(sch_1):page196_i129"
				( attribute "CDS_LIB" "mstr_discrete"
					( Origin gPackager )
				)
				( attribute "LOCATION" "Q1P2"
					( Origin gFrontEnd )
				)
				( attribute "MATERIAL" "FET"
					( Origin gFrontEnd )
				)
				( attribute "PACK_TYPE" "SOT23LF"
					( Origin gFrontEnd )
				)
				( attribute "PART_NUMBER" "C79254-001"
					( Origin gFrontEnd )
				)
				( attribute "PHYS_PAGE" "196"
					( Origin gFrontEnd )
				)
				( attribute "ROOM" "HOT_SWAP"
					( Origin gFrontEnd )
				)
				( attribute "ROT" "0"
					( Origin gFrontEnd )
				)
				( attribute "VALUE" "2N7002"
					( Origin gFrontEnd )
				)
				( attribute "VER" "8"
					( Origin gFrontEnd )
				)
				( attribute "XY" "(750,1750)"
					( Origin gFrontEnd )
				)
				( attribute "CHIPS_PART_NAME" "FET_N"
					( Origin gPackager )
				)
				( attribute "CDS_PART_NAME" "FET_N_SOT23LF-2N7002,FET,C7925A"
					( Origin gPackager )
				)
				( attribute "CDS_LOCATION" "Q1P2"
					( Origin gPackager )
				)
				( attribute "CDS_SEC" "1"
					( Origin gPackager )
				)
				( attribute "SEC" "1"
					( Origin gPackager )
				)
				( objectStatus "Q1P2" )
			)
			( gate "@baseboard_fab2_lib.baseboard_fab2(sch_1):page89_i23"
				( attribute "BOM_COST" "MEM_NV"
					( Origin gFrontEnd )
				)
				( attribute "CDS_LIB" "mstr_discrete"
					( Origin gPackager )
				)
				( attribute "CDS_LOCATION" "R2P12"
					( Origin gPackager )
				)
				( attribute "CDS_SEC" "1"
					( Origin gPackager )
				)
				( attribute "LOCATION" "R2P12"
					( Origin gFrontEnd )
				)
				( attribute "MATERIAL" "EMPTY"
					( Origin gFrontEnd )
				)
				( attribute "PACK_TYPE" "0402"
					( Origin gFrontEnd )
				)
				( attribute "PART_NUMBER" "G21497-005"
					( Origin gFrontEnd )
				)
				( attribute "PHYS_PAGE" "89"
					( Origin gFrontEnd )
				)
				( attribute "ROOM" "NV_DIMM"
					( Origin gFrontEnd )
				)
				( attribute "ROT" "0"
					( Origin gFrontEnd )
				)
				( attribute "SEC" "1"
					( Origin gPackager )
				)
				( attribute "TOLERANCE" "5%"
					( Origin gFrontEnd )
				)
				( attribute "VALUE" "0.0"
					( Origin gFrontEnd )
				)
				( attribute "VER" "1"
					( Origin gFrontEnd )
				)
				( attribute "WATTAGE" "1/16W"
					( Origin gFrontEnd )
				)
				( attribute "XY" "(3225,3525)"
					( Origin gFrontEnd )
				)
				( attribute "CHIPS_PART_NAME" "RES"
					( Origin gPackager )
				)
				( attribute "CDS_PART_NAME" "RES_0402-0.0,5%,1/16W,EMPTY,G2A"
					( Origin gPackager )
				)
				( objectStatus "R2P12" )
			)
			( gate "@baseboard_fab2_lib.baseboard_fab2(sch_1):page89_i26"
				( attribute "CDS_LIB" "mstr_discrete"
					( Origin gPackager )
				)
				( attribute "CDS_LOCATION" "R8D29"
					( Origin gPackager )
				)
				( attribute "CDS_SEC" "1"
					( Origin gPackager )
				)
				( attribute "LOCATION" "R8D29"
					( Origin gFrontEnd )
				)
				( attribute "MATERIAL" "CHIP"
					( Origin gFrontEnd )
				)
				( attribute "PACK_TYPE" "0402"
					( Origin gFrontEnd )
				)
				( attribute "PART_NUMBER" "G21796-072"
					( Origin gFrontEnd )
				)
				( attribute "PHYS_PAGE" "89"
					( Origin gFrontEnd )
				)
				( attribute "ROOM" "NVDIMM"
					( Origin gFrontEnd )
				)
				( attribute "ROT" "0"
					( Origin gFrontEnd )
				)
				( attribute "SEC" "1"
					( Origin gPackager )
				)
				( attribute "TOLERANCE" "1%"
					( Origin gFrontEnd )
				)
				( attribute "VALUE" "4.75K"
					( Origin gFrontEnd )
				)
				( attribute "VER" "2"
					( Origin gFrontEnd )
				)
				( attribute "WATTAGE" "1/16W"
					( Origin gFrontEnd )
				)
				( attribute "XY" "(1750,4500)"
					( Origin gFrontEnd )
				)
				( attribute "CHIPS_PART_NAME" "RES"
					( Origin gPackager )
				)
				( attribute "CDS_PART_NAME" "RES_0402-4.75K,1%,1/16W,CHIP,GA"
					( Origin gPackager )
				)
				( objectStatus "R8D29" )
			)
			( gate "@baseboard_fab2_lib.baseboard_fab2(sch_1):page89_i27"
				( attribute "CDS_LIB" "mstr_discrete"
					( Origin gPackager )
				)
				( attribute "CDS_LOCATION" "R8D31"
					( Origin gPackager )
				)
				( attribute "CDS_SEC" "1"
					( Origin gPackager )
				)
				( attribute "LOCATION" "R8D31"
					( Origin gFrontEnd )
				)
				( attribute "MATERIAL" "CHIP"
					( Origin gFrontEnd )
				)
				( attribute "PACK_TYPE" "0402"
					( Origin gFrontEnd )
				)
				( attribute "PART_NUMBER" "G21796-072"
					( Origin gFrontEnd )
				)
				( attribute "PHYS_PAGE" "89"
					( Origin gFrontEnd )
				)
				( attribute "ROOM" "NVDIMM"
					( Origin gFrontEnd )
				)
				( attribute "ROT" "0"
					( Origin gFrontEnd )
				)
				( attribute "SEC" "1"
					( Origin gPackager )
				)
				( attribute "TOLERANCE" "1%"
					( Origin gFrontEnd )
				)
				( attribute "VALUE" "4.75K"
					( Origin gFrontEnd )
				)
				( attribute "VER" "2"
					( Origin gFrontEnd )
				)
				( attribute "WATTAGE" "1/16W"
					( Origin gFrontEnd )
				)
				( attribute "XY" "(2450,4725)"
					( Origin gFrontEnd )
				)
				( attribute "CHIPS_PART_NAME" "RES"
					( Origin gPackager )
				)
				( attribute "CDS_PART_NAME" "RES_0402-4.75K,1%,1/16W,CHIP,GA"
					( Origin gPackager )
				)
				( objectStatus "R8D31" )
			)
			( gate "@baseboard_fab2_lib.baseboard_fab2(sch_1):page89_i34"
				( attribute "BOM_COST" "MEM_NV"
					( Origin gFrontEnd )
				)
				( attribute "CDS_LIB" "mstr_discrete"
					( Origin gPackager )
				)
				( attribute "CDS_LOCATION" "R8D30"
					( Origin gPackager )
				)
				( attribute "CDS_SEC" "1"
					( Origin gPackager )
				)
				( attribute "LOCATION" "R8D30"
					( Origin gFrontEnd )
				)
				( attribute "MATERIAL" "CHIP"
					( Origin gFrontEnd )
				)
				( attribute "PACK_TYPE" "0402"
					( Origin gFrontEnd )
				)
				( attribute "PART_NUMBER" "G21796-016"
					( Origin gFrontEnd )
				)
				( attribute "PHYS_PAGE" "89"
					( Origin gFrontEnd )
				)
				( attribute "ROOM" "NV_DIMM"
					( Origin gFrontEnd )
				)
				( attribute "ROT" "0"
					( Origin gFrontEnd )
				)
				( attribute "SEC" "1"
					( Origin gFrontEnd )
				)
				( attribute "SEC_TYPE" "0402"
					( Origin gFrontEnd )
				)
				( attribute "TOLERANCE" "1%"
					( Origin gFrontEnd )
				)
				( attribute "VALUE" "10.0K"
					( Origin gFrontEnd )
				)
				( attribute "VER" "1"
					( Origin gFrontEnd )
				)
				( attribute "WATTAGE" "1/16W"
					( Origin gFrontEnd )
				)
				( attribute "XY" "(775,3700)"
					( Origin gFrontEnd )
				)
				( attribute "CHIPS_PART_NAME" "RES"
					( Origin gPackager )
				)
				( attribute "CDS_PART_NAME" "RES_0402-10.0K,1%,1/16W,CHIP,GA"
					( Origin gPackager )
				)
				( objectStatus "R8D30" )
			)
			( gate "@baseboard_fab2_lib.baseboard_fab2(sch_1):page89_i35"
				( attribute "BOM_COST" "MEM_NV"
					( Origin gFrontEnd )
				)
				( attribute "CDS_LIB" "mstr_discrete"
					( Origin gPackager )
				)
				( attribute "CDS_LOCATION" "Q8D1"
					( Origin gPackager )
				)
				( attribute "CDS_SEC" "1"
					( Origin gPackager )
				)
				( attribute "LOCATION" "Q8D1"
					( Origin gFrontEnd )
				)
				( attribute "MATERIAL" "XSTR"
					( Origin gFrontEnd )
				)
				( attribute "PACK_TYPE" "SSOPLF"
					( Origin gFrontEnd )
				)
				( attribute "PART_NUMBER" "C52264-001"
					( Origin gFrontEnd )
				)
				( attribute "PHYS_PAGE" "89"
					( Origin gFrontEnd )
				)
				( attribute "ROOM" "NV_DIMM"
					( Origin gFrontEnd )
				)
				( attribute "ROT" "0"
					( Origin gFrontEnd )
				)
				( attribute "SEC" "1"
					( Origin gFrontEnd )
				)
				( attribute "SEC_TYPE" "SSOPLF"
					( Origin gFrontEnd )
				)
				( attribute "VALUE" "MBT3904"
					( Origin gFrontEnd )
				)
				( attribute "VER" "1"
					( Origin gFrontEnd )
				)
				( attribute "XY" "(1700,3700)"
					( Origin gFrontEnd )
				)
				( attribute "CHIPS_PART_NAME" "NPN_DUAL"
					( Origin gPackager )
				)
				( attribute "CDS_PART_NAME" "NPN_DUAL_SSOPLF-MBT3904,XSTR,CA"
					( Origin gPackager )
				)
				( objectStatus "Q8D1" )
			)
			( gate "@baseboard_fab2_lib.baseboard_fab2(sch_1):page90_i17"
				( attribute "BOM_COST" "PROC"
					( Origin gFrontEnd )
				)
				( attribute "CDS_LIB" "mstr_discrete"
					( Origin gPackager )
				)
				( attribute "CDS_LOCATION" "R3D22"
					( Origin gPackager )
				)
				( attribute "CDS_SEC" "1"
					( Origin gPackager )
				)
				( attribute "LOCATION" "R3D22"
					( Origin gFrontEnd )
				)
				( attribute "MATERIAL" "EMPTY"
					( Origin gFrontEnd )
				)
				( attribute "PACK_TYPE" "0402"
					( Origin gFrontEnd )
				)
				( attribute "PART_NUMBER" "G21796-294"
					( Origin gFrontEnd )
				)
				( attribute "PHYS_PAGE" "90"
					( Origin gFrontEnd )
				)
				( attribute "ROOM" "PROC_SIDEBAND"
					( Origin gFrontEnd )
				)
				( attribute "ROT" "0"
					( Origin gFrontEnd )
				)
				( attribute "SEC" "1"
					( Origin gFrontEnd )
				)
				( attribute "SEC_TYPE" "0402"
					( Origin gFrontEnd )
				)
				( attribute "TOLERANCE" "1.0%"
					( Origin gFrontEnd )
				)
				( attribute "VALUE" "240"
					( Origin gFrontEnd )
				)
				( attribute "VER" "1"
					( Origin gFrontEnd )
				)
				( attribute "WATTAGE" "1/16W"
					( Origin gFrontEnd )
				)
				( attribute "XY" "(-2450,1875)"
					( Origin gFrontEnd )
				)
				( attribute "CHIPS_PART_NAME" "RES"
					( Origin gPackager )
				)
				( attribute "CDS_PART_NAME" "RES_0402-240,1.0%,1/16W,EMPTY,A"
					( Origin gPackager )
				)
				( objectStatus "R3D22" )
			)
			( gate "@baseboard_fab2_lib.baseboard_fab2(sch_1):page90_i24"
				( attribute "BOM_COST" "PROC"
					( Origin gFrontEnd )
				)
				( attribute "CDS_LIB" "mstr_discrete"
					( Origin gPackager )
				)
				( attribute "CDS_LOCATION" "R3D16"
					( Origin gPackager )
				)
				( attribute "CDS_SEC" "1"
					( Origin gPackager )
				)
				( attribute "LOCATION" "R3D16"
					( Origin gFrontEnd )
				)
				( attribute "MATERIAL" "EMPTY"
					( Origin gFrontEnd )
				)
				( attribute "PACK_TYPE" "0402"
					( Origin gFrontEnd )
				)
				( attribute "PART_NUMBER" "G21796-294"
					( Origin gFrontEnd )
				)
				( attribute "PHYS_PAGE" "90"
					( Origin gFrontEnd )
				)
				( attribute "ROOM" "PROC_SIDEBAND"
					( Origin gFrontEnd )
				)
				( attribute "ROT" "0"
					( Origin gFrontEnd )
				)
				( attribute "SEC" "1"
					( Origin gFrontEnd )
				)
				( attribute "SEC_TYPE" "0402"
					( Origin gFrontEnd )
				)
				( attribute "TOLERANCE" "1.0%"
					( Origin gFrontEnd )
				)
				( attribute "VALUE" "240"
					( Origin gFrontEnd )
				)
				( attribute "VER" "1"
					( Origin gFrontEnd )
				)
				( attribute "WATTAGE" "1/16W"
					( Origin gFrontEnd )
				)
				( attribute "XY" "(-2450,1675)"
					( Origin gFrontEnd )
				)
				( attribute "CHIPS_PART_NAME" "RES"
					( Origin gPackager )
				)
				( attribute "CDS_PART_NAME" "RES_0402-240,1.0%,1/16W,EMPTY,A"
					( Origin gPackager )
				)
				( objectStatus "R3D16" )
			)
			( gate "@baseboard_fab2_lib.baseboard_fab2(sch_1):page90_i25"
				( attribute "BOM_COST" "PROC"
					( Origin gFrontEnd )
				)
				( attribute "CDS_LIB" "mstr_discrete"
					( Origin gPackager )
				)
				( attribute "CDS_LOCATION" "R3D23"
					( Origin gPackager )
				)
				( attribute "CDS_SEC" "1"
					( Origin gPackager )
				)
				( attribute "LOCATION" "R3D23"
					( Origin gFrontEnd )
				)
				( attribute "MATERIAL" "EMPTY"
					( Origin gFrontEnd )
				)
				( attribute "PACK_TYPE" "0402"
					( Origin gFrontEnd )
				)
				( attribute "PART_NUMBER" "G21796-294"
					( Origin gFrontEnd )
				)
				( attribute "PHYS_PAGE" "90"
					( Origin gFrontEnd )
				)
				( attribute "ROOM" "PROC_SIDEBAND"
					( Origin gFrontEnd )
				)
				( attribute "ROT" "0"
					( Origin gFrontEnd )
				)
				( attribute "SEC" "1"
					( Origin gPackager )
				)
				( attribute "TOLERANCE" "1.0%"
					( Origin gFrontEnd )
				)
				( attribute "VALUE" "240"
					( Origin gFrontEnd )
				)
				( attribute "VER" "1"
					( Origin gFrontEnd )
				)
				( attribute "WATTAGE" "1/16W"
					( Origin gFrontEnd )
				)
				( attribute "XY" "(-2450,1475)"
					( Origin gFrontEnd )
				)
				( attribute "CHIPS_PART_NAME" "RES"
					( Origin gPackager )
				)
				( attribute "CDS_PART_NAME" "RES_0402-240,1.0%,1/16W,EMPTY,A"
					( Origin gPackager )
				)
				( objectStatus "R3D23" )
			)
			( gate "@baseboard_fab2_lib.baseboard_fab2(sch_1):page90_i28"
				( attribute "BOM_COST" "PROC"
					( Origin gFrontEnd )
				)
				( attribute "CDS_LIB" "mstr_discrete"
					( Origin gPackager )
				)
				( attribute "CDS_LOCATION" "R3D26"
					( Origin gPackager )
				)
				( attribute "CDS_SEC" "1"
					( Origin gPackager )
				)
				( attribute "LOCATION" "R3D26"
					( Origin gFrontEnd )
				)
				( attribute "MATERIAL" "EMPTY"
					( Origin gFrontEnd )
				)
				( attribute "PACK_TYPE" "0402"
					( Origin gFrontEnd )
				)
				( attribute "PART_NUMBER" "G21796-294"
					( Origin gFrontEnd )
				)
				( attribute "PHYS_PAGE" "90"
					( Origin gFrontEnd )
				)
				( attribute "ROOM" "PROC_SIDEBAND"
					( Origin gFrontEnd )
				)
				( attribute "ROT" "0"
					( Origin gFrontEnd )
				)
				( attribute "SEC" "1"
					( Origin gFrontEnd )
				)
				( attribute "SEC_TYPE" "0402"
					( Origin gFrontEnd )
				)
				( attribute "TOLERANCE" "1.0%"
					( Origin gFrontEnd )
				)
				( attribute "VALUE" "240"
					( Origin gFrontEnd )
				)
				( attribute "VER" "1"
					( Origin gFrontEnd )
				)
				( attribute "WATTAGE" "1/16W"
					( Origin gFrontEnd )
				)
				( attribute "XY" "(-2450,1275)"
					( Origin gFrontEnd )
				)
				( attribute "CHIPS_PART_NAME" "RES"
					( Origin gPackager )
				)
				( attribute "CDS_PART_NAME" "RES_0402-240,1.0%,1/16W,EMPTY,A"
					( Origin gPackager )
				)
				( objectStatus "R3D26" )
			)
			( gate "@baseboard_fab2_lib.baseboard_fab2(sch_1):page90_i29"
				( attribute "BOM_COST" "PROC"
					( Origin gFrontEnd )
				)
				( attribute "CDS_LIB" "mstr_discrete"
					( Origin gPackager )
				)
				( attribute "CDS_LOCATION" "R5D3"
					( Origin gPackager )
				)
				( attribute "CDS_SEC" "1"
					( Origin gPackager )
				)
				( attribute "LOCATION" "R5D3"
					( Origin gFrontEnd )
				)
				( attribute "MATERIAL" "CHIP"
					( Origin gFrontEnd )
				)
				( attribute "PACK_TYPE" "0402"
					( Origin gFrontEnd )
				)
				( attribute "PART_NUMBER" "G21796-294"
					( Origin gFrontEnd )
				)
				( attribute "PHYS_PAGE" "90"
					( Origin gFrontEnd )
				)
				( attribute "ROOM" "PROC_SIDEBAND"
					( Origin gFrontEnd )
				)
				( attribute "ROT" "0"
					( Origin gFrontEnd )
				)
				( attribute "SEC" "1"
					( Origin gFrontEnd )
				)
				( attribute "SEC_TYPE" "0402"
					( Origin gFrontEnd )
				)
				( attribute "TOLERANCE" "1.0%"
					( Origin gFrontEnd )
				)
				( attribute "VALUE" "240"
					( Origin gFrontEnd )
				)
				( attribute "VER" "1"
					( Origin gFrontEnd )
				)
				( attribute "WATTAGE" "1/16W"
					( Origin gFrontEnd )
				)
				( attribute "XY" "(-2475,4400)"
					( Origin gFrontEnd )
				)
				( attribute "CHIPS_PART_NAME" "RES"
					( Origin gPackager )
				)
				( attribute "CDS_PART_NAME" "RES_0402-240,1.0%,1/16W,CHIP,GA"
					( Origin gPackager )
				)
				( objectStatus "R5D3" )
			)
			( gate "@baseboard_fab2_lib.baseboard_fab2(sch_1):page90_i31"
				( attribute "BOM_COST" "PROC"
					( Origin gFrontEnd )
				)
				( attribute "CDS_LIB" "mstr_discrete"
					( Origin gPackager )
				)
				( attribute "CDS_LOCATION" "R6D7"
					( Origin gPackager )
				)
				( attribute "CDS_SEC" "1"
					( Origin gPackager )
				)
				( attribute "LOCATION" "R6D7"
					( Origin gFrontEnd )
				)
				( attribute "MATERIAL" "EMPTY"
					( Origin gFrontEnd )
				)
				( attribute "PACK_TYPE" "0402"
					( Origin gFrontEnd )
				)
				( attribute "PART_NUMBER" "G21796-294"
					( Origin gFrontEnd )
				)
				( attribute "PHYS_PAGE" "90"
					( Origin gFrontEnd )
				)
				( attribute "ROOM" "PROC_SIDEBAND"
					( Origin gFrontEnd )
				)
				( attribute "ROT" "0"
					( Origin gFrontEnd )
				)
				( attribute "SEC" "1"
					( Origin gFrontEnd )
				)
				( attribute "SEC_TYPE" "0402"
					( Origin gFrontEnd )
				)
				( attribute "TOLERANCE" "1.0%"
					( Origin gFrontEnd )
				)
				( attribute "VALUE" "240"
					( Origin gFrontEnd )
				)
				( attribute "VER" "1"
					( Origin gFrontEnd )
				)
				( attribute "WATTAGE" "1/16W"
					( Origin gFrontEnd )
				)
				( attribute "XY" "(-2475,4200)"
					( Origin gFrontEnd )
				)
				( attribute "CHIPS_PART_NAME" "RES"
					( Origin gPackager )
				)
				( attribute "CDS_PART_NAME" "RES_0402-240,1.0%,1/16W,EMPTY,A"
					( Origin gPackager )
				)
				( objectStatus "R6D7" )
			)
			( gate "@baseboard_fab2_lib.baseboard_fab2(sch_1):page90_i33"
				( attribute "BOM_COST" "PROC"
					( Origin gFrontEnd )
				)
				( attribute "CDS_LIB" "mstr_discrete"
					( Origin gPackager )
				)
				( attribute "CDS_LOCATION" "R6D13"
					( Origin gPackager )
				)
				( attribute "CDS_SEC" "1"
					( Origin gPackager )
				)
				( attribute "LOCATION" "R6D13"
					( Origin gFrontEnd )
				)
				( attribute "MATERIAL" "EMPTY"
					( Origin gFrontEnd )
				)
				( attribute "PACK_TYPE" "0402"
					( Origin gFrontEnd )
				)
				( attribute "PART_NUMBER" "G21796-294"
					( Origin gFrontEnd )
				)
				( attribute "PHYS_PAGE" "90"
					( Origin gFrontEnd )
				)
				( attribute "ROOM" "PROC_SIDEBAND"
					( Origin gFrontEnd )
				)
				( attribute "ROT" "0"
					( Origin gFrontEnd )
				)
				( attribute "SEC" "1"
					( Origin gFrontEnd )
				)
				( attribute "SEC_TYPE" "0402"
					( Origin gFrontEnd )
				)
				( attribute "TOLERANCE" "1.0%"
					( Origin gFrontEnd )
				)
				( attribute "VALUE" "240"
					( Origin gFrontEnd )
				)
				( attribute "VER" "1"
					( Origin gFrontEnd )
				)
				( attribute "WATTAGE" "1/16W"
					( Origin gFrontEnd )
				)
				( attribute "XY" "(-2475,3800)"
					( Origin gFrontEnd )
				)
				( attribute "CHIPS_PART_NAME" "RES"
					( Origin gPackager )
				)
				( attribute "CDS_PART_NAME" "RES_0402-240,1.0%,1/16W,EMPTY,A"
					( Origin gPackager )
				)
				( objectStatus "R6D13" )
			)
			( gate "@baseboard_fab2_lib.baseboard_fab2(sch_1):page90_i48"
				( attribute "BOM_COST" "PROC"
					( Origin gFrontEnd )
				)
				( attribute "CDS_LIB" "mstr_discrete"
					( Origin gPackager )
				)
				( attribute "CDS_LOCATION" "R6D15"
					( Origin gPackager )
				)
				( attribute "CDS_SEC" "1"
					( Origin gPackager )
				)
				( attribute "LOCATION" "R6D15"
					( Origin gFrontEnd )
				)
				( attribute "MATERIAL" "EMPTY"
					( Origin gFrontEnd )
				)
				( attribute "PACK_TYPE" "0402"
					( Origin gFrontEnd )
				)
				( attribute "PART_NUMBER" "G21796-294"
					( Origin gFrontEnd )
				)
				( attribute "PHYS_PAGE" "90"
					( Origin gFrontEnd )
				)
				( attribute "ROOM" "PROC_SIDEBAND"
					( Origin gFrontEnd )
				)
				( attribute "ROT" "0"
					( Origin gFrontEnd )
				)
				( attribute "SEC" "1"
					( Origin gFrontEnd )
				)
				( attribute "SEC_TYPE" "0402"
					( Origin gFrontEnd )
				)
				( attribute "TOLERANCE" "1.0%"
					( Origin gFrontEnd )
				)
				( attribute "VALUE" "240"
					( Origin gFrontEnd )
				)
				( attribute "VER" "1"
					( Origin gFrontEnd )
				)
				( attribute "WATTAGE" "1/16W"
					( Origin gFrontEnd )
				)
				( attribute "XY" "(-475,4400)"
					( Origin gFrontEnd )
				)
				( attribute "CHIPS_PART_NAME" "RES"
					( Origin gPackager )
				)
				( attribute "CDS_PART_NAME" "RES_0402-240,1.0%,1/16W,EMPTY,A"
					( Origin gPackager )
				)
				( objectStatus "R6D15" )
			)
			( gate "@baseboard_fab2_lib.baseboard_fab2(sch_1):page90_i49"
				( attribute "BOM_COST" "PROC"
					( Origin gFrontEnd )
				)
				( attribute "CDS_LIB" "mstr_discrete"
					( Origin gPackager )
				)
				( attribute "CDS_LOCATION" "R6D10"
					( Origin gPackager )
				)
				( attribute "CDS_SEC" "1"
					( Origin gPackager )
				)
				( attribute "LOCATION" "R6D10"
					( Origin gFrontEnd )
				)
				( attribute "MATERIAL" "EMPTY"
					( Origin gFrontEnd )
				)
				( attribute "PACK_TYPE" "0402"
					( Origin gFrontEnd )
				)
				( attribute "PART_NUMBER" "G21796-294"
					( Origin gFrontEnd )
				)
				( attribute "PHYS_PAGE" "90"
					( Origin gFrontEnd )
				)
				( attribute "ROOM" "PROC_SIDEBAND"
					( Origin gFrontEnd )
				)
				( attribute "ROT" "0"
					( Origin gFrontEnd )
				)
				( attribute "SEC" "1"
					( Origin gFrontEnd )
				)
				( attribute "SEC_TYPE" "0402"
					( Origin gFrontEnd )
				)
				( attribute "TOLERANCE" "1.0%"
					( Origin gFrontEnd )
				)
				( attribute "VALUE" "240"
					( Origin gFrontEnd )
				)
				( attribute "VER" "1"
					( Origin gFrontEnd )
				)
				( attribute "WATTAGE" "1/16W"
					( Origin gFrontEnd )
				)
				( attribute "XY" "(-475,4200)"
					( Origin gFrontEnd )
				)
				( attribute "CHIPS_PART_NAME" "RES"
					( Origin gPackager )
				)
				( attribute "CDS_PART_NAME" "RES_0402-240,1.0%,1/16W,EMPTY,A"
					( Origin gPackager )
				)
				( objectStatus "R6D10" )
			)
			( gate "@baseboard_fab2_lib.baseboard_fab2(sch_1):page90_i52"
				( attribute "BOM_COST" "PROC"
					( Origin gFrontEnd )
				)
				( attribute "CDS_LIB" "mstr_discrete"
					( Origin gPackager )
				)
				( attribute "CDS_LOCATION" "R6D14"
					( Origin gPackager )
				)
				( attribute "LOCATION" "R6D14"
					( Origin gFrontEnd )
				)
				( attribute "MATERIAL" "EMPTY"
					( Origin gFrontEnd )
				)
				( attribute "PACK_TYPE" "0402"
					( Origin gFrontEnd )
				)
				( attribute "PART_NUMBER" "G21796-294"
					( Origin gFrontEnd )
				)
				( attribute "PHYS_PAGE" "90"
					( Origin gFrontEnd )
				)
				( attribute "ROOM" "PROC_SIDEBAND"
					( Origin gFrontEnd )
				)
				( attribute "ROT" "0"
					( Origin gFrontEnd )
				)
				( attribute "SEC" "1"
					( Origin gFrontEnd )
				)
				( attribute "SEC_TYPE" "0402"
					( Origin gFrontEnd )
				)
				( attribute "TOLERANCE" "1.0%"
					( Origin gFrontEnd )
				)
				( attribute "VALUE" "240"
					( Origin gFrontEnd )
				)
				( attribute "VER" "1"
					( Origin gFrontEnd )
				)
				( attribute "WATTAGE" "1/16W"
					( Origin gFrontEnd )
				)
				( attribute "XY" "(-2475,3600)"
					( Origin gFrontEnd )
				)
				( attribute "CHIPS_PART_NAME" "RES"
					( Origin gPackager )
				)
				( attribute "CDS_PART_NAME" "RES_0402-240,1.0%,1/16W,EMPTY,A"
					( Origin gPackager )
				)
				( attribute "CDS_SEC" "1"
					( Origin gPackager )
				)
				( objectStatus "R6D14" )
			)
			( gate "@baseboard_fab2_lib.baseboard_fab2(sch_1):page90_i53"
				( attribute "BOM_COST" "PROC"
					( Origin gFrontEnd )
				)
				( attribute "CDS_LIB" "mstr_discrete"
					( Origin gPackager )
				)
				( attribute "CDS_LOCATION" "R4P14"
					( Origin gPackager )
				)
				( attribute "LOCATION" "R4P14"
					( Origin gFrontEnd )
				)
				( attribute "MATERIAL" "CHIP"
					( Origin gFrontEnd )
				)
				( attribute "PACK_TYPE" "0402"
					( Origin gFrontEnd )
				)
				( attribute "PART_NUMBER" "G21796-294"
					( Origin gFrontEnd )
				)
				( attribute "PHYS_PAGE" "90"
					( Origin gFrontEnd )
				)
				( attribute "ROOM" "PROC_SIDEBAND"
					( Origin gFrontEnd )
				)
				( attribute "ROT" "0"
					( Origin gFrontEnd )
				)
				( attribute "SEC" "1"
					( Origin gFrontEnd )
				)
				( attribute "SEC_TYPE" "0402"
					( Origin gFrontEnd )
				)
				( attribute "TOLERANCE" "1.0%"
					( Origin gFrontEnd )
				)
				( attribute "VALUE" "240"
					( Origin gFrontEnd )
				)
				( attribute "VER" "1"
					( Origin gFrontEnd )
				)
				( attribute "WATTAGE" "1/16W"
					( Origin gFrontEnd )
				)
				( attribute "XY" "(-2475,3400)"
					( Origin gFrontEnd )
				)
				( attribute "CHIPS_PART_NAME" "RES"
					( Origin gPackager )
				)
				( attribute "CDS_PART_NAME" "RES_0402-240,1.0%,1/16W,CHIP,GA"
					( Origin gPackager )
				)
				( attribute "CDS_SEC" "1"
					( Origin gPackager )
				)
				( objectStatus "R4P14" )
			)
			( gate "@baseboard_fab2_lib.baseboard_fab2(sch_1):page90_i59"
				( attribute "BOM_COST" "PROC"
					( Origin gFrontEnd )
				)
				( attribute "CDS_LIB" "mstr_discrete"
					( Origin gPackager )
				)
				( attribute "CDS_LOCATION" "R3D24"
					( Origin gPackager )
				)
				( attribute "LOCATION" "R3D24"
					( Origin gFrontEnd )
				)
				( attribute "MATERIAL" "CHIP"
					( Origin gFrontEnd )
				)
				( attribute "PACK_TYPE" "0402"
					( Origin gFrontEnd )
				)
				( attribute "PART_NUMBER" "G21796-294"
					( Origin gFrontEnd )
				)
				( attribute "PHYS_PAGE" "90"
					( Origin gFrontEnd )
				)
				( attribute "ROOM" "PROC_SIDEBAND"
					( Origin gFrontEnd )
				)
				( attribute "ROT" "0"
					( Origin gFrontEnd )
				)
				( attribute "SEC" "1"
					( Origin gFrontEnd )
				)
				( attribute "TOLERANCE" "1.0%"
					( Origin gFrontEnd )
				)
				( attribute "VALUE" "240"
					( Origin gFrontEnd )
				)
				( attribute "VER" "1"
					( Origin gFrontEnd )
				)
				( attribute "WATTAGE" "1/16W"
					( Origin gFrontEnd )
				)
				( attribute "XY" "(-425,1675)"
					( Origin gFrontEnd )
				)
				( attribute "CHIPS_PART_NAME" "RES"
					( Origin gPackager )
				)
				( attribute "CDS_PART_NAME" "RES_0402-240,1.0%,1/16W,CHIP,GA"
					( Origin gPackager )
				)
				( attribute "SEC_TYPE" "0402"
					( Origin gFrontEnd )
				)
				( attribute "CDS_SEC" "1"
					( Origin gPackager )
				)
				( objectStatus "R3D24" )
			)
			( gate "@baseboard_fab2_lib.baseboard_fab2(sch_1):page90_i60"
				( attribute "BOM_COST" "PROC"
					( Origin gFrontEnd )
				)
				( attribute "CDS_LIB" "mstr_discrete"
					( Origin gPackager )
				)
				( attribute "CDS_LOCATION" "R3D17"
					( Origin gPackager )
				)
				( attribute "LOCATION" "R3D17"
					( Origin gFrontEnd )
				)
				( attribute "MATERIAL" "EMPTY"
					( Origin gFrontEnd )
				)
				( attribute "PACK_TYPE" "0402"
					( Origin gFrontEnd )
				)
				( attribute "PART_NUMBER" "G21796-294"
					( Origin gFrontEnd )
				)
				( attribute "PHYS_PAGE" "90"
					( Origin gFrontEnd )
				)
				( attribute "ROOM" "PROC_SIDEBAND"
					( Origin gFrontEnd )
				)
				( attribute "ROT" "0"
					( Origin gFrontEnd )
				)
				( attribute "SEC" "1"
					( Origin gFrontEnd )
				)
				( attribute "TOLERANCE" "1.0%"
					( Origin gFrontEnd )
				)
				( attribute "VALUE" "240"
					( Origin gFrontEnd )
				)
				( attribute "VER" "1"
					( Origin gFrontEnd )
				)
				( attribute "WATTAGE" "1/16W"
					( Origin gFrontEnd )
				)
				( attribute "XY" "(-425,1475)"
					( Origin gFrontEnd )
				)
				( attribute "CHIPS_PART_NAME" "RES"
					( Origin gPackager )
				)
				( attribute "CDS_PART_NAME" "RES_0402-240,1.0%,1/16W,EMPTY,A"
					( Origin gPackager )
				)
				( attribute "SEC_TYPE" "0402"
					( Origin gFrontEnd )
				)
				( attribute "CDS_SEC" "1"
					( Origin gPackager )
				)
				( objectStatus "R3D17" )
			)
			( gate "@baseboard_fab2_lib.baseboard_fab2(sch_1):page90_i66"
				( attribute "BOM_COST" "PROC"
					( Origin gFrontEnd )
				)
				( attribute "CDS_LIB" "mstr_discrete"
					( Origin gPackager )
				)
				( attribute "CDS_LOCATION" "R3D25"
					( Origin gPackager )
				)
				( attribute "CDS_SEC" "1"
					( Origin gPackager )
				)
				( attribute "LOCATION" "R3D25"
					( Origin gFrontEnd )
				)
				( attribute "MATERIAL" "EMPTY"
					( Origin gFrontEnd )
				)
				( attribute "PACK_TYPE" "0402"
					( Origin gFrontEnd )
				)
				( attribute "PART_NUMBER" "G21796-294"
					( Origin gFrontEnd )
				)
				( attribute "PHYS_PAGE" "90"
					( Origin gFrontEnd )
				)
				( attribute "ROOM" "PROC_SIDEBAND"
					( Origin gFrontEnd )
				)
				( attribute "ROT" "0"
					( Origin gFrontEnd )
				)
				( attribute "SEC" "1"
					( Origin gFrontEnd )
				)
				( attribute "SEC_TYPE" "0402"
					( Origin gFrontEnd )
				)
				( attribute "TOLERANCE" "1.0%"
					( Origin gFrontEnd )
				)
				( attribute "VALUE" "240"
					( Origin gFrontEnd )
				)
				( attribute "VER" "1"
					( Origin gFrontEnd )
				)
				( attribute "WATTAGE" "1/16W"
					( Origin gFrontEnd )
				)
				( attribute "XY" "(-2450,1025)"
					( Origin gFrontEnd )
				)
				( attribute "CHIPS_PART_NAME" "RES"
					( Origin gPackager )
				)
				( attribute "CDS_PART_NAME" "RES_0402-240,1.0%,1/16W,EMPTY,A"
					( Origin gPackager )
				)
				( objectStatus "R3D25" )
			)
			( gate "@baseboard_fab2_lib.baseboard_fab2(sch_1):page90_i68"
				( attribute "BOM_COST" "PROC"
					( Origin gFrontEnd )
				)
				( attribute "CDS_LIB" "mstr_discrete"
					( Origin gPackager )
				)
				( attribute "CDS_LOCATION" "R4P6"
					( Origin gPackager )
				)
				( attribute "CDS_SEC" "1"
					( Origin gPackager )
				)
				( attribute "LOCATION" "R4P6"
					( Origin gFrontEnd )
				)
				( attribute "MATERIAL" "EMPTY"
					( Origin gFrontEnd )
				)
				( attribute "PACK_TYPE" "0402"
					( Origin gFrontEnd )
				)
				( attribute "PART_NUMBER" "G21796-294"
					( Origin gFrontEnd )
				)
				( attribute "PHYS_PAGE" "90"
					( Origin gFrontEnd )
				)
				( attribute "ROOM" "PROC_SIDEBAND"
					( Origin gFrontEnd )
				)
				( attribute "ROT" "0"
					( Origin gFrontEnd )
				)
				( attribute "SEC" "1"
					( Origin gFrontEnd )
				)
				( attribute "SEC_TYPE" "0402"
					( Origin gFrontEnd )
				)
				( attribute "TOLERANCE" "1.0%"
					( Origin gFrontEnd )
				)
				( attribute "VALUE" "240"
					( Origin gFrontEnd )
				)
				( attribute "VER" "1"
					( Origin gFrontEnd )
				)
				( attribute "WATTAGE" "1/16W"
					( Origin gFrontEnd )
				)
				( attribute "XY" "(-575,3000)"
					( Origin gFrontEnd )
				)
				( attribute "CHIPS_PART_NAME" "RES"
					( Origin gPackager )
				)
				( attribute "CDS_PART_NAME" "RES_0402-240,1.0%,1/16W,EMPTY,A"
					( Origin gPackager )
				)
				( objectStatus "R4P6" )
			)
			( gate "@baseboard_fab2_lib.baseboard_fab2(sch_1):page125_i88"
				( attribute "BOM_COST" "SYS_CLOCK"
					( Origin gFrontEnd )
				)
				( attribute "CDS_LIB" "mstr_discrete"
					( Origin gPackager )
				)
				( attribute "CDS_LOCATION" "R2U30"
					( Origin gPackager )
				)
				( attribute "CDS_SEC" "1"
					( Origin gPackager )
				)
				( attribute "LOCATION" "R2U30"
					( Origin gFrontEnd )
				)
				( attribute "MATERIAL" "EMPTY"
					( Origin gFrontEnd )
				)
				( attribute "PACK_TYPE" "0402"
					( Origin gFrontEnd )
				)
				( attribute "PART_NUMBER" "G21796-072"
					( Origin gFrontEnd )
				)
				( attribute "PHYS_PAGE" "125"
					( Origin gFrontEnd )
				)
				( attribute "ROOM" "DB1200ZL"
					( Origin gFrontEnd )
				)
				( attribute "ROT" "2"
					( Origin gFrontEnd )
				)
				( attribute "SEC" "1"
					( Origin gFrontEnd )
				)
				( attribute "SEC_TYPE" "0402"
					( Origin gFrontEnd )
				)
				( attribute "TOLERANCE" "1%"
					( Origin gFrontEnd )
				)
				( attribute "VALUE" "4.75K"
					( Origin gFrontEnd )
				)
				( attribute "VER" "2"
					( Origin gFrontEnd )
				)
				( attribute "WATTAGE" "1/16W"
					( Origin gFrontEnd )
				)
				( attribute "XY" "(-3350,1375)"
					( Origin gFrontEnd )
				)
				( attribute "CHIPS_PART_NAME" "RES"
					( Origin gPackager )
				)
				( attribute "CDS_PART_NAME" "RES_0402-4.75K,1%,1/16W,EMPTY,A"
					( Origin gPackager )
				)
				( objectStatus "R2U30" )
			)
			( gate "@baseboard_fab2_lib.baseboard_fab2(sch_1):page90_i72"
				( attribute "BOM_COST" "PROC"
					( Origin gFrontEnd )
				)
				( attribute "CDS_LIB" "mstr_discrete"
					( Origin gPackager )
				)
				( attribute "CDS_LOCATION" "R4P7"
					( Origin gPackager )
				)
				( attribute "CDS_SEC" "1"
					( Origin gPackager )
				)
				( attribute "LOCATION" "R4P7"
					( Origin gFrontEnd )
				)
				( attribute "MATERIAL" "EMPTY"
					( Origin gFrontEnd )
				)
				( attribute "PACK_TYPE" "0402"
					( Origin gFrontEnd )
				)
				( attribute "PART_NUMBER" "G21796-294"
					( Origin gFrontEnd )
				)
				( attribute "PHYS_PAGE" "90"
					( Origin gFrontEnd )
				)
				( attribute "ROOM" "PROC_SIDEBAND"
					( Origin gFrontEnd )
				)
				( attribute "ROT" "0"
					( Origin gFrontEnd )
				)
				( attribute "SEC" "1"
					( Origin gFrontEnd )
				)
				( attribute "SEC_TYPE" "0402"
					( Origin gFrontEnd )
				)
				( attribute "TOLERANCE" "1.0%"
					( Origin gFrontEnd )
				)
				( attribute "VALUE" "240"
					( Origin gFrontEnd )
				)
				( attribute "VER" "1"
					( Origin gFrontEnd )
				)
				( attribute "WATTAGE" "1/16W"
					( Origin gFrontEnd )
				)
				( attribute "XY" "(-575,2800)"
					( Origin gFrontEnd )
				)
				( attribute "CHIPS_PART_NAME" "RES"
					( Origin gPackager )
				)
				( attribute "CDS_PART_NAME" "RES_0402-240,1.0%,1/16W,EMPTY,A"
					( Origin gPackager )
				)
				( objectStatus "R4P7" )
			)
			( gate "@baseboard_fab2_lib.baseboard_fab2(sch_1):page90_i74"
				( attribute "BOM_COST" "PROC"
					( Origin gFrontEnd )
				)
				( attribute "CDS_LIB" "mstr_discrete"
					( Origin gPackager )
				)
				( attribute "CDS_LOCATION" "R7P15"
					( Origin gPackager )
				)
				( attribute "CDS_SEC" "1"
					( Origin gPackager )
				)
				( attribute "LOCATION" "R7P15"
					( Origin gFrontEnd )
				)
				( attribute "MATERIAL" "EMPTY"
					( Origin gFrontEnd )
				)
				( attribute "PACK_TYPE" "0402"
					( Origin gFrontEnd )
				)
				( attribute "PART_NUMBER" "G21796-294"
					( Origin gFrontEnd )
				)
				( attribute "PHYS_PAGE" "90"
					( Origin gFrontEnd )
				)
				( attribute "ROOM" "PROC_SIDEBAND"
					( Origin gFrontEnd )
				)
				( attribute "ROT" "0"
					( Origin gFrontEnd )
				)
				( attribute "SEC" "1"
					( Origin gFrontEnd )
				)
				( attribute "SEC_TYPE" "0402"
					( Origin gFrontEnd )
				)
				( attribute "TOLERANCE" "1.0%"
					( Origin gFrontEnd )
				)
				( attribute "VALUE" "240"
					( Origin gFrontEnd )
				)
				( attribute "VER" "1"
					( Origin gFrontEnd )
				)
				( attribute "WATTAGE" "1/16W"
					( Origin gFrontEnd )
				)
				( attribute "XY" "(-425,650)"
					( Origin gFrontEnd )
				)
				( attribute "CHIPS_PART_NAME" "RES"
					( Origin gPackager )
				)
				( attribute "CDS_PART_NAME" "RES_0402-240,1.0%,1/16W,EMPTY,A"
					( Origin gPackager )
				)
				( objectStatus "R7P15" )
			)
			( gate "@baseboard_fab2_lib.baseboard_fab2(sch_1):page90_i76"
				( attribute "BOM_COST" "PROC"
					( Origin gFrontEnd )
				)
				( attribute "CDS_LIB" "mstr_discrete"
					( Origin gPackager )
				)
				( attribute "CDS_LOCATION" "R7P22"
					( Origin gPackager )
				)
				( attribute "CDS_SEC" "1"
					( Origin gPackager )
				)
				( attribute "LOCATION" "R7P22"
					( Origin gFrontEnd )
				)
				( attribute "MATERIAL" "EMPTY"
					( Origin gFrontEnd )
				)
				( attribute "PACK_TYPE" "0402"
					( Origin gFrontEnd )
				)
				( attribute "PART_NUMBER" "G21796-294"
					( Origin gFrontEnd )
				)
				( attribute "PHYS_PAGE" "90"
					( Origin gFrontEnd )
				)
				( attribute "ROOM" "PROC_SIDEBAND"
					( Origin gFrontEnd )
				)
				( attribute "ROT" "0"
					( Origin gFrontEnd )
				)
				( attribute "SEC" "1"
					( Origin gFrontEnd )
				)
				( attribute "SEC_TYPE" "0402"
					( Origin gFrontEnd )
				)
				( attribute "TOLERANCE" "1.0%"
					( Origin gFrontEnd )
				)
				( attribute "VALUE" "240"
					( Origin gFrontEnd )
				)
				( attribute "VER" "1"
					( Origin gFrontEnd )
				)
				( attribute "WATTAGE" "1/16W"
					( Origin gFrontEnd )
				)
				( attribute "XY" "(-2450,800)"
					( Origin gFrontEnd )
				)
				( attribute "CHIPS_PART_NAME" "RES"
					( Origin gPackager )
				)
				( attribute "CDS_PART_NAME" "RES_0402-240,1.0%,1/16W,EMPTY,A"
					( Origin gPackager )
				)
				( objectStatus "R7P22" )
			)
			( gate "@baseboard_fab2_lib.baseboard_fab2(sch_1):page90_i79"
				( attribute "CDS_LIB" "mstr_discrete"
					( Origin gPackager )
				)
				( attribute "CDS_LOCATION" "R5P2"
					( Origin gPackager )
				)
				( attribute "CDS_SEC" "1"
					( Origin gPackager )
				)
				( attribute "LOCATION" "R5P2"
					( Origin gFrontEnd )
				)
				( attribute "MATERIAL" "CHIP"
					( Origin gFrontEnd )
				)
				( attribute "PACK_TYPE" "0402"
					( Origin gFrontEnd )
				)
				( attribute "PART_NUMBER" "G21796-047"
					( Origin gFrontEnd )
				)
				( attribute "PHYS_PAGE" "90"
					( Origin gFrontEnd )
				)
				( attribute "ROOM" "CPU0"
					( Origin gFrontEnd )
				)
				( attribute "ROT" "0"
					( Origin gFrontEnd )
				)
				( attribute "SEC" "1"
					( Origin gFrontEnd )
				)
				( attribute "SEC_TYPE" "0402"
					( Origin gFrontEnd )
				)
				( attribute "TOLERANCE" "1%"
					( Origin gFrontEnd )
				)
				( attribute "VALUE" "49.9"
					( Origin gFrontEnd )
				)
				( attribute "VER" "1"
					( Origin gFrontEnd )
				)
				( attribute "WATTAGE" "1/16W"
					( Origin gFrontEnd )
				)
				( attribute "XY" "(-1575,3200)"
					( Origin gFrontEnd )
				)
				( attribute "CHIPS_PART_NAME" "RES"
					( Origin gPackager )
				)
				( attribute "CDS_PART_NAME" "RES_0402-49.9,1%,1/16W,CHIP,G2A"
					( Origin gPackager )
				)
				( objectStatus "R5P2" )
			)
			( gate "@baseboard_fab2_lib.baseboard_fab2(sch_1):page90_i80"
				( attribute "CDS_LIB" "mstr_discrete"
					( Origin gPackager )
				)
				( attribute "CDS_LOCATION" "R5P3"
					( Origin gPackager )
				)
				( attribute "CDS_SEC" "1"
					( Origin gPackager )
				)
				( attribute "LOCATION" "R5P3"
					( Origin gFrontEnd )
				)
				( attribute "MATERIAL" "CHIP"
					( Origin gFrontEnd )
				)
				( attribute "PACK_TYPE" "0402"
					( Origin gFrontEnd )
				)
				( attribute "PART_NUMBER" "G21796-047"
					( Origin gFrontEnd )
				)
				( attribute "PHYS_PAGE" "90"
					( Origin gFrontEnd )
				)
				( attribute "ROOM" "CPU0"
					( Origin gFrontEnd )
				)
				( attribute "ROT" "0"
					( Origin gFrontEnd )
				)
				( attribute "SEC" "1"
					( Origin gFrontEnd )
				)
				( attribute "SEC_TYPE" "0402"
					( Origin gFrontEnd )
				)
				( attribute "TOLERANCE" "1%"
					( Origin gFrontEnd )
				)
				( attribute "VALUE" "49.9"
					( Origin gFrontEnd )
				)
				( attribute "VER" "1"
					( Origin gFrontEnd )
				)
				( attribute "WATTAGE" "1/16W"
					( Origin gFrontEnd )
				)
				( attribute "XY" "(-1575,3075)"
					( Origin gFrontEnd )
				)
				( attribute "CHIPS_PART_NAME" "RES"
					( Origin gPackager )
				)
				( attribute "CDS_PART_NAME" "RES_0402-49.9,1%,1/16W,CHIP,G2A"
					( Origin gPackager )
				)
				( objectStatus "R5P3" )
			)
			( gate "@baseboard_fab2_lib.baseboard_fab2(sch_1):page90_i81"
				( attribute "CDS_LIB" "mstr_discrete"
					( Origin gPackager )
				)
				( attribute "CDS_LOCATION" "R6D5"
					( Origin gPackager )
				)
				( attribute "CDS_SEC" "1"
					( Origin gPackager )
				)
				( attribute "LOCATION" "R6D5"
					( Origin gFrontEnd )
				)
				( attribute "MATERIAL" "CHIP"
					( Origin gFrontEnd )
				)
				( attribute "PACK_TYPE" "0402"
					( Origin gFrontEnd )
				)
				( attribute "PART_NUMBER" "G21796-047"
					( Origin gFrontEnd )
				)
				( attribute "PHYS_PAGE" "90"
					( Origin gFrontEnd )
				)
				( attribute "ROOM" "CPU0"
					( Origin gFrontEnd )
				)
				( attribute "ROT" "0"
					( Origin gFrontEnd )
				)
				( attribute "SEC" "1"
					( Origin gFrontEnd )
				)
				( attribute "SEC_TYPE" "0402"
					( Origin gFrontEnd )
				)
				( attribute "TOLERANCE" "1%"
					( Origin gFrontEnd )
				)
				( attribute "VALUE" "49.9"
					( Origin gFrontEnd )
				)
				( attribute "VER" "1"
					( Origin gFrontEnd )
				)
				( attribute "WATTAGE" "1/16W"
					( Origin gFrontEnd )
				)
				( attribute "XY" "(-1575,2925)"
					( Origin gFrontEnd )
				)
				( attribute "CHIPS_PART_NAME" "RES"
					( Origin gPackager )
				)
				( attribute "CDS_PART_NAME" "RES_0402-49.9,1%,1/16W,CHIP,G2A"
					( Origin gPackager )
				)
				( objectStatus "R6D5" )
			)
			( gate "@baseboard_fab2_lib.baseboard_fab2(sch_1):page90_i85"
				( attribute "CDS_LIB" "mstr_discrete"
					( Origin gPackager )
				)
				( attribute "CDS_LOCATION" "R8P1"
					( Origin gPackager )
				)
				( attribute "CDS_SEC" "1"
					( Origin gPackager )
				)
				( attribute "LOCATION" "R8P1"
					( Origin gFrontEnd )
				)
				( attribute "MATERIAL" "CHIP"
					( Origin gFrontEnd )
				)
				( attribute "PACK_TYPE" "0402"
					( Origin gFrontEnd )
				)
				( attribute "PART_NUMBER" "G21796-047"
					( Origin gFrontEnd )
				)
				( attribute "PHYS_PAGE" "90"
					( Origin gFrontEnd )
				)
				( attribute "ROOM" "CPU1"
					( Origin gFrontEnd )
				)
				( attribute "ROT" "0"
					( Origin gFrontEnd )
				)
				( attribute "SEC" "1"
					( Origin gFrontEnd )
				)
				( attribute "SEC_TYPE" "0402"
					( Origin gFrontEnd )
				)
				( attribute "TOLERANCE" "1%"
					( Origin gFrontEnd )
				)
				( attribute "VALUE" "49.9"
					( Origin gFrontEnd )
				)
				( attribute "VER" "1"
					( Origin gFrontEnd )
				)
				( attribute "WATTAGE" "1/16W"
					( Origin gFrontEnd )
				)
				( attribute "XY" "(325,2475)"
					( Origin gFrontEnd )
				)
				( attribute "CHIPS_PART_NAME" "RES"
					( Origin gPackager )
				)
				( attribute "CDS_PART_NAME" "RES_0402-49.9,1%,1/16W,CHIP,G2A"
					( Origin gPackager )
				)
				( objectStatus "R8P1" )
			)
			( gate "@baseboard_fab2_lib.baseboard_fab2(sch_1):page90_i86"
				( attribute "CDS_LIB" "mstr_discrete"
					( Origin gPackager )
				)
				( attribute "CDS_LOCATION" "R8P2"
					( Origin gPackager )
				)
				( attribute "CDS_SEC" "1"
					( Origin gPackager )
				)
				( attribute "LOCATION" "R8P2"
					( Origin gFrontEnd )
				)
				( attribute "MATERIAL" "CHIP"
					( Origin gFrontEnd )
				)
				( attribute "PACK_TYPE" "0402"
					( Origin gFrontEnd )
				)
				( attribute "PART_NUMBER" "G21796-047"
					( Origin gFrontEnd )
				)
				( attribute "PHYS_PAGE" "90"
					( Origin gFrontEnd )
				)
				( attribute "ROOM" "CPU1"
					( Origin gFrontEnd )
				)
				( attribute "ROT" "0"
					( Origin gFrontEnd )
				)
				( attribute "SEC" "1"
					( Origin gFrontEnd )
				)
				( attribute "SEC_TYPE" "0402"
					( Origin gFrontEnd )
				)
				( attribute "TOLERANCE" "1%"
					( Origin gFrontEnd )
				)
				( attribute "VALUE" "49.9"
					( Origin gFrontEnd )
				)
				( attribute "VER" "1"
					( Origin gFrontEnd )
				)
				( attribute "WATTAGE" "1/16W"
					( Origin gFrontEnd )
				)
				( attribute "XY" "(325,2350)"
					( Origin gFrontEnd )
				)
				( attribute "CHIPS_PART_NAME" "RES"
					( Origin gPackager )
				)
				( attribute "CDS_PART_NAME" "RES_0402-49.9,1%,1/16W,CHIP,G2A"
					( Origin gPackager )
				)
				( objectStatus "R8P2" )
			)
			( gate "@baseboard_fab2_lib.baseboard_fab2(sch_1):page90_i88"
				( attribute "CDS_LIB" "mstr_discrete"
					( Origin gPackager )
				)
				( attribute "CDS_LOCATION" "R3D9"
					( Origin gPackager )
				)
				( attribute "CDS_SEC" "1"
					( Origin gPackager )
				)
				( attribute "LOCATION" "R3D9"
					( Origin gFrontEnd )
				)
				( attribute "MATERIAL" "CHIP"
					( Origin gFrontEnd )
				)
				( attribute "PACK_TYPE" "0402"
					( Origin gFrontEnd )
				)
				( attribute "PART_NUMBER" "G21796-047"
					( Origin gFrontEnd )
				)
				( attribute "PHYS_PAGE" "90"
					( Origin gFrontEnd )
				)
				( attribute "ROOM" "CPU1"
					( Origin gFrontEnd )
				)
				( attribute "ROT" "0"
					( Origin gFrontEnd )
				)
				( attribute "SEC" "1"
					( Origin gFrontEnd )
				)
				( attribute "SEC_TYPE" "0402"
					( Origin gFrontEnd )
				)
				( attribute "TOLERANCE" "1%"
					( Origin gFrontEnd )
				)
				( attribute "VALUE" "49.9"
					( Origin gFrontEnd )
				)
				( attribute "VER" "1"
					( Origin gFrontEnd )
				)
				( attribute "WATTAGE" "1/16W"
					( Origin gFrontEnd )
				)
				( attribute "XY" "(325,2200)"
					( Origin gFrontEnd )
				)
				( attribute "CHIPS_PART_NAME" "RES"
					( Origin gPackager )
				)
				( attribute "CDS_PART_NAME" "RES_0402-49.9,1%,1/16W,CHIP,G2A"
					( Origin gPackager )
				)
				( objectStatus "R3D9" )
			)
			( gate "@baseboard_fab2_lib.baseboard_fab2(sch_1):page91_i1"
				( attribute "CDS_LIB" "mstr_sconn"
					( Origin gPackager )
				)
				( attribute "CDS_LOCATION" "J8B1"
					( Origin gPackager )
				)
				( attribute "CDS_SEC" "1"
					( Origin gPackager )
				)
				( attribute "LOCATION" "J8B1"
					( Origin gFrontEnd )
				)
				( attribute "MATERIAL" "SCONN"
					( Origin gFrontEnd )
				)
				( attribute "PACK_TYPE" "SM"
					( Origin gFrontEnd )
				)
				( attribute "PART_NUMBER" "H46321-001"
					( Origin gFrontEnd )
				)
				( attribute "PHYS_PAGE" "91"
					( Origin gFrontEnd )
				)
				( attribute "ROOM" "HFI"
					( Origin gFrontEnd )
				)
				( attribute "ROT" "0"
					( Origin gFrontEnd )
				)
				( attribute "SEC" "1"
					( Origin gPackager )
				)
				( attribute "VER" "1"
					( Origin gFrontEnd )
				)
				( attribute "XY" "(-125,2850)"
					( Origin gFrontEnd )
				)
				( attribute "CHIPS_PART_NAME" "SCONN24_H46321001"
					( Origin gPackager )
				)
				( attribute "CDS_PART_NAME" "SCONN24_H46321001_SM-SCONN,H46A"
					( Origin gPackager )
				)
				( objectStatus "J8B1" )
			)
			( gate "@baseboard_fab2_lib.baseboard_fab2(sch_1):page91_i14"
				( attribute "CDS_LIB" "mstr_discrete"
					( Origin gPackager )
				)
				( attribute "CDS_LOCATION" "R8B8"
					( Origin gPackager )
				)
				( attribute "CDS_SEC" "1"
					( Origin gPackager )
				)
				( attribute "LOCATION" "R8B8"
					( Origin gFrontEnd )
				)
				( attribute "MATERIAL" "CHIP"
					( Origin gFrontEnd )
				)
				( attribute "PACK_TYPE" "0402"
					( Origin gFrontEnd )
				)
				( attribute "PART_NUMBER" "G21796-072"
					( Origin gFrontEnd )
				)
				( attribute "PHYS_PAGE" "91"
					( Origin gFrontEnd )
				)
				( attribute "ROOM" "HFI"
					( Origin gFrontEnd )
				)
				( attribute "ROT" "0"
					( Origin gFrontEnd )
				)
				( attribute "SEC" "1"
					( Origin gFrontEnd )
				)
				( attribute "SEC_TYPE" "0402"
					( Origin gFrontEnd )
				)
				( attribute "SIGNAL_MODEL" "DEFAULT_RESISTOR_4750OHM_2_1"
					( Origin gFrontEnd )
				)
				( attribute "TOLERANCE" "1%"
					( Origin gFrontEnd )
				)
				( attribute "VALUE" "4.75K"
					( Origin gFrontEnd )
				)
				( attribute "VER" "2"
					( Origin gFrontEnd )
				)
				( attribute "WATTAGE" "1/16W"
					( Origin gFrontEnd )
				)
				( attribute "XY" "(1250,3375)"
					( Origin gFrontEnd )
				)
				( attribute "CHIPS_PART_NAME" "RES"
					( Origin gPackager )
				)
				( attribute "CDS_PART_NAME" "RES_0402-4.75K,1%,1/16W,CHIP,GA"
					( Origin gPackager )
				)
				( objectStatus "R8B8" )
			)
			( gate "@baseboard_fab2_lib.baseboard_fab2(sch_1):page91_i16"
				( attribute "CDS_LIB" "mstr_discrete"
					( Origin gPackager )
				)
				( attribute "CDS_LOCATION" "R8B10"
					( Origin gPackager )
				)
				( attribute "CDS_SEC" "1"
					( Origin gPackager )
				)
				( attribute "LOCATION" "R8B10"
					( Origin gFrontEnd )
				)
				( attribute "MATERIAL" "CHIP"
					( Origin gFrontEnd )
				)
				( attribute "PACK_TYPE" "0402"
					( Origin gFrontEnd )
				)
				( attribute "PART_NUMBER" "G21796-072"
					( Origin gFrontEnd )
				)
				( attribute "PHYS_PAGE" "91"
					( Origin gFrontEnd )
				)
				( attribute "ROOM" "HFI"
					( Origin gFrontEnd )
				)
				( attribute "ROT" "0"
					( Origin gFrontEnd )
				)
				( attribute "SEC" "1"
					( Origin gFrontEnd )
				)
				( attribute "SEC_TYPE" "0402"
					( Origin gFrontEnd )
				)
				( attribute "SIGNAL_MODEL" "DEFAULT_RESISTOR_4750OHM_2_1"
					( Origin gFrontEnd )
				)
				( attribute "TOLERANCE" "1%"
					( Origin gFrontEnd )
				)
				( attribute "VALUE" "4.75K"
					( Origin gFrontEnd )
				)
				( attribute "VER" "2"
					( Origin gFrontEnd )
				)
				( attribute "WATTAGE" "1/16W"
					( Origin gFrontEnd )
				)
				( attribute "XY" "(1000,3375)"
					( Origin gFrontEnd )
				)
				( attribute "CHIPS_PART_NAME" "RES"
					( Origin gPackager )
				)
				( attribute "CDS_PART_NAME" "RES_0402-4.75K,1%,1/16W,CHIP,GA"
					( Origin gPackager )
				)
				( objectStatus "R8B10" )
			)
			( gate "@baseboard_fab2_lib.baseboard_fab2(sch_1):page91_i17"
				( attribute "CDS_LIB" "mstr_discrete"
					( Origin gPackager )
				)
				( attribute "CDS_LOCATION" "R8B16"
					( Origin gPackager )
				)
				( attribute "CDS_SEC" "1"
					( Origin gPackager )
				)
				( attribute "LOCATION" "R8B16"
					( Origin gFrontEnd )
				)
				( attribute "MATERIAL" "CHIP"
					( Origin gFrontEnd )
				)
				( attribute "PACK_TYPE" "0402"
					( Origin gFrontEnd )
				)
				( attribute "PART_NUMBER" "G21796-072"
					( Origin gFrontEnd )
				)
				( attribute "PHYS_PAGE" "91"
					( Origin gFrontEnd )
				)
				( attribute "ROOM" "HFI"
					( Origin gFrontEnd )
				)
				( attribute "ROT" "0"
					( Origin gFrontEnd )
				)
				( attribute "SEC" "1"
					( Origin gFrontEnd )
				)
				( attribute "SEC_TYPE" "0402"
					( Origin gFrontEnd )
				)
				( attribute "SIGNAL_MODEL" "DEFAULT_RESISTOR_4750OHM_2_1"
					( Origin gFrontEnd )
				)
				( attribute "TOLERANCE" "1%"
					( Origin gFrontEnd )
				)
				( attribute "VALUE" "4.75K"
					( Origin gFrontEnd )
				)
				( attribute "VER" "2"
					( Origin gFrontEnd )
				)
				( attribute "WATTAGE" "1/16W"
					( Origin gFrontEnd )
				)
				( attribute "XY" "(750,3375)"
					( Origin gFrontEnd )
				)
				( attribute "CHIPS_PART_NAME" "RES"
					( Origin gPackager )
				)
				( attribute "CDS_PART_NAME" "RES_0402-4.75K,1%,1/16W,CHIP,GA"
					( Origin gPackager )
				)
				( objectStatus "R8B16" )
			)
			( gate "@baseboard_fab2_lib.baseboard_fab2(sch_1):page91_i18"
				( attribute "CDS_LIB" "mstr_discrete"
					( Origin gPackager )
				)
				( attribute "CDS_LOCATION" "R8B17"
					( Origin gPackager )
				)
				( attribute "CDS_SEC" "1"
					( Origin gPackager )
				)
				( attribute "LOCATION" "R8B17"
					( Origin gFrontEnd )
				)
				( attribute "MATERIAL" "CHIP"
					( Origin gFrontEnd )
				)
				( attribute "PACK_TYPE" "0402"
					( Origin gFrontEnd )
				)
				( attribute "PART_NUMBER" "G21796-072"
					( Origin gFrontEnd )
				)
				( attribute "PHYS_PAGE" "91"
					( Origin gFrontEnd )
				)
				( attribute "ROOM" "HFI"
					( Origin gFrontEnd )
				)
				( attribute "ROT" "0"
					( Origin gFrontEnd )
				)
				( attribute "SEC" "1"
					( Origin gFrontEnd )
				)
				( attribute "SEC_TYPE" "0402"
					( Origin gFrontEnd )
				)
				( attribute "SIGNAL_MODEL" "DEFAULT_RESISTOR_4750OHM_2_1"
					( Origin gFrontEnd )
				)
				( attribute "TOLERANCE" "1%"
					( Origin gFrontEnd )
				)
				( attribute "VALUE" "4.75K"
					( Origin gFrontEnd )
				)
				( attribute "VER" "2"
					( Origin gFrontEnd )
				)
				( attribute "WATTAGE" "1/16W"
					( Origin gFrontEnd )
				)
				( attribute "XY" "(500,3375)"
					( Origin gFrontEnd )
				)
				( attribute "CHIPS_PART_NAME" "RES"
					( Origin gPackager )
				)
				( attribute "CDS_PART_NAME" "RES_0402-4.75K,1%,1/16W,CHIP,GA"
					( Origin gPackager )
				)
				( objectStatus "R8B17" )
			)
			( gate "@baseboard_fab2_lib.baseboard_fab2(sch_1):page91_i20"
				( attribute "CDS_LIB" "mstr_discrete"
					( Origin gPackager )
				)
				( attribute "CDS_LOCATION" "R8B18"
					( Origin gPackager )
				)
				( attribute "CDS_SEC" "1"
					( Origin gPackager )
				)
				( attribute "LOCATION" "R8B18"
					( Origin gFrontEnd )
				)
				( attribute "MATERIAL" "CHIP"
					( Origin gFrontEnd )
				)
				( attribute "PACK_TYPE" "0402"
					( Origin gFrontEnd )
				)
				( attribute "PART_NUMBER" "G21796-072"
					( Origin gFrontEnd )
				)
				( attribute "PHYS_PAGE" "91"
					( Origin gFrontEnd )
				)
				( attribute "ROOM" "HFI"
					( Origin gFrontEnd )
				)
				( attribute "ROT" "2"
					( Origin gFrontEnd )
				)
				( attribute "SEC" "1"
					( Origin gFrontEnd )
				)
				( attribute "SEC_TYPE" "0402"
					( Origin gFrontEnd )
				)
				( attribute "SIGNAL_MODEL" "DEFAULT_RESISTOR_4750OHM_2_1"
					( Origin gFrontEnd )
				)
				( attribute "TOLERANCE" "1%"
					( Origin gFrontEnd )
				)
				( attribute "VALUE" "4.75K"
					( Origin gFrontEnd )
				)
				( attribute "VER" "2"
					( Origin gFrontEnd )
				)
				( attribute "WATTAGE" "1/16W"
					( Origin gFrontEnd )
				)
				( attribute "XY" "(-750,3350)"
					( Origin gFrontEnd )
				)
				( attribute "CHIPS_PART_NAME" "RES"
					( Origin gPackager )
				)
				( attribute "CDS_PART_NAME" "RES_0402-4.75K,1%,1/16W,CHIP,GA"
					( Origin gPackager )
				)
				( objectStatus "R8B18" )
			)
			( gate "@baseboard_fab2_lib.baseboard_fab2(sch_1):page91_i21"
				( attribute "CDS_LIB" "mstr_discrete"
					( Origin gPackager )
				)
				( attribute "CDS_LOCATION" "R8B19"
					( Origin gPackager )
				)
				( attribute "CDS_SEC" "1"
					( Origin gPackager )
				)
				( attribute "LOCATION" "R8B19"
					( Origin gFrontEnd )
				)
				( attribute "MATERIAL" "CHIP"
					( Origin gFrontEnd )
				)
				( attribute "PACK_TYPE" "0402"
					( Origin gFrontEnd )
				)
				( attribute "PART_NUMBER" "G21796-072"
					( Origin gFrontEnd )
				)
				( attribute "PHYS_PAGE" "91"
					( Origin gFrontEnd )
				)
				( attribute "ROOM" "HFI"
					( Origin gFrontEnd )
				)
				( attribute "ROT" "2"
					( Origin gFrontEnd )
				)
				( attribute "SEC" "1"
					( Origin gFrontEnd )
				)
				( attribute "SEC_TYPE" "0402"
					( Origin gFrontEnd )
				)
				( attribute "SIGNAL_MODEL" "DEFAULT_RESISTOR_4750OHM_2_1"
					( Origin gFrontEnd )
				)
				( attribute "TOLERANCE" "1%"
					( Origin gFrontEnd )
				)
				( attribute "VALUE" "4.75K"
					( Origin gFrontEnd )
				)
				( attribute "VER" "2"
					( Origin gFrontEnd )
				)
				( attribute "WATTAGE" "1/16W"
					( Origin gFrontEnd )
				)
				( attribute "XY" "(-1125,3350)"
					( Origin gFrontEnd )
				)
				( attribute "CHIPS_PART_NAME" "RES"
					( Origin gPackager )
				)
				( attribute "CDS_PART_NAME" "RES_0402-4.75K,1%,1/16W,CHIP,GA"
					( Origin gPackager )
				)
				( objectStatus "R8B19" )
			)
			( gate "@baseboard_fab2_lib.baseboard_fab2(sch_1):page91_i22"
				( attribute "CDS_LIB" "mstr_discrete"
					( Origin gPackager )
				)
				( attribute "CDS_LOCATION" "R8B5"
					( Origin gPackager )
				)
				( attribute "CDS_SEC" "1"
					( Origin gPackager )
				)
				( attribute "LOCATION" "R8B5"
					( Origin gFrontEnd )
				)
				( attribute "MATERIAL" "CHIP"
					( Origin gFrontEnd )
				)
				( attribute "PACK_TYPE" "0402"
					( Origin gFrontEnd )
				)
				( attribute "PART_NUMBER" "G21796-072"
					( Origin gFrontEnd )
				)
				( attribute "PHYS_PAGE" "91"
					( Origin gFrontEnd )
				)
				( attribute "ROOM" "HFI"
					( Origin gFrontEnd )
				)
				( attribute "ROT" "2"
					( Origin gFrontEnd )
				)
				( attribute "SEC" "1"
					( Origin gFrontEnd )
				)
				( attribute "SEC_TYPE" "0402"
					( Origin gFrontEnd )
				)
				( attribute "SIGNAL_MODEL" "DEFAULT_RESISTOR_4750OHM_2_1"
					( Origin gFrontEnd )
				)
				( attribute "TOLERANCE" "1%"
					( Origin gFrontEnd )
				)
				( attribute "VALUE" "4.75K"
					( Origin gFrontEnd )
				)
				( attribute "VER" "2"
					( Origin gFrontEnd )
				)
				( attribute "WATTAGE" "1/16W"
					( Origin gFrontEnd )
				)
				( attribute "XY" "(-1500,3350)"
					( Origin gFrontEnd )
				)
				( attribute "CHIPS_PART_NAME" "RES"
					( Origin gPackager )
				)
				( attribute "CDS_PART_NAME" "RES_0402-4.75K,1%,1/16W,CHIP,GA"
					( Origin gPackager )
				)
				( objectStatus "R8B5" )
			)
			( gate "@baseboard_fab2_lib.baseboard_fab2(sch_1):page91_i24"
				( attribute "CDS_LIB" "mstr_discrete"
					( Origin gPackager )
				)
				( attribute "CDS_LOCATION" "R8B3"
					( Origin gPackager )
				)
				( attribute "CDS_SEC" "1"
					( Origin gPackager )
				)
				( attribute "LOCATION" "R8B3"
					( Origin gFrontEnd )
				)
				( attribute "MATERIAL" "CHIP"
					( Origin gFrontEnd )
				)
				( attribute "PACK_TYPE" "0402"
					( Origin gFrontEnd )
				)
				( attribute "PART_NUMBER" "G21796-072"
					( Origin gFrontEnd )
				)
				( attribute "PHYS_PAGE" "91"
					( Origin gFrontEnd )
				)
				( attribute "ROOM" "HFI"
					( Origin gFrontEnd )
				)
				( attribute "ROT" "2"
					( Origin gFrontEnd )
				)
				( attribute "SEC" "1"
					( Origin gFrontEnd )
				)
				( attribute "SEC_TYPE" "0402"
					( Origin gFrontEnd )
				)
				( attribute "SIGNAL_MODEL" "DEFAULT_RESISTOR_4750OHM_2_1"
					( Origin gFrontEnd )
				)
				( attribute "TOLERANCE" "1%"
					( Origin gFrontEnd )
				)
				( attribute "VALUE" "4.75K"
					( Origin gFrontEnd )
				)
				( attribute "VER" "2"
					( Origin gFrontEnd )
				)
				( attribute "WATTAGE" "1/16W"
					( Origin gFrontEnd )
				)
				( attribute "XY" "(-1875,3350)"
					( Origin gFrontEnd )
				)
				( attribute "CHIPS_PART_NAME" "RES"
					( Origin gPackager )
				)
				( attribute "CDS_PART_NAME" "RES_0402-4.75K,1%,1/16W,CHIP,GA"
					( Origin gPackager )
				)
				( objectStatus "R8B3" )
			)
			( gate "@baseboard_fab2_lib.baseboard_fab2(sch_1):page91_i34"
				( attribute "CDS_LIB" "mstr_discrete"
					( Origin gPackager )
				)
				( attribute "CDS_LOCATION" "R8B13"
					( Origin gPackager )
				)
				( attribute "CDS_SEC" "1"
					( Origin gPackager )
				)
				( attribute "LOCATION" "R8B13"
					( Origin gFrontEnd )
				)
				( attribute "MATERIAL" "CHIP"
					( Origin gFrontEnd )
				)
				( attribute "PACK_TYPE" "0402"
					( Origin gFrontEnd )
				)
				( attribute "PART_NUMBER" "G21796-336"
					( Origin gFrontEnd )
				)
				( attribute "PHYS_PAGE" "91"
					( Origin gFrontEnd )
				)
				( attribute "ROOM" "SMBUS_CPU0_STL"
					( Origin gFrontEnd )
				)
				( attribute "ROT" "0"
					( Origin gFrontEnd )
				)
				( attribute "SEC" "1"
					( Origin gFrontEnd )
				)
				( attribute "SEC_TYPE" "0402"
					( Origin gFrontEnd )
				)
				( attribute "TOLERANCE" "1%"
					( Origin gFrontEnd )
				)
				( attribute "VALUE" "1.8K"
					( Origin gFrontEnd )
				)
				( attribute "VER" "2"
					( Origin gFrontEnd )
				)
				( attribute "WATTAGE" "1/16W"
					( Origin gFrontEnd )
				)
				( attribute "XY" "(1500,3375)"
					( Origin gFrontEnd )
				)
				( attribute "CHIPS_PART_NAME" "RES"
					( Origin gPackager )
				)
				( attribute "CDS_PART_NAME" "RES_0402-1.8K,1%,1/16W,CHIP,G2A"
					( Origin gPackager )
				)
				( objectStatus "R8B13" )
			)
			( gate "@baseboard_fab2_lib.baseboard_fab2(sch_1):page91_i35"
				( attribute "CDS_LIB" "mstr_discrete"
					( Origin gPackager )
				)
				( attribute "CDS_LOCATION" "R8B11"
					( Origin gPackager )
				)
				( attribute "CDS_SEC" "1"
					( Origin gPackager )
				)
				( attribute "LOCATION" "R8B11"
					( Origin gFrontEnd )
				)
				( attribute "MATERIAL" "CHIP"
					( Origin gFrontEnd )
				)
				( attribute "PACK_TYPE" "0402"
					( Origin gFrontEnd )
				)
				( attribute "PART_NUMBER" "G21796-336"
					( Origin gFrontEnd )
				)
				( attribute "PHYS_PAGE" "91"
					( Origin gFrontEnd )
				)
				( attribute "ROOM" "SMBUS_CPU0_STL"
					( Origin gFrontEnd )
				)
				( attribute "ROT" "0"
					( Origin gFrontEnd )
				)
				( attribute "SEC" "1"
					( Origin gFrontEnd )
				)
				( attribute "SEC_TYPE" "0402"
					( Origin gFrontEnd )
				)
				( attribute "TOLERANCE" "1%"
					( Origin gFrontEnd )
				)
				( attribute "VALUE" "1.8K"
					( Origin gFrontEnd )
				)
				( attribute "VER" "2"
					( Origin gFrontEnd )
				)
				( attribute "WATTAGE" "1/16W"
					( Origin gFrontEnd )
				)
				( attribute "XY" "(1725,3375)"
					( Origin gFrontEnd )
				)
				( attribute "CHIPS_PART_NAME" "RES"
					( Origin gPackager )
				)
				( attribute "CDS_PART_NAME" "RES_0402-1.8K,1%,1/16W,CHIP,G2A"
					( Origin gPackager )
				)
				( objectStatus "R8B11" )
			)
			( gate "@baseboard_fab2_lib.baseboard_fab2(sch_1):page91_i36"
				( attribute "CDS_LIB" "mstr_discrete"
					( Origin gPackager )
				)
				( attribute "CDS_LOCATION" "R8B7"
					( Origin gPackager )
				)
				( attribute "CDS_SEC" "1"
					( Origin gPackager )
				)
				( attribute "LOCATION" "R8B7"
					( Origin gFrontEnd )
				)
				( attribute "MATERIAL" "CHIP"
					( Origin gFrontEnd )
				)
				( attribute "PACK_TYPE" "0402"
					( Origin gFrontEnd )
				)
				( attribute "PART_NUMBER" "G21796-336"
					( Origin gFrontEnd )
				)
				( attribute "PHYS_PAGE" "91"
					( Origin gFrontEnd )
				)
				( attribute "ROOM" "SMBUS_CPU0_STL"
					( Origin gFrontEnd )
				)
				( attribute "ROT" "0"
					( Origin gFrontEnd )
				)
				( attribute "SEC" "1"
					( Origin gFrontEnd )
				)
				( attribute "SEC_TYPE" "0402"
					( Origin gFrontEnd )
				)
				( attribute "TOLERANCE" "1%"
					( Origin gFrontEnd )
				)
				( attribute "VALUE" "1.8K"
					( Origin gFrontEnd )
				)
				( attribute "VER" "2"
					( Origin gFrontEnd )
				)
				( attribute "WATTAGE" "1/16W"
					( Origin gFrontEnd )
				)
				( attribute "XY" "(1975,3375)"
					( Origin gFrontEnd )
				)
				( attribute "CHIPS_PART_NAME" "RES"
					( Origin gPackager )
				)
				( attribute "CDS_PART_NAME" "RES_0402-1.8K,1%,1/16W,CHIP,G2A"
					( Origin gPackager )
				)
				( objectStatus "R8B7" )
			)
			( gate "@baseboard_fab2_lib.baseboard_fab2(sch_1):page91_i37"
				( attribute "CDS_LIB" "mstr_discrete"
					( Origin gPackager )
				)
				( attribute "CDS_LOCATION" "R8B6"
					( Origin gPackager )
				)
				( attribute "CDS_SEC" "1"
					( Origin gPackager )
				)
				( attribute "LOCATION" "R8B6"
					( Origin gFrontEnd )
				)
				( attribute "MATERIAL" "CHIP"
					( Origin gFrontEnd )
				)
				( attribute "PACK_TYPE" "0402"
					( Origin gFrontEnd )
				)
				( attribute "PART_NUMBER" "G21796-336"
					( Origin gFrontEnd )
				)
				( attribute "PHYS_PAGE" "91"
					( Origin gFrontEnd )
				)
				( attribute "ROOM" "SMBUS_CPU0_STL"
					( Origin gFrontEnd )
				)
				( attribute "ROT" "0"
					( Origin gFrontEnd )
				)
				( attribute "SEC" "1"
					( Origin gFrontEnd )
				)
				( attribute "SEC_TYPE" "0402"
					( Origin gFrontEnd )
				)
				( attribute "TOLERANCE" "1%"
					( Origin gFrontEnd )
				)
				( attribute "VALUE" "1.8K"
					( Origin gFrontEnd )
				)
				( attribute "VER" "2"
					( Origin gFrontEnd )
				)
				( attribute "WATTAGE" "1/16W"
					( Origin gFrontEnd )
				)
				( attribute "XY" "(2250,3375)"
					( Origin gFrontEnd )
				)
				( attribute "CHIPS_PART_NAME" "RES"
					( Origin gPackager )
				)
				( attribute "CDS_PART_NAME" "RES_0402-1.8K,1%,1/16W,CHIP,G2A"
					( Origin gPackager )
				)
				( objectStatus "R8B6" )
			)
			( gate "@baseboard_fab2_lib.baseboard_fab2(sch_1):page92_i1"
				( attribute "BOM_COST" "PROC_SIDEBAND"
					( Origin gFrontEnd )
				)
				( attribute "CDS_LIB" "mstr_digital"
					( Origin gPackager )
				)
				( attribute "CDS_LOCATION" "U3P2"
					( Origin gPackager )
				)
				( attribute "CDS_SEC" "1"
					( Origin gPackager )
				)
				( attribute "LOCATION" "U3P2"
					( Origin gFrontEnd )
				)
				( attribute "MATERIAL" "IC"
					( Origin gFrontEnd )
				)
				( attribute "PACK_TYPE" "SM"
					( Origin gFrontEnd )
				)
				( attribute "PART_NUMBER" "D66151-001"
					( Origin gFrontEnd )
				)
				( attribute "PHYS_PAGE" "92"
					( Origin gFrontEnd )
				)
				( attribute "ROOM" "PROC_SIDEBAND"
					( Origin gFrontEnd )
				)
				( attribute "ROT" "2"
					( Origin gFrontEnd )
				)
				( attribute "SEC" "1"
					( Origin gFrontEnd )
				)
				( attribute "SEC_TYPE" "SM"
					( Origin gFrontEnd )
				)
				( attribute "VER" "1"
					( Origin gFrontEnd )
				)
				( attribute "XY" "(-1825,4250)"
					( Origin gFrontEnd )
				)
				( attribute "CHIPS_PART_NAME" "GTL2014"
					( Origin gPackager )
				)
				( attribute "CDS_PART_NAME" "GTL2014_SM-IC,D66151-001"
					( Origin gPackager )
				)
				( objectStatus "U3P2" )
			)
			( gate "@baseboard_fab2_lib.baseboard_fab2(sch_1):page92_i9"
				( attribute "BOM_COST" "PROC_SIDEBAND"
					( Origin gFrontEnd )
				)
				( attribute "CDS_LIB" "mstr_discrete"
					( Origin gPackager )
				)
				( attribute "CDS_LOCATION" "R3P41"
					( Origin gPackager )
				)
				( attribute "CDS_SEC" "1"
					( Origin gPackager )
				)
				( attribute "LOCATION" "R3P41"
					( Origin gFrontEnd )
				)
				( attribute "MATERIAL" "CHIP"
					( Origin gFrontEnd )
				)
				( attribute "PACK_TYPE" "0402"
					( Origin gFrontEnd )
				)
				( attribute "PART_NUMBER" "G21796-267"
					( Origin gFrontEnd )
				)
				( attribute "PHYS_PAGE" "92"
					( Origin gFrontEnd )
				)
				( attribute "ROOM" "PROC_SIDEBAND"
					( Origin gFrontEnd )
				)
				( attribute "ROT" "0"
					( Origin gFrontEnd )
				)
				( attribute "SEC" "1"
					( Origin gFrontEnd )
				)
				( attribute "SEC_TYPE" "0402"
					( Origin gFrontEnd )
				)
				( attribute "TOLERANCE" "1.0%"
					( Origin gFrontEnd )
				)
				( attribute "VALUE" "75"
					( Origin gFrontEnd )
				)
				( attribute "VER" "2"
					( Origin gFrontEnd )
				)
				( attribute "WATTAGE" "1/16W"
					( Origin gFrontEnd )
				)
				( attribute "XY" "(-2900,4525)"
					( Origin gFrontEnd )
				)
				( attribute "CHIPS_PART_NAME" "RES"
					( Origin gPackager )
				)
				( attribute "CDS_PART_NAME" "RES_0402-75,1.0%,1/16W,CHIP,G2A"
					( Origin gPackager )
				)
				( objectStatus "R3P41" )
			)
			( gate "@baseboard_fab2_lib.baseboard_fab2(sch_1):page92_i12"
				( attribute "BOM_COST" "PROC_SIDEBAND"
					( Origin gFrontEnd )
				)
				( attribute "CDS_LIB" "mstr_discrete"
					( Origin gPackager )
				)
				( attribute "CDS_LOCATION" "R3P46"
					( Origin gPackager )
				)
				( attribute "CDS_SEC" "1"
					( Origin gPackager )
				)
				( attribute "LOCATION" "R3P46"
					( Origin gFrontEnd )
				)
				( attribute "MATERIAL" "CHIP"
					( Origin gFrontEnd )
				)
				( attribute "PACK_TYPE" "0402"
					( Origin gFrontEnd )
				)
				( attribute "PART_NUMBER" "G21796-074"
					( Origin gFrontEnd )
				)
				( attribute "PHYS_PAGE" "92"
					( Origin gFrontEnd )
				)
				( attribute "ROOM" "PROC_SIDEBAND"
					( Origin gFrontEnd )
				)
				( attribute "ROT" "0"
					( Origin gFrontEnd )
				)
				( attribute "SEC" "1"
					( Origin gFrontEnd )
				)
				( attribute "SEC_TYPE" "0402"
					( Origin gFrontEnd )
				)
				( attribute "TOLERANCE" "1%"
					( Origin gFrontEnd )
				)
				( attribute "VALUE" "33.2"
					( Origin gFrontEnd )
				)
				( attribute "VER" "1"
					( Origin gFrontEnd )
				)
				( attribute "WATTAGE" "1/16W"
					( Origin gFrontEnd )
				)
				( attribute "XY" "(-125,3750)"
					( Origin gFrontEnd )
				)
				( attribute "CHIPS_PART_NAME" "RES"
					( Origin gPackager )
				)
				( attribute "CDS_PART_NAME" "RES_0402-33.2,1%,1/16W,CHIP,G2A"
					( Origin gPackager )
				)
				( objectStatus "R3P46" )
			)
			( gate "@baseboard_fab2_lib.baseboard_fab2(sch_1):page92_i13"
				( attribute "BOM_COST" "PROC_SIDEBAND"
					( Origin gFrontEnd )
				)
				( attribute "CDS_LIB" "mstr_discrete"
					( Origin gPackager )
				)
				( attribute "CDS_LOCATION" "R3P43"
					( Origin gPackager )
				)
				( attribute "CDS_SEC" "1"
					( Origin gPackager )
				)
				( attribute "LOCATION" "R3P43"
					( Origin gFrontEnd )
				)
				( attribute "MATERIAL" "CHIP"
					( Origin gFrontEnd )
				)
				( attribute "PACK_TYPE" "0402"
					( Origin gFrontEnd )
				)
				( attribute "PART_NUMBER" "G21796-074"
					( Origin gFrontEnd )
				)
				( attribute "PHYS_PAGE" "92"
					( Origin gFrontEnd )
				)
				( attribute "ROOM" "PROC_SIDEBAND"
					( Origin gFrontEnd )
				)
				( attribute "ROT" "0"
					( Origin gFrontEnd )
				)
				( attribute "SEC" "1"
					( Origin gFrontEnd )
				)
				( attribute "SEC_TYPE" "0402"
					( Origin gFrontEnd )
				)
				( attribute "TOLERANCE" "1%"
					( Origin gFrontEnd )
				)
				( attribute "VALUE" "33.2"
					( Origin gFrontEnd )
				)
				( attribute "VER" "1"
					( Origin gFrontEnd )
				)
				( attribute "WATTAGE" "1/16W"
					( Origin gFrontEnd )
				)
				( attribute "XY" "(-125,4000)"
					( Origin gFrontEnd )
				)
				( attribute "CHIPS_PART_NAME" "RES"
					( Origin gPackager )
				)
				( attribute "CDS_PART_NAME" "RES_0402-33.2,1%,1/16W,CHIP,G2A"
					( Origin gPackager )
				)
				( objectStatus "R3P43" )
			)
			( gate "@baseboard_fab2_lib.baseboard_fab2(sch_1):page92_i14"
				( attribute "BOM_COST" "PROC_SIDEBAND"
					( Origin gFrontEnd )
				)
				( attribute "CDS_LIB" "mstr_discrete"
					( Origin gPackager )
				)
				( attribute "CDS_LOCATION" "R3P42"
					( Origin gPackager )
				)
				( attribute "CDS_SEC" "1"
					( Origin gPackager )
				)
				( attribute "LOCATION" "R3P42"
					( Origin gFrontEnd )
				)
				( attribute "MATERIAL" "CHIP"
					( Origin gFrontEnd )
				)
				( attribute "PACK_TYPE" "0402"
					( Origin gFrontEnd )
				)
				( attribute "PART_NUMBER" "G21796-074"
					( Origin gFrontEnd )
				)
				( attribute "PHYS_PAGE" "92"
					( Origin gFrontEnd )
				)
				( attribute "ROOM" "PROC_SIDEBAND"
					( Origin gFrontEnd )
				)
				( attribute "ROT" "0"
					( Origin gFrontEnd )
				)
				( attribute "SEC" "1"
					( Origin gFrontEnd )
				)
				( attribute "SEC_TYPE" "0402"
					( Origin gFrontEnd )
				)
				( attribute "TOLERANCE" "1%"
					( Origin gFrontEnd )
				)
				( attribute "VALUE" "33.2"
					( Origin gFrontEnd )
				)
				( attribute "VER" "1"
					( Origin gFrontEnd )
				)
				( attribute "WATTAGE" "1/16W"
					( Origin gFrontEnd )
				)
				( attribute "XY" "(-125,4250)"
					( Origin gFrontEnd )
				)
				( attribute "CHIPS_PART_NAME" "RES"
					( Origin gPackager )
				)
				( attribute "CDS_PART_NAME" "RES_0402-33.2,1%,1/16W,CHIP,G2A"
					( Origin gPackager )
				)
				( objectStatus "R3P42" )
			)
			( gate "@baseboard_fab2_lib.baseboard_fab2(sch_1):page92_i19"
				( attribute "BOM_COST" "PROC_SIDEBAND"
					( Origin gFrontEnd )
				)
				( attribute "CDS_LIB" "mstr_discrete"
					( Origin gPackager )
				)
				( attribute "CDS_LOCATION" "R7E2"
					( Origin gPackager )
				)
				( attribute "CDS_SEC" "1"
					( Origin gPackager )
				)
				( attribute "LOCATION" "R7E2"
					( Origin gFrontEnd )
				)
				( attribute "MATERIAL" "CHIP"
					( Origin gFrontEnd )
				)
				( attribute "PACK_TYPE" "0402"
					( Origin gFrontEnd )
				)
				( attribute "PART_NUMBER" "G21796-267"
					( Origin gFrontEnd )
				)
				( attribute "PHYS_PAGE" "92"
					( Origin gFrontEnd )
				)
				( attribute "ROOM" "PROC_SIDEBAND"
					( Origin gFrontEnd )
				)
				( attribute "ROT" "0"
					( Origin gFrontEnd )
				)
				( attribute "SEC" "1"
					( Origin gFrontEnd )
				)
				( attribute "SEC_TYPE" "0402"
					( Origin gFrontEnd )
				)
				( attribute "TOLERANCE" "1.0%"
					( Origin gFrontEnd )
				)
				( attribute "VALUE" "75"
					( Origin gFrontEnd )
				)
				( attribute "VER" "2"
					( Origin gFrontEnd )
				)
				( attribute "WATTAGE" "1/16W"
					( Origin gFrontEnd )
				)
				( attribute "XY" "(-2850,2325)"
					( Origin gFrontEnd )
				)
				( attribute "CHIPS_PART_NAME" "RES"
					( Origin gPackager )
				)
				( attribute "CDS_PART_NAME" "RES_0402-75,1.0%,1/16W,CHIP,G2A"
					( Origin gPackager )
				)
				( objectStatus "R7E2" )
			)
			( gate "@baseboard_fab2_lib.baseboard_fab2(sch_1):page92_i24"
				( attribute "BOM_COST" "PROC_SIDEBAND"
					( Origin gFrontEnd )
				)
				( attribute "CDS_LIB" "mstr_discrete"
					( Origin gPackager )
				)
				( attribute "CDS_LOCATION" "R7D34"
					( Origin gPackager )
				)
				( attribute "CDS_SEC" "1"
					( Origin gPackager )
				)
				( attribute "LOCATION" "R7D34"
					( Origin gFrontEnd )
				)
				( attribute "MATERIAL" "CHIP"
					( Origin gFrontEnd )
				)
				( attribute "PACK_TYPE" "0402"
					( Origin gFrontEnd )
				)
				( attribute "PART_NUMBER" "G21796-074"
					( Origin gFrontEnd )
				)
				( attribute "PHYS_PAGE" "92"
					( Origin gFrontEnd )
				)
				( attribute "ROOM" "PROC_SIDEBAND"
					( Origin gFrontEnd )
				)
				( attribute "ROT" "0"
					( Origin gFrontEnd )
				)
				( attribute "SEC" "1"
					( Origin gFrontEnd )
				)
				( attribute "SEC_TYPE" "0402"
					( Origin gFrontEnd )
				)
				( attribute "TOLERANCE" "1%"
					( Origin gFrontEnd )
				)
				( attribute "VALUE" "33.2"
					( Origin gFrontEnd )
				)
				( attribute "VER" "1"
					( Origin gFrontEnd )
				)
				( attribute "WATTAGE" "1/16W"
					( Origin gFrontEnd )
				)
				( attribute "XY" "(-125,2050)"
					( Origin gFrontEnd )
				)
				( attribute "CHIPS_PART_NAME" "RES"
					( Origin gPackager )
				)
				( attribute "CDS_PART_NAME" "RES_0402-33.2,1%,1/16W,CHIP,G2A"
					( Origin gPackager )
				)
				( objectStatus "R7D34" )
			)
			( gate "@baseboard_fab2_lib.baseboard_fab2(sch_1):page92_i29"
				( attribute "BOM_COST" "PROC_SIDEBAND"
					( Origin gFrontEnd )
				)
				( attribute "CDS_LIB" "mstr_discrete"
					( Origin gPackager )
				)
				( attribute "CDS_LOCATION" "R7D31"
					( Origin gPackager )
				)
				( attribute "CDS_SEC" "1"
					( Origin gPackager )
				)
				( attribute "LOCATION" "R7D31"
					( Origin gFrontEnd )
				)
				( attribute "MATERIAL" "CHIP"
					( Origin gFrontEnd )
				)
				( attribute "PACK_TYPE" "0402"
					( Origin gFrontEnd )
				)
				( attribute "PART_NUMBER" "G21796-074"
					( Origin gFrontEnd )
				)
				( attribute "PHYS_PAGE" "92"
					( Origin gFrontEnd )
				)
				( attribute "ROOM" "PROC_SIDEBAND"
					( Origin gFrontEnd )
				)
				( attribute "ROT" "0"
					( Origin gFrontEnd )
				)
				( attribute "SEC" "1"
					( Origin gFrontEnd )
				)
				( attribute "SEC_TYPE" "0402"
					( Origin gFrontEnd )
				)
				( attribute "TOLERANCE" "1%"
					( Origin gFrontEnd )
				)
				( attribute "VALUE" "33.2"
					( Origin gFrontEnd )
				)
				( attribute "VER" "1"
					( Origin gFrontEnd )
				)
				( attribute "WATTAGE" "1/16W"
					( Origin gFrontEnd )
				)
				( attribute "XY" "(-100,1800)"
					( Origin gFrontEnd )
				)
				( attribute "CHIPS_PART_NAME" "RES"
					( Origin gPackager )
				)
				( attribute "CDS_PART_NAME" "RES_0402-33.2,1%,1/16W,CHIP,G2A"
					( Origin gPackager )
				)
				( objectStatus "R7D31" )
			)
			( gate "@baseboard_fab2_lib.baseboard_fab2(sch_1):page92_i30"
				( attribute "BOM_COST" "PROC_SIDEBAND"
					( Origin gFrontEnd )
				)
				( attribute "CDS_LIB" "mstr_discrete"
					( Origin gPackager )
				)
				( attribute "CDS_LOCATION" "R7D29"
					( Origin gPackager )
				)
				( attribute "CDS_SEC" "1"
					( Origin gPackager )
				)
				( attribute "LOCATION" "R7D29"
					( Origin gFrontEnd )
				)
				( attribute "MATERIAL" "CHIP"
					( Origin gFrontEnd )
				)
				( attribute "PACK_TYPE" "0402"
					( Origin gFrontEnd )
				)
				( attribute "PART_NUMBER" "G21796-074"
					( Origin gFrontEnd )
				)
				( attribute "PHYS_PAGE" "92"
					( Origin gFrontEnd )
				)
				( attribute "ROOM" "PROC_SIDEBAND"
					( Origin gFrontEnd )
				)
				( attribute "ROT" "0"
					( Origin gFrontEnd )
				)
				( attribute "SEC" "1"
					( Origin gFrontEnd )
				)
				( attribute "SEC_TYPE" "0402"
					( Origin gFrontEnd )
				)
				( attribute "TOLERANCE" "1%"
					( Origin gFrontEnd )
				)
				( attribute "VALUE" "33.2"
					( Origin gFrontEnd )
				)
				( attribute "VER" "1"
					( Origin gFrontEnd )
				)
				( attribute "WATTAGE" "1/16W"
					( Origin gFrontEnd )
				)
				( attribute "XY" "(-100,1550)"
					( Origin gFrontEnd )
				)
				( attribute "CHIPS_PART_NAME" "RES"
					( Origin gPackager )
				)
				( attribute "CDS_PART_NAME" "RES_0402-33.2,1%,1/16W,CHIP,G2A"
					( Origin gPackager )
				)
				( objectStatus "R7D29" )
			)
			( gate "@baseboard_fab2_lib.baseboard_fab2(sch_1):page92_i32"
				( attribute "BOM_COST" "PROC_SIDEBAND"
					( Origin gFrontEnd )
				)
				( attribute "CDS_LIB" "mstr_digital"
					( Origin gPackager )
				)
				( attribute "CDS_LOCATION" "U7D2"
					( Origin gPackager )
				)
				( attribute "CDS_SEC" "1"
					( Origin gPackager )
				)
				( attribute "LOCATION" "U7D2"
					( Origin gFrontEnd )
				)
				( attribute "MATERIAL" "IC"
					( Origin gFrontEnd )
				)
				( attribute "PACK_TYPE" "SM"
					( Origin gFrontEnd )
				)
				( attribute "PART_NUMBER" "D66151-001"
					( Origin gFrontEnd )
				)
				( attribute "PHYS_PAGE" "92"
					( Origin gFrontEnd )
				)
				( attribute "ROOM" "PROC_SIDEBAND"
					( Origin gFrontEnd )
				)
				( attribute "ROT" "2"
					( Origin gFrontEnd )
				)
				( attribute "SEC" "1"
					( Origin gFrontEnd )
				)
				( attribute "SEC_TYPE" "SM"
					( Origin gFrontEnd )
				)
				( attribute "VER" "1"
					( Origin gFrontEnd )
				)
				( attribute "XY" "(-1750,2050)"
					( Origin gFrontEnd )
				)
				( attribute "CHIPS_PART_NAME" "GTL2014"
					( Origin gPackager )
				)
				( attribute "CDS_PART_NAME" "GTL2014_SM-IC,D66151-001"
					( Origin gPackager )
				)
				( objectStatus "U7D2" )
			)
			( gate "@baseboard_fab2_lib.baseboard_fab2(sch_1):page92_i37"
				( attribute "BOM_COST" "PROC_SIDEBAND"
					( Origin gFrontEnd )
				)
				( attribute "CDS_LIB" "dev_discrete"
					( Origin gPackager )
				)
				( attribute "CDS_LOCATION" "C3P49"
					( Origin gPackager )
				)
				( attribute "CDS_SEC" "1"
					( Origin gPackager )
				)
				( attribute "LOCATION" "C3P49"
					( Origin gFrontEnd )
				)
				( attribute "MATERIAL" "X7R"
					( Origin gFrontEnd )
				)
				( attribute "PACK_TYPE" "0402V"
					( Origin gFrontEnd )
				)
				( attribute "PART_NUMBER" "A36096-030"
					( Origin gFrontEnd )
				)
				( attribute "PHYS_PAGE" "92"
					( Origin gFrontEnd )
				)
				( attribute "ROOM" "PROC_SIDEBAND"
					( Origin gFrontEnd )
				)
				( attribute "ROT" "0"
					( Origin gFrontEnd )
				)
				( attribute "SEC" "1"
					( Origin gFrontEnd )
				)
				( attribute "SEC_TYPE" "0402V"
					( Origin gFrontEnd )
				)
				( attribute "TOLERANCE" "10%"
					( Origin gFrontEnd )
				)
				( attribute "VALUE" "0.1UF"
					( Origin gFrontEnd )
				)
				( attribute "VER" "1"
					( Origin gFrontEnd )
				)
				( attribute "VOLTAGE" "16V"
					( Units "uVoltage" "V" 1.000000)
					( Origin gFrontEnd )
				)
				( attribute "XY" "(-400,4800)"
					( Origin gFrontEnd )
				)
				( attribute "CHIPS_PART_NAME" "CAP_A"
					( Origin gPackager )
				)
				( attribute "CDS_PART_NAME" "CAP_A_0402V-0.1UF,16V,10%,X7R,A"
					( Origin gPackager )
				)
				( objectStatus "C3P49" )
			)
			( gate "@baseboard_fab2_lib.baseboard_fab2(sch_1):page92_i38"
				( attribute "BOM_COST" "PROC_SIDEBAND"
					( Origin gFrontEnd )
				)
				( attribute "CDS_LIB" "mstr_discrete"
					( Origin gPackager )
				)
				( attribute "CDS_LOCATION" "R3P49"
					( Origin gPackager )
				)
				( attribute "LOCATION" "R3P49"
					( Origin gFrontEnd )
				)
				( attribute "MATERIAL" "CHIP"
					( Origin gFrontEnd )
				)
				( attribute "PACK_TYPE" "0402"
					( Origin gFrontEnd )
				)
				( attribute "PART_NUMBER" "G21796-017"
					( Origin gFrontEnd )
				)
				( attribute "PHYS_PAGE" "92"
					( Origin gFrontEnd )
				)
				( attribute "ROOM" "PROC_SIDEBAND"
					( Origin gFrontEnd )
				)
				( attribute "ROT" "0"
					( Origin gFrontEnd )
				)
				( attribute "SEC" "1"
					( Origin gFrontEnd )
				)
				( attribute "SEC_TYPE" "0402"
					( Origin gFrontEnd )
				)
				( attribute "TOLERANCE" "1%"
					( Origin gFrontEnd )
				)
				( attribute "VALUE" "100.0"
					( Origin gFrontEnd )
				)
				( attribute "VER" "2"
					( Origin gFrontEnd )
				)
				( attribute "WATTAGE" "1/16W"
					( Origin gFrontEnd )
				)
				( attribute "XY" "(100,4800)"
					( Origin gFrontEnd )
				)
				( attribute "CHIPS_PART_NAME" "RES"
					( Origin gPackager )
				)
				( attribute "CDS_PART_NAME" "RES_0402-100.0,1%,1/16W,CHIP,GA"
					( Origin gPackager )
				)
				( attribute "CDS_SEC" "1"
					( Origin gPackager )
				)
				( objectStatus "R3P49" )
			)
			( gate "@baseboard_fab2_lib.baseboard_fab2(sch_1):page176_i175"
				( attribute "BOM_COST" "PROC_SIDEBAND"
					( Origin gFrontEnd )
				)
				( attribute "CDS_LIB" "mstr_discrete"
					( Origin gPackager )
				)
				( attribute "CDS_LOCATION" "R1W39"
					( Origin gPackager )
				)
				( attribute "CDS_SEC" "1"
					( Origin gPackager )
				)
				( attribute "LOCATION" "R1W39"
					( Origin gFrontEnd )
				)
				( attribute "MATERIAL" "CHIP"
					( Origin gFrontEnd )
				)
				( attribute "PACK_TYPE" "0402"
					( Origin gFrontEnd )
				)
				( attribute "PART_NUMBER" "G21497-005"
					( Origin gFrontEnd )
				)
				( attribute "PHYS_PAGE" "176"
					( Origin gFrontEnd )
				)
				( attribute "POP" "NOPOP"
					( Origin gFrontEnd )
				)
				( attribute "ROOM" "CPU0"
					( Origin gFrontEnd )
				)
				( attribute "ROT" "0"
					( Origin gFrontEnd )
				)
				( attribute "SEC" "1"
					( Origin gFrontEnd )
				)
				( attribute "SEC_TYPE" "0402"
					( Origin gFrontEnd )
				)
				( attribute "TOLERANCE" "5%"
					( Origin gFrontEnd )
				)
				( attribute "VALUE" "0.0"
					( Origin gFrontEnd )
				)
				( attribute "VER" "1"
					( Origin gFrontEnd )
				)
				( attribute "WATTAGE" "1/16W"
					( Origin gFrontEnd )
				)
				( attribute "XY" "(-5950,1550)"
					( Origin gFrontEnd )
				)
				( attribute "CHIPS_PART_NAME" "RES"
					( Origin gPackager )
				)
				( attribute "CDS_PART_NAME" "RES_0402-0.0,5%,1/16W,CHIP,G21A"
					( Origin gPackager )
				)
				( objectStatus "R1W39" )
			)
			( gate "@baseboard_fab2_lib.baseboard_fab2(sch_1):page92_i46"
				( attribute "BOM_COST" "PROC_SIDEBAND"
					( Origin gFrontEnd )
				)
				( attribute "CDS_LIB" "mstr_discrete"
					( Origin gPackager )
				)
				( attribute "CDS_LOCATION" "R3R1"
					( Origin gPackager )
				)
				( attribute "CDS_SEC" "1"
					( Origin gPackager )
				)
				( attribute "LOCATION" "R3R1"
					( Origin gFrontEnd )
				)
				( attribute "MATERIAL" "CHIP"
					( Origin gFrontEnd )
				)
				( attribute "PACK_TYPE" "0402"
					( Origin gFrontEnd )
				)
				( attribute "PART_NUMBER" "G21796-026"
					( Origin gFrontEnd )
				)
				( attribute "PHYS_PAGE" "92"
					( Origin gFrontEnd )
				)
				( attribute "ROOM" "PROC_SIDEBAND"
					( Origin gFrontEnd )
				)
				( attribute "ROT" "0"
					( Origin gFrontEnd )
				)
				( attribute "SEC" "1"
					( Origin gFrontEnd )
				)
				( attribute "SEC_TYPE" "0402"
					( Origin gFrontEnd )
				)
				( attribute "TOLERANCE" "1%"
					( Origin gFrontEnd )
				)
				( attribute "VALUE" "1.00K"
					( Origin gFrontEnd )
				)
				( attribute "VER" "1"
					( Origin gFrontEnd )
				)
				( attribute "WATTAGE" "1/16W"
					( Origin gFrontEnd )
				)
				( attribute "XY" "(-675,4400)"
					( Origin gFrontEnd )
				)
				( attribute "CHIPS_PART_NAME" "RES"
					( Origin gPackager )
				)
				( attribute "CDS_PART_NAME" "RES_0402-1.00K,1%,1/16W,CHIP,GA"
					( Origin gPackager )
				)
				( objectStatus "R3R1" )
			)
			( gate "@baseboard_fab2_lib.baseboard_fab2(sch_1):page92_i48"
				( attribute "BOM_COST" "PROC_SIDEBAND"
					( Origin gFrontEnd )
				)
				( attribute "CDS_LIB" "mstr_discrete"
					( Origin gPackager )
				)
				( attribute "CDS_LOCATION" "R7D32"
					( Origin gPackager )
				)
				( attribute "CDS_SEC" "1"
					( Origin gPackager )
				)
				( attribute "LOCATION" "R7D32"
					( Origin gFrontEnd )
				)
				( attribute "MATERIAL" "CHIP"
					( Origin gFrontEnd )
				)
				( attribute "PACK_TYPE" "0402"
					( Origin gFrontEnd )
				)
				( attribute "PART_NUMBER" "G21796-017"
					( Origin gFrontEnd )
				)
				( attribute "PHYS_PAGE" "92"
					( Origin gFrontEnd )
				)
				( attribute "ROOM" "PROC_SIDEBAND"
					( Origin gFrontEnd )
				)
				( attribute "ROT" "0"
					( Origin gFrontEnd )
				)
				( attribute "SEC" "1"
					( Origin gFrontEnd )
				)
				( attribute "SEC_TYPE" "0402"
					( Origin gFrontEnd )
				)
				( attribute "TOLERANCE" "1%"
					( Origin gFrontEnd )
				)
				( attribute "VALUE" "100.0"
					( Origin gFrontEnd )
				)
				( attribute "VER" "2"
					( Origin gFrontEnd )
				)
				( attribute "WATTAGE" "1/16W"
					( Origin gFrontEnd )
				)
				( attribute "XY" "(350,2550)"
					( Origin gFrontEnd )
				)
				( attribute "CHIPS_PART_NAME" "RES"
					( Origin gPackager )
				)
				( attribute "CDS_PART_NAME" "RES_0402-100.0,1%,1/16W,CHIP,GA"
					( Origin gPackager )
				)
				( objectStatus "R7D32" )
			)
			( gate "@baseboard_fab2_lib.baseboard_fab2(sch_1):page93_i148"
				( attribute "CDS_LIB" "w_hdl"
					( Origin gPackager )
				)
				( attribute "CDS_LMAN_SYM_OUTLINE" "-50,75,50,-75"
					( Origin gPackager )
				)
				( attribute "LOCATION" "R2T36"
					( Origin gFrontEnd )
				)
				( attribute "PACK_TYPE" "SMD-RG"
					( Origin gFrontEnd )
				)
				( attribute "PART_NUMBER" "64.37405.6DL"
					( Origin gFrontEnd )
				)
				( attribute "PHYS_PAGE" "93"
					( Origin gFrontEnd )
				)
				( attribute "ROT" "0"
					( Origin gFrontEnd )
				)
				( attribute "VALUE" "374R2F-1-GP"
					( Origin gFrontEnd )
				)
				( attribute "VER" "1"
					( Origin gFrontEnd )
				)
				( attribute "XY" "(2300,1075)"
					( Origin gFrontEnd )
				)
				( attribute "CHIPS_PART_NAME" "374R2F-1-GP"
					( Origin gPackager )
				)
				( attribute "CDS_PART_NAME" "374R2F-1-GP_SMD-RG-374R2F-1-GPA"
					( Origin gPackager )
				)
				( attribute "CDS_LOCATION" "R2T36"
					( Origin gPackager )
				)
				( attribute "CDS_SEC" "1"
					( Origin gPackager )
				)
				( attribute "SEC" "1"
					( Origin gPackager )
				)
				( attribute "ATTRIBUTE" "374 OHM"
					( Origin gFrontEnd )
				)
				( attribute "PACK_SIZE" "0402"
					( Origin gFrontEnd )
				)
				( attribute "RATED" "1/16W"
					( Origin gFrontEnd )
				)
				( attribute "TOLERANCE" "1%"
					( Origin gFrontEnd )
				)
				( objectStatus "R2T36" )
			)
			( gate "@baseboard_fab2_lib.baseboard_fab2(sch_1):page92_i52"
				( attribute "BOM_COST" "PROC_SIDEBAND"
					( Origin gFrontEnd )
				)
				( attribute "CDS_LIB" "dev_discrete"
					( Origin gPackager )
				)
				( attribute "CDS_LOCATION" "C7D5"
					( Origin gPackager )
				)
				( attribute "CDS_SEC" "1"
					( Origin gPackager )
				)
				( attribute "LOCATION" "C7D5"
					( Origin gFrontEnd )
				)
				( attribute "MATERIAL" "X7R"
					( Origin gFrontEnd )
				)
				( attribute "PACK_TYPE" "0402V"
					( Origin gFrontEnd )
				)
				( attribute "PART_NUMBER" "A36096-030"
					( Origin gFrontEnd )
				)
				( attribute "PHYS_PAGE" "92"
					( Origin gFrontEnd )
				)
				( attribute "ROOM" "PROC_SIDEBAND"
					( Origin gFrontEnd )
				)
				( attribute "ROT" "0"
					( Origin gFrontEnd )
				)
				( attribute "SEC" "1"
					( Origin gFrontEnd )
				)
				( attribute "SEC_TYPE" "0402V"
					( Origin gFrontEnd )
				)
				( attribute "TOLERANCE" "10%"
					( Origin gFrontEnd )
				)
				( attribute "VALUE" "0.1UF"
					( Origin gFrontEnd )
				)
				( attribute "VER" "1"
					( Origin gFrontEnd )
				)
				( attribute "VOLTAGE" "16V"
					( Units "uVoltage" "V" 1.000000)
					( Origin gFrontEnd )
				)
				( attribute "XY" "(-100,2550)"
					( Origin gFrontEnd )
				)
				( attribute "CHIPS_PART_NAME" "CAP_A"
					( Origin gPackager )
				)
				( attribute "CDS_PART_NAME" "CAP_A_0402V-0.1UF,16V,10%,X7R,A"
					( Origin gPackager )
				)
				( objectStatus "C7D5" )
			)
			( gate "@baseboard_fab2_lib.baseboard_fab2(sch_1):page92_i54"
				( attribute "BOM_COST" "PROC_SIDEBAND"
					( Origin gFrontEnd )
				)
				( attribute "CDS_LIB" "mstr_discrete"
					( Origin gPackager )
				)
				( attribute "CDS_LOCATION" "R7D26"
					( Origin gPackager )
				)
				( attribute "CDS_SEC" "1"
					( Origin gPackager )
				)
				( attribute "LOCATION" "R7D26"
					( Origin gFrontEnd )
				)
				( attribute "MATERIAL" "CHIP"
					( Origin gFrontEnd )
				)
				( attribute "PACK_TYPE" "0402"
					( Origin gFrontEnd )
				)
				( attribute "PART_NUMBER" "G21796-026"
					( Origin gFrontEnd )
				)
				( attribute "PHYS_PAGE" "92"
					( Origin gFrontEnd )
				)
				( attribute "ROOM" "PROC_SIDEBAND"
					( Origin gFrontEnd )
				)
				( attribute "ROT" "0"
					( Origin gFrontEnd )
				)
				( attribute "SEC" "1"
					( Origin gFrontEnd )
				)
				( attribute "SEC_TYPE" "0402"
					( Origin gFrontEnd )
				)
				( attribute "TOLERANCE" "1%"
					( Origin gFrontEnd )
				)
				( attribute "VALUE" "1.00K"
					( Origin gFrontEnd )
				)
				( attribute "VER" "1"
					( Origin gFrontEnd )
				)
				( attribute "WATTAGE" "1/16W"
					( Origin gFrontEnd )
				)
				( attribute "XY" "(-600,2200)"
					( Origin gFrontEnd )
				)
				( attribute "CHIPS_PART_NAME" "RES"
					( Origin gPackager )
				)
				( attribute "CDS_PART_NAME" "RES_0402-1.00K,1%,1/16W,CHIP,GA"
					( Origin gPackager )
				)
				( objectStatus "R7D26" )
			)
			( gate "@baseboard_fab2_lib.baseboard_fab2(sch_1):page92_i61"
				( attribute "BOM_COST" "PROC_SIDEBAND"
					( Origin gFrontEnd )
				)
				( attribute "CDS_LIB" "mstr_discrete"
					( Origin gPackager )
				)
				( attribute "CDS_LOCATION" "R3R3"
					( Origin gPackager )
				)
				( attribute "CDS_SEC" "1"
					( Origin gPackager )
				)
				( attribute "LOCATION" "R3R3"
					( Origin gFrontEnd )
				)
				( attribute "MATERIAL" "CHIP"
					( Origin gFrontEnd )
				)
				( attribute "PACK_TYPE" "0402"
					( Origin gFrontEnd )
				)
				( attribute "PART_NUMBER" "G21796-074"
					( Origin gFrontEnd )
				)
				( attribute "PHYS_PAGE" "92"
					( Origin gFrontEnd )
				)
				( attribute "ROOM" "PROC_SIDEBAND"
					( Origin gFrontEnd )
				)
				( attribute "ROT" "0"
					( Origin gFrontEnd )
				)
				( attribute "SEC" "1"
					( Origin gFrontEnd )
				)
				( attribute "SEC_TYPE" "0402"
					( Origin gFrontEnd )
				)
				( attribute "TOLERANCE" "1%"
					( Origin gFrontEnd )
				)
				( attribute "VALUE" "33.2"
					( Origin gFrontEnd )
				)
				( attribute "VER" "1"
					( Origin gFrontEnd )
				)
				( attribute "WATTAGE" "1/16W"
					( Origin gFrontEnd )
				)
				( attribute "XY" "(-125,3550)"
					( Origin gFrontEnd )
				)
				( attribute "CHIPS_PART_NAME" "RES"
					( Origin gPackager )
				)
				( attribute "CDS_PART_NAME" "RES_0402-33.2,1%,1/16W,CHIP,G2A"
					( Origin gPackager )
				)
				( objectStatus "R3R3" )
			)
			( gate "@baseboard_fab2_lib.baseboard_fab2(sch_1):page92_i64"
				( attribute "BOM_COST" "PROC_SIDEBAND"
					( Origin gFrontEnd )
				)
				( attribute "CDS_LIB" "mstr_discrete"
					( Origin gPackager )
				)
				( attribute "CDS_LOCATION" "R6D9"
					( Origin gPackager )
				)
				( attribute "CDS_SEC" "1"
					( Origin gPackager )
				)
				( attribute "LOCATION" "R6D9"
					( Origin gFrontEnd )
				)
				( attribute "MATERIAL" "CHIP"
					( Origin gFrontEnd )
				)
				( attribute "PACK_TYPE" "0402"
					( Origin gFrontEnd )
				)
				( attribute "PART_NUMBER" "G21796-009"
					( Origin gFrontEnd )
				)
				( attribute "PHYS_PAGE" "92"
					( Origin gFrontEnd )
				)
				( attribute "ROOM" "PROC_SIDEBAND"
					( Origin gFrontEnd )
				)
				( attribute "ROT" "2"
					( Origin gFrontEnd )
				)
				( attribute "SEC" "1"
					( Origin gFrontEnd )
				)
				( attribute "SEC_TYPE" "0402"
					( Origin gFrontEnd )
				)
				( attribute "TOLERANCE" "1%"
					( Origin gFrontEnd )
				)
				( attribute "VALUE" "150.0"
					( Origin gFrontEnd )
				)
				( attribute "VER" "2"
					( Origin gFrontEnd )
				)
				( attribute "WATTAGE" "1/16W"
					( Origin gFrontEnd )
				)
				( attribute "XY" "(-4600,1825)"
					( Origin gFrontEnd )
				)
				( attribute "CHIPS_PART_NAME" "RES"
					( Origin gPackager )
				)
				( attribute "CDS_PART_NAME" "RES_0402-150.0,1%,1/16W,CHIP,GA"
					( Origin gPackager )
				)
				( objectStatus "R6D9" )
			)
			( gate "@baseboard_fab2_lib.baseboard_fab2(sch_1):page92_i65"
				( attribute "BOM_COST" "PROC_SIDEBAND"
					( Origin gFrontEnd )
				)
				( attribute "CDS_LIB" "mstr_discrete"
					( Origin gPackager )
				)
				( attribute "CDS_LOCATION" "R7P27"
					( Origin gPackager )
				)
				( attribute "CDS_SEC" "1"
					( Origin gPackager )
				)
				( attribute "LOCATION" "R7P27"
					( Origin gFrontEnd )
				)
				( attribute "MATERIAL" "CHIP"
					( Origin gFrontEnd )
				)
				( attribute "PACK_TYPE" "0402"
					( Origin gFrontEnd )
				)
				( attribute "PART_NUMBER" "G21796-009"
					( Origin gFrontEnd )
				)
				( attribute "PHYS_PAGE" "92"
					( Origin gFrontEnd )
				)
				( attribute "ROOM" "PROC_SIDEBAND"
					( Origin gFrontEnd )
				)
				( attribute "ROT" "0"
					( Origin gFrontEnd )
				)
				( attribute "SEC" "1"
					( Origin gFrontEnd )
				)
				( attribute "SEC_TYPE" "0402"
					( Origin gFrontEnd )
				)
				( attribute "TOLERANCE" "1%"
					( Origin gFrontEnd )
				)
				( attribute "VALUE" "150.0"
					( Origin gFrontEnd )
				)
				( attribute "VER" "2"
					( Origin gFrontEnd )
				)
				( attribute "WATTAGE" "1/16W"
					( Origin gFrontEnd )
				)
				( attribute "XY" "(-4275,1800)"
					( Origin gFrontEnd )
				)
				( attribute "CHIPS_PART_NAME" "RES"
					( Origin gPackager )
				)
				( attribute "CDS_PART_NAME" "RES_0402-150.0,1%,1/16W,CHIP,GA"
					( Origin gPackager )
				)
				( objectStatus "R7P27" )
			)
			( gate "@baseboard_fab2_lib.baseboard_fab2(sch_1):page92_i67"
				( attribute "BOM_COST" "PROC_SIDEBAND"
					( Origin gFrontEnd )
				)
				( attribute "CDS_LIB" "mstr_discrete"
					( Origin gPackager )
				)
				( attribute "CDS_LOCATION" "R7D28"
					( Origin gPackager )
				)
				( attribute "CDS_SEC" "1"
					( Origin gPackager )
				)
				( attribute "LOCATION" "R7D28"
					( Origin gFrontEnd )
				)
				( attribute "MATERIAL" "CHIP"
					( Origin gFrontEnd )
				)
				( attribute "PACK_TYPE" "0402"
					( Origin gFrontEnd )
				)
				( attribute "PART_NUMBER" "G21497-005"
					( Origin gFrontEnd )
				)
				( attribute "PHYS_PAGE" "92"
					( Origin gFrontEnd )
				)
				( attribute "ROOM" "PROC_SIDEBAND"
					( Origin gFrontEnd )
				)
				( attribute "ROT" "0"
					( Origin gFrontEnd )
				)
				( attribute "SEC" "1"
					( Origin gFrontEnd )
				)
				( attribute "SEC_TYPE" "0402"
					( Origin gFrontEnd )
				)
				( attribute "TOLERANCE" "5%"
					( Origin gFrontEnd )
				)
				( attribute "VALUE" "0.0"
					( Origin gFrontEnd )
				)
				( attribute "VER" "1"
					( Origin gFrontEnd )
				)
				( attribute "WATTAGE" "1/16W"
					( Origin gFrontEnd )
				)
				( attribute "XY" "(-3725,1275)"
					( Origin gFrontEnd )
				)
				( attribute "CHIPS_PART_NAME" "RES"
					( Origin gPackager )
				)
				( attribute "CDS_PART_NAME" "RES_0402-0.0,5%,1/16W,CHIP,G21A"
					( Origin gPackager )
				)
				( objectStatus "R7D28" )
			)
			( gate "@baseboard_fab2_lib.baseboard_fab2(sch_1):page92_i68"
				( attribute "BOM_COST" "PROC_SIDEBAND"
					( Origin gFrontEnd )
				)
				( attribute "CDS_LIB" "mstr_discrete"
					( Origin gPackager )
				)
				( attribute "CDS_LOCATION" "R7D27"
					( Origin gPackager )
				)
				( attribute "CDS_SEC" "1"
					( Origin gPackager )
				)
				( attribute "LOCATION" "R7D27"
					( Origin gFrontEnd )
				)
				( attribute "MATERIAL" "CHIP"
					( Origin gFrontEnd )
				)
				( attribute "PACK_TYPE" "0402"
					( Origin gFrontEnd )
				)
				( attribute "PART_NUMBER" "G21497-005"
					( Origin gFrontEnd )
				)
				( attribute "PHYS_PAGE" "92"
					( Origin gFrontEnd )
				)
				( attribute "ROOM" "PROC_SIDEBAND"
					( Origin gFrontEnd )
				)
				( attribute "ROT" "0"
					( Origin gFrontEnd )
				)
				( attribute "SEC" "1"
					( Origin gFrontEnd )
				)
				( attribute "SEC_TYPE" "0402"
					( Origin gFrontEnd )
				)
				( attribute "TOLERANCE" "5%"
					( Origin gFrontEnd )
				)
				( attribute "VALUE" "0.0"
					( Origin gFrontEnd )
				)
				( attribute "VER" "1"
					( Origin gFrontEnd )
				)
				( attribute "WATTAGE" "1/16W"
					( Origin gFrontEnd )
				)
				( attribute "XY" "(-3775,1550)"
					( Origin gFrontEnd )
				)
				( attribute "CHIPS_PART_NAME" "RES"
					( Origin gPackager )
				)
				( attribute "CDS_PART_NAME" "RES_0402-0.0,5%,1/16W,CHIP,G21A"
					( Origin gPackager )
				)
				( objectStatus "R7D27" )
			)
			( gate "@baseboard_fab2_lib.baseboard_fab2(sch_1):page92_i70"
				( attribute "BOM_COST" "PROC_SIDEBAND"
					( Origin gFrontEnd )
				)
				( attribute "CDS_LIB" "mstr_discrete"
					( Origin gPackager )
				)
				( attribute "CDS_LOCATION" "R7D25"
					( Origin gPackager )
				)
				( attribute "CDS_SEC" "1"
					( Origin gPackager )
				)
				( attribute "LOCATION" "R7D25"
					( Origin gFrontEnd )
				)
				( attribute "MATERIAL" "CHIP"
					( Origin gFrontEnd )
				)
				( attribute "PACK_TYPE" "0402"
					( Origin gFrontEnd )
				)
				( attribute "PART_NUMBER" "G21796-074"
					( Origin gFrontEnd )
				)
				( attribute "PHYS_PAGE" "92"
					( Origin gFrontEnd )
				)
				( attribute "ROOM" "PROC_SIDEBAND"
					( Origin gFrontEnd )
				)
				( attribute "ROT" "0"
					( Origin gFrontEnd )
				)
				( attribute "SEC" "1"
					( Origin gFrontEnd )
				)
				( attribute "SEC_TYPE" "0402"
					( Origin gFrontEnd )
				)
				( attribute "TOLERANCE" "1%"
					( Origin gFrontEnd )
				)
				( attribute "VALUE" "33.2"
					( Origin gFrontEnd )
				)
				( attribute "VER" "1"
					( Origin gFrontEnd )
				)
				( attribute "WATTAGE" "1/16W"
					( Origin gFrontEnd )
				)
				( attribute "XY" "(-100,1250)"
					( Origin gFrontEnd )
				)
				( attribute "CHIPS_PART_NAME" "RES"
					( Origin gPackager )
				)
				( attribute "CDS_PART_NAME" "RES_0402-33.2,1%,1/16W,CHIP,G2A"
					( Origin gPackager )
				)
				( objectStatus "R7D25" )
			)
			( gate "@baseboard_fab2_lib.baseboard_fab2(sch_1):page92_i75"
				( attribute "CDS_LIB" "mstr_discrete"
					( Origin gPackager )
				)
				( attribute "CDS_LOCATION" "R3R2"
					( Origin gPackager )
				)
				( attribute "CDS_SEC" "1"
					( Origin gPackager )
				)
				( attribute "LOCATION" "R3R2"
					( Origin gFrontEnd )
				)
				( attribute "MATERIAL" "CHIP"
					( Origin gFrontEnd )
				)
				( attribute "PACK_TYPE" "0402"
					( Origin gFrontEnd )
				)
				( attribute "PART_NUMBER" "G21796-026"
					( Origin gFrontEnd )
				)
				( attribute "PHYS_PAGE" "92"
					( Origin gFrontEnd )
				)
				( attribute "ROOM" "PROC_SIDEBAND"
					( Origin gFrontEnd )
				)
				( attribute "ROT" "0"
					( Origin gFrontEnd )
				)
				( attribute "SEC" "1"
					( Origin gFrontEnd )
				)
				( attribute "SEC_TYPE" "0402"
					( Origin gFrontEnd )
				)
				( attribute "TOLERANCE" "1%"
					( Origin gFrontEnd )
				)
				( attribute "VALUE" "1.00K"
					( Origin gFrontEnd )
				)
				( attribute "VER" "2"
					( Origin gFrontEnd )
				)
				( attribute "WATTAGE" "1/16W"
					( Origin gFrontEnd )
				)
				( attribute "XY" "(-2925,3900)"
					( Origin gFrontEnd )
				)
				( attribute "CHIPS_PART_NAME" "RES"
					( Origin gPackager )
				)
				( attribute "CDS_PART_NAME" "RES_0402-1.00K,1%,1/16W,CHIP,GA"
					( Origin gPackager )
				)
				( objectStatus "R3R2" )
			)
			( gate "@baseboard_fab2_lib.baseboard_fab2(sch_1):page92_i79"
				( attribute "BOM_COST" "PROC"
					( Origin gFrontEnd )
				)
				( attribute "CDS_LIB" "mstr_discrete"
					( Origin gPackager )
				)
				( attribute "CDS_LOCATION" "C7D4"
					( Origin gPackager )
				)
				( attribute "CDS_SEC" "1"
					( Origin gPackager )
				)
				( attribute "LOCATION" "C7D4"
					( Origin gFrontEnd )
				)
				( attribute "MATERIAL" "X6S"
					( Origin gFrontEnd )
				)
				( attribute "PACK_TYPE" "0402"
					( Origin gFrontEnd )
				)
				( attribute "PART_NUMBER" "D97712-011"
					( Origin gFrontEnd )
				)
				( attribute "PHYS_PAGE" "92"
					( Origin gFrontEnd )
				)
				( attribute "ROOM" "PROC_SIDEBAND"
					( Origin gFrontEnd )
				)
				( attribute "ROT" "0"
					( Origin gFrontEnd )
				)
				( attribute "SEC" "1"
					( Origin gFrontEnd )
				)
				( attribute "SEC_TYPE" "0402"
					( Origin gFrontEnd )
				)
				( attribute "TOLERANCE" "10%"
					( Origin gFrontEnd )
				)
				( attribute "VALUE" "1.0UF"
					( Origin gFrontEnd )
				)
				( attribute "VER" "1"
					( Origin gFrontEnd )
				)
				( attribute "VOLTAGE" "16V"
					( Units "uVoltage" "V" 1.000000)
					( Origin gFrontEnd )
				)
				( attribute "XY" "(-900,2525)"
					( Origin gFrontEnd )
				)
				( attribute "CHIPS_PART_NAME" "CAP"
					( Origin gPackager )
				)
				( attribute "CDS_PART_NAME" "CAP_0402-1.0UF,16V,10%,X6S,D97A"
					( Origin gPackager )
				)
				( objectStatus "C7D4" )
			)
			( gate "@baseboard_fab2_lib.baseboard_fab2(sch_1):page92_i84"
				( attribute "BOM_COST" "PROC"
					( Origin gFrontEnd )
				)
				( attribute "CDS_LIB" "mstr_discrete"
					( Origin gPackager )
				)
				( attribute "CDS_LOCATION" "C3P50"
					( Origin gPackager )
				)
				( attribute "CDS_SEC" "1"
					( Origin gPackager )
				)
				( attribute "LOCATION" "C3P50"
					( Origin gFrontEnd )
				)
				( attribute "MATERIAL" "X6S"
					( Origin gFrontEnd )
				)
				( attribute "PACK_TYPE" "0402"
					( Origin gFrontEnd )
				)
				( attribute "PART_NUMBER" "D97712-011"
					( Origin gFrontEnd )
				)
				( attribute "PHYS_PAGE" "92"
					( Origin gFrontEnd )
				)
				( attribute "ROOM" "PROC_SIDEBAND"
					( Origin gFrontEnd )
				)
				( attribute "ROT" "0"
					( Origin gFrontEnd )
				)
				( attribute "SEC" "1"
					( Origin gFrontEnd )
				)
				( attribute "SEC_TYPE" "0402"
					( Origin gFrontEnd )
				)
				( attribute "TOLERANCE" "10%"
					( Origin gFrontEnd )
				)
				( attribute "VALUE" "1.0UF"
					( Origin gFrontEnd )
				)
				( attribute "VER" "1"
					( Origin gFrontEnd )
				)
				( attribute "VOLTAGE" "16V"
					( Units "uVoltage" "V" 1.000000)
					( Origin gFrontEnd )
				)
				( attribute "XY" "(-1025,4725)"
					( Origin gFrontEnd )
				)
				( attribute "CHIPS_PART_NAME" "CAP"
					( Origin gPackager )
				)
				( attribute "CDS_PART_NAME" "CAP_0402-1.0UF,16V,10%,X6S,D97A"
					( Origin gPackager )
				)
				( objectStatus "C3P50" )
			)
			( gate "@baseboard_fab2_lib.baseboard_fab2(sch_1):page92_i92"
				( attribute "BOM_COST" "PROC"
					( Origin gFrontEnd )
				)
				( attribute "CDS_LIB" "mstr_discrete"
					( Origin gPackager )
				)
				( attribute "CDS_LOCATION" "R2T44"
					( Origin gPackager )
				)
				( attribute "CDS_SEC" "1"
					( Origin gPackager )
				)
				( attribute "LOCATION" "R2T44"
					( Origin gFrontEnd )
				)
				( attribute "MATERIAL" "CHIP"
					( Origin gFrontEnd )
				)
				( attribute "PACK_TYPE" "0402"
					( Origin gFrontEnd )
				)
				( attribute "PART_NUMBER" "G21497-005"
					( Origin gFrontEnd )
				)
				( attribute "PHYS_PAGE" "92"
					( Origin gFrontEnd )
				)
				( attribute "ROOM" "PROC_SIDEBAND"
					( Origin gFrontEnd )
				)
				( attribute "ROT" "0"
					( Origin gFrontEnd )
				)
				( attribute "SEC" "1"
					( Origin gPackager )
				)
				( attribute "TOLERANCE" "5%"
					( Origin gFrontEnd )
				)
				( attribute "VALUE" "0.0"
					( Origin gFrontEnd )
				)
				( attribute "VER" "1"
					( Origin gFrontEnd )
				)
				( attribute "WATTAGE" "1/16W"
					( Origin gFrontEnd )
				)
				( attribute "XY" "(-4725,2550)"
					( Origin gFrontEnd )
				)
				( attribute "CHIPS_PART_NAME" "RES"
					( Origin gPackager )
				)
				( attribute "CDS_PART_NAME" "RES_0402-0.0,5%,1/16W,CHIP,G21A"
					( Origin gPackager )
				)
				( objectStatus "R2T44" )
			)
			( gate "@baseboard_fab2_lib.baseboard_fab2(sch_1):page92_i93"
				( attribute "BOM_COST" "PROC"
					( Origin gFrontEnd )
				)
				( attribute "CDS_LIB" "mstr_discrete"
					( Origin gPackager )
				)
				( attribute "CDS_LOCATION" "R2T40"
					( Origin gPackager )
				)
				( attribute "CDS_SEC" "1"
					( Origin gPackager )
				)
				( attribute "LOCATION" "R2T40"
					( Origin gFrontEnd )
				)
				( attribute "MATERIAL" "CHIP"
					( Origin gFrontEnd )
				)
				( attribute "PACK_TYPE" "0402"
					( Origin gFrontEnd )
				)
				( attribute "PART_NUMBER" "G21497-005"
					( Origin gFrontEnd )
				)
				( attribute "PHYS_PAGE" "92"
					( Origin gFrontEnd )
				)
				( attribute "ROOM" "PROC_SIDEBAND"
					( Origin gFrontEnd )
				)
				( attribute "ROT" "0"
					( Origin gFrontEnd )
				)
				( attribute "SEC" "1"
					( Origin gPackager )
				)
				( attribute "TOLERANCE" "5%"
					( Origin gFrontEnd )
				)
				( attribute "VALUE" "0.0"
					( Origin gFrontEnd )
				)
				( attribute "VER" "1"
					( Origin gFrontEnd )
				)
				( attribute "WATTAGE" "1/16W"
					( Origin gFrontEnd )
				)
				( attribute "XY" "(-4750,2800)"
					( Origin gFrontEnd )
				)
				( attribute "CHIPS_PART_NAME" "RES"
					( Origin gPackager )
				)
				( attribute "CDS_PART_NAME" "RES_0402-0.0,5%,1/16W,CHIP,G21A"
					( Origin gPackager )
				)
				( objectStatus "R2T40" )
			)
			( gate "@baseboard_fab2_lib.baseboard_fab2(sch_1):page92_i94"
				( attribute "BOM_COST" "PROC"
					( Origin gFrontEnd )
				)
				( attribute "CDS_LIB" "mstr_discrete"
					( Origin gPackager )
				)
				( attribute "CDS_LOCATION" "R2T37"
					( Origin gPackager )
				)
				( attribute "CDS_SEC" "1"
					( Origin gPackager )
				)
				( attribute "LOCATION" "R2T37"
					( Origin gFrontEnd )
				)
				( attribute "MATERIAL" "CHIP"
					( Origin gFrontEnd )
				)
				( attribute "PACK_TYPE" "0402"
					( Origin gFrontEnd )
				)
				( attribute "PART_NUMBER" "G21796-004"
					( Origin gFrontEnd )
				)
				( attribute "PHYS_PAGE" "92"
					( Origin gFrontEnd )
				)
				( attribute "ROOM" "PROC_SIDEBAND"
					( Origin gFrontEnd )
				)
				( attribute "ROT" "0"
					( Origin gFrontEnd )
				)
				( attribute "SEC" "1"
					( Origin gPackager )
				)
				( attribute "TOLERANCE" "1%"
					( Origin gFrontEnd )
				)
				( attribute "VALUE" "200.0"
					( Origin gFrontEnd )
				)
				( attribute "VER" "2"
					( Origin gFrontEnd )
				)
				( attribute "WATTAGE" "1/16W"
					( Origin gFrontEnd )
				)
				( attribute "XY" "(-4000,2950)"
					( Origin gFrontEnd )
				)
				( attribute "CHIPS_PART_NAME" "RES"
					( Origin gPackager )
				)
				( attribute "CDS_PART_NAME" "RES_0402-200.0,1%,1/16W,CHIP,GA"
					( Origin gPackager )
				)
				( objectStatus "R2T37" )
			)
			( gate "@baseboard_fab2_lib.baseboard_fab2(sch_1):page92_i96"
				( attribute "BOM_COST" "PROC"
					( Origin gFrontEnd )
				)
				( attribute "CDS_LIB" "mstr_discrete"
					( Origin gPackager )
				)
				( attribute "CDS_LOCATION" "R2T43"
					( Origin gPackager )
				)
				( attribute "CDS_SEC" "1"
					( Origin gPackager )
				)
				( attribute "LOCATION" "R2T43"
					( Origin gFrontEnd )
				)
				( attribute "MATERIAL" "CHIP"
					( Origin gFrontEnd )
				)
				( attribute "PACK_TYPE" "0402"
					( Origin gFrontEnd )
				)
				( attribute "PART_NUMBER" "G21796-267"
					( Origin gFrontEnd )
				)
				( attribute "PHYS_PAGE" "92"
					( Origin gFrontEnd )
				)
				( attribute "ROOM" "PROC_SIDEBAND"
					( Origin gFrontEnd )
				)
				( attribute "ROT" "0"
					( Origin gFrontEnd )
				)
				( attribute "SEC" "1"
					( Origin gPackager )
				)
				( attribute "TOLERANCE" "1.0%"
					( Origin gFrontEnd )
				)
				( attribute "VALUE" "75"
					( Origin gFrontEnd )
				)
				( attribute "VER" "1"
					( Origin gFrontEnd )
				)
				( attribute "WATTAGE" "1/16W"
					( Origin gFrontEnd )
				)
				( attribute "XY" "(-3675,2675)"
					( Origin gFrontEnd )
				)
				( attribute "CHIPS_PART_NAME" "RES"
					( Origin gPackager )
				)
				( attribute "CDS_PART_NAME" "RES_0402-75,1.0%,1/16W,CHIP,G2A"
					( Origin gPackager )
				)
				( objectStatus "R2T43" )
			)
			( gate "@baseboard_fab2_lib.baseboard_fab2(sch_1):page92_i97"
				( attribute "BOM_COST" "PROC"
					( Origin gFrontEnd )
				)
				( attribute "CDS_LIB" "mstr_discrete"
					( Origin gPackager )
				)
				( attribute "CDS_LOCATION" "R3P59"
					( Origin gPackager )
				)
				( attribute "CDS_SEC" "1"
					( Origin gPackager )
				)
				( attribute "LOCATION" "R3P59"
					( Origin gFrontEnd )
				)
				( attribute "MATERIAL" "CHIP"
					( Origin gFrontEnd )
				)
				( attribute "PACK_TYPE" "0402"
					( Origin gFrontEnd )
				)
				( attribute "PART_NUMBER" "G21497-005"
					( Origin gFrontEnd )
				)
				( attribute "PHYS_PAGE" "92"
					( Origin gFrontEnd )
				)
				( attribute "ROOM" "PROC_SIDEBAND"
					( Origin gFrontEnd )
				)
				( attribute "ROT" "0"
					( Origin gFrontEnd )
				)
				( attribute "SEC" "1"
					( Origin gFrontEnd )
				)
				( attribute "SEC_TYPE" "0402"
					( Origin gFrontEnd )
				)
				( attribute "TOLERANCE" "5%"
					( Origin gFrontEnd )
				)
				( attribute "VALUE" "0.0"
					( Origin gFrontEnd )
				)
				( attribute "VER" "1"
					( Origin gFrontEnd )
				)
				( attribute "WATTAGE" "1/16W"
					( Origin gFrontEnd )
				)
				( attribute "XY" "(-3775,4350)"
					( Origin gFrontEnd )
				)
				( attribute "CHIPS_PART_NAME" "RES"
					( Origin gPackager )
				)
				( attribute "CDS_PART_NAME" "RES_0402-0.0,5%,1/16W,CHIP,G21A"
					( Origin gPackager )
				)
				( objectStatus "R3P59" )
			)
			( gate "@baseboard_fab2_lib.baseboard_fab2(sch_1):page92_i98"
				( attribute "BOM_COST" "PROC"
					( Origin gFrontEnd )
				)
				( attribute "CDS_LIB" "mstr_discrete"
					( Origin gPackager )
				)
				( attribute "CDS_LOCATION" "R3P58"
					( Origin gPackager )
				)
				( attribute "CDS_SEC" "1"
					( Origin gPackager )
				)
				( attribute "LOCATION" "R3P58"
					( Origin gFrontEnd )
				)
				( attribute "MATERIAL" "CHIP"
					( Origin gFrontEnd )
				)
				( attribute "PACK_TYPE" "0402"
					( Origin gFrontEnd )
				)
				( attribute "PART_NUMBER" "G21497-005"
					( Origin gFrontEnd )
				)
				( attribute "PHYS_PAGE" "92"
					( Origin gFrontEnd )
				)
				( attribute "ROOM" "PROC_SIDEBAND"
					( Origin gFrontEnd )
				)
				( attribute "ROT" "0"
					( Origin gFrontEnd )
				)
				( attribute "SEC" "1"
					( Origin gFrontEnd )
				)
				( attribute "SEC_TYPE" "0402"
					( Origin gFrontEnd )
				)
				( attribute "TOLERANCE" "5%"
					( Origin gFrontEnd )
				)
				( attribute "VALUE" "0.0"
					( Origin gFrontEnd )
				)
				( attribute "VER" "1"
					( Origin gFrontEnd )
				)
				( attribute "WATTAGE" "1/16W"
					( Origin gFrontEnd )
				)
				( attribute "XY" "(-3750,4100)"
					( Origin gFrontEnd )
				)
				( attribute "CHIPS_PART_NAME" "RES"
					( Origin gPackager )
				)
				( attribute "CDS_PART_NAME" "RES_0402-0.0,5%,1/16W,CHIP,G21A"
					( Origin gPackager )
				)
				( objectStatus "R3P58" )
			)
			( gate "@baseboard_fab2_lib.baseboard_fab2(sch_1):page92_i100"
				( attribute "BOM_COST" "PROC"
					( Origin gFrontEnd )
				)
				( attribute "CDS_LIB" "mstr_discrete"
					( Origin gPackager )
				)
				( attribute "CDS_LOCATION" "R7P18"
					( Origin gPackager )
				)
				( attribute "CDS_SEC" "1"
					( Origin gPackager )
				)
				( attribute "LOCATION" "R7P18"
					( Origin gFrontEnd )
				)
				( attribute "MATERIAL" "CHIP"
					( Origin gFrontEnd )
				)
				( attribute "PACK_TYPE" "0402"
					( Origin gFrontEnd )
				)
				( attribute "PART_NUMBER" "G21796-009"
					( Origin gFrontEnd )
				)
				( attribute "PHYS_PAGE" "92"
					( Origin gFrontEnd )
				)
				( attribute "ROOM" "PROC_SIDEBAND"
					( Origin gFrontEnd )
				)
				( attribute "ROT" "0"
					( Origin gFrontEnd )
				)
				( attribute "SEC" "1"
					( Origin gFrontEnd )
				)
				( attribute "SEC_TYPE" "0402"
					( Origin gFrontEnd )
				)
				( attribute "TOLERANCE" "1%"
					( Origin gFrontEnd )
				)
				( attribute "VALUE" "150.0"
					( Origin gFrontEnd )
				)
				( attribute "VER" "2"
					( Origin gFrontEnd )
				)
				( attribute "WATTAGE" "1/16W"
					( Origin gFrontEnd )
				)
				( attribute "XY" "(-4350,4600)"
					( Origin gFrontEnd )
				)
				( attribute "CHIPS_PART_NAME" "RES"
					( Origin gPackager )
				)
				( attribute "CDS_PART_NAME" "RES_0402-150.0,1%,1/16W,CHIP,GA"
					( Origin gPackager )
				)
				( objectStatus "R7P18" )
			)
			( gate "@baseboard_fab2_lib.baseboard_fab2(sch_1):page92_i101"
				( attribute "BOM_COST" "PROC"
					( Origin gFrontEnd )
				)
				( attribute "CDS_LIB" "mstr_discrete"
					( Origin gPackager )
				)
				( attribute "CDS_LOCATION" "R4R2"
					( Origin gPackager )
				)
				( attribute "CDS_SEC" "1"
					( Origin gPackager )
				)
				( attribute "LOCATION" "R4R2"
					( Origin gFrontEnd )
				)
				( attribute "MATERIAL" "CHIP"
					( Origin gFrontEnd )
				)
				( attribute "PACK_TYPE" "0402"
					( Origin gFrontEnd )
				)
				( attribute "PART_NUMBER" "G21796-009"
					( Origin gFrontEnd )
				)
				( attribute "PHYS_PAGE" "92"
					( Origin gFrontEnd )
				)
				( attribute "ROOM" "PROC_SIDEBAND"
					( Origin gFrontEnd )
				)
				( attribute "ROT" "2"
					( Origin gFrontEnd )
				)
				( attribute "SEC" "1"
					( Origin gFrontEnd )
				)
				( attribute "SEC_TYPE" "0402"
					( Origin gFrontEnd )
				)
				( attribute "TOLERANCE" "1%"
					( Origin gFrontEnd )
				)
				( attribute "VALUE" "150.0"
					( Origin gFrontEnd )
				)
				( attribute "VER" "2"
					( Origin gFrontEnd )
				)
				( attribute "WATTAGE" "1/16W"
					( Origin gFrontEnd )
				)
				( attribute "XY" "(-4450,4600)"
					( Origin gFrontEnd )
				)
				( attribute "CHIPS_PART_NAME" "RES"
					( Origin gPackager )
				)
				( attribute "CDS_PART_NAME" "RES_0402-150.0,1%,1/16W,CHIP,GA"
					( Origin gPackager )
				)
				( objectStatus "R4R2" )
			)
			( gate "@baseboard_fab2_lib.baseboard_fab2(sch_1):page93_i13"
				( attribute "BOM_COST" "PROC"
					( Origin gFrontEnd )
				)
				( attribute "CDS_LIB" "mstr_discrete"
					( Origin gPackager )
				)
				( attribute "CDS_LOCATION" "R2T27"
					( Origin gPackager )
				)
				( attribute "CDS_SEC" "1"
					( Origin gPackager )
				)
				( attribute "LOCATION" "R2T27"
					( Origin gFrontEnd )
				)
				( attribute "MATERIAL" "CHIP"
					( Origin gFrontEnd )
				)
				( attribute "PACK_TYPE" "0402"
					( Origin gFrontEnd )
				)
				( attribute "PART_NUMBER" "G21497-005"
					( Origin gFrontEnd )
				)
				( attribute "PHYS_PAGE" "93"
					( Origin gFrontEnd )
				)
				( attribute "ROOM" "PROC_SIDEBAND"
					( Origin gFrontEnd )
				)
				( attribute "ROT" "0"
					( Origin gFrontEnd )
				)
				( attribute "SEC" "1"
					( Origin gFrontEnd )
				)
				( attribute "SEC_TYPE" "0402"
					( Origin gFrontEnd )
				)
				( attribute "TOLERANCE" "5%"
					( Origin gFrontEnd )
				)
				( attribute "VALUE" "0.0"
					( Origin gFrontEnd )
				)
				( attribute "VER" "1"
					( Origin gFrontEnd )
				)
				( attribute "WATTAGE" "1/16W"
					( Origin gFrontEnd )
				)
				( attribute "XY" "(-2750,3200)"
					( Origin gFrontEnd )
				)
				( attribute "CHIPS_PART_NAME" "RES"
					( Origin gPackager )
				)
				( attribute "CDS_PART_NAME" "RES_0402-0.0,5%,1/16W,CHIP,G21A"
					( Origin gPackager )
				)
				( objectStatus "R2T27" )
			)
			( gate "@baseboard_fab2_lib.baseboard_fab2(sch_1):page93_i15"
				( attribute "BOM_COST" "PROC"
					( Origin gFrontEnd )
				)
				( attribute "CDS_LIB" "mstr_discrete"
					( Origin gPackager )
				)
				( attribute "CDS_LOCATION" "R2T32"
					( Origin gPackager )
				)
				( attribute "CDS_SEC" "1"
					( Origin gPackager )
				)
				( attribute "LOCATION" "R2T32"
					( Origin gFrontEnd )
				)
				( attribute "MATERIAL" "CHIP"
					( Origin gFrontEnd )
				)
				( attribute "PACK_TYPE" "0402"
					( Origin gFrontEnd )
				)
				( attribute "PART_NUMBER" "G21497-005"
					( Origin gFrontEnd )
				)
				( attribute "PHYS_PAGE" "93"
					( Origin gFrontEnd )
				)
				( attribute "ROOM" "PROC_SIDEBAND"
					( Origin gFrontEnd )
				)
				( attribute "ROT" "0"
					( Origin gFrontEnd )
				)
				( attribute "SEC" "1"
					( Origin gFrontEnd )
				)
				( attribute "SEC_TYPE" "0402"
					( Origin gFrontEnd )
				)
				( attribute "TOLERANCE" "5%"
					( Origin gFrontEnd )
				)
				( attribute "VALUE" "0.0"
					( Origin gFrontEnd )
				)
				( attribute "VER" "1"
					( Origin gFrontEnd )
				)
				( attribute "WATTAGE" "1/16W"
					( Origin gFrontEnd )
				)
				( attribute "XY" "(-2750,3425)"
					( Origin gFrontEnd )
				)
				( attribute "CHIPS_PART_NAME" "RES"
					( Origin gPackager )
				)
				( attribute "CDS_PART_NAME" "RES_0402-0.0,5%,1/16W,CHIP,G21A"
					( Origin gPackager )
				)
				( objectStatus "R2T32" )
			)
			( gate "@baseboard_fab2_lib.baseboard_fab2(sch_1):page93_i16"
				( attribute "BOM_COST" "PROC"
					( Origin gFrontEnd )
				)
				( attribute "CDS_LIB" "mstr_discrete"
					( Origin gPackager )
				)
				( attribute "CDS_LOCATION" "R2T20"
					( Origin gPackager )
				)
				( attribute "CDS_SEC" "1"
					( Origin gPackager )
				)
				( attribute "LOCATION" "R2T20"
					( Origin gFrontEnd )
				)
				( attribute "MATERIAL" "CHIP"
					( Origin gFrontEnd )
				)
				( attribute "PACK_TYPE" "0402"
					( Origin gFrontEnd )
				)
				( attribute "PART_NUMBER" "G21497-005"
					( Origin gFrontEnd )
				)
				( attribute "PHYS_PAGE" "93"
					( Origin gFrontEnd )
				)
				( attribute "ROOM" "PROC_SIDEBAND"
					( Origin gFrontEnd )
				)
				( attribute "ROT" "0"
					( Origin gFrontEnd )
				)
				( attribute "SEC" "1"
					( Origin gFrontEnd )
				)
				( attribute "SEC_TYPE" "0402"
					( Origin gFrontEnd )
				)
				( attribute "TOLERANCE" "5%"
					( Origin gFrontEnd )
				)
				( attribute "VALUE" "0.0"
					( Origin gFrontEnd )
				)
				( attribute "VER" "1"
					( Origin gFrontEnd )
				)
				( attribute "WATTAGE" "1/16W"
					( Origin gFrontEnd )
				)
				( attribute "XY" "(-2750,3725)"
					( Origin gFrontEnd )
				)
				( attribute "CHIPS_PART_NAME" "RES"
					( Origin gPackager )
				)
				( attribute "CDS_PART_NAME" "RES_0402-0.0,5%,1/16W,CHIP,G21A"
					( Origin gPackager )
				)
				( objectStatus "R2T20" )
			)
			( gate "@baseboard_fab2_lib.baseboard_fab2(sch_1):page93_i23"
				( attribute "BOM_COST" "PROC"
					( Origin gFrontEnd )
				)
				( attribute "CDS_LIB" "mstr_discrete"
					( Origin gPackager )
				)
				( attribute "CDS_LOCATION" "R2T17"
					( Origin gPackager )
				)
				( attribute "CDS_SEC" "1"
					( Origin gPackager )
				)
				( attribute "LOCATION" "R2T17"
					( Origin gFrontEnd )
				)
				( attribute "MATERIAL" "CHIP"
					( Origin gFrontEnd )
				)
				( attribute "PACK_TYPE" "0402"
					( Origin gFrontEnd )
				)
				( attribute "PART_NUMBER" "G21497-005"
					( Origin gFrontEnd )
				)
				( attribute "PHYS_PAGE" "93"
					( Origin gFrontEnd )
				)
				( attribute "ROOM" "PROC_SIDEBAND"
					( Origin gFrontEnd )
				)
				( attribute "ROT" "0"
					( Origin gFrontEnd )
				)
				( attribute "SEC" "1"
					( Origin gFrontEnd )
				)
				( attribute "SEC_TYPE" "0402"
					( Origin gFrontEnd )
				)
				( attribute "TOLERANCE" "5%"
					( Origin gFrontEnd )
				)
				( attribute "VALUE" "0.0"
					( Origin gFrontEnd )
				)
				( attribute "VER" "1"
					( Origin gFrontEnd )
				)
				( attribute "WATTAGE" "1/16W"
					( Origin gFrontEnd )
				)
				( attribute "XY" "(-2750,3975)"
					( Origin gFrontEnd )
				)
				( attribute "CHIPS_PART_NAME" "RES"
					( Origin gPackager )
				)
				( attribute "CDS_PART_NAME" "RES_0402-0.0,5%,1/16W,CHIP,G21A"
					( Origin gPackager )
				)
				( objectStatus "R2T17" )
			)
			( gate "@baseboard_fab2_lib.baseboard_fab2(sch_1):page93_i30"
				( attribute "BOM_COST" "PROC"
					( Origin gFrontEnd )
				)
				( attribute "CDS_LIB" "mstr_digital"
					( Origin gPackager )
				)
				( attribute "CDS_LOCATION" "U2T4"
					( Origin gPackager )
				)
				( attribute "CDS_SEC" "1"
					( Origin gPackager )
				)
				( attribute "LOCATION" "U2T4"
					( Origin gFrontEnd )
				)
				( attribute "MATERIAL" "IC"
					( Origin gFrontEnd )
				)
				( attribute "PACK_TYPE" "SM"
					( Origin gFrontEnd )
				)
				( attribute "PART_NUMBER" "D66151-001"
					( Origin gFrontEnd )
				)
				( attribute "PHYS_PAGE" "93"
					( Origin gFrontEnd )
				)
				( attribute "ROOM" "PROC_SIDEBAND"
					( Origin gFrontEnd )
				)
				( attribute "ROT" "2"
					( Origin gFrontEnd )
				)
				( attribute "SEC" "1"
					( Origin gFrontEnd )
				)
				( attribute "SEC_TYPE" "SM"
					( Origin gFrontEnd )
				)
				( attribute "VER" "1"
					( Origin gFrontEnd )
				)
				( attribute "XY" "(425,3350)"
					( Origin gFrontEnd )
				)
				( attribute "CHIPS_PART_NAME" "GTL2014"
					( Origin gPackager )
				)
				( attribute "CDS_PART_NAME" "GTL2014_SM-IC,D66151-001"
					( Origin gPackager )
				)
				( objectStatus "U2T4" )
			)
			( gate "@baseboard_fab2_lib.baseboard_fab2(sch_1):page93_i39"
				( attribute "BOM_COST" "PROC"
					( Origin gFrontEnd )
				)
				( attribute "CDS_LIB" "mstr_discrete"
					( Origin gPackager )
				)
				( attribute "CDS_LOCATION" "R2T38"
					( Origin gPackager )
				)
				( attribute "CDS_SEC" "1"
					( Origin gPackager )
				)
				( attribute "LOCATION" "R2T38"
					( Origin gFrontEnd )
				)
				( attribute "MATERIAL" "CHIP"
					( Origin gFrontEnd )
				)
				( attribute "PACK_TYPE" "0402"
					( Origin gFrontEnd )
				)
				( attribute "PART_NUMBER" "G21796-074"
					( Origin gFrontEnd )
				)
				( attribute "PHYS_PAGE" "93"
					( Origin gFrontEnd )
				)
				( attribute "ROOM" "PROC_SIDEBAND"
					( Origin gFrontEnd )
				)
				( attribute "ROT" "0"
					( Origin gFrontEnd )
				)
				( attribute "SEC" "1"
					( Origin gFrontEnd )
				)
				( attribute "SEC_TYPE" "0402"
					( Origin gFrontEnd )
				)
				( attribute "TOLERANCE" "1%"
					( Origin gFrontEnd )
				)
				( attribute "VALUE" "33.2"
					( Origin gFrontEnd )
				)
				( attribute "VER" "1"
					( Origin gFrontEnd )
				)
				( attribute "WATTAGE" "1/16W"
					( Origin gFrontEnd )
				)
				( attribute "XY" "(2950,2850)"
					( Origin gFrontEnd )
				)
				( attribute "CHIPS_PART_NAME" "RES"
					( Origin gPackager )
				)
				( attribute "CDS_PART_NAME" "RES_0402-33.2,1%,1/16W,CHIP,G2A"
					( Origin gPackager )
				)
				( objectStatus "R2T38" )
			)
			( gate "@baseboard_fab2_lib.baseboard_fab2(sch_1):page93_i40"
				( attribute "BOM_COST" "PROC"
					( Origin gFrontEnd )
				)
				( attribute "CDS_LIB" "mstr_discrete"
					( Origin gPackager )
				)
				( attribute "CDS_LOCATION" "R2T33"
					( Origin gPackager )
				)
				( attribute "CDS_SEC" "1"
					( Origin gPackager )
				)
				( attribute "LOCATION" "R2T33"
					( Origin gFrontEnd )
				)
				( attribute "MATERIAL" "CHIP"
					( Origin gFrontEnd )
				)
				( attribute "PACK_TYPE" "0402"
					( Origin gFrontEnd )
				)
				( attribute "PART_NUMBER" "G21796-074"
					( Origin gFrontEnd )
				)
				( attribute "PHYS_PAGE" "93"
					( Origin gFrontEnd )
				)
				( attribute "ROOM" "PROC_SIDEBAND"
					( Origin gFrontEnd )
				)
				( attribute "ROT" "0"
					( Origin gFrontEnd )
				)
				( attribute "SEC" "1"
					( Origin gFrontEnd )
				)
				( attribute "SEC_TYPE" "0402"
					( Origin gFrontEnd )
				)
				( attribute "TOLERANCE" "1%"
					( Origin gFrontEnd )
				)
				( attribute "VALUE" "33.2"
					( Origin gFrontEnd )
				)
				( attribute "VER" "1"
					( Origin gFrontEnd )
				)
				( attribute "WATTAGE" "1/16W"
					( Origin gFrontEnd )
				)
				( attribute "XY" "(2950,3100)"
					( Origin gFrontEnd )
				)
				( attribute "CHIPS_PART_NAME" "RES"
					( Origin gPackager )
				)
				( attribute "CDS_PART_NAME" "RES_0402-33.2,1%,1/16W,CHIP,G2A"
					( Origin gPackager )
				)
				( objectStatus "R2T33" )
			)
			( gate "@baseboard_fab2_lib.baseboard_fab2(sch_1):page93_i42"
				( attribute "BOM_COST" "PROC"
					( Origin gFrontEnd )
				)
				( attribute "CDS_LIB" "mstr_discrete"
					( Origin gPackager )
				)
				( attribute "CDS_LOCATION" "R2T30"
					( Origin gPackager )
				)
				( attribute "CDS_SEC" "1"
					( Origin gPackager )
				)
				( attribute "LOCATION" "R2T30"
					( Origin gFrontEnd )
				)
				( attribute "MATERIAL" "CHIP"
					( Origin gFrontEnd )
				)
				( attribute "PACK_TYPE" "0402"
					( Origin gFrontEnd )
				)
				( attribute "PART_NUMBER" "G21796-074"
					( Origin gFrontEnd )
				)
				( attribute "PHYS_PAGE" "93"
					( Origin gFrontEnd )
				)
				( attribute "ROOM" "PROC_SIDEBAND"
					( Origin gFrontEnd )
				)
				( attribute "ROT" "0"
					( Origin gFrontEnd )
				)
				( attribute "SEC" "1"
					( Origin gFrontEnd )
				)
				( attribute "SEC_TYPE" "0402"
					( Origin gFrontEnd )
				)
				( attribute "TOLERANCE" "1%"
					( Origin gFrontEnd )
				)
				( attribute "VALUE" "33.2"
					( Origin gFrontEnd )
				)
				( attribute "VER" "1"
					( Origin gFrontEnd )
				)
				( attribute "WATTAGE" "1/16W"
					( Origin gFrontEnd )
				)
				( attribute "XY" "(2950,3350)"
					( Origin gFrontEnd )
				)
				( attribute "CHIPS_PART_NAME" "RES"
					( Origin gPackager )
				)
				( attribute "CDS_PART_NAME" "RES_0402-33.2,1%,1/16W,CHIP,G2A"
					( Origin gPackager )
				)
				( objectStatus "R2T30" )
			)
			( gate "@baseboard_fab2_lib.baseboard_fab2(sch_1):page93_i62"
				( attribute "BOM_COST" "PROC"
					( Origin gFrontEnd )
				)
				( attribute "CDS_LIB" "mstr_discrete"
					( Origin gPackager )
				)
				( attribute "CDS_LOCATION" "R7D24"
					( Origin gPackager )
				)
				( attribute "CDS_SEC" "1"
					( Origin gPackager )
				)
				( attribute "LOCATION" "R7D24"
					( Origin gFrontEnd )
				)
				( attribute "MATERIAL" "CHIP"
					( Origin gFrontEnd )
				)
				( attribute "PACK_TYPE" "0402"
					( Origin gFrontEnd )
				)
				( attribute "PART_NUMBER" "G21796-074"
					( Origin gFrontEnd )
				)
				( attribute "PHYS_PAGE" "93"
					( Origin gFrontEnd )
				)
				( attribute "ROOM" "PROC_SIDEBAND"
					( Origin gFrontEnd )
				)
				( attribute "ROT" "0"
					( Origin gFrontEnd )
				)
				( attribute "SEC" "1"
					( Origin gFrontEnd )
				)
				( attribute "SEC_TYPE" "0402"
					( Origin gFrontEnd )
				)
				( attribute "TOLERANCE" "1%"
					( Origin gFrontEnd )
				)
				( attribute "VALUE" "33.2"
					( Origin gFrontEnd )
				)
				( attribute "VER" "1"
					( Origin gFrontEnd )
				)
				( attribute "WATTAGE" "1/16W"
					( Origin gFrontEnd )
				)
				( attribute "XY" "(2950,2575)"
					( Origin gFrontEnd )
				)
				( attribute "CHIPS_PART_NAME" "RES"
					( Origin gPackager )
				)
				( attribute "CDS_PART_NAME" "RES_0402-33.2,1%,1/16W,CHIP,G2A"
					( Origin gPackager )
				)
				( objectStatus "R7D24" )
			)
			( gate "@baseboard_fab2_lib.baseboard_fab2(sch_1):page93_i63"
				( attribute "BOM_COST" "PROC"
					( Origin gFrontEnd )
				)
				( attribute "CDS_LIB" "mstr_discrete"
					( Origin gPackager )
				)
				( attribute "CDS_LOCATION" "R2T19"
					( Origin gPackager )
				)
				( attribute "CDS_SEC" "1"
					( Origin gPackager )
				)
				( attribute "LOCATION" "R2T19"
					( Origin gFrontEnd )
				)
				( attribute "MATERIAL" "CHIP"
					( Origin gFrontEnd )
				)
				( attribute "PACK_TYPE" "0402"
					( Origin gFrontEnd )
				)
				( attribute "PART_NUMBER" "G21796-004"
					( Origin gFrontEnd )
				)
				( attribute "PHYS_PAGE" "93"
					( Origin gFrontEnd )
				)
				( attribute "ROOM" "PROC_SIDEBAND"
					( Origin gFrontEnd )
				)
				( attribute "ROT" "0"
					( Origin gFrontEnd )
				)
				( attribute "SEC" "1"
					( Origin gFrontEnd )
				)
				( attribute "SEC_TYPE" "0402"
					( Origin gFrontEnd )
				)
				( attribute "TOLERANCE" "1%"
					( Origin gFrontEnd )
				)
				( attribute "VALUE" "200.0"
					( Origin gFrontEnd )
				)
				( attribute "VER" "2"
					( Origin gFrontEnd )
				)
				( attribute "WATTAGE" "1/16W"
					( Origin gFrontEnd )
				)
				( attribute "XY" "(-2325,4050)"
					( Origin gFrontEnd )
				)
				( attribute "CHIPS_PART_NAME" "RES"
					( Origin gPackager )
				)
				( attribute "CDS_PART_NAME" "RES_0402-200.0,1%,1/16W,CHIP,GA"
					( Origin gPackager )
				)
				( objectStatus "R2T19" )
			)
			( gate "@baseboard_fab2_lib.baseboard_fab2(sch_1):page93_i67"
				( attribute "CDS_LIB" "mstr_discrete"
					( Origin gPackager )
				)
				( attribute "CDS_LOCATION" "R2T16"
					( Origin gPackager )
				)
				( attribute "CDS_SEC" "1"
					( Origin gPackager )
				)
				( attribute "LOCATION" "R2T16"
					( Origin gFrontEnd )
				)
				( attribute "MATERIAL" "CHIP"
					( Origin gFrontEnd )
				)
				( attribute "PACK_TYPE" "0402"
					( Origin gFrontEnd )
				)
				( attribute "PART_NUMBER" "G21796-267"
					( Origin gFrontEnd )
				)
				( attribute "PHYS_PAGE" "93"
					( Origin gFrontEnd )
				)
				( attribute "ROOM" "PROC_SIDEBAND"
					( Origin gFrontEnd )
				)
				( attribute "ROT" "0"
					( Origin gFrontEnd )
				)
				( attribute "SEC" "1"
					( Origin gFrontEnd )
				)
				( attribute "SEC_TYPE" "0402"
					( Origin gFrontEnd )
				)
				( attribute "TOLERANCE" "1.0%"
					( Origin gFrontEnd )
				)
				( attribute "VALUE" "75"
					( Origin gFrontEnd )
				)
				( attribute "VER" "1"
					( Origin gFrontEnd )
				)
				( attribute "WATTAGE" "1/16W"
					( Origin gFrontEnd )
				)
				( attribute "XY" "(-925,3825)"
					( Origin gFrontEnd )
				)
				( attribute "CHIPS_PART_NAME" "RES"
					( Origin gPackager )
				)
				( attribute "CDS_PART_NAME" "RES_0402-75,1.0%,1/16W,CHIP,G2A"
					( Origin gPackager )
				)
				( objectStatus "R2T16" )
			)
			( gate "@baseboard_fab2_lib.baseboard_fab2(sch_1):page93_i68"
				( attribute "CDS_LIB" "mstr_discrete"
					( Origin gPackager )
				)
				( attribute "CDS_LOCATION" "R2T31"
					( Origin gPackager )
				)
				( attribute "CDS_SEC" "1"
					( Origin gPackager )
				)
				( attribute "LOCATION" "R2T31"
					( Origin gFrontEnd )
				)
				( attribute "MATERIAL" "CHIP"
					( Origin gFrontEnd )
				)
				( attribute "PACK_TYPE" "0402"
					( Origin gFrontEnd )
				)
				( attribute "PART_NUMBER" "G21796-267"
					( Origin gFrontEnd )
				)
				( attribute "PHYS_PAGE" "93"
					( Origin gFrontEnd )
				)
				( attribute "ROOM" "PROC_SIDEBAND"
					( Origin gFrontEnd )
				)
				( attribute "ROT" "0"
					( Origin gFrontEnd )
				)
				( attribute "SEC" "1"
					( Origin gFrontEnd )
				)
				( attribute "SEC_TYPE" "0402"
					( Origin gFrontEnd )
				)
				( attribute "TOLERANCE" "1.0%"
					( Origin gFrontEnd )
				)
				( attribute "VALUE" "75"
					( Origin gFrontEnd )
				)
				( attribute "VER" "1"
					( Origin gFrontEnd )
				)
				( attribute "WATTAGE" "1/16W"
					( Origin gFrontEnd )
				)
				( attribute "XY" "(-925,3300)"
					( Origin gFrontEnd )
				)
				( attribute "CHIPS_PART_NAME" "RES"
					( Origin gPackager )
				)
				( attribute "CDS_PART_NAME" "RES_0402-75,1.0%,1/16W,CHIP,G2A"
					( Origin gPackager )
				)
				( objectStatus "R2T31" )
			)
			( gate "@baseboard_fab2_lib.baseboard_fab2(sch_1):page93_i72"
				( attribute "BOM_COST" "PROC"
					( Origin gFrontEnd )
				)
				( attribute "CDS_LIB" "dev_discrete"
					( Origin gPackager )
				)
				( attribute "CDS_LOCATION" "C2T33"
					( Origin gPackager )
				)
				( attribute "CDS_SEC" "1"
					( Origin gPackager )
				)
				( attribute "LOCATION" "C2T33"
					( Origin gFrontEnd )
				)
				( attribute "MATERIAL" "X6S"
					( Origin gFrontEnd )
				)
				( attribute "PACK_TYPE" "0402V"
					( Origin gFrontEnd )
				)
				( attribute "PART_NUMBER" "D97712-004"
					( Origin gFrontEnd )
				)
				( attribute "PHYS_PAGE" "93"
					( Origin gFrontEnd )
				)
				( attribute "ROOM" "PROC_SIDEBAND"
					( Origin gFrontEnd )
				)
				( attribute "ROT" "0"
					( Origin gFrontEnd )
				)
				( attribute "SEC" "1"
					( Origin gFrontEnd )
				)
				( attribute "SEC_TYPE" "0402V"
					( Origin gFrontEnd )
				)
				( attribute "TOLERANCE" "10%"
					( Origin gFrontEnd )
				)
				( attribute "VALUE" "1.0UF"
					( Origin gFrontEnd )
				)
				( attribute "VER" "1"
					( Origin gFrontEnd )
				)
				( attribute "VOLTAGE" "6.3V"
					( Units "uVoltage" "V" 1.000000)
					( Origin gFrontEnd )
				)
				( attribute "XY" "(1150,3875)"
					( Origin gFrontEnd )
				)
				( attribute "CHIPS_PART_NAME" "CAP_A"
					( Origin gPackager )
				)
				( attribute "CDS_PART_NAME" "CAP_A_0402V-1.0UF,6.3V,10%,X6SA"
					( Origin gPackager )
				)
				( objectStatus "C2T33" )
			)
			( gate "@baseboard_fab2_lib.baseboard_fab2(sch_1):page93_i79"
				( attribute "BOM_COST" "PROC_SIDEBAND"
					( Origin gFrontEnd )
				)
				( attribute "CDS_LIB" "mstr_discrete"
					( Origin gPackager )
				)
				( attribute "CDS_LOCATION" "R4R3"
					( Origin gPackager )
				)
				( attribute "CDS_SEC" "1"
					( Origin gPackager )
				)
				( attribute "LOCATION" "R4R3"
					( Origin gFrontEnd )
				)
				( attribute "MATERIAL" "CHIP"
					( Origin gFrontEnd )
				)
				( attribute "PACK_TYPE" "0402"
					( Origin gFrontEnd )
				)
				( attribute "PART_NUMBER" "G21796-009"
					( Origin gFrontEnd )
				)
				( attribute "PHYS_PAGE" "93"
					( Origin gFrontEnd )
				)
				( attribute "ROOM" "PROC_SIDEBAND"
					( Origin gFrontEnd )
				)
				( attribute "ROT" "0"
					( Origin gFrontEnd )
				)
				( attribute "SEC" "1"
					( Origin gFrontEnd )
				)
				( attribute "SEC_TYPE" "0402"
					( Origin gFrontEnd )
				)
				( attribute "TOLERANCE" "1%"
					( Origin gFrontEnd )
				)
				( attribute "VALUE" "150.0"
					( Origin gFrontEnd )
				)
				( attribute "VER" "2"
					( Origin gFrontEnd )
				)
				( attribute "WATTAGE" "1/16W"
					( Origin gFrontEnd )
				)
				( attribute "XY" "(-2750,2525)"
					( Origin gFrontEnd )
				)
				( attribute "CHIPS_PART_NAME" "RES"
					( Origin gPackager )
				)
				( attribute "CDS_PART_NAME" "RES_0402-150.0,1%,1/16W,CHIP,GA"
					( Origin gPackager )
				)
				( objectStatus "R4R3" )
			)
			( gate "@baseboard_fab2_lib.baseboard_fab2(sch_1):page93_i87"
				( attribute "BOM_COST" "PROC"
					( Origin gFrontEnd )
				)
				( attribute "CDS_LIB" "mstr_discrete"
					( Origin gPackager )
				)
				( attribute "CDS_LOCATION" "R2T26"
					( Origin gPackager )
				)
				( attribute "CDS_SEC" "1"
					( Origin gPackager )
				)
				( attribute "LOCATION" "R2T26"
					( Origin gFrontEnd )
				)
				( attribute "MATERIAL" "CHIP"
					( Origin gFrontEnd )
				)
				( attribute "PACK_TYPE" "0402"
					( Origin gFrontEnd )
				)
				( attribute "PART_NUMBER" "G21796-004"
					( Origin gFrontEnd )
				)
				( attribute "PHYS_PAGE" "93"
					( Origin gFrontEnd )
				)
				( attribute "ROOM" "PROC_SIDEBAND"
					( Origin gFrontEnd )
				)
				( attribute "ROT" "0"
					( Origin gFrontEnd )
				)
				( attribute "SEC" "1"
					( Origin gFrontEnd )
				)
				( attribute "SEC_TYPE" "0402"
					( Origin gFrontEnd )
				)
				( attribute "TOLERANCE" "1%"
					( Origin gFrontEnd )
				)
				( attribute "VALUE" "200.0"
					( Origin gFrontEnd )
				)
				( attribute "VER" "2"
					( Origin gFrontEnd )
				)
				( attribute "WATTAGE" "1/16W"
					( Origin gFrontEnd )
				)
				( attribute "XY" "(-2025,4050)"
					( Origin gFrontEnd )
				)
				( attribute "CHIPS_PART_NAME" "RES"
					( Origin gPackager )
				)
				( attribute "CDS_PART_NAME" "RES_0402-200.0,1%,1/16W,CHIP,GA"
					( Origin gPackager )
				)
				( objectStatus "R2T26" )
			)
			( gate "@baseboard_fab2_lib.baseboard_fab2(sch_1):page93_i88"
				( attribute "CDS_LIB" "mstr_discrete"
					( Origin gPackager )
				)
				( attribute "CDS_LOCATION" "R2T57"
					( Origin gPackager )
				)
				( attribute "CDS_SEC" "1"
					( Origin gPackager )
				)
				( attribute "LOCATION" "R2T57"
					( Origin gFrontEnd )
				)
				( attribute "MATERIAL" "EMPTY"
					( Origin gFrontEnd )
				)
				( attribute "PACK_TYPE" "0402"
					( Origin gFrontEnd )
				)
				( attribute "PART_NUMBER" "G21497-005"
					( Origin gFrontEnd )
				)
				( attribute "PHYS_PAGE" "93"
					( Origin gFrontEnd )
				)
				( attribute "ROT" "0"
					( Origin gFrontEnd )
				)
				( attribute "SEC" "1"
					( Origin gFrontEnd )
				)
				( attribute "SEC_TYPE" "0402"
					( Origin gFrontEnd )
				)
				( attribute "TOLERANCE" "5%"
					( Origin gFrontEnd )
				)
				( attribute "VALUE" "0.0"
					( Origin gFrontEnd )
				)
				( attribute "VER" "2"
					( Origin gFrontEnd )
				)
				( attribute "WATTAGE" "1/16W"
					( Origin gFrontEnd )
				)
				( attribute "XY" "(-1375,4125)"
					( Origin gFrontEnd )
				)
				( attribute "CHIPS_PART_NAME" "RES"
					( Origin gPackager )
				)
				( attribute "CDS_PART_NAME" "RES_0402-0.0,5%,1/16W,EMPTY,G2A"
					( Origin gPackager )
				)
				( objectStatus "R2T57" )
			)
			( gate "@baseboard_fab2_lib.baseboard_fab2(sch_1):page93_i89"
				( attribute "CDS_LIB" "mstr_discrete"
					( Origin gPackager )
				)
				( attribute "CDS_LOCATION" "R2T61"
					( Origin gPackager )
				)
				( attribute "CDS_SEC" "1"
					( Origin gPackager )
				)
				( attribute "LOCATION" "R2T61"
					( Origin gFrontEnd )
				)
				( attribute "MATERIAL" "EMPTY"
					( Origin gFrontEnd )
				)
				( attribute "PACK_TYPE" "0402"
					( Origin gFrontEnd )
				)
				( attribute "PART_NUMBER" "G21497-005"
					( Origin gFrontEnd )
				)
				( attribute "PHYS_PAGE" "93"
					( Origin gFrontEnd )
				)
				( attribute "ROT" "0"
					( Origin gFrontEnd )
				)
				( attribute "SEC" "1"
					( Origin gFrontEnd )
				)
				( attribute "SEC_TYPE" "0402"
					( Origin gFrontEnd )
				)
				( attribute "TOLERANCE" "5%"
					( Origin gFrontEnd )
				)
				( attribute "VALUE" "0.0"
					( Origin gFrontEnd )
				)
				( attribute "VER" "2"
					( Origin gFrontEnd )
				)
				( attribute "WATTAGE" "1/16W"
					( Origin gFrontEnd )
				)
				( attribute "XY" "(-1100,4125)"
					( Origin gFrontEnd )
				)
				( attribute "CHIPS_PART_NAME" "RES"
					( Origin gPackager )
				)
				( attribute "CDS_PART_NAME" "RES_0402-0.0,5%,1/16W,EMPTY,G2A"
					( Origin gPackager )
				)
				( objectStatus "R2T61" )
			)
			( gate "@baseboard_fab2_lib.baseboard_fab2(sch_1):page93_i93"
				( attribute "CDS_LIB" "mstr_discrete"
					( Origin gPackager )
				)
				( attribute "CDS_LOCATION" "R2T62"
					( Origin gPackager )
				)
				( attribute "CDS_SEC" "1"
					( Origin gPackager )
				)
				( attribute "LOCATION" "R2T62"
					( Origin gFrontEnd )
				)
				( attribute "MATERIAL" "EMPTY"
					( Origin gFrontEnd )
				)
				( attribute "PACK_TYPE" "0402"
					( Origin gFrontEnd )
				)
				( attribute "PART_NUMBER" "G21497-005"
					( Origin gFrontEnd )
				)
				( attribute "PHYS_PAGE" "93"
					( Origin gFrontEnd )
				)
				( attribute "ROT" "0"
					( Origin gFrontEnd )
				)
				( attribute "SEC" "1"
					( Origin gFrontEnd )
				)
				( attribute "SEC_TYPE" "0402"
					( Origin gFrontEnd )
				)
				( attribute "TOLERANCE" "5%"
					( Origin gFrontEnd )
				)
				( attribute "VALUE" "0.0"
					( Origin gFrontEnd )
				)
				( attribute "VER" "2"
					( Origin gFrontEnd )
				)
				( attribute "WATTAGE" "1/16W"
					( Origin gFrontEnd )
				)
				( attribute "XY" "(2025,3850)"
					( Origin gFrontEnd )
				)
				( attribute "CHIPS_PART_NAME" "RES"
					( Origin gPackager )
				)
				( attribute "CDS_PART_NAME" "RES_0402-0.0,5%,1/16W,EMPTY,G2A"
					( Origin gPackager )
				)
				( objectStatus "R2T62" )
			)
			( gate "@baseboard_fab2_lib.baseboard_fab2(sch_1):page93_i94"
				( attribute "CDS_LIB" "mstr_discrete"
					( Origin gPackager )
				)
				( attribute "CDS_LOCATION" "R2T58"
					( Origin gPackager )
				)
				( attribute "CDS_SEC" "1"
					( Origin gPackager )
				)
				( attribute "LOCATION" "R2T58"
					( Origin gFrontEnd )
				)
				( attribute "MATERIAL" "EMPTY"
					( Origin gFrontEnd )
				)
				( attribute "PACK_TYPE" "0402"
					( Origin gFrontEnd )
				)
				( attribute "PART_NUMBER" "G21497-005"
					( Origin gFrontEnd )
				)
				( attribute "PHYS_PAGE" "93"
					( Origin gFrontEnd )
				)
				( attribute "ROT" "0"
					( Origin gFrontEnd )
				)
				( attribute "SEC" "1"
					( Origin gFrontEnd )
				)
				( attribute "SEC_TYPE" "0402"
					( Origin gFrontEnd )
				)
				( attribute "TOLERANCE" "5%"
					( Origin gFrontEnd )
				)
				( attribute "VALUE" "0.0"
					( Origin gFrontEnd )
				)
				( attribute "VER" "2"
					( Origin gFrontEnd )
				)
				( attribute "WATTAGE" "1/16W"
					( Origin gFrontEnd )
				)
				( attribute "XY" "(2400,3850)"
					( Origin gFrontEnd )
				)
				( attribute "CHIPS_PART_NAME" "RES"
					( Origin gPackager )
				)
				( attribute "CDS_PART_NAME" "RES_0402-0.0,5%,1/16W,EMPTY,G2A"
					( Origin gPackager )
				)
				( objectStatus "R2T58" )
			)
			( gate "@baseboard_fab2_lib.baseboard_fab2(sch_1):page93_i95"
				( attribute "BOM_COST" "PROC"
					( Origin gFrontEnd )
				)
				( attribute "CDS_LIB" "dev_discrete"
					( Origin gPackager )
				)
				( attribute "CDS_LOCATION" "C2T32"
					( Origin gPackager )
				)
				( attribute "CDS_SEC" "1"
					( Origin gPackager )
				)
				( attribute "LOCATION" "C2T32"
					( Origin gFrontEnd )
				)
				( attribute "MATERIAL" "X7R"
					( Origin gFrontEnd )
				)
				( attribute "PACK_TYPE" "0402V"
					( Origin gFrontEnd )
				)
				( attribute "PART_NUMBER" "A36096-030"
					( Origin gFrontEnd )
				)
				( attribute "PHYS_PAGE" "93"
					( Origin gFrontEnd )
				)
				( attribute "ROOM" "PROC_SIDEBAND"
					( Origin gFrontEnd )
				)
				( attribute "ROT" "0"
					( Origin gFrontEnd )
				)
				( attribute "SEC" "1"
					( Origin gFrontEnd )
				)
				( attribute "SEC_TYPE" "0402V"
					( Origin gFrontEnd )
				)
				( attribute "TOLERANCE" "10%"
					( Origin gFrontEnd )
				)
				( attribute "VALUE" "0.1UF"
					( Origin gFrontEnd )
				)
				( attribute "VER" "1"
					( Origin gFrontEnd )
				)
				( attribute "VOLTAGE" "16V"
					( Units "uVoltage" "V" 1.000000)
					( Origin gFrontEnd )
				)
				( attribute "XY" "(1950,600)"
					( Origin gFrontEnd )
				)
				( attribute "CHIPS_PART_NAME" "CAP_A"
					( Origin gPackager )
				)
				( attribute "CDS_PART_NAME" "CAP_A_0402V-0.1UF,16V,10%,X7R,A"
					( Origin gPackager )
				)
				( objectStatus "C2T32" )
			)
			( gate "@baseboard_fab2_lib.baseboard_fab2(sch_1):page152_i106"
				( attribute "CDS_LIB" "w_hdl"
					( Origin gPackager )
				)
				( attribute "CDS_LMAN_SYM_OUTLINE" "-50,75,50,-75"
					( Origin gPackager )
				)
				( attribute "LOCATION" "R1U43"
					( Origin gFrontEnd )
				)
				( attribute "PACK_TYPE" "SMD-RG"
					( Origin gFrontEnd )
				)
				( attribute "PART_NUMBER" "64.37405.6DL"
					( Origin gFrontEnd )
				)
				( attribute "PHYS_PAGE" "152"
					( Origin gFrontEnd )
				)
				( attribute "ROT" "0"
					( Origin gFrontEnd )
				)
				( attribute "VALUE" "374R2F-1-GP"
					( Origin gFrontEnd )
				)
				( attribute "VER" "1"
					( Origin gFrontEnd )
				)
				( attribute "XY" "(-2550,2075)"
					( Origin gFrontEnd )
				)
				( attribute "CHIPS_PART_NAME" "374R2F-1-GP"
					( Origin gPackager )
				)
				( attribute "CDS_PART_NAME" "374R2F-1-GP_SMD-RG-374R2F-1-GPA"
					( Origin gPackager )
				)
				( attribute "CDS_LOCATION" "R1U43"
					( Origin gPackager )
				)
				( attribute "CDS_SEC" "1"
					( Origin gPackager )
				)
				( attribute "SEC" "1"
					( Origin gPackager )
				)
				( attribute "ATTRIBUTE" "374 OHM"
					( Origin gFrontEnd )
				)
				( attribute "PACK_SIZE" "0402"
					( Origin gFrontEnd )
				)
				( attribute "RATED" "1/16W"
					( Origin gFrontEnd )
				)
				( attribute "TOLERANCE" "1%"
					( Origin gFrontEnd )
				)
				( objectStatus "R1U43" )
			)
			( gate "@baseboard_fab2_lib.baseboard_fab2(sch_1):page93_i98"
				( attribute "BOM_COST" "PROC"
					( Origin gFrontEnd )
				)
				( attribute "CDS_LIB" "mstr_discrete"
					( Origin gPackager )
				)
				( attribute "CDS_LOCATION" "R2T39"
					( Origin gPackager )
				)
				( attribute "CDS_SEC" "1"
					( Origin gPackager )
				)
				( attribute "LOCATION" "R2T39"
					( Origin gFrontEnd )
				)
				( attribute "MATERIAL" "CHIP"
					( Origin gFrontEnd )
				)
				( attribute "PACK_TYPE" "0402"
					( Origin gFrontEnd )
				)
				( attribute "PART_NUMBER" "G21796-017"
					( Origin gFrontEnd )
				)
				( attribute "PHYS_PAGE" "93"
					( Origin gFrontEnd )
				)
				( attribute "ROOM" "PROC_SIDEBAND"
					( Origin gFrontEnd )
				)
				( attribute "ROT" "0"
					( Origin gFrontEnd )
				)
				( attribute "SEC" "1"
					( Origin gFrontEnd )
				)
				( attribute "SEC_TYPE" "0402"
					( Origin gFrontEnd )
				)
				( attribute "TOLERANCE" "1%"
					( Origin gFrontEnd )
				)
				( attribute "VALUE" "100.0"
					( Origin gFrontEnd )
				)
				( attribute "VER" "2"
					( Origin gFrontEnd )
				)
				( attribute "WATTAGE" "1/16W"
					( Origin gFrontEnd )
				)
				( attribute "XY" "(2300,600)"
					( Origin gFrontEnd )
				)
				( attribute "CHIPS_PART_NAME" "RES"
					( Origin gPackager )
				)
				( attribute "CDS_PART_NAME" "RES_0402-100.0,1%,1/16W,CHIP,GA"
					( Origin gPackager )
				)
				( objectStatus "R2T39" )
			)
			( gate "@baseboard_fab2_lib.baseboard_fab2(sch_1):page93_i102"
				( attribute "CDS_LIB" "mstr_discrete"
					( Origin gPackager )
				)
				( attribute "CDS_LOCATION" "R2T68"
					( Origin gPackager )
				)
				( attribute "CDS_SEC" "1"
					( Origin gPackager )
				)
				( attribute "LOCATION" "R2T68"
					( Origin gFrontEnd )
				)
				( attribute "MATERIAL" "CHIP"
					( Origin gFrontEnd )
				)
				( attribute "PACK_TYPE" "0402"
					( Origin gFrontEnd )
				)
				( attribute "PART_NUMBER" "G21497-005"
					( Origin gFrontEnd )
				)
				( attribute "PHYS_PAGE" "93"
					( Origin gFrontEnd )
				)
				( attribute "ROT" "0"
					( Origin gFrontEnd )
				)
				( attribute "SEC" "1"
					( Origin gFrontEnd )
				)
				( attribute "SEC_TYPE" "0402"
					( Origin gFrontEnd )
				)
				( attribute "TOLERANCE" "5%"
					( Origin gFrontEnd )
				)
				( attribute "VALUE" "0.0"
					( Origin gFrontEnd )
				)
				( attribute "VER" "1"
					( Origin gFrontEnd )
				)
				( attribute "WATTAGE" "1/16W"
					( Origin gFrontEnd )
				)
				( attribute "XY" "(-825,2175)"
					( Origin gFrontEnd )
				)
				( attribute "CHIPS_PART_NAME" "RES"
					( Origin gPackager )
				)
				( attribute "CDS_PART_NAME" "RES_0402-0.0,5%,1/16W,CHIP,G21A"
					( Origin gPackager )
				)
				( objectStatus "R2T68" )
			)
			( gate "@baseboard_fab2_lib.baseboard_fab2(sch_1):page93_i103"
				( attribute "CDS_LIB" "mstr_discrete"
					( Origin gPackager )
				)
				( attribute "CDS_LOCATION" "R2T60"
					( Origin gPackager )
				)
				( attribute "CDS_SEC" "1"
					( Origin gPackager )
				)
				( attribute "LOCATION" "R2T60"
					( Origin gFrontEnd )
				)
				( attribute "MATERIAL" "CHIP"
					( Origin gFrontEnd )
				)
				( attribute "PACK_TYPE" "0402"
					( Origin gFrontEnd )
				)
				( attribute "PART_NUMBER" "G21497-005"
					( Origin gFrontEnd )
				)
				( attribute "PHYS_PAGE" "93"
					( Origin gFrontEnd )
				)
				( attribute "ROT" "0"
					( Origin gFrontEnd )
				)
				( attribute "SEC" "1"
					( Origin gFrontEnd )
				)
				( attribute "SEC_TYPE" "0402"
					( Origin gFrontEnd )
				)
				( attribute "TOLERANCE" "5%"
					( Origin gFrontEnd )
				)
				( attribute "VALUE" "0.0"
					( Origin gFrontEnd )
				)
				( attribute "VER" "1"
					( Origin gFrontEnd )
				)
				( attribute "WATTAGE" "1/16W"
					( Origin gFrontEnd )
				)
				( attribute "XY" "(-825,2300)"
					( Origin gFrontEnd )
				)
				( attribute "CHIPS_PART_NAME" "RES"
					( Origin gPackager )
				)
				( attribute "CDS_PART_NAME" "RES_0402-0.0,5%,1/16W,CHIP,G21A"
					( Origin gPackager )
				)
				( objectStatus "R2T60" )
			)
			( gate "@baseboard_fab2_lib.baseboard_fab2(sch_1):page93_i106"
				( attribute "BOM_COST" "PROC_SIDEBAND"
					( Origin gFrontEnd )
				)
				( attribute "CDS_LIB" "mstr_discrete"
					( Origin gPackager )
				)
				( attribute "CDS_LOCATION" "R7P28"
					( Origin gPackager )
				)
				( attribute "CDS_SEC" "1"
					( Origin gPackager )
				)
				( attribute "LOCATION" "R7P28"
					( Origin gFrontEnd )
				)
				( attribute "MATERIAL" "CHIP"
					( Origin gFrontEnd )
				)
				( attribute "PACK_TYPE" "0402"
					( Origin gFrontEnd )
				)
				( attribute "PART_NUMBER" "G21796-009"
					( Origin gFrontEnd )
				)
				( attribute "PHYS_PAGE" "93"
					( Origin gFrontEnd )
				)
				( attribute "ROOM" "PROC_SIDEBAND"
					( Origin gFrontEnd )
				)
				( attribute "ROT" "0"
					( Origin gFrontEnd )
				)
				( attribute "SEC" "1"
					( Origin gFrontEnd )
				)
				( attribute "SEC_TYPE" "0402"
					( Origin gFrontEnd )
				)
				( attribute "TOLERANCE" "1%"
					( Origin gFrontEnd )
				)
				( attribute "VALUE" "150.0"
					( Origin gFrontEnd )
				)
				( attribute "VER" "2"
					( Origin gFrontEnd )
				)
				( attribute "WATTAGE" "1/16W"
					( Origin gFrontEnd )
				)
				( attribute "XY" "(-2200,2500)"
					( Origin gFrontEnd )
				)
				( attribute "CHIPS_PART_NAME" "RES"
					( Origin gPackager )
				)
				( attribute "CDS_PART_NAME" "RES_0402-150.0,1%,1/16W,CHIP,GA"
					( Origin gPackager )
				)
				( objectStatus "R7P28" )
			)
			( gate "@baseboard_fab2_lib.baseboard_fab2(sch_1):page93_i107"
				( attribute "CDS_LIB" "mstr_discrete"
					( Origin gPackager )
				)
				( attribute "CDS_LOCATION" "R2T59"
					( Origin gPackager )
				)
				( attribute "CDS_SEC" "1"
					( Origin gPackager )
				)
				( attribute "LOCATION" "R2T59"
					( Origin gFrontEnd )
				)
				( attribute "MATERIAL" "EMPTY"
					( Origin gFrontEnd )
				)
				( attribute "PACK_TYPE" "0402"
					( Origin gFrontEnd )
				)
				( attribute "PART_NUMBER" "G21497-005"
					( Origin gFrontEnd )
				)
				( attribute "PHYS_PAGE" "93"
					( Origin gFrontEnd )
				)
				( attribute "ROT" "0"
					( Origin gFrontEnd )
				)
				( attribute "SEC" "1"
					( Origin gFrontEnd )
				)
				( attribute "SEC_TYPE" "0402"
					( Origin gFrontEnd )
				)
				( attribute "TOLERANCE" "5%"
					( Origin gFrontEnd )
				)
				( attribute "VALUE" "0.0"
					( Origin gFrontEnd )
				)
				( attribute "VER" "2"
					( Origin gFrontEnd )
				)
				( attribute "WATTAGE" "1/16W"
					( Origin gFrontEnd )
				)
				( attribute "XY" "(-1100,1900)"
					( Origin gFrontEnd )
				)
				( attribute "CHIPS_PART_NAME" "RES"
					( Origin gPackager )
				)
				( attribute "CDS_PART_NAME" "RES_0402-0.0,5%,1/16W,EMPTY,G2A"
					( Origin gPackager )
				)
				( objectStatus "R2T59" )
			)
			( gate "@baseboard_fab2_lib.baseboard_fab2(sch_1):page93_i108"
				( attribute "CDS_LIB" "mstr_discrete"
					( Origin gPackager )
				)
				( attribute "CDS_LOCATION" "R2T69"
					( Origin gPackager )
				)
				( attribute "CDS_SEC" "1"
					( Origin gPackager )
				)
				( attribute "LOCATION" "R2T69"
					( Origin gFrontEnd )
				)
				( attribute "MATERIAL" "EMPTY"
					( Origin gFrontEnd )
				)
				( attribute "PACK_TYPE" "0402"
					( Origin gFrontEnd )
				)
				( attribute "PART_NUMBER" "G21497-005"
					( Origin gFrontEnd )
				)
				( attribute "PHYS_PAGE" "93"
					( Origin gFrontEnd )
				)
				( attribute "ROT" "0"
					( Origin gFrontEnd )
				)
				( attribute "SEC" "1"
					( Origin gFrontEnd )
				)
				( attribute "SEC_TYPE" "0402"
					( Origin gFrontEnd )
				)
				( attribute "TOLERANCE" "5%"
					( Origin gFrontEnd )
				)
				( attribute "VALUE" "0.0"
					( Origin gFrontEnd )
				)
				( attribute "VER" "2"
					( Origin gFrontEnd )
				)
				( attribute "WATTAGE" "1/16W"
					( Origin gFrontEnd )
				)
				( attribute "XY" "(-1400,1900)"
					( Origin gFrontEnd )
				)
				( attribute "CHIPS_PART_NAME" "RES"
					( Origin gPackager )
				)
				( attribute "CDS_PART_NAME" "RES_0402-0.0,5%,1/16W,EMPTY,G2A"
					( Origin gPackager )
				)
				( objectStatus "R2T69" )
			)
			( gate "@baseboard_fab2_lib.baseboard_fab2(sch_1):page93_i109"
				( attribute "CDS_LIB" "mstr_discrete"
					( Origin gPackager )
				)
				( attribute "CDS_LOCATION" "R2T71"
					( Origin gPackager )
				)
				( attribute "CDS_SEC" "1"
					( Origin gPackager )
				)
				( attribute "LOCATION" "R2T71"
					( Origin gFrontEnd )
				)
				( attribute "MATERIAL" "EMPTY"
					( Origin gFrontEnd )
				)
				( attribute "PACK_TYPE" "0402"
					( Origin gFrontEnd )
				)
				( attribute "PART_NUMBER" "G21497-005"
					( Origin gFrontEnd )
				)
				( attribute "PHYS_PAGE" "93"
					( Origin gFrontEnd )
				)
				( attribute "ROT" "0"
					( Origin gFrontEnd )
				)
				( attribute "SEC" "1"
					( Origin gFrontEnd )
				)
				( attribute "SEC_TYPE" "0402"
					( Origin gFrontEnd )
				)
				( attribute "TOLERANCE" "5%"
					( Origin gFrontEnd )
				)
				( attribute "VALUE" "0.0"
					( Origin gFrontEnd )
				)
				( attribute "VER" "2"
					( Origin gFrontEnd )
				)
				( attribute "WATTAGE" "1/16W"
					( Origin gFrontEnd )
				)
				( attribute "XY" "(2025,2225)"
					( Origin gFrontEnd )
				)
				( attribute "CHIPS_PART_NAME" "RES"
					( Origin gPackager )
				)
				( attribute "CDS_PART_NAME" "RES_0402-0.0,5%,1/16W,EMPTY,G2A"
					( Origin gPackager )
				)
				( objectStatus "R2T71" )
			)
			( gate "@baseboard_fab2_lib.baseboard_fab2(sch_1):page93_i110"
				( attribute "CDS_LIB" "mstr_discrete"
					( Origin gPackager )
				)
				( attribute "CDS_LOCATION" "R7D43"
					( Origin gPackager )
				)
				( attribute "CDS_SEC" "1"
					( Origin gPackager )
				)
				( attribute "LOCATION" "R7D43"
					( Origin gFrontEnd )
				)
				( attribute "MATERIAL" "EMPTY"
					( Origin gFrontEnd )
				)
				( attribute "PACK_TYPE" "0402"
					( Origin gFrontEnd )
				)
				( attribute "PART_NUMBER" "G21497-005"
					( Origin gFrontEnd )
				)
				( attribute "PHYS_PAGE" "93"
					( Origin gFrontEnd )
				)
				( attribute "ROT" "0"
					( Origin gFrontEnd )
				)
				( attribute "SEC" "1"
					( Origin gFrontEnd )
				)
				( attribute "SEC_TYPE" "0402"
					( Origin gFrontEnd )
				)
				( attribute "TOLERANCE" "5%"
					( Origin gFrontEnd )
				)
				( attribute "VALUE" "0.0"
					( Origin gFrontEnd )
				)
				( attribute "VER" "2"
					( Origin gFrontEnd )
				)
				( attribute "WATTAGE" "1/16W"
					( Origin gFrontEnd )
				)
				( attribute "XY" "(2400,2225)"
					( Origin gFrontEnd )
				)
				( attribute "CHIPS_PART_NAME" "RES"
					( Origin gPackager )
				)
				( attribute "CDS_PART_NAME" "RES_0402-0.0,5%,1/16W,EMPTY,G2A"
					( Origin gPackager )
				)
				( objectStatus "R7D43" )
			)
			( gate "@baseboard_fab2_lib.baseboard_fab2(sch_1):page93_i111"
				( attribute "CDS_LIB" "mstr_discrete"
					( Origin gPackager )
				)
				( attribute "CDS_LOCATION" "R2T65"
					( Origin gPackager )
				)
				( attribute "CDS_SEC" "1"
					( Origin gPackager )
				)
				( attribute "LOCATION" "R2T65"
					( Origin gFrontEnd )
				)
				( attribute "MATERIAL" "CHIP"
					( Origin gFrontEnd )
				)
				( attribute "PACK_TYPE" "0402"
					( Origin gFrontEnd )
				)
				( attribute "PART_NUMBER" "G21497-005"
					( Origin gFrontEnd )
				)
				( attribute "PHYS_PAGE" "93"
					( Origin gFrontEnd )
				)
				( attribute "ROT" "0"
					( Origin gFrontEnd )
				)
				( attribute "SEC" "1"
					( Origin gFrontEnd )
				)
				( attribute "SEC_TYPE" "0402"
					( Origin gFrontEnd )
				)
				( attribute "TOLERANCE" "5%"
					( Origin gFrontEnd )
				)
				( attribute "VALUE" "0.0"
					( Origin gFrontEnd )
				)
				( attribute "VER" "1"
					( Origin gFrontEnd )
				)
				( attribute "WATTAGE" "1/16W"
					( Origin gFrontEnd )
				)
				( attribute "XY" "(1875,3350)"
					( Origin gFrontEnd )
				)
				( attribute "CHIPS_PART_NAME" "RES"
					( Origin gPackager )
				)
				( attribute "CDS_PART_NAME" "RES_0402-0.0,5%,1/16W,CHIP,G21A"
					( Origin gPackager )
				)
				( objectStatus "R2T65" )
			)
			( gate "@baseboard_fab2_lib.baseboard_fab2(sch_1):page93_i112"
				( attribute "CDS_LIB" "mstr_discrete"
					( Origin gPackager )
				)
				( attribute "CDS_LOCATION" "R2T66"
					( Origin gPackager )
				)
				( attribute "CDS_SEC" "1"
					( Origin gPackager )
				)
				( attribute "LOCATION" "R2T66"
					( Origin gFrontEnd )
				)
				( attribute "MATERIAL" "CHIP"
					( Origin gFrontEnd )
				)
				( attribute "PACK_TYPE" "0402"
					( Origin gFrontEnd )
				)
				( attribute "PART_NUMBER" "G21497-005"
					( Origin gFrontEnd )
				)
				( attribute "PHYS_PAGE" "93"
					( Origin gFrontEnd )
				)
				( attribute "ROT" "0"
					( Origin gFrontEnd )
				)
				( attribute "SEC" "1"
					( Origin gFrontEnd )
				)
				( attribute "SEC_TYPE" "0402"
					( Origin gFrontEnd )
				)
				( attribute "TOLERANCE" "5%"
					( Origin gFrontEnd )
				)
				( attribute "VALUE" "0.0"
					( Origin gFrontEnd )
				)
				( attribute "VER" "1"
					( Origin gFrontEnd )
				)
				( attribute "WATTAGE" "1/16W"
					( Origin gFrontEnd )
				)
				( attribute "XY" "(1875,3100)"
					( Origin gFrontEnd )
				)
				( attribute "CHIPS_PART_NAME" "RES"
					( Origin gPackager )
				)
				( attribute "CDS_PART_NAME" "RES_0402-0.0,5%,1/16W,CHIP,G21A"
					( Origin gPackager )
				)
				( objectStatus "R2T66" )
			)
			( gate "@baseboard_fab2_lib.baseboard_fab2(sch_1):page93_i113"
				( attribute "CDS_LIB" "mstr_discrete"
					( Origin gPackager )
				)
				( attribute "CDS_LOCATION" "R2T67"
					( Origin gPackager )
				)
				( attribute "CDS_SEC" "1"
					( Origin gPackager )
				)
				( attribute "LOCATION" "R2T67"
					( Origin gFrontEnd )
				)
				( attribute "MATERIAL" "CHIP"
					( Origin gFrontEnd )
				)
				( attribute "PACK_TYPE" "0402"
					( Origin gFrontEnd )
				)
				( attribute "PART_NUMBER" "G21497-005"
					( Origin gFrontEnd )
				)
				( attribute "PHYS_PAGE" "93"
					( Origin gFrontEnd )
				)
				( attribute "ROT" "0"
					( Origin gFrontEnd )
				)
				( attribute "SEC" "1"
					( Origin gFrontEnd )
				)
				( attribute "SEC_TYPE" "0402"
					( Origin gFrontEnd )
				)
				( attribute "TOLERANCE" "5%"
					( Origin gFrontEnd )
				)
				( attribute "VALUE" "0.0"
					( Origin gFrontEnd )
				)
				( attribute "VER" "1"
					( Origin gFrontEnd )
				)
				( attribute "WATTAGE" "1/16W"
					( Origin gFrontEnd )
				)
				( attribute "XY" "(1875,2850)"
					( Origin gFrontEnd )
				)
				( attribute "CHIPS_PART_NAME" "RES"
					( Origin gPackager )
				)
				( attribute "CDS_PART_NAME" "RES_0402-0.0,5%,1/16W,CHIP,G21A"
					( Origin gPackager )
				)
				( objectStatus "R2T67" )
			)
			( gate "@baseboard_fab2_lib.baseboard_fab2(sch_1):page93_i114"
				( attribute "CDS_LIB" "mstr_discrete"
					( Origin gPackager )
				)
				( attribute "CDS_LOCATION" "R7D41"
					( Origin gPackager )
				)
				( attribute "CDS_SEC" "1"
					( Origin gPackager )
				)
				( attribute "LOCATION" "R7D41"
					( Origin gFrontEnd )
				)
				( attribute "MATERIAL" "CHIP"
					( Origin gFrontEnd )
				)
				( attribute "PACK_TYPE" "0402"
					( Origin gFrontEnd )
				)
				( attribute "PART_NUMBER" "G21497-005"
					( Origin gFrontEnd )
				)
				( attribute "PHYS_PAGE" "93"
					( Origin gFrontEnd )
				)
				( attribute "ROT" "0"
					( Origin gFrontEnd )
				)
				( attribute "SEC" "1"
					( Origin gFrontEnd )
				)
				( attribute "SEC_TYPE" "0402"
					( Origin gFrontEnd )
				)
				( attribute "TOLERANCE" "5%"
					( Origin gFrontEnd )
				)
				( attribute "VALUE" "0.0"
					( Origin gFrontEnd )
				)
				( attribute "VER" "1"
					( Origin gFrontEnd )
				)
				( attribute "WATTAGE" "1/16W"
					( Origin gFrontEnd )
				)
				( attribute "XY" "(1875,2575)"
					( Origin gFrontEnd )
				)
				( attribute "CHIPS_PART_NAME" "RES"
					( Origin gPackager )
				)
				( attribute "CDS_PART_NAME" "RES_0402-0.0,5%,1/16W,CHIP,G21A"
					( Origin gPackager )
				)
				( objectStatus "R7D41" )
			)
			( gate "@baseboard_fab2_lib.baseboard_fab2(sch_1):page93_i119"
				( attribute "CDS_LIB" "mstr_discrete"
					( Origin gPackager )
				)
				( attribute "CDS_LOCATION" "R8F38"
					( Origin gPackager )
				)
				( attribute "CDS_SEC" "1"
					( Origin gPackager )
				)
				( attribute "LOCATION" "R8F38"
					( Origin gFrontEnd )
				)
				( attribute "MATERIAL" "CHIP"
					( Origin gFrontEnd )
				)
				( attribute "PACK_TYPE" "0402"
					( Origin gFrontEnd )
				)
				( attribute "PART_NUMBER" "G21497-005"
					( Origin gFrontEnd )
				)
				( attribute "PHYS_PAGE" "93"
					( Origin gFrontEnd )
				)
				( attribute "ROT" "0"
					( Origin gFrontEnd )
				)
				( attribute "SEC" "1"
					( Origin gFrontEnd )
				)
				( attribute "SEC_TYPE" "0402"
					( Origin gFrontEnd )
				)
				( attribute "TOLERANCE" "5%"
					( Origin gFrontEnd )
				)
				( attribute "VALUE" "0.0"
					( Origin gFrontEnd )
				)
				( attribute "VER" "1"
					( Origin gFrontEnd )
				)
				( attribute "WATTAGE" "1/16W"
					( Origin gFrontEnd )
				)
				( attribute "XY" "(-2225,1450)"
					( Origin gFrontEnd )
				)
				( attribute "CHIPS_PART_NAME" "RES"
					( Origin gPackager )
				)
				( attribute "CDS_PART_NAME" "RES_0402-0.0,5%,1/16W,CHIP,G21A"
					( Origin gPackager )
				)
				( objectStatus "R8F38" )
			)
			( gate "@baseboard_fab2_lib.baseboard_fab2(sch_1):page93_i121"
				( attribute "CDS_LIB" "mstr_discrete"
					( Origin gPackager )
				)
				( attribute "CDS_LOCATION" "R2T64"
					( Origin gPackager )
				)
				( attribute "CDS_SEC" "1"
					( Origin gPackager )
				)
				( attribute "LOCATION" "R2T64"
					( Origin gFrontEnd )
				)
				( attribute "MATERIAL" "CHIP"
					( Origin gFrontEnd )
				)
				( attribute "PACK_TYPE" "0402"
					( Origin gFrontEnd )
				)
				( attribute "PART_NUMBER" "G21497-005"
					( Origin gFrontEnd )
				)
				( attribute "PHYS_PAGE" "93"
					( Origin gFrontEnd )
				)
				( attribute "ROT" "0"
					( Origin gFrontEnd )
				)
				( attribute "SEC" "1"
					( Origin gFrontEnd )
				)
				( attribute "SEC_TYPE" "0402"
					( Origin gFrontEnd )
				)
				( attribute "TOLERANCE" "5%"
					( Origin gFrontEnd )
				)
				( attribute "VALUE" "0.0"
					( Origin gFrontEnd )
				)
				( attribute "VER" "1"
					( Origin gFrontEnd )
				)
				( attribute "WATTAGE" "1/16W"
					( Origin gFrontEnd )
				)
				( attribute "XY" "(-2225,1050)"
					( Origin gFrontEnd )
				)
				( attribute "CHIPS_PART_NAME" "RES"
					( Origin gPackager )
				)
				( attribute "CDS_PART_NAME" "RES_0402-0.0,5%,1/16W,CHIP,G21A"
					( Origin gPackager )
				)
				( objectStatus "R2T64" )
			)
			( gate "@baseboard_fab2_lib.baseboard_fab2(sch_1):page93_i122"
				( attribute "CDS_LIB" "mstr_discrete"
					( Origin gPackager )
				)
				( attribute "CDS_LOCATION" "R1T36"
					( Origin gPackager )
				)
				( attribute "CDS_SEC" "1"
					( Origin gPackager )
				)
				( attribute "LOCATION" "R1T36"
					( Origin gFrontEnd )
				)
				( attribute "MATERIAL" "CHIP"
					( Origin gFrontEnd )
				)
				( attribute "PACK_TYPE" "0402"
					( Origin gFrontEnd )
				)
				( attribute "PART_NUMBER" "G21497-005"
					( Origin gFrontEnd )
				)
				( attribute "PHYS_PAGE" "93"
					( Origin gFrontEnd )
				)
				( attribute "ROT" "0"
					( Origin gFrontEnd )
				)
				( attribute "SEC" "1"
					( Origin gFrontEnd )
				)
				( attribute "SEC_TYPE" "0402"
					( Origin gFrontEnd )
				)
				( attribute "TOLERANCE" "5%"
					( Origin gFrontEnd )
				)
				( attribute "VALUE" "0.0"
					( Origin gFrontEnd )
				)
				( attribute "VER" "1"
					( Origin gFrontEnd )
				)
				( attribute "WATTAGE" "1/16W"
					( Origin gFrontEnd )
				)
				( attribute "XY" "(-2225,675)"
					( Origin gFrontEnd )
				)
				( attribute "CHIPS_PART_NAME" "RES"
					( Origin gPackager )
				)
				( attribute "CDS_PART_NAME" "RES_0402-0.0,5%,1/16W,CHIP,G21A"
					( Origin gPackager )
				)
				( objectStatus "R1T36" )
			)
			( gate "@baseboard_fab2_lib.baseboard_fab2(sch_1):page93_i123"
				( attribute "CDS_LIB" "mstr_discrete"
					( Origin gPackager )
				)
				( attribute "CDS_LOCATION" "R1T37"
					( Origin gPackager )
				)
				( attribute "CDS_SEC" "1"
					( Origin gPackager )
				)
				( attribute "LOCATION" "R1T37"
					( Origin gFrontEnd )
				)
				( attribute "MATERIAL" "CHIP"
					( Origin gFrontEnd )
				)
				( attribute "PACK_TYPE" "0402"
					( Origin gFrontEnd )
				)
				( attribute "PART_NUMBER" "G21497-005"
					( Origin gFrontEnd )
				)
				( attribute "PHYS_PAGE" "93"
					( Origin gFrontEnd )
				)
				( attribute "ROT" "0"
					( Origin gFrontEnd )
				)
				( attribute "SEC" "1"
					( Origin gFrontEnd )
				)
				( attribute "SEC_TYPE" "0402"
					( Origin gFrontEnd )
				)
				( attribute "TOLERANCE" "5%"
					( Origin gFrontEnd )
				)
				( attribute "VALUE" "0.0"
					( Origin gFrontEnd )
				)
				( attribute "VER" "1"
					( Origin gFrontEnd )
				)
				( attribute "WATTAGE" "1/16W"
					( Origin gFrontEnd )
				)
				( attribute "XY" "(-2225,275)"
					( Origin gFrontEnd )
				)
				( attribute "CHIPS_PART_NAME" "RES"
					( Origin gPackager )
				)
				( attribute "CDS_PART_NAME" "RES_0402-0.0,5%,1/16W,CHIP,G21A"
					( Origin gPackager )
				)
				( objectStatus "R1T37" )
			)
			( gate "@baseboard_fab2_lib.baseboard_fab2(sch_1):page93_i127"
				( attribute "BOM_COST" "PROC"
					( Origin gFrontEnd )
				)
				( attribute "CDS_LIB" "mstr_discrete"
					( Origin gPackager )
				)
				( attribute "CDS_LOCATION" "R2T50"
					( Origin gPackager )
				)
				( attribute "CDS_SEC" "1"
					( Origin gPackager )
				)
				( attribute "LOCATION" "R2T50"
					( Origin gFrontEnd )
				)
				( attribute "MATERIAL" "CHIP"
					( Origin gFrontEnd )
				)
				( attribute "PACK_TYPE" "0402"
					( Origin gFrontEnd )
				)
				( attribute "PART_NUMBER" "G21796-026"
					( Origin gFrontEnd )
				)
				( attribute "PHYS_PAGE" "93"
					( Origin gFrontEnd )
				)
				( attribute "ROOM" "PROC_SIDEBAND"
					( Origin gFrontEnd )
				)
				( attribute "ROT" "0"
					( Origin gFrontEnd )
				)
				( attribute "SEC" "1"
					( Origin gFrontEnd )
				)
				( attribute "SEC_TYPE" "0402"
					( Origin gFrontEnd )
				)
				( attribute "TOLERANCE" "1%"
					( Origin gFrontEnd )
				)
				( attribute "VALUE" "1.00K"
					( Origin gFrontEnd )
				)
				( attribute "VER" "2"
					( Origin gFrontEnd )
				)
				( attribute "WATTAGE" "1/16W"
					( Origin gFrontEnd )
				)
				( attribute "XY" "(3700,425)"
					( Origin gFrontEnd )
				)
				( attribute "CHIPS_PART_NAME" "RES"
					( Origin gPackager )
				)
				( attribute "CDS_PART_NAME" "RES_0402-1.00K,1%,1/16W,CHIP,GA"
					( Origin gPackager )
				)
				( objectStatus "R2T50" )
			)
			( gate "@baseboard_fab2_lib.baseboard_fab2(sch_1):page93_i131"
				( attribute "CDS_LIB" "mstr_discrete"
					( Origin gPackager )
				)
				( attribute "CDS_LOCATION" "R8F37"
					( Origin gPackager )
				)
				( attribute "CDS_SEC" "1"
					( Origin gPackager )
				)
				( attribute "LOCATION" "R8F37"
					( Origin gFrontEnd )
				)
				( attribute "MATERIAL" "EMPTY"
					( Origin gFrontEnd )
				)
				( attribute "PACK_TYPE" "0402"
					( Origin gFrontEnd )
				)
				( attribute "PART_NUMBER" "G21497-005"
					( Origin gFrontEnd )
				)
				( attribute "PHYS_PAGE" "93"
					( Origin gFrontEnd )
				)
				( attribute "ROT" "0"
					( Origin gFrontEnd )
				)
				( attribute "SEC" "1"
					( Origin gFrontEnd )
				)
				( attribute "SEC_TYPE" "0402"
					( Origin gFrontEnd )
				)
				( attribute "TOLERANCE" "5%"
					( Origin gFrontEnd )
				)
				( attribute "VALUE" "0.0"
					( Origin gFrontEnd )
				)
				( attribute "VER" "1"
					( Origin gFrontEnd )
				)
				( attribute "WATTAGE" "1/16W"
					( Origin gFrontEnd )
				)
				( attribute "XY" "(-2225,1250)"
					( Origin gFrontEnd )
				)
				( attribute "CHIPS_PART_NAME" "RES"
					( Origin gPackager )
				)
				( attribute "CDS_PART_NAME" "RES_0402-0.0,5%,1/16W,EMPTY,G2A"
					( Origin gPackager )
				)
				( objectStatus "R8F37" )
			)
			( gate "@baseboard_fab2_lib.baseboard_fab2(sch_1):page93_i133"
				( attribute "CDS_LIB" "mstr_discrete"
					( Origin gPackager )
				)
				( attribute "CDS_LOCATION" "R2T63"
					( Origin gPackager )
				)
				( attribute "CDS_SEC" "1"
					( Origin gPackager )
				)
				( attribute "LOCATION" "R2T63"
					( Origin gFrontEnd )
				)
				( attribute "MATERIAL" "EMPTY"
					( Origin gFrontEnd )
				)
				( attribute "PACK_TYPE" "0402"
					( Origin gFrontEnd )
				)
				( attribute "PART_NUMBER" "G21497-005"
					( Origin gFrontEnd )
				)
				( attribute "PHYS_PAGE" "93"
					( Origin gFrontEnd )
				)
				( attribute "ROT" "0"
					( Origin gFrontEnd )
				)
				( attribute "SEC" "1"
					( Origin gFrontEnd )
				)
				( attribute "SEC_TYPE" "0402"
					( Origin gFrontEnd )
				)
				( attribute "TOLERANCE" "5%"
					( Origin gFrontEnd )
				)
				( attribute "VALUE" "0.0"
					( Origin gFrontEnd )
				)
				( attribute "VER" "1"
					( Origin gFrontEnd )
				)
				( attribute "WATTAGE" "1/16W"
					( Origin gFrontEnd )
				)
				( attribute "XY" "(-2225,850)"
					( Origin gFrontEnd )
				)
				( attribute "CHIPS_PART_NAME" "RES"
					( Origin gPackager )
				)
				( attribute "CDS_PART_NAME" "RES_0402-0.0,5%,1/16W,EMPTY,G2A"
					( Origin gPackager )
				)
				( objectStatus "R2T63" )
			)
			( gate "@baseboard_fab2_lib.baseboard_fab2(sch_1):page93_i135"
				( attribute "CDS_LIB" "mstr_discrete"
					( Origin gPackager )
				)
				( attribute "CDS_LOCATION" "R1T35"
					( Origin gPackager )
				)
				( attribute "CDS_SEC" "1"
					( Origin gPackager )
				)
				( attribute "LOCATION" "R1T35"
					( Origin gFrontEnd )
				)
				( attribute "MATERIAL" "EMPTY"
					( Origin gFrontEnd )
				)
				( attribute "PACK_TYPE" "0402"
					( Origin gFrontEnd )
				)
				( attribute "PART_NUMBER" "G21497-005"
					( Origin gFrontEnd )
				)
				( attribute "PHYS_PAGE" "93"
					( Origin gFrontEnd )
				)
				( attribute "ROT" "0"
					( Origin gFrontEnd )
				)
				( attribute "SEC" "1"
					( Origin gFrontEnd )
				)
				( attribute "SEC_TYPE" "0402"
					( Origin gFrontEnd )
				)
				( attribute "TOLERANCE" "5%"
					( Origin gFrontEnd )
				)
				( attribute "VALUE" "0.0"
					( Origin gFrontEnd )
				)
				( attribute "VER" "1"
					( Origin gFrontEnd )
				)
				( attribute "WATTAGE" "1/16W"
					( Origin gFrontEnd )
				)
				( attribute "XY" "(-2225,475)"
					( Origin gFrontEnd )
				)
				( attribute "CHIPS_PART_NAME" "RES"
					( Origin gPackager )
				)
				( attribute "CDS_PART_NAME" "RES_0402-0.0,5%,1/16W,EMPTY,G2A"
					( Origin gPackager )
				)
				( objectStatus "R1T35" )
			)
			( gate "@baseboard_fab2_lib.baseboard_fab2(sch_1):page93_i137"
				( attribute "CDS_LIB" "mstr_discrete"
					( Origin gPackager )
				)
				( attribute "CDS_LOCATION" "R1T38"
					( Origin gPackager )
				)
				( attribute "CDS_SEC" "1"
					( Origin gPackager )
				)
				( attribute "LOCATION" "R1T38"
					( Origin gFrontEnd )
				)
				( attribute "MATERIAL" "EMPTY"
					( Origin gFrontEnd )
				)
				( attribute "PACK_TYPE" "0402"
					( Origin gFrontEnd )
				)
				( attribute "PART_NUMBER" "G21497-005"
					( Origin gFrontEnd )
				)
				( attribute "PHYS_PAGE" "93"
					( Origin gFrontEnd )
				)
				( attribute "ROT" "0"
					( Origin gFrontEnd )
				)
				( attribute "SEC" "1"
					( Origin gFrontEnd )
				)
				( attribute "SEC_TYPE" "0402"
					( Origin gFrontEnd )
				)
				( attribute "TOLERANCE" "5%"
					( Origin gFrontEnd )
				)
				( attribute "VALUE" "0.0"
					( Origin gFrontEnd )
				)
				( attribute "VER" "1"
					( Origin gFrontEnd )
				)
				( attribute "WATTAGE" "1/16W"
					( Origin gFrontEnd )
				)
				( attribute "XY" "(-2225,75)"
					( Origin gFrontEnd )
				)
				( attribute "CHIPS_PART_NAME" "RES"
					( Origin gPackager )
				)
				( attribute "CDS_PART_NAME" "RES_0402-0.0,5%,1/16W,EMPTY,G2A"
					( Origin gPackager )
				)
				( objectStatus "R1T38" )
			)
			( gate "@baseboard_fab2_lib.baseboard_fab2(sch_1):page93_i143"
				( attribute "BOM_COST" "PROC_SIDEBAND"
					( Origin gFrontEnd )
				)
				( attribute "CDS_LIB" "mstr_discrete"
					( Origin gPackager )
				)
				( attribute "CDS_LOCATION" "R2T72"
					( Origin gPackager )
				)
				( attribute "CDS_SEC" "1"
					( Origin gPackager )
				)
				( attribute "LOCATION" "R2T72"
					( Origin gFrontEnd )
				)
				( attribute "MATERIAL" "CHIP"
					( Origin gFrontEnd )
				)
				( attribute "PACK_TYPE" "0402"
					( Origin gFrontEnd )
				)
				( attribute "PART_NUMBER" "G21796-009"
					( Origin gFrontEnd )
				)
				( attribute "PHYS_PAGE" "93"
					( Origin gFrontEnd )
				)
				( attribute "ROOM" "PROC_SIDEBAND"
					( Origin gFrontEnd )
				)
				( attribute "ROT" "0"
					( Origin gFrontEnd )
				)
				( attribute "SEC" "1"
					( Origin gFrontEnd )
				)
				( attribute "SEC_TYPE" "0402"
					( Origin gFrontEnd )
				)
				( attribute "TOLERANCE" "1%"
					( Origin gFrontEnd )
				)
				( attribute "VALUE" "150.0"
					( Origin gFrontEnd )
				)
				( attribute "VER" "2"
					( Origin gFrontEnd )
				)
				( attribute "WATTAGE" "1/16W"
					( Origin gFrontEnd )
				)
				( attribute "XY" "(-2475,2525)"
					( Origin gFrontEnd )
				)
				( attribute "CHIPS_PART_NAME" "RES"
					( Origin gPackager )
				)
				( attribute "CDS_PART_NAME" "RES_0402-150.0,1%,1/16W,CHIP,GA"
					( Origin gPackager )
				)
				( objectStatus "R2T72" )
			)
			( gate "@baseboard_fab2_lib.baseboard_fab2(sch_1):page93_i144"
				( attribute "BOM_COST" "PROC_SIDEBAND"
					( Origin gFrontEnd )
				)
				( attribute "CDS_LIB" "mstr_discrete"
					( Origin gPackager )
				)
				( attribute "CDS_LOCATION" "R2T73"
					( Origin gPackager )
				)
				( attribute "CDS_SEC" "1"
					( Origin gPackager )
				)
				( attribute "LOCATION" "R2T73"
					( Origin gFrontEnd )
				)
				( attribute "MATERIAL" "CHIP"
					( Origin gFrontEnd )
				)
				( attribute "PACK_TYPE" "0402"
					( Origin gFrontEnd )
				)
				( attribute "PART_NUMBER" "G21796-009"
					( Origin gFrontEnd )
				)
				( attribute "PHYS_PAGE" "93"
					( Origin gFrontEnd )
				)
				( attribute "ROOM" "PROC_SIDEBAND"
					( Origin gFrontEnd )
				)
				( attribute "ROT" "0"
					( Origin gFrontEnd )
				)
				( attribute "SEC" "1"
					( Origin gFrontEnd )
				)
				( attribute "SEC_TYPE" "0402"
					( Origin gFrontEnd )
				)
				( attribute "TOLERANCE" "1%"
					( Origin gFrontEnd )
				)
				( attribute "VALUE" "150.0"
					( Origin gFrontEnd )
				)
				( attribute "VER" "2"
					( Origin gFrontEnd )
				)
				( attribute "WATTAGE" "1/16W"
					( Origin gFrontEnd )
				)
				( attribute "XY" "(-1900,2500)"
					( Origin gFrontEnd )
				)
				( attribute "CHIPS_PART_NAME" "RES"
					( Origin gPackager )
				)
				( attribute "CDS_PART_NAME" "RES_0402-150.0,1%,1/16W,CHIP,GA"
					( Origin gPackager )
				)
				( objectStatus "R2T73" )
			)
			( gate "@baseboard_fab2_lib.baseboard_fab2(sch_1):page94_i49"
				( attribute "CDS_LIB" "mstr_discrete"
					( Origin gPackager )
				)
				( attribute "CDS_LOCATION" "Q3U1"
					( Origin gPackager )
				)
				( attribute "CDS_SEC" "1"
					( Origin gPackager )
				)
				( attribute "LOCATION" "Q3U1"
					( Origin gFrontEnd )
				)
				( attribute "MATERIAL" "FET"
					( Origin gFrontEnd )
				)
				( attribute "PACK_TYPE" "SMLF"
					( Origin gFrontEnd )
				)
				( attribute "PART_NUMBER" "E40049-001"
					( Origin gFrontEnd )
				)
				( attribute "PHYS_PAGE" "94"
					( Origin gFrontEnd )
				)
				( attribute "ROOM" "PROC_SIDEBAND"
					( Origin gFrontEnd )
				)
				( attribute "ROT" "0"
					( Origin gFrontEnd )
				)
				( attribute "SEC" "1"
					( Origin gFrontEnd )
				)
				( attribute "SEC_TYPE" "SMLF"
					( Origin gFrontEnd )
				)
				( attribute "VALUE" "NTJD4001N"
					( Origin gFrontEnd )
				)
				( attribute "VER" "5"
					( Origin gFrontEnd )
				)
				( attribute "XY" "(-2150,1925)"
					( Origin gFrontEnd )
				)
				( attribute "CHIPS_PART_NAME" "FET_N_DUAL"
					( Origin gPackager )
				)
				( attribute "CDS_PART_NAME" "FET_N_DUAL_SMLF-NTJD4001N,FET,A"
					( Origin gPackager )
				)
				( objectStatus "Q3U1" )
			)
			( gate "@baseboard_fab2_lib.baseboard_fab2(sch_1):page94_i51"
				( attribute "BOM_COST" "PROC_SIDEBAND"
					( Origin gFrontEnd )
				)
				( attribute "CDS_LIB" "mstr_discrete"
					( Origin gPackager )
				)
				( attribute "CDS_LOCATION" "R7G7"
					( Origin gPackager )
				)
				( attribute "CDS_SEC" "1"
					( Origin gPackager )
				)
				( attribute "LOCATION" "R7G7"
					( Origin gFrontEnd )
				)
				( attribute "MATERIAL" "CHIP"
					( Origin gFrontEnd )
				)
				( attribute "PACK_TYPE" "0402"
					( Origin gFrontEnd )
				)
				( attribute "PART_NUMBER" "G21796-072"
					( Origin gFrontEnd )
				)
				( attribute "PHYS_PAGE" "94"
					( Origin gFrontEnd )
				)
				( attribute "ROOM" "PROC_SIDEBAND"
					( Origin gFrontEnd )
				)
				( attribute "ROT" "2"
					( Origin gFrontEnd )
				)
				( attribute "SEC" "1"
					( Origin gPackager )
				)
				( attribute "TOLERANCE" "1%"
					( Origin gFrontEnd )
				)
				( attribute "VALUE" "4.75K"
					( Origin gFrontEnd )
				)
				( attribute "VER" "2"
					( Origin gFrontEnd )
				)
				( attribute "WATTAGE" "1/16W"
					( Origin gFrontEnd )
				)
				( attribute "XY" "(-2150,2375)"
					( Origin gFrontEnd )
				)
				( attribute "CHIPS_PART_NAME" "RES"
					( Origin gPackager )
				)
				( attribute "CDS_PART_NAME" "RES_0402-4.75K,1%,1/16W,CHIP,GA"
					( Origin gPackager )
				)
				( objectStatus "R7G7" )
			)
			( gate "@baseboard_fab2_lib.baseboard_fab2(sch_1):page94_i60"
				( attribute "CDS_LIB" "mstr_discrete"
					( Origin gPackager )
				)
				( attribute "CDS_LOCATION" "Q7E1"
					( Origin gPackager )
				)
				( attribute "CDS_SEC" "1"
					( Origin gPackager )
				)
				( attribute "LOCATION" "Q7E1"
					( Origin gFrontEnd )
				)
				( attribute "MATERIAL" "FET"
					( Origin gFrontEnd )
				)
				( attribute "PACK_TYPE" "SMLF"
					( Origin gFrontEnd )
				)
				( attribute "PART_NUMBER" "E40049-001"
					( Origin gFrontEnd )
				)
				( attribute "PHYS_PAGE" "94"
					( Origin gFrontEnd )
				)
				( attribute "ROOM" "PROC_SIDEBAND"
					( Origin gFrontEnd )
				)
				( attribute "ROT" "0"
					( Origin gFrontEnd )
				)
				( attribute "SEC" "1"
					( Origin gFrontEnd )
				)
				( attribute "SEC_TYPE" "SMLF"
					( Origin gFrontEnd )
				)
				( attribute "VALUE" "NTJD4001N"
					( Origin gFrontEnd )
				)
				( attribute "VER" "5"
					( Origin gFrontEnd )
				)
				( attribute "XY" "(-2150,825)"
					( Origin gFrontEnd )
				)
				( attribute "CHIPS_PART_NAME" "FET_N_DUAL"
					( Origin gPackager )
				)
				( attribute "CDS_PART_NAME" "FET_N_DUAL_SMLF-NTJD4001N,FET,A"
					( Origin gPackager )
				)
				( objectStatus "Q7E1" )
			)
			( gate "@baseboard_fab2_lib.baseboard_fab2(sch_1):page94_i64"
				( attribute "CDS_LIB" "mstr_discrete"
					( Origin gPackager )
				)
				( attribute "CDS_LOCATION" "Q7E1"
					( Origin gPackager )
				)
				( attribute "CDS_SEC" "2"
					( Origin gPackager )
				)
				( attribute "LOCATION" "Q7E1"
					( Origin gFrontEnd )
				)
				( attribute "MATERIAL" "FET"
					( Origin gFrontEnd )
				)
				( attribute "PACK_TYPE" "SMLF"
					( Origin gFrontEnd )
				)
				( attribute "PART_NUMBER" "E40049-001"
					( Origin gFrontEnd )
				)
				( attribute "PHYS_PAGE" "94"
					( Origin gFrontEnd )
				)
				( attribute "ROOM" "PROC_SIDEBAND"
					( Origin gFrontEnd )
				)
				( attribute "ROT" "0"
					( Origin gFrontEnd )
				)
				( attribute "SEC" "2"
					( Origin gFrontEnd )
				)
				( attribute "SEC_TYPE" "SMLF"
					( Origin gFrontEnd )
				)
				( attribute "VALUE" "NTJD4001N"
					( Origin gFrontEnd )
				)
				( attribute "VER" "5"
					( Origin gFrontEnd )
				)
				( attribute "XY" "(-1425,950)"
					( Origin gFrontEnd )
				)
				( attribute "CHIPS_PART_NAME" "FET_N_DUAL"
					( Origin gPackager )
				)
				( attribute "CDS_PART_NAME" "FET_N_DUAL_SMLF-NTJD4001N,FET,A"
					( Origin gPackager )
				)
				( objectStatus "Q7E1" )
			)
			( gate "@baseboard_fab2_lib.baseboard_fab2(sch_1):page94_i66"
				( attribute "BOM_COST" "PROC_SIDEBAND"
					( Origin gFrontEnd )
				)
				( attribute "CDS_LIB" "mstr_discrete"
					( Origin gPackager )
				)
				( attribute "CDS_LOCATION" "R3R4"
					( Origin gPackager )
				)
				( attribute "CDS_SEC" "1"
					( Origin gPackager )
				)
				( attribute "LOCATION" "R3R4"
					( Origin gFrontEnd )
				)
				( attribute "MATERIAL" "CHIP"
					( Origin gFrontEnd )
				)
				( attribute "PACK_TYPE" "0402"
					( Origin gFrontEnd )
				)
				( attribute "PART_NUMBER" "G21796-072"
					( Origin gFrontEnd )
				)
				( attribute "PHYS_PAGE" "94"
					( Origin gFrontEnd )
				)
				( attribute "ROOM" "PROC_SIDEBAND"
					( Origin gFrontEnd )
				)
				( attribute "ROT" "2"
					( Origin gFrontEnd )
				)
				( attribute "SEC" "1"
					( Origin gPackager )
				)
				( attribute "TOLERANCE" "1%"
					( Origin gFrontEnd )
				)
				( attribute "VALUE" "4.75K"
					( Origin gFrontEnd )
				)
				( attribute "VER" "2"
					( Origin gFrontEnd )
				)
				( attribute "WATTAGE" "1/16W"
					( Origin gFrontEnd )
				)
				( attribute "XY" "(-2150,1275)"
					( Origin gFrontEnd )
				)
				( attribute "CHIPS_PART_NAME" "RES"
					( Origin gPackager )
				)
				( attribute "CDS_PART_NAME" "RES_0402-4.75K,1%,1/16W,CHIP,GA"
					( Origin gPackager )
				)
				( objectStatus "R3R4" )
			)
			( gate "@baseboard_fab2_lib.baseboard_fab2(sch_1):page94_i69"
				( attribute "CDS_LIB" "mstr_discrete"
					( Origin gPackager )
				)
				( attribute "CDS_LOCATION" "Q7E2"
					( Origin gPackager )
				)
				( attribute "CDS_SEC" "1"
					( Origin gPackager )
				)
				( attribute "LOCATION" "Q7E2"
					( Origin gFrontEnd )
				)
				( attribute "MATERIAL" "FET"
					( Origin gFrontEnd )
				)
				( attribute "PACK_TYPE" "SMLF"
					( Origin gFrontEnd )
				)
				( attribute "PART_NUMBER" "E40049-001"
					( Origin gFrontEnd )
				)
				( attribute "PHYS_PAGE" "94"
					( Origin gFrontEnd )
				)
				( attribute "ROOM" "PROC_SIDEBAND"
					( Origin gFrontEnd )
				)
				( attribute "ROT" "0"
					( Origin gFrontEnd )
				)
				( attribute "SEC" "1"
					( Origin gFrontEnd )
				)
				( attribute "SEC_TYPE" "SMLF"
					( Origin gFrontEnd )
				)
				( attribute "VALUE" "NTJD4001N"
					( Origin gFrontEnd )
				)
				( attribute "VER" "5"
					( Origin gFrontEnd )
				)
				( attribute "XY" "(1175,1975)"
					( Origin gFrontEnd )
				)
				( attribute "CHIPS_PART_NAME" "FET_N_DUAL"
					( Origin gPackager )
				)
				( attribute "CDS_PART_NAME" "FET_N_DUAL_SMLF-NTJD4001N,FET,A"
					( Origin gPackager )
				)
				( objectStatus "Q7E2" )
			)
			( gate "@baseboard_fab2_lib.baseboard_fab2(sch_1):page94_i75"
				( attribute "CDS_LIB" "mstr_discrete"
					( Origin gPackager )
				)
				( attribute "CDS_LOCATION" "Q7E2"
					( Origin gPackager )
				)
				( attribute "CDS_SEC" "2"
					( Origin gPackager )
				)
				( attribute "LOCATION" "Q7E2"
					( Origin gFrontEnd )
				)
				( attribute "MATERIAL" "FET"
					( Origin gFrontEnd )
				)
				( attribute "PACK_TYPE" "SMLF"
					( Origin gFrontEnd )
				)
				( attribute "PART_NUMBER" "E40049-001"
					( Origin gFrontEnd )
				)
				( attribute "PHYS_PAGE" "94"
					( Origin gFrontEnd )
				)
				( attribute "ROOM" "PROC_SIDEBAND"
					( Origin gFrontEnd )
				)
				( attribute "ROT" "0"
					( Origin gFrontEnd )
				)
				( attribute "SEC" "2"
					( Origin gFrontEnd )
				)
				( attribute "SEC_TYPE" "SMLF"
					( Origin gFrontEnd )
				)
				( attribute "VALUE" "NTJD4001N"
					( Origin gFrontEnd )
				)
				( attribute "VER" "5"
					( Origin gFrontEnd )
				)
				( attribute "XY" "(1900,2100)"
					( Origin gFrontEnd )
				)
				( attribute "CHIPS_PART_NAME" "FET_N_DUAL"
					( Origin gPackager )
				)
				( attribute "CDS_PART_NAME" "FET_N_DUAL_SMLF-NTJD4001N,FET,A"
					( Origin gPackager )
				)
				( objectStatus "Q7E2" )
			)
			( gate "@baseboard_fab2_lib.baseboard_fab2(sch_1):page94_i77"
				( attribute "CDS_LIB" "mstr_discrete"
					( Origin gPackager )
				)
				( attribute "CDS_LOCATION" "Q4B1"
					( Origin gPackager )
				)
				( attribute "CDS_SEC" "2"
					( Origin gPackager )
				)
				( attribute "LOCATION" "Q4B1"
					( Origin gFrontEnd )
				)
				( attribute "MATERIAL" "FET"
					( Origin gFrontEnd )
				)
				( attribute "PACK_TYPE" "SMLF"
					( Origin gFrontEnd )
				)
				( attribute "PART_NUMBER" "E40049-001"
					( Origin gFrontEnd )
				)
				( attribute "PHYS_PAGE" "94"
					( Origin gFrontEnd )
				)
				( attribute "ROOM" "PROC_SIDEBAND"
					( Origin gFrontEnd )
				)
				( attribute "ROT" "0"
					( Origin gFrontEnd )
				)
				( attribute "SEC" "2"
					( Origin gFrontEnd )
				)
				( attribute "SEC_TYPE" "SMLF"
					( Origin gFrontEnd )
				)
				( attribute "VALUE" "NTJD4001N"
					( Origin gFrontEnd )
				)
				( attribute "VER" "5"
					( Origin gFrontEnd )
				)
				( attribute "XY" "(1900,1000)"
					( Origin gFrontEnd )
				)
				( attribute "CHIPS_PART_NAME" "FET_N_DUAL"
					( Origin gPackager )
				)
				( attribute "CDS_PART_NAME" "FET_N_DUAL_SMLF-NTJD4001N,FET,A"
					( Origin gPackager )
				)
				( objectStatus "Q4B1" )
			)
			( gate "@baseboard_fab2_lib.baseboard_fab2(sch_1):page94_i79"
				( attribute "BOM_COST" "PROC_SIDEBAND"
					( Origin gFrontEnd )
				)
				( attribute "CDS_LIB" "mstr_discrete"
					( Origin gPackager )
				)
				( attribute "CDS_LOCATION" "R3R10"
					( Origin gPackager )
				)
				( attribute "CDS_SEC" "1"
					( Origin gPackager )
				)
				( attribute "LOCATION" "R3R10"
					( Origin gFrontEnd )
				)
				( attribute "MATERIAL" "CHIP"
					( Origin gFrontEnd )
				)
				( attribute "PACK_TYPE" "0402"
					( Origin gFrontEnd )
				)
				( attribute "PART_NUMBER" "G21796-072"
					( Origin gFrontEnd )
				)
				( attribute "PHYS_PAGE" "94"
					( Origin gFrontEnd )
				)
				( attribute "ROOM" "PROC_SIDEBAND"
					( Origin gFrontEnd )
				)
				( attribute "ROT" "2"
					( Origin gFrontEnd )
				)
				( attribute "SEC" "1"
					( Origin gPackager )
				)
				( attribute "TOLERANCE" "1%"
					( Origin gFrontEnd )
				)
				( attribute "VALUE" "4.75K"
					( Origin gFrontEnd )
				)
				( attribute "VER" "2"
					( Origin gFrontEnd )
				)
				( attribute "WATTAGE" "1/16W"
					( Origin gFrontEnd )
				)
				( attribute "XY" "(1175,2425)"
					( Origin gFrontEnd )
				)
				( attribute "CHIPS_PART_NAME" "RES"
					( Origin gPackager )
				)
				( attribute "CDS_PART_NAME" "RES_0402-4.75K,1%,1/16W,CHIP,GA"
					( Origin gPackager )
				)
				( objectStatus "R3R10" )
			)
			( gate "@baseboard_fab2_lib.baseboard_fab2(sch_1):page94_i82"
				( attribute "BOM_COST" "PROC_SIDEBAND"
					( Origin gFrontEnd )
				)
				( attribute "CDS_LIB" "mstr_discrete"
					( Origin gPackager )
				)
				( attribute "CDS_LOCATION" "R6M4"
					( Origin gPackager )
				)
				( attribute "CDS_SEC" "1"
					( Origin gPackager )
				)
				( attribute "LOCATION" "R6M4"
					( Origin gFrontEnd )
				)
				( attribute "MATERIAL" "CHIP"
					( Origin gFrontEnd )
				)
				( attribute "PACK_TYPE" "0402"
					( Origin gFrontEnd )
				)
				( attribute "PART_NUMBER" "G21796-072"
					( Origin gFrontEnd )
				)
				( attribute "PHYS_PAGE" "94"
					( Origin gFrontEnd )
				)
				( attribute "ROOM" "PROC_SIDEBAND"
					( Origin gFrontEnd )
				)
				( attribute "ROT" "2"
					( Origin gFrontEnd )
				)
				( attribute "SEC" "1"
					( Origin gPackager )
				)
				( attribute "TOLERANCE" "1%"
					( Origin gFrontEnd )
				)
				( attribute "VALUE" "4.75K"
					( Origin gFrontEnd )
				)
				( attribute "VER" "2"
					( Origin gFrontEnd )
				)
				( attribute "WATTAGE" "1/16W"
					( Origin gFrontEnd )
				)
				( attribute "XY" "(1175,1325)"
					( Origin gFrontEnd )
				)
				( attribute "CHIPS_PART_NAME" "RES"
					( Origin gPackager )
				)
				( attribute "CDS_PART_NAME" "RES_0402-4.75K,1%,1/16W,CHIP,GA"
					( Origin gPackager )
				)
				( objectStatus "R6M4" )
			)
			( gate "@baseboard_fab2_lib.baseboard_fab2(sch_1):page94_i84"
				( attribute "CDS_LIB" "mstr_discrete"
					( Origin gPackager )
				)
				( attribute "CDS_LOCATION" "Q4B1"
					( Origin gPackager )
				)
				( attribute "CDS_SEC" "1"
					( Origin gPackager )
				)
				( attribute "LOCATION" "Q4B1"
					( Origin gFrontEnd )
				)
				( attribute "MATERIAL" "FET"
					( Origin gFrontEnd )
				)
				( attribute "PACK_TYPE" "SMLF"
					( Origin gFrontEnd )
				)
				( attribute "PART_NUMBER" "E40049-001"
					( Origin gFrontEnd )
				)
				( attribute "PHYS_PAGE" "94"
					( Origin gFrontEnd )
				)
				( attribute "ROOM" "PROC_SIDEBAND"
					( Origin gFrontEnd )
				)
				( attribute "ROT" "0"
					( Origin gFrontEnd )
				)
				( attribute "SEC" "1"
					( Origin gFrontEnd )
				)
				( attribute "SEC_TYPE" "SMLF"
					( Origin gFrontEnd )
				)
				( attribute "VALUE" "NTJD4001N"
					( Origin gFrontEnd )
				)
				( attribute "VER" "5"
					( Origin gFrontEnd )
				)
				( attribute "XY" "(1175,875)"
					( Origin gFrontEnd )
				)
				( attribute "CHIPS_PART_NAME" "FET_N_DUAL"
					( Origin gPackager )
				)
				( attribute "CDS_PART_NAME" "FET_N_DUAL_SMLF-NTJD4001N,FET,A"
					( Origin gPackager )
				)
				( objectStatus "Q4B1" )
			)
			( gate "@baseboard_fab2_lib.baseboard_fab2(sch_1):page94_i89"
				( attribute "CDS_LIB" "mstr_discrete"
					( Origin gPackager )
				)
				( attribute "CDS_LOCATION" "Q3U1"
					( Origin gPackager )
				)
				( attribute "CDS_SEC" "2"
					( Origin gPackager )
				)
				( attribute "LOCATION" "Q3U1"
					( Origin gFrontEnd )
				)
				( attribute "MATERIAL" "FET"
					( Origin gFrontEnd )
				)
				( attribute "PACK_TYPE" "SMLF"
					( Origin gFrontEnd )
				)
				( attribute "PART_NUMBER" "E40049-001"
					( Origin gFrontEnd )
				)
				( attribute "PHYS_PAGE" "94"
					( Origin gFrontEnd )
				)
				( attribute "ROOM" "PROC_SIDEBAND"
					( Origin gFrontEnd )
				)
				( attribute "ROT" "0"
					( Origin gFrontEnd )
				)
				( attribute "SEC" "2"
					( Origin gFrontEnd )
				)
				( attribute "SEC_TYPE" "SMLF"
					( Origin gFrontEnd )
				)
				( attribute "VALUE" "NTJD4001N"
					( Origin gFrontEnd )
				)
				( attribute "VER" "5"
					( Origin gFrontEnd )
				)
				( attribute "XY" "(-1425,2050)"
					( Origin gFrontEnd )
				)
				( attribute "CHIPS_PART_NAME" "FET_N_DUAL"
					( Origin gPackager )
				)
				( attribute "CDS_PART_NAME" "FET_N_DUAL_SMLF-NTJD4001N,FET,A"
					( Origin gPackager )
				)
				( objectStatus "Q3U1" )
			)
			( gate "@baseboard_fab2_lib.baseboard_fab2(sch_1):page94_i91"
				( attribute "BOM_COST" "PROC_SIDEBAND"
					( Origin gFrontEnd )
				)
				( attribute "CDS_LIB" "mstr_discrete"
					( Origin gPackager )
				)
				( attribute "CDS_LOCATION" "R4U1"
					( Origin gPackager )
				)
				( attribute "CDS_SEC" "1"
					( Origin gPackager )
				)
				( attribute "LOCATION" "R4U1"
					( Origin gFrontEnd )
				)
				( attribute "MATERIAL" "CHIP"
					( Origin gFrontEnd )
				)
				( attribute "PACK_TYPE" "0402"
					( Origin gFrontEnd )
				)
				( attribute "PART_NUMBER" "G21796-072"
					( Origin gFrontEnd )
				)
				( attribute "PHYS_PAGE" "94"
					( Origin gFrontEnd )
				)
				( attribute "ROOM" "PROC_SIDEBAND"
					( Origin gFrontEnd )
				)
				( attribute "ROT" "2"
					( Origin gFrontEnd )
				)
				( attribute "SEC" "1"
					( Origin gFrontEnd )
				)
				( attribute "SEC_TYPE" "0402"
					( Origin gFrontEnd )
				)
				( attribute "TOLERANCE" "1%"
					( Origin gFrontEnd )
				)
				( attribute "VALUE" "4.75K"
					( Origin gFrontEnd )
				)
				( attribute "VER" "2"
					( Origin gFrontEnd )
				)
				( attribute "WATTAGE" "1/16W"
					( Origin gFrontEnd )
				)
				( attribute "XY" "(1400,4450)"
					( Origin gFrontEnd )
				)
				( attribute "CHIPS_PART_NAME" "RES"
					( Origin gPackager )
				)
				( attribute "CDS_PART_NAME" "RES_0402-4.75K,1%,1/16W,CHIP,GA"
					( Origin gPackager )
				)
				( objectStatus "R4U1" )
			)
			( gate "@baseboard_fab2_lib.baseboard_fab2(sch_1):page94_i94"
				( attribute "BOM_COST" "PROC_SIDEBAND"
					( Origin gFrontEnd )
				)
				( attribute "CDS_LIB" "mstr_discrete"
					( Origin gPackager )
				)
				( attribute "CDS_LOCATION" "R4U3"
					( Origin gPackager )
				)
				( attribute "CDS_SEC" "1"
					( Origin gPackager )
				)
				( attribute "LOCATION" "R4U3"
					( Origin gFrontEnd )
				)
				( attribute "MATERIAL" "CHIP"
					( Origin gFrontEnd )
				)
				( attribute "PACK_TYPE" "0402"
					( Origin gFrontEnd )
				)
				( attribute "PART_NUMBER" "G21796-072"
					( Origin gFrontEnd )
				)
				( attribute "PHYS_PAGE" "94"
					( Origin gFrontEnd )
				)
				( attribute "ROOM" "PROC_SIDEBAND"
					( Origin gFrontEnd )
				)
				( attribute "ROT" "2"
					( Origin gFrontEnd )
				)
				( attribute "SEC" "1"
					( Origin gFrontEnd )
				)
				( attribute "SEC_TYPE" "0402"
					( Origin gFrontEnd )
				)
				( attribute "TOLERANCE" "1%"
					( Origin gFrontEnd )
				)
				( attribute "VALUE" "4.75K"
					( Origin gFrontEnd )
				)
				( attribute "VER" "2"
					( Origin gFrontEnd )
				)
				( attribute "WATTAGE" "1/16W"
					( Origin gFrontEnd )
				)
				( attribute "XY" "(175,4075)"
					( Origin gFrontEnd )
				)
				( attribute "CHIPS_PART_NAME" "RES"
					( Origin gPackager )
				)
				( attribute "CDS_PART_NAME" "RES_0402-4.75K,1%,1/16W,CHIP,GA"
					( Origin gPackager )
				)
				( objectStatus "R4U3" )
			)
			( gate "@baseboard_fab2_lib.baseboard_fab2(sch_1):page94_i98"
				( attribute "BOM_COST" "PROC_SIDEBAND"
					( Origin gFrontEnd )
				)
				( attribute "CDS_LIB" "mstr_discrete"
					( Origin gPackager )
				)
				( attribute "CDS_LOCATION" "Q4U1"
					( Origin gPackager )
				)
				( attribute "CDS_SEC" "1"
					( Origin gPackager )
				)
				( attribute "LOCATION" "Q4U1"
					( Origin gFrontEnd )
				)
				( attribute "MATERIAL" "FET"
					( Origin gFrontEnd )
				)
				( attribute "PACK_TYPE" "SMLF"
					( Origin gFrontEnd )
				)
				( attribute "PART_NUMBER" "E40049-001"
					( Origin gFrontEnd )
				)
				( attribute "PHYS_PAGE" "94"
					( Origin gFrontEnd )
				)
				( attribute "ROOM" "PROC_SIDEBAND"
					( Origin gFrontEnd )
				)
				( attribute "ROT" "0"
					( Origin gFrontEnd )
				)
				( attribute "SEC" "1"
					( Origin gFrontEnd )
				)
				( attribute "SEC_TYPE" "SMLF"
					( Origin gFrontEnd )
				)
				( attribute "VALUE" "NTJD4001N"
					( Origin gFrontEnd )
				)
				( attribute "VER" "5"
					( Origin gFrontEnd )
				)
				( attribute "XY" "(175,3525)"
					( Origin gFrontEnd )
				)
				( attribute "CHIPS_PART_NAME" "FET_N_DUAL"
					( Origin gPackager )
				)
				( attribute "CDS_PART_NAME" "FET_N_DUAL_SMLF-NTJD4001N,FET,A"
					( Origin gPackager )
				)
				( objectStatus "Q4U1" )
			)
			( gate "@baseboard_fab2_lib.baseboard_fab2(sch_1):page94_i100"
				( attribute "BOM_COST" "PROC_SIDEBAND"
					( Origin gFrontEnd )
				)
				( attribute "CDS_LIB" "mstr_discrete"
					( Origin gPackager )
				)
				( attribute "CDS_LOCATION" "R4U2"
					( Origin gPackager )
				)
				( attribute "CDS_SEC" "1"
					( Origin gPackager )
				)
				( attribute "LOCATION" "R4U2"
					( Origin gFrontEnd )
				)
				( attribute "MATERIAL" "CHIP"
					( Origin gFrontEnd )
				)
				( attribute "PACK_TYPE" "0402"
					( Origin gFrontEnd )
				)
				( attribute "PART_NUMBER" "G21796-112"
					( Origin gFrontEnd )
				)
				( attribute "PHYS_PAGE" "94"
					( Origin gFrontEnd )
				)
				( attribute "ROOM" "PROC_SIDEBAND"
					( Origin gFrontEnd )
				)
				( attribute "ROT" "2"
					( Origin gFrontEnd )
				)
				( attribute "SEC" "1"
					( Origin gFrontEnd )
				)
				( attribute "SEC_TYPE" "0402"
					( Origin gFrontEnd )
				)
				( attribute "TOLERANCE" "1%"
					( Origin gFrontEnd )
				)
				( attribute "VALUE" "2.21K"
					( Origin gFrontEnd )
				)
				( attribute "VER" "2"
					( Origin gFrontEnd )
				)
				( attribute "WATTAGE" "1/16W"
					( Origin gFrontEnd )
				)
				( attribute "XY" "(-300,3650)"
					( Origin gFrontEnd )
				)
				( attribute "CHIPS_PART_NAME" "RES"
					( Origin gPackager )
				)
				( attribute "CDS_PART_NAME" "RES_0402-2.21K,1%,1/16W,CHIP,GA"
					( Origin gPackager )
				)
				( objectStatus "R4U2" )
			)
			( gate "@baseboard_fab2_lib.baseboard_fab2(sch_1):page94_i102"
				( attribute "BOM_COST" "PROC_SIDEBAND"
					( Origin gFrontEnd )
				)
				( attribute "CDS_LIB" "mstr_discrete"
					( Origin gPackager )
				)
				( attribute "CDS_LOCATION" "Q4U1"
					( Origin gPackager )
				)
				( attribute "CDS_SEC" "2"
					( Origin gPackager )
				)
				( attribute "LOCATION" "Q4U1"
					( Origin gFrontEnd )
				)
				( attribute "MATERIAL" "FET"
					( Origin gFrontEnd )
				)
				( attribute "PACK_TYPE" "SMLF"
					( Origin gFrontEnd )
				)
				( attribute "PART_NUMBER" "E40049-001"
					( Origin gFrontEnd )
				)
				( attribute "PHYS_PAGE" "94"
					( Origin gFrontEnd )
				)
				( attribute "ROOM" "PROC_SIDEBAND"
					( Origin gFrontEnd )
				)
				( attribute "ROT" "0"
					( Origin gFrontEnd )
				)
				( attribute "SEC" "2"
					( Origin gFrontEnd )
				)
				( attribute "SEC_TYPE" "SMLF"
					( Origin gFrontEnd )
				)
				( attribute "VALUE" "NTJD4001N"
					( Origin gFrontEnd )
				)
				( attribute "VER" "5"
					( Origin gFrontEnd )
				)
				( attribute "XY" "(1400,3950)"
					( Origin gFrontEnd )
				)
				( attribute "CHIPS_PART_NAME" "FET_N_DUAL"
					( Origin gPackager )
				)
				( attribute "CDS_PART_NAME" "FET_N_DUAL_SMLF-NTJD4001N,FET,A"
					( Origin gPackager )
				)
				( objectStatus "Q4U1" )
			)
			( gate "@baseboard_fab2_lib.baseboard_fab2(sch_1):page94_i104"
				( attribute "CDS_LIB" "mstr_discrete"
					( Origin gPackager )
				)
				( attribute "CDS_LOCATION" "R4U4"
					( Origin gPackager )
				)
				( attribute "CDS_SEC" "1"
					( Origin gPackager )
				)
				( attribute "LOCATION" "R4U4"
					( Origin gFrontEnd )
				)
				( attribute "MATERIAL" "CHIP"
					( Origin gFrontEnd )
				)
				( attribute "PACK_TYPE" "0402"
					( Origin gFrontEnd )
				)
				( attribute "PART_NUMBER" "G21497-023"
					( Origin gFrontEnd )
				)
				( attribute "PHYS_PAGE" "94"
					( Origin gFrontEnd )
				)
				( attribute "ROT" "0"
					( Origin gFrontEnd )
				)
				( attribute "SEC" "1"
					( Origin gFrontEnd )
				)
				( attribute "SEC_TYPE" "0402"
					( Origin gFrontEnd )
				)
				( attribute "TOLERANCE" "5%"
					( Origin gFrontEnd )
				)
				( attribute "VALUE" "33.0K"
					( Origin gFrontEnd )
				)
				( attribute "VER" "2"
					( Origin gFrontEnd )
				)
				( attribute "WATTAGE" "1/16W"
					( Origin gFrontEnd )
				)
				( attribute "XY" "(750,3575)"
					( Origin gFrontEnd )
				)
				( attribute "CHIPS_PART_NAME" "RES"
					( Origin gPackager )
				)
				( attribute "CDS_PART_NAME" "RES_0402-33.0K,5%,1/16W,CHIP,GA"
					( Origin gPackager )
				)
				( objectStatus "R4U4" )
			)
			( gate "@baseboard_fab2_lib.baseboard_fab2(sch_1):page95_i28"
				( attribute "BOM_COST" "PROC_SIDEBAND"
					( Origin gFrontEnd )
				)
				( attribute "CDS_LIB" "mstr_discrete"
					( Origin gPackager )
				)
				( attribute "CDS_LOCATION" "Q2U1"
					( Origin gPackager )
				)
				( attribute "CDS_SEC" "1"
					( Origin gPackager )
				)
				( attribute "LOCATION" "Q2U1"
					( Origin gFrontEnd )
				)
				( attribute "MATERIAL" "FET"
					( Origin gFrontEnd )
				)
				( attribute "PACK_TYPE" "SMLF"
					( Origin gFrontEnd )
				)
				( attribute "PART_NUMBER" "E40049-001"
					( Origin gFrontEnd )
				)
				( attribute "PHYS_PAGE" "95"
					( Origin gFrontEnd )
				)
				( attribute "ROOM" "PROC_SIDEBAND"
					( Origin gFrontEnd )
				)
				( attribute "ROT" "0"
					( Origin gFrontEnd )
				)
				( attribute "SEC" "1"
					( Origin gFrontEnd )
				)
				( attribute "SEC_TYPE" "SMLF"
					( Origin gFrontEnd )
				)
				( attribute "VALUE" "NTJD4001N"
					( Origin gFrontEnd )
				)
				( attribute "VER" "5"
					( Origin gFrontEnd )
				)
				( attribute "XY" "(-3100,2625)"
					( Origin gFrontEnd )
				)
				( attribute "CHIPS_PART_NAME" "FET_N_DUAL"
					( Origin gPackager )
				)
				( attribute "CDS_PART_NAME" "FET_N_DUAL_SMLF-NTJD4001N,FET,A"
					( Origin gPackager )
				)
				( objectStatus "Q2U1" )
			)
			( gate "@baseboard_fab2_lib.baseboard_fab2(sch_1):page95_i32"
				( attribute "BOM_COST" "PROC_SIDEBAND"
					( Origin gFrontEnd )
				)
				( attribute "CDS_LIB" "mstr_discrete"
					( Origin gPackager )
				)
				( attribute "CDS_LOCATION" "Q4B2"
					( Origin gPackager )
				)
				( attribute "CDS_SEC" "1"
					( Origin gPackager )
				)
				( attribute "LOCATION" "Q4B2"
					( Origin gFrontEnd )
				)
				( attribute "MATERIAL" "FET"
					( Origin gFrontEnd )
				)
				( attribute "PACK_TYPE" "SMLF"
					( Origin gFrontEnd )
				)
				( attribute "PART_NUMBER" "E40049-001"
					( Origin gFrontEnd )
				)
				( attribute "PHYS_PAGE" "95"
					( Origin gFrontEnd )
				)
				( attribute "ROOM" "PROC_SIDEBAND"
					( Origin gFrontEnd )
				)
				( attribute "ROT" "0"
					( Origin gFrontEnd )
				)
				( attribute "SEC" "1"
					( Origin gFrontEnd )
				)
				( attribute "SEC_TYPE" "SMLF"
					( Origin gFrontEnd )
				)
				( attribute "VALUE" "NTJD4001N"
					( Origin gFrontEnd )
				)
				( attribute "VER" "5"
					( Origin gFrontEnd )
				)
				( attribute "XY" "(-3100,1300)"
					( Origin gFrontEnd )
				)
				( attribute "CHIPS_PART_NAME" "FET_N_DUAL"
					( Origin gPackager )
				)
				( attribute "CDS_PART_NAME" "FET_N_DUAL_SMLF-NTJD4001N,FET,A"
					( Origin gPackager )
				)
				( objectStatus "Q4B2" )
			)
			( gate "@baseboard_fab2_lib.baseboard_fab2(sch_1):page95_i33"
				( attribute "BOM_COST" "PROC_SIDEBAND"
					( Origin gFrontEnd )
				)
				( attribute "CDS_LIB" "mstr_discrete"
					( Origin gPackager )
				)
				( attribute "CDS_LOCATION" "Q4B2"
					( Origin gPackager )
				)
				( attribute "CDS_SEC" "2"
					( Origin gPackager )
				)
				( attribute "LOCATION" "Q4B2"
					( Origin gFrontEnd )
				)
				( attribute "MATERIAL" "FET"
					( Origin gFrontEnd )
				)
				( attribute "PACK_TYPE" "SMLF"
					( Origin gFrontEnd )
				)
				( attribute "PART_NUMBER" "E40049-001"
					( Origin gFrontEnd )
				)
				( attribute "PHYS_PAGE" "95"
					( Origin gFrontEnd )
				)
				( attribute "ROOM" "PROC_SIDEBAND"
					( Origin gFrontEnd )
				)
				( attribute "ROT" "0"
					( Origin gFrontEnd )
				)
				( attribute "SEC" "2"
					( Origin gFrontEnd )
				)
				( attribute "SEC_TYPE" "SMLF"
					( Origin gFrontEnd )
				)
				( attribute "VALUE" "NTJD4001N"
					( Origin gFrontEnd )
				)
				( attribute "VER" "5"
					( Origin gFrontEnd )
				)
				( attribute "XY" "(-3100,700)"
					( Origin gFrontEnd )
				)
				( attribute "CHIPS_PART_NAME" "FET_N_DUAL"
					( Origin gPackager )
				)
				( attribute "CDS_PART_NAME" "FET_N_DUAL_SMLF-NTJD4001N,FET,A"
					( Origin gPackager )
				)
				( objectStatus "Q4B2" )
			)
			( gate "@baseboard_fab2_lib.baseboard_fab2(sch_1):page95_i51"
				( attribute "BOM_COST" "PROC_SIDEBAND"
					( Origin gFrontEnd )
				)
				( attribute "CDS_LIB" "mstr_discrete"
					( Origin gPackager )
				)
				( attribute "CDS_LOCATION" "Q7E3"
					( Origin gPackager )
				)
				( attribute "CDS_SEC" "2"
					( Origin gPackager )
				)
				( attribute "LOCATION" "Q7E3"
					( Origin gFrontEnd )
				)
				( attribute "MATERIAL" "FET"
					( Origin gFrontEnd )
				)
				( attribute "PACK_TYPE" "SMLF"
					( Origin gFrontEnd )
				)
				( attribute "PART_NUMBER" "E40049-001"
					( Origin gFrontEnd )
				)
				( attribute "PHYS_PAGE" "95"
					( Origin gFrontEnd )
				)
				( attribute "ROOM" "PROC_SIDEBAND"
					( Origin gFrontEnd )
				)
				( attribute "ROT" "0"
					( Origin gFrontEnd )
				)
				( attribute "SEC" "2"
					( Origin gFrontEnd )
				)
				( attribute "SEC_TYPE" "SMLF"
					( Origin gFrontEnd )
				)
				( attribute "VALUE" "NTJD4001N"
					( Origin gFrontEnd )
				)
				( attribute "VER" "5"
					( Origin gFrontEnd )
				)
				( attribute "XY" "(-3100,3275)"
					( Origin gFrontEnd )
				)
				( attribute "CHIPS_PART_NAME" "FET_N_DUAL"
					( Origin gPackager )
				)
				( attribute "CDS_PART_NAME" "FET_N_DUAL_SMLF-NTJD4001N,FET,A"
					( Origin gPackager )
				)
				( objectStatus "Q7E3" )
			)
			( gate "@baseboard_fab2_lib.baseboard_fab2(sch_1):page95_i52"
				( attribute "BOM_COST" "PROC_SIDEBAND"
					( Origin gFrontEnd )
				)
				( attribute "CDS_LIB" "mstr_discrete"
					( Origin gPackager )
				)
				( attribute "CDS_LOCATION" "Q7E3"
					( Origin gPackager )
				)
				( attribute "CDS_SEC" "1"
					( Origin gPackager )
				)
				( attribute "LOCATION" "Q7E3"
					( Origin gFrontEnd )
				)
				( attribute "MATERIAL" "FET"
					( Origin gFrontEnd )
				)
				( attribute "PACK_TYPE" "SMLF"
					( Origin gFrontEnd )
				)
				( attribute "PART_NUMBER" "E40049-001"
					( Origin gFrontEnd )
				)
				( attribute "PHYS_PAGE" "95"
					( Origin gFrontEnd )
				)
				( attribute "ROOM" "PROC_SIDEBAND"
					( Origin gFrontEnd )
				)
				( attribute "ROT" "0"
					( Origin gFrontEnd )
				)
				( attribute "SEC" "1"
					( Origin gFrontEnd )
				)
				( attribute "SEC_TYPE" "SMLF"
					( Origin gFrontEnd )
				)
				( attribute "VALUE" "NTJD4001N"
					( Origin gFrontEnd )
				)
				( attribute "VER" "5"
					( Origin gFrontEnd )
				)
				( attribute "XY" "(-3100,3950)"
					( Origin gFrontEnd )
				)
				( attribute "CHIPS_PART_NAME" "FET_N_DUAL"
					( Origin gPackager )
				)
				( attribute "CDS_PART_NAME" "FET_N_DUAL_SMLF-NTJD4001N,FET,A"
					( Origin gPackager )
				)
				( objectStatus "Q7E3" )
			)
			( gate "@baseboard_fab2_lib.baseboard_fab2(sch_1):page95_i59"
				( attribute "BOM_COST" "PROC_SIDEBAND"
					( Origin gFrontEnd )
				)
				( attribute "CDS_LIB" "mstr_discrete"
					( Origin gPackager )
				)
				( attribute "CDS_LOCATION" "Q7E5"
					( Origin gPackager )
				)
				( attribute "CDS_SEC" "2"
					( Origin gPackager )
				)
				( attribute "LOCATION" "Q7E5"
					( Origin gFrontEnd )
				)
				( attribute "MATERIAL" "FET"
					( Origin gFrontEnd )
				)
				( attribute "PACK_TYPE" "SMLF"
					( Origin gFrontEnd )
				)
				( attribute "PART_NUMBER" "E40049-001"
					( Origin gFrontEnd )
				)
				( attribute "PHYS_PAGE" "95"
					( Origin gFrontEnd )
				)
				( attribute "ROOM" "HOT_EVENTS"
					( Origin gFrontEnd )
				)
				( attribute "ROT" "0"
					( Origin gFrontEnd )
				)
				( attribute "SEC" "2"
					( Origin gFrontEnd )
				)
				( attribute "SEC_TYPE" "SMLF"
					( Origin gFrontEnd )
				)
				( attribute "VALUE" "NTJD4001N"
					( Origin gFrontEnd )
				)
				( attribute "VER" "5"
					( Origin gFrontEnd )
				)
				( attribute "XY" "(3050,4725)"
					( Origin gFrontEnd )
				)
				( attribute "CHIPS_PART_NAME" "FET_N_DUAL"
					( Origin gPackager )
				)
				( attribute "CDS_PART_NAME" "FET_N_DUAL_SMLF-NTJD4001N,FET,A"
					( Origin gPackager )
				)
				( objectStatus "Q7E5" )
			)
			( gate "@baseboard_fab2_lib.baseboard_fab2(sch_1):page95_i62"
				( attribute "BOM_COST" "PROC_SIDEBAND"
					( Origin gFrontEnd )
				)
				( attribute "CDS_LIB" "mstr_discrete"
					( Origin gPackager )
				)
				( attribute "CDS_LOCATION" "R7E10"
					( Origin gPackager )
				)
				( attribute "CDS_SEC" "1"
					( Origin gPackager )
				)
				( attribute "LOCATION" "R7E10"
					( Origin gFrontEnd )
				)
				( attribute "MATERIAL" "CHIP"
					( Origin gFrontEnd )
				)
				( attribute "PACK_TYPE" "0402"
					( Origin gFrontEnd )
				)
				( attribute "PART_NUMBER" "G21796-072"
					( Origin gFrontEnd )
				)
				( attribute "PHYS_PAGE" "95"
					( Origin gFrontEnd )
				)
				( attribute "ROOM" "HOT_EVENTS"
					( Origin gFrontEnd )
				)
				( attribute "ROT" "2"
					( Origin gFrontEnd )
				)
				( attribute "SEC" "1"
					( Origin gPackager )
				)
				( attribute "TOLERANCE" "1%"
					( Origin gFrontEnd )
				)
				( attribute "VALUE" "4.75K"
					( Origin gFrontEnd )
				)
				( attribute "VER" "2"
					( Origin gFrontEnd )
				)
				( attribute "WATTAGE" "1/16W"
					( Origin gFrontEnd )
				)
				( attribute "XY" "(2475,4800)"
					( Origin gFrontEnd )
				)
				( attribute "CHIPS_PART_NAME" "RES"
					( Origin gPackager )
				)
				( attribute "CDS_PART_NAME" "RES_0402-4.75K,1%,1/16W,CHIP,GA"
					( Origin gPackager )
				)
				( objectStatus "R7E10" )
			)
			( gate "@baseboard_fab2_lib.baseboard_fab2(sch_1):page95_i69"
				( attribute "BOM_COST" "PROC_SIDEBAND"
					( Origin gFrontEnd )
				)
				( attribute "CDS_LIB" "mstr_discrete"
					( Origin gPackager )
				)
				( attribute "CDS_LOCATION" "Q7E6"
					( Origin gPackager )
				)
				( attribute "CDS_SEC" "2"
					( Origin gPackager )
				)
				( attribute "LOCATION" "Q7E6"
					( Origin gFrontEnd )
				)
				( attribute "MATERIAL" "FET"
					( Origin gFrontEnd )
				)
				( attribute "PACK_TYPE" "SMLF"
					( Origin gFrontEnd )
				)
				( attribute "PART_NUMBER" "E40049-001"
					( Origin gFrontEnd )
				)
				( attribute "PHYS_PAGE" "95"
					( Origin gFrontEnd )
				)
				( attribute "ROOM" "HOT_EVENTS"
					( Origin gFrontEnd )
				)
				( attribute "ROT" "0"
					( Origin gFrontEnd )
				)
				( attribute "SEC" "2"
					( Origin gFrontEnd )
				)
				( attribute "SEC_TYPE" "SMLF"
					( Origin gFrontEnd )
				)
				( attribute "VALUE" "NTJD4001N"
					( Origin gFrontEnd )
				)
				( attribute "VER" "5"
					( Origin gFrontEnd )
				)
				( attribute "XY" "(3225,3250)"
					( Origin gFrontEnd )
				)
				( attribute "CHIPS_PART_NAME" "FET_N_DUAL"
					( Origin gPackager )
				)
				( attribute "CDS_PART_NAME" "FET_N_DUAL_SMLF-NTJD4001N,FET,A"
					( Origin gPackager )
				)
				( objectStatus "Q7E6" )
			)
			( gate "@baseboard_fab2_lib.baseboard_fab2(sch_1):page95_i72"
				( attribute "BOM_COST" "PROC_SIDEBAND"
					( Origin gFrontEnd )
				)
				( attribute "CDS_LIB" "mstr_discrete"
					( Origin gPackager )
				)
				( attribute "CDS_LOCATION" "R7E11"
					( Origin gPackager )
				)
				( attribute "CDS_SEC" "1"
					( Origin gPackager )
				)
				( attribute "LOCATION" "R7E11"
					( Origin gFrontEnd )
				)
				( attribute "MATERIAL" "CHIP"
					( Origin gFrontEnd )
				)
				( attribute "PACK_TYPE" "0402"
					( Origin gFrontEnd )
				)
				( attribute "PART_NUMBER" "G21796-072"
					( Origin gFrontEnd )
				)
				( attribute "PHYS_PAGE" "95"
					( Origin gFrontEnd )
				)
				( attribute "ROOM" "HOT_EVENTS"
					( Origin gFrontEnd )
				)
				( attribute "ROT" "2"
					( Origin gFrontEnd )
				)
				( attribute "SEC" "1"
					( Origin gPackager )
				)
				( attribute "TOLERANCE" "1%"
					( Origin gFrontEnd )
				)
				( attribute "VALUE" "4.75K"
					( Origin gFrontEnd )
				)
				( attribute "VER" "2"
					( Origin gFrontEnd )
				)
				( attribute "WATTAGE" "1/16W"
					( Origin gFrontEnd )
				)
				( attribute "XY" "(2550,3375)"
					( Origin gFrontEnd )
				)
				( attribute "CHIPS_PART_NAME" "RES"
					( Origin gPackager )
				)
				( attribute "CDS_PART_NAME" "RES_0402-4.75K,1%,1/16W,CHIP,GA"
					( Origin gPackager )
				)
				( objectStatus "R7E11" )
			)
			( gate "@baseboard_fab2_lib.baseboard_fab2(sch_1):page95_i92"
				( attribute "BOM_COST" "PROC_SIDEBAND"
					( Origin gFrontEnd )
				)
				( attribute "CDS_LIB" "dev_discrete"
					( Origin gPackager )
				)
				( attribute "CDS_LOCATION" "C7E3"
					( Origin gPackager )
				)
				( attribute "CDS_SEC" "1"
					( Origin gPackager )
				)
				( attribute "LOCATION" "C7E3"
					( Origin gFrontEnd )
				)
				( attribute "MATERIAL" "X7R"
					( Origin gFrontEnd )
				)
				( attribute "PACK_TYPE" "0402V"
					( Origin gFrontEnd )
				)
				( attribute "PART_NUMBER" "A36096-030"
					( Origin gFrontEnd )
				)
				( attribute "PHYS_PAGE" "95"
					( Origin gFrontEnd )
				)
				( attribute "ROOM" "PROC_SIDEBAND"
					( Origin gFrontEnd )
				)
				( attribute "ROT" "0"
					( Origin gFrontEnd )
				)
				( attribute "SEC" "1"
					( Origin gFrontEnd )
				)
				( attribute "SEC_TYPE" "0402V"
					( Origin gFrontEnd )
				)
				( attribute "TOLERANCE" "10%"
					( Origin gFrontEnd )
				)
				( attribute "VALUE" "0.1UF"
					( Origin gFrontEnd )
				)
				( attribute "VER" "1"
					( Origin gFrontEnd )
				)
				( attribute "VOLTAGE" "16V"
					( Units "uVoltage" "V" 1.000000)
					( Origin gFrontEnd )
				)
				( attribute "XY" "(700,4775)"
					( Origin gFrontEnd )
				)
				( attribute "CHIPS_PART_NAME" "CAP_A"
					( Origin gPackager )
				)
				( attribute "CDS_PART_NAME" "CAP_A_0402V-0.1UF,16V,10%,X7R,A"
					( Origin gPackager )
				)
				( objectStatus "C7E3" )
			)
			( gate "@baseboard_fab2_lib.baseboard_fab2(sch_1):page134_i15"
				( attribute "CDS_LIB" "mstr_discrete"
					( Origin gPackager )
				)
				( attribute "LOCATION" "Q8D2"
					( Origin gFrontEnd )
				)
				( attribute "MATERIAL" "FET"
					( Origin gFrontEnd )
				)
				( attribute "PACK_TYPE" "SOT23LF"
					( Origin gFrontEnd )
				)
				( attribute "PART_NUMBER" "C79254-001"
					( Origin gFrontEnd )
				)
				( attribute "PHYS_PAGE" "134"
					( Origin gFrontEnd )
				)
				( attribute "ROOM" "HOT_SWAP"
					( Origin gFrontEnd )
				)
				( attribute "ROT" "0"
					( Origin gFrontEnd )
				)
				( attribute "VALUE" "2N7002"
					( Origin gFrontEnd )
				)
				( attribute "VER" "8"
					( Origin gFrontEnd )
				)
				( attribute "XY" "(700,4375)"
					( Origin gFrontEnd )
				)
				( attribute "CHIPS_PART_NAME" "FET_N"
					( Origin gPackager )
				)
				( attribute "CDS_PART_NAME" "FET_N_SOT23LF-2N7002,FET,C7925A"
					( Origin gPackager )
				)
				( attribute "CDS_LOCATION" "Q8D2"
					( Origin gPackager )
				)
				( attribute "CDS_SEC" "1"
					( Origin gPackager )
				)
				( attribute "SEC" "1"
					( Origin gPackager )
				)
				( objectStatus "Q8D2" )
			)
			( gate "@baseboard_fab2_lib.baseboard_fab2(sch_1):page95_i106"
				( attribute "CDS_LIB" "mstr_discrete"
					( Origin gPackager )
				)
				( attribute "CDS_LOCATION" "R7E7"
					( Origin gPackager )
				)
				( attribute "CDS_SEC" "1"
					( Origin gPackager )
				)
				( attribute "LOCATION" "R7E7"
					( Origin gFrontEnd )
				)
				( attribute "MATERIAL" "CHIP"
					( Origin gFrontEnd )
				)
				( attribute "PACK_TYPE" "0402"
					( Origin gFrontEnd )
				)
				( attribute "PART_NUMBER" "G21796-072"
					( Origin gFrontEnd )
				)
				( attribute "PHYS_PAGE" "95"
					( Origin gFrontEnd )
				)
				( attribute "ROOM" "PROC_SIDEBAND"
					( Origin gFrontEnd )
				)
				( attribute "ROT" "0"
					( Origin gFrontEnd )
				)
				( attribute "SEC" "1"
					( Origin gFrontEnd )
				)
				( attribute "SEC_TYPE" "0402"
					( Origin gFrontEnd )
				)
				( attribute "TOLERANCE" "1%"
					( Origin gFrontEnd )
				)
				( attribute "VALUE" "4.75K"
					( Origin gFrontEnd )
				)
				( attribute "VER" "2"
					( Origin gFrontEnd )
				)
				( attribute "WATTAGE" "1/16W"
					( Origin gFrontEnd )
				)
				( attribute "XY" "(2150,1800)"
					( Origin gFrontEnd )
				)
				( attribute "CHIPS_PART_NAME" "RES"
					( Origin gPackager )
				)
				( attribute "CDS_PART_NAME" "RES_0402-4.75K,1%,1/16W,CHIP,GA"
					( Origin gPackager )
				)
				( objectStatus "R7E7" )
			)
			( gate "@baseboard_fab2_lib.baseboard_fab2(sch_1):page95_i108"
				( attribute "BOM_COST" "PROC_SIDEBAND"
					( Origin gFrontEnd )
				)
				( attribute "CDS_LIB" "mstr_discrete"
					( Origin gPackager )
				)
				( attribute "CDS_LOCATION" "R7E9"
					( Origin gPackager )
				)
				( attribute "CDS_SEC" "1"
					( Origin gPackager )
				)
				( attribute "LOCATION" "R7E9"
					( Origin gFrontEnd )
				)
				( attribute "MATERIAL" "CHIP"
					( Origin gFrontEnd )
				)
				( attribute "PACK_TYPE" "0402"
					( Origin gFrontEnd )
				)
				( attribute "PART_NUMBER" "G21497-005"
					( Origin gFrontEnd )
				)
				( attribute "PHYS_PAGE" "95"
					( Origin gFrontEnd )
				)
				( attribute "ROOM" "PROC_SIDEBAND"
					( Origin gFrontEnd )
				)
				( attribute "ROT" "0"
					( Origin gFrontEnd )
				)
				( attribute "SEC" "1"
					( Origin gFrontEnd )
				)
				( attribute "SEC_TYPE" "0402"
					( Origin gFrontEnd )
				)
				( attribute "TOLERANCE" "5%"
					( Origin gFrontEnd )
				)
				( attribute "VALUE" "0.0"
					( Origin gFrontEnd )
				)
				( attribute "VER" "1"
					( Origin gFrontEnd )
				)
				( attribute "WATTAGE" "1/16W"
					( Origin gFrontEnd )
				)
				( attribute "XY" "(1325,1250)"
					( Origin gFrontEnd )
				)
				( attribute "CHIPS_PART_NAME" "RES"
					( Origin gPackager )
				)
				( attribute "CDS_PART_NAME" "RES_0402-0.0,5%,1/16W,CHIP,G21A"
					( Origin gPackager )
				)
				( objectStatus "R7E9" )
			)
			( gate "@baseboard_fab2_lib.baseboard_fab2(sch_1):page95_i111"
				( attribute "BOM_COST" "PROC_SIDEBAND"
					( Origin gFrontEnd )
				)
				( attribute "CDS_LIB" "mstr_discrete"
					( Origin gPackager )
				)
				( attribute "CDS_LOCATION" "Q7E5"
					( Origin gPackager )
				)
				( attribute "CDS_SEC" "1"
					( Origin gPackager )
				)
				( attribute "LOCATION" "Q7E5"
					( Origin gFrontEnd )
				)
				( attribute "MATERIAL" "FET"
					( Origin gFrontEnd )
				)
				( attribute "PACK_TYPE" "SMLF"
					( Origin gFrontEnd )
				)
				( attribute "PART_NUMBER" "E40049-001"
					( Origin gFrontEnd )
				)
				( attribute "PHYS_PAGE" "95"
					( Origin gFrontEnd )
				)
				( attribute "ROOM" "HOT_EVENTS"
					( Origin gFrontEnd )
				)
				( attribute "ROT" "0"
					( Origin gFrontEnd )
				)
				( attribute "SEC" "1"
					( Origin gFrontEnd )
				)
				( attribute "SEC_TYPE" "SMLF"
					( Origin gFrontEnd )
				)
				( attribute "VALUE" "NTJD4001N"
					( Origin gFrontEnd )
				)
				( attribute "VER" "5"
					( Origin gFrontEnd )
				)
				( attribute "XY" "(2475,4325)"
					( Origin gFrontEnd )
				)
				( attribute "CHIPS_PART_NAME" "FET_N_DUAL"
					( Origin gPackager )
				)
				( attribute "CDS_PART_NAME" "FET_N_DUAL_SMLF-NTJD4001N,FET,A"
					( Origin gPackager )
				)
				( objectStatus "Q7E5" )
			)
			( gate "@baseboard_fab2_lib.baseboard_fab2(sch_1):page95_i112"
				( attribute "BOM_COST" "PROC_SIDEBAND"
					( Origin gFrontEnd )
				)
				( attribute "CDS_LIB" "mstr_discrete"
					( Origin gPackager )
				)
				( attribute "CDS_LOCATION" "Q7E6"
					( Origin gPackager )
				)
				( attribute "CDS_SEC" "1"
					( Origin gPackager )
				)
				( attribute "LOCATION" "Q7E6"
					( Origin gFrontEnd )
				)
				( attribute "MATERIAL" "FET"
					( Origin gFrontEnd )
				)
				( attribute "PACK_TYPE" "SMLF"
					( Origin gFrontEnd )
				)
				( attribute "PART_NUMBER" "E40049-001"
					( Origin gFrontEnd )
				)
				( attribute "PHYS_PAGE" "95"
					( Origin gFrontEnd )
				)
				( attribute "ROOM" "HOT_EVENTS"
					( Origin gFrontEnd )
				)
				( attribute "ROT" "0"
					( Origin gFrontEnd )
				)
				( attribute "SEC" "1"
					( Origin gFrontEnd )
				)
				( attribute "SEC_TYPE" "SMLF"
					( Origin gFrontEnd )
				)
				( attribute "VALUE" "NTJD4001N"
					( Origin gFrontEnd )
				)
				( attribute "VER" "5"
					( Origin gFrontEnd )
				)
				( attribute "XY" "(2550,2875)"
					( Origin gFrontEnd )
				)
				( attribute "CHIPS_PART_NAME" "FET_N_DUAL"
					( Origin gPackager )
				)
				( attribute "CDS_PART_NAME" "FET_N_DUAL_SMLF-NTJD4001N,FET,A"
					( Origin gPackager )
				)
				( objectStatus "Q7E6" )
			)
			( gate "@baseboard_fab2_lib.baseboard_fab2(sch_1):page95_i113"
				( attribute "BOM_COST" "PROC_SIDEBAND"
					( Origin gFrontEnd )
				)
				( attribute "CDS_LIB" "mstr_discrete"
					( Origin gPackager )
				)
				( attribute "CDS_LOCATION" "Q2U1"
					( Origin gPackager )
				)
				( attribute "CDS_SEC" "2"
					( Origin gPackager )
				)
				( attribute "LOCATION" "Q2U1"
					( Origin gFrontEnd )
				)
				( attribute "MATERIAL" "FET"
					( Origin gFrontEnd )
				)
				( attribute "PACK_TYPE" "SMLF"
					( Origin gFrontEnd )
				)
				( attribute "PART_NUMBER" "E40049-001"
					( Origin gFrontEnd )
				)
				( attribute "PHYS_PAGE" "95"
					( Origin gFrontEnd )
				)
				( attribute "ROOM" "PROC_SIDEBAND"
					( Origin gFrontEnd )
				)
				( attribute "ROT" "0"
					( Origin gFrontEnd )
				)
				( attribute "SEC" "2"
					( Origin gFrontEnd )
				)
				( attribute "SEC_TYPE" "SMLF"
					( Origin gFrontEnd )
				)
				( attribute "VALUE" "NTJD4001N"
					( Origin gFrontEnd )
				)
				( attribute "VER" "5"
					( Origin gFrontEnd )
				)
				( attribute "XY" "(-3100,1950)"
					( Origin gFrontEnd )
				)
				( attribute "CHIPS_PART_NAME" "FET_N_DUAL"
					( Origin gPackager )
				)
				( attribute "CDS_PART_NAME" "FET_N_DUAL_SMLF-NTJD4001N,FET,A"
					( Origin gPackager )
				)
				( objectStatus "Q2U1" )
			)
			( gate "@baseboard_fab2_lib.baseboard_fab2(sch_1):page95_i115"
				( attribute "BOM_COST" "PROC_SIDEBAND"
					( Origin gFrontEnd )
				)
				( attribute "CDS_LIB" "dev_discrete"
					( Origin gPackager )
				)
				( attribute "CDS_LOCATION" "C7E4"
					( Origin gPackager )
				)
				( attribute "CDS_SEC" "1"
					( Origin gPackager )
				)
				( attribute "LOCATION" "C7E4"
					( Origin gFrontEnd )
				)
				( attribute "MATERIAL" "X7R"
					( Origin gFrontEnd )
				)
				( attribute "PACK_TYPE" "0402V"
					( Origin gFrontEnd )
				)
				( attribute "PART_NUMBER" "A36096-030"
					( Origin gFrontEnd )
				)
				( attribute "PHYS_PAGE" "95"
					( Origin gFrontEnd )
				)
				( attribute "ROOM" "PROC_SIDEBAND"
					( Origin gFrontEnd )
				)
				( attribute "ROT" "0"
					( Origin gFrontEnd )
				)
				( attribute "SEC" "1"
					( Origin gFrontEnd )
				)
				( attribute "SEC_TYPE" "0402V"
					( Origin gFrontEnd )
				)
				( attribute "TOLERANCE" "10%"
					( Origin gFrontEnd )
				)
				( attribute "VALUE" "0.1UF"
					( Origin gFrontEnd )
				)
				( attribute "VER" "1"
					( Origin gFrontEnd )
				)
				( attribute "VOLTAGE" "16V"
					( Units "uVoltage" "V" 1.000000)
					( Origin gFrontEnd )
				)
				( attribute "XY" "(1125,3450)"
					( Origin gFrontEnd )
				)
				( attribute "CHIPS_PART_NAME" "CAP_A"
					( Origin gPackager )
				)
				( attribute "CDS_PART_NAME" "CAP_A_0402V-0.1UF,16V,10%,X7R,A"
					( Origin gPackager )
				)
				( objectStatus "C7E4" )
			)
			( gate "@baseboard_fab2_lib.baseboard_fab2(sch_1):page95_i117"
				( attribute "BOM_COST" "PROC_SIDEBAND"
					( Origin gFrontEnd )
				)
				( attribute "CDS_LIB" "mstr_ttl"
					( Origin gPackager )
				)
				( attribute "CDS_LOCATION" "U7E2"
					( Origin gPackager )
				)
				( attribute "CDS_SEC" "1"
					( Origin gPackager )
				)
				( attribute "LOCATION" "U7E2"
					( Origin gFrontEnd )
				)
				( attribute "MATERIAL" "IC"
					( Origin gFrontEnd )
				)
				( attribute "PACK_TYPE" "SOTLF"
					( Origin gFrontEnd )
				)
				( attribute "PART_NUMBER" "D10321-001"
					( Origin gFrontEnd )
				)
				( attribute "PHYS_PAGE" "95"
					( Origin gFrontEnd )
				)
				( attribute "ROOM" "CAT_ERR"
					( Origin gFrontEnd )
				)
				( attribute "ROT" "0"
					( Origin gFrontEnd )
				)
				( attribute "SEC" "1"
					( Origin gFrontEnd )
				)
				( attribute "SEC_TYPE" "SOTLF"
					( Origin gFrontEnd )
				)
				( attribute "VALUE" "NC7SZ08"
					( Origin gFrontEnd )
				)
				( attribute "VER" "1"
					( Origin gFrontEnd )
				)
				( attribute "XY" "(1550,4225)"
					( Origin gFrontEnd )
				)
				( attribute "CHIPS_PART_NAME" "TTL1G08"
					( Origin gPackager )
				)
				( attribute "CDS_PART_NAME" "TTL1G08_SOTLF-NC7SZ08,IC,D1032B"
					( Origin gPackager )
				)
				( objectStatus "U7E2" )
			)
			( gate "@baseboard_fab2_lib.baseboard_fab2(sch_1):page95_i118"
				( attribute "BOM_COST" "PROC_SIDEBAND"
					( Origin gFrontEnd )
				)
				( attribute "CDS_LIB" "mstr_ttl"
					( Origin gPackager )
				)
				( attribute "CDS_LOCATION" "U7E3"
					( Origin gPackager )
				)
				( attribute "CDS_SEC" "1"
					( Origin gPackager )
				)
				( attribute "LOCATION" "U7E3"
					( Origin gFrontEnd )
				)
				( attribute "MATERIAL" "IC"
					( Origin gFrontEnd )
				)
				( attribute "PACK_TYPE" "SOTLF"
					( Origin gFrontEnd )
				)
				( attribute "PART_NUMBER" "D10321-001"
					( Origin gFrontEnd )
				)
				( attribute "PHYS_PAGE" "95"
					( Origin gFrontEnd )
				)
				( attribute "ROOM" "CAT_ERR"
					( Origin gFrontEnd )
				)
				( attribute "ROT" "0"
					( Origin gFrontEnd )
				)
				( attribute "SEC" "1"
					( Origin gFrontEnd )
				)
				( attribute "SEC_TYPE" "SOTLF"
					( Origin gFrontEnd )
				)
				( attribute "VALUE" "NC7SZ08"
					( Origin gFrontEnd )
				)
				( attribute "VER" "1"
					( Origin gFrontEnd )
				)
				( attribute "XY" "(1575,2775)"
					( Origin gFrontEnd )
				)
				( attribute "CHIPS_PART_NAME" "TTL1G08"
					( Origin gPackager )
				)
				( attribute "CDS_PART_NAME" "TTL1G08_SOTLF-NC7SZ08,IC,D1032B"
					( Origin gPackager )
				)
				( objectStatus "U7E3" )
			)
			( gate "@baseboard_fab2_lib.baseboard_fab2(sch_1):page149_i90"
				( attribute "BOM_COST" "NT_GBE_BASE"
					( Origin gFrontEnd )
				)
				( attribute "CDS_LIB" "mstr_discrete"
					( Origin gPackager )
				)
				( attribute "LOCATION" "R25W93"
					( Origin gFrontEnd )
				)
				( attribute "MATERIAL" "CHIP"
					( Origin gFrontEnd )
				)
				( attribute "PACK_TYPE" "0603"
					( Origin gFrontEnd )
				)
				( attribute "PART_NUMBER" "G22178-002"
					( Origin gFrontEnd )
				)
				( attribute "PHYS_PAGE" "149"
					( Origin gFrontEnd )
				)
				( attribute "ROOM" "NIC_SPRV"
					( Origin gFrontEnd )
				)
				( attribute "ROT" "0"
					( Origin gFrontEnd )
				)
				( attribute "TOLERANCE" "5.0%"
					( Origin gFrontEnd )
				)
				( attribute "VALUE" "0"
					( Origin gFrontEnd )
				)
				( attribute "VER" "1"
					( Origin gFrontEnd )
				)
				( attribute "WATTAGE" "1/10W"
					( Origin gFrontEnd )
				)
				( attribute "XY" "(125,4275)"
					( Origin gFrontEnd )
				)
				( attribute "CHIPS_PART_NAME" "RES"
					( Origin gPackager )
				)
				( attribute "CDS_PART_NAME" "RES_0603-0,5.0%,1/10W,CHIP,G22A"
					( Origin gPackager )
				)
				( attribute "CDS_LOCATION" "R25W93"
					( Origin gPackager )
				)
				( attribute "CDS_SEC" "1"
					( Origin gPackager )
				)
				( attribute "SEC" "1"
					( Origin gPackager )
				)
				( objectStatus "R25W93" )
			)
			( gate "@baseboard_fab2_lib.baseboard_fab2(sch_1):page96_i2"
				( attribute "BOM_COST" "PROC_SIDEBAND"
					( Origin gFrontEnd )
				)
				( attribute "CDS_LIB" "mstr_discrete"
					( Origin gPackager )
				)
				( attribute "CDS_LOCATION" "R6D12"
					( Origin gPackager )
				)
				( attribute "CDS_SEC" "1"
					( Origin gPackager )
				)
				( attribute "LOCATION" "R6D12"
					( Origin gFrontEnd )
				)
				( attribute "MATERIAL" "CHIP"
					( Origin gFrontEnd )
				)
				( attribute "PACK_TYPE" "0402"
					( Origin gFrontEnd )
				)
				( attribute "PART_NUMBER" "G21796-047"
					( Origin gFrontEnd )
				)
				( attribute "PHYS_PAGE" "96"
					( Origin gFrontEnd )
				)
				( attribute "ROOM" "PROC_RSTS_PGOODS"
					( Origin gFrontEnd )
				)
				( attribute "ROT" "0"
					( Origin gFrontEnd )
				)
				( attribute "SEC" "1"
					( Origin gFrontEnd )
				)
				( attribute "SEC_TYPE" "0402"
					( Origin gFrontEnd )
				)
				( attribute "TOLERANCE" "1%"
					( Origin gFrontEnd )
				)
				( attribute "VALUE" "49.9"
					( Origin gFrontEnd )
				)
				( attribute "VER" "2"
					( Origin gFrontEnd )
				)
				( attribute "WATTAGE" "1/16W"
					( Origin gFrontEnd )
				)
				( attribute "XY" "(1900,4450)"
					( Origin gFrontEnd )
				)
				( attribute "CHIPS_PART_NAME" "RES"
					( Origin gPackager )
				)
				( attribute "CDS_PART_NAME" "RES_0402-49.9,1%,1/16W,CHIP,G2A"
					( Origin gPackager )
				)
				( objectStatus "R6D12" )
			)
			( gate "@baseboard_fab2_lib.baseboard_fab2(sch_1):page96_i3"
				( attribute "BOM_COST" "PROC_SIDEBAND"
					( Origin gFrontEnd )
				)
				( attribute "CDS_LIB" "mstr_discrete"
					( Origin gPackager )
				)
				( attribute "CDS_LOCATION" "R6D8"
					( Origin gPackager )
				)
				( attribute "CDS_SEC" "1"
					( Origin gPackager )
				)
				( attribute "LOCATION" "R6D8"
					( Origin gFrontEnd )
				)
				( attribute "MATERIAL" "CHIP"
					( Origin gFrontEnd )
				)
				( attribute "PACK_TYPE" "0402"
					( Origin gFrontEnd )
				)
				( attribute "PART_NUMBER" "G21796-047"
					( Origin gFrontEnd )
				)
				( attribute "PHYS_PAGE" "96"
					( Origin gFrontEnd )
				)
				( attribute "ROOM" "PROC_RSTS_PGOODS"
					( Origin gFrontEnd )
				)
				( attribute "ROT" "2"
					( Origin gFrontEnd )
				)
				( attribute "SEC" "1"
					( Origin gFrontEnd )
				)
				( attribute "SEC_TYPE" "0402"
					( Origin gFrontEnd )
				)
				( attribute "TOLERANCE" "1%"
					( Origin gFrontEnd )
				)
				( attribute "VALUE" "49.9"
					( Origin gFrontEnd )
				)
				( attribute "VER" "2"
					( Origin gFrontEnd )
				)
				( attribute "WATTAGE" "1/16W"
					( Origin gFrontEnd )
				)
				( attribute "XY" "(1700,4450)"
					( Origin gFrontEnd )
				)
				( attribute "CHIPS_PART_NAME" "RES"
					( Origin gPackager )
				)
				( attribute "CDS_PART_NAME" "RES_0402-49.9,1%,1/16W,CHIP,G2A"
					( Origin gPackager )
				)
				( objectStatus "R6D8" )
			)
			( gate "@baseboard_fab2_lib.baseboard_fab2(sch_1):page96_i5"
				( attribute "BOM_COST" "PROC_SIDEBAND"
					( Origin gFrontEnd )
				)
				( attribute "CDS_LIB" "mstr_discrete"
					( Origin gPackager )
				)
				( attribute "CDS_LOCATION" "R3P29"
					( Origin gPackager )
				)
				( attribute "CDS_SEC" "1"
					( Origin gPackager )
				)
				( attribute "LOCATION" "R3P29"
					( Origin gFrontEnd )
				)
				( attribute "MATERIAL" "CHIP"
					( Origin gFrontEnd )
				)
				( attribute "PACK_TYPE" "0402"
					( Origin gFrontEnd )
				)
				( attribute "PART_NUMBER" "G21796-298"
					( Origin gFrontEnd )
				)
				( attribute "PHYS_PAGE" "96"
					( Origin gFrontEnd )
				)
				( attribute "ROOM" "PROC_RSTS_PGOODS"
					( Origin gFrontEnd )
				)
				( attribute "ROT" "0"
					( Origin gFrontEnd )
				)
				( attribute "SEC" "1"
					( Origin gPackager )
				)
				( attribute "TOLERANCE" "1.0%"
					( Origin gFrontEnd )
				)
				( attribute "VALUE" "64.9"
					( Origin gFrontEnd )
				)
				( attribute "VER" "2"
					( Origin gFrontEnd )
				)
				( attribute "WATTAGE" "1/16W"
					( Origin gFrontEnd )
				)
				( attribute "XY" "(975,4450)"
					( Origin gFrontEnd )
				)
				( attribute "CHIPS_PART_NAME" "RES"
					( Origin gPackager )
				)
				( attribute "CDS_PART_NAME" "RES_0402-64.9,1.0%,1/16W,CHIP,A"
					( Origin gPackager )
				)
				( objectStatus "R3P29" )
			)
			( gate "@baseboard_fab2_lib.baseboard_fab2(sch_1):page96_i7"
				( attribute "BOM_COST" "PROC_SIDEBAND"
					( Origin gFrontEnd )
				)
				( attribute "CDS_LIB" "mstr_discrete"
					( Origin gPackager )
				)
				( attribute "CDS_LOCATION" "R3P38"
					( Origin gPackager )
				)
				( attribute "CDS_SEC" "1"
					( Origin gPackager )
				)
				( attribute "LOCATION" "R3P38"
					( Origin gFrontEnd )
				)
				( attribute "MATERIAL" "CHIP"
					( Origin gFrontEnd )
				)
				( attribute "PACK_TYPE" "0402"
					( Origin gFrontEnd )
				)
				( attribute "PART_NUMBER" "G21796-298"
					( Origin gFrontEnd )
				)
				( attribute "PHYS_PAGE" "96"
					( Origin gFrontEnd )
				)
				( attribute "ROOM" "PROC_RSTS_PGOODS"
					( Origin gFrontEnd )
				)
				( attribute "ROT" "0"
					( Origin gFrontEnd )
				)
				( attribute "SEC" "1"
					( Origin gPackager )
				)
				( attribute "TOLERANCE" "1.0%"
					( Origin gFrontEnd )
				)
				( attribute "VALUE" "64.9"
					( Origin gFrontEnd )
				)
				( attribute "VER" "2"
					( Origin gFrontEnd )
				)
				( attribute "WATTAGE" "1/16W"
					( Origin gFrontEnd )
				)
				( attribute "XY" "(575,4450)"
					( Origin gFrontEnd )
				)
				( attribute "CHIPS_PART_NAME" "RES"
					( Origin gPackager )
				)
				( attribute "CDS_PART_NAME" "RES_0402-64.9,1.0%,1/16W,CHIP,A"
					( Origin gPackager )
				)
				( objectStatus "R3P38" )
			)
			( gate "@baseboard_fab2_lib.baseboard_fab2(sch_1):page96_i25"
				( attribute "BOM_COST" "PROC_SIDEBAND"
					( Origin gFrontEnd )
				)
				( attribute "CDS_LIB" "mstr_discrete"
					( Origin gPackager )
				)
				( attribute "CDS_LOCATION" "R3D20"
					( Origin gPackager )
				)
				( attribute "CDS_SEC" "1"
					( Origin gPackager )
				)
				( attribute "LOCATION" "R3D20"
					( Origin gFrontEnd )
				)
				( attribute "MATERIAL" "CHIP"
					( Origin gFrontEnd )
				)
				( attribute "PACK_TYPE" "0402"
					( Origin gFrontEnd )
				)
				( attribute "PART_NUMBER" "G21796-047"
					( Origin gFrontEnd )
				)
				( attribute "PHYS_PAGE" "96"
					( Origin gFrontEnd )
				)
				( attribute "ROOM" "PROC_RSTS_PGOODS"
					( Origin gFrontEnd )
				)
				( attribute "ROT" "0"
					( Origin gFrontEnd )
				)
				( attribute "SEC" "1"
					( Origin gFrontEnd )
				)
				( attribute "SEC_TYPE" "0402"
					( Origin gFrontEnd )
				)
				( attribute "TOLERANCE" "1%"
					( Origin gFrontEnd )
				)
				( attribute "VALUE" "49.9"
					( Origin gFrontEnd )
				)
				( attribute "VER" "2"
					( Origin gFrontEnd )
				)
				( attribute "WATTAGE" "1/16W"
					( Origin gFrontEnd )
				)
				( attribute "XY" "(1900,2150)"
					( Origin gFrontEnd )
				)
				( attribute "CHIPS_PART_NAME" "RES"
					( Origin gPackager )
				)
				( attribute "CDS_PART_NAME" "RES_0402-49.9,1%,1/16W,CHIP,G2A"
					( Origin gPackager )
				)
				( objectStatus "R3D20" )
			)
			( gate "@baseboard_fab2_lib.baseboard_fab2(sch_1):page96_i26"
				( attribute "BOM_COST" "PROC_SIDEBAND"
					( Origin gFrontEnd )
				)
				( attribute "CDS_LIB" "mstr_discrete"
					( Origin gPackager )
				)
				( attribute "CDS_LOCATION" "R3D15"
					( Origin gPackager )
				)
				( attribute "CDS_SEC" "1"
					( Origin gPackager )
				)
				( attribute "LOCATION" "R3D15"
					( Origin gFrontEnd )
				)
				( attribute "MATERIAL" "CHIP"
					( Origin gFrontEnd )
				)
				( attribute "PACK_TYPE" "0402"
					( Origin gFrontEnd )
				)
				( attribute "PART_NUMBER" "G21796-047"
					( Origin gFrontEnd )
				)
				( attribute "PHYS_PAGE" "96"
					( Origin gFrontEnd )
				)
				( attribute "ROOM" "PROC_RSTS_PGOODS"
					( Origin gFrontEnd )
				)
				( attribute "ROT" "2"
					( Origin gFrontEnd )
				)
				( attribute "SEC" "1"
					( Origin gFrontEnd )
				)
				( attribute "SEC_TYPE" "0402"
					( Origin gFrontEnd )
				)
				( attribute "TOLERANCE" "1%"
					( Origin gFrontEnd )
				)
				( attribute "VALUE" "49.9"
					( Origin gFrontEnd )
				)
				( attribute "VER" "2"
					( Origin gFrontEnd )
				)
				( attribute "WATTAGE" "1/16W"
					( Origin gFrontEnd )
				)
				( attribute "XY" "(1700,2150)"
					( Origin gFrontEnd )
				)
				( attribute "CHIPS_PART_NAME" "RES"
					( Origin gPackager )
				)
				( attribute "CDS_PART_NAME" "RES_0402-49.9,1%,1/16W,CHIP,G2A"
					( Origin gPackager )
				)
				( objectStatus "R3D15" )
			)
			( gate "@baseboard_fab2_lib.baseboard_fab2(sch_1):page96_i28"
				( attribute "BOM_COST" "PROC_SIDEBAND"
					( Origin gFrontEnd )
				)
				( attribute "CDS_LIB" "mstr_discrete"
					( Origin gPackager )
				)
				( attribute "CDS_LOCATION" "R7M9"
					( Origin gPackager )
				)
				( attribute "CDS_SEC" "1"
					( Origin gPackager )
				)
				( attribute "LOCATION" "R7M9"
					( Origin gFrontEnd )
				)
				( attribute "MATERIAL" "CHIP"
					( Origin gFrontEnd )
				)
				( attribute "PACK_TYPE" "0402"
					( Origin gFrontEnd )
				)
				( attribute "PART_NUMBER" "G21796-298"
					( Origin gFrontEnd )
				)
				( attribute "PHYS_PAGE" "96"
					( Origin gFrontEnd )
				)
				( attribute "ROOM" "PROC_RSTS_PGOODS"
					( Origin gFrontEnd )
				)
				( attribute "ROT" "0"
					( Origin gFrontEnd )
				)
				( attribute "SEC" "1"
					( Origin gPackager )
				)
				( attribute "TOLERANCE" "1.0%"
					( Origin gFrontEnd )
				)
				( attribute "VALUE" "64.9"
					( Origin gFrontEnd )
				)
				( attribute "VER" "2"
					( Origin gFrontEnd )
				)
				( attribute "WATTAGE" "1/16W"
					( Origin gFrontEnd )
				)
				( attribute "XY" "(975,2150)"
					( Origin gFrontEnd )
				)
				( attribute "CHIPS_PART_NAME" "RES"
					( Origin gPackager )
				)
				( attribute "CDS_PART_NAME" "RES_0402-64.9,1.0%,1/16W,CHIP,A"
					( Origin gPackager )
				)
				( objectStatus "R7M9" )
			)
			( gate "@baseboard_fab2_lib.baseboard_fab2(sch_1):page96_i30"
				( attribute "BOM_COST" "PROC_SIDEBAND"
					( Origin gFrontEnd )
				)
				( attribute "CDS_LIB" "mstr_discrete"
					( Origin gPackager )
				)
				( attribute "CDS_LOCATION" "R3D21"
					( Origin gPackager )
				)
				( attribute "CDS_SEC" "1"
					( Origin gPackager )
				)
				( attribute "LOCATION" "R3D21"
					( Origin gFrontEnd )
				)
				( attribute "MATERIAL" "CHIP"
					( Origin gFrontEnd )
				)
				( attribute "PACK_TYPE" "0402"
					( Origin gFrontEnd )
				)
				( attribute "PART_NUMBER" "G21796-298"
					( Origin gFrontEnd )
				)
				( attribute "PHYS_PAGE" "96"
					( Origin gFrontEnd )
				)
				( attribute "ROOM" "PROC_RSTS_PGOODS"
					( Origin gFrontEnd )
				)
				( attribute "ROT" "0"
					( Origin gFrontEnd )
				)
				( attribute "SEC" "1"
					( Origin gPackager )
				)
				( attribute "TOLERANCE" "1.0%"
					( Origin gFrontEnd )
				)
				( attribute "VALUE" "64.9"
					( Origin gFrontEnd )
				)
				( attribute "VER" "2"
					( Origin gFrontEnd )
				)
				( attribute "WATTAGE" "1/16W"
					( Origin gFrontEnd )
				)
				( attribute "XY" "(575,2150)"
					( Origin gFrontEnd )
				)
				( attribute "CHIPS_PART_NAME" "RES"
					( Origin gPackager )
				)
				( attribute "CDS_PART_NAME" "RES_0402-64.9,1.0%,1/16W,CHIP,A"
					( Origin gPackager )
				)
				( objectStatus "R3D21" )
			)
			( gate "@baseboard_fab2_lib.baseboard_fab2(sch_1):page96_i36"
				( attribute "BOM_COST" "PROC_SIDEBAND"
					( Origin gFrontEnd )
				)
				( attribute "CDS_LIB" "mstr_discrete"
					( Origin gPackager )
				)
				( attribute "CDS_LOCATION" "R3P36"
					( Origin gPackager )
				)
				( attribute "CDS_SEC" "1"
					( Origin gPackager )
				)
				( attribute "LOCATION" "R3P36"
					( Origin gFrontEnd )
				)
				( attribute "MATERIAL" "CHIP"
					( Origin gFrontEnd )
				)
				( attribute "PACK_TYPE" "0402"
					( Origin gFrontEnd )
				)
				( attribute "PART_NUMBER" "G21796-026"
					( Origin gFrontEnd )
				)
				( attribute "PHYS_PAGE" "96"
					( Origin gFrontEnd )
				)
				( attribute "ROOM" "PROC_RSTS_PGOODS"
					( Origin gFrontEnd )
				)
				( attribute "ROT" "0"
					( Origin gFrontEnd )
				)
				( attribute "SEC" "1"
					( Origin gPackager )
				)
				( attribute "TOLERANCE" "1%"
					( Origin gFrontEnd )
				)
				( attribute "VALUE" "1.00K"
					( Origin gFrontEnd )
				)
				( attribute "VER" "2"
					( Origin gFrontEnd )
				)
				( attribute "WATTAGE" "1/16W"
					( Origin gFrontEnd )
				)
				( attribute "XY" "(-2100,4650)"
					( Origin gFrontEnd )
				)
				( attribute "CHIPS_PART_NAME" "RES"
					( Origin gPackager )
				)
				( attribute "CDS_PART_NAME" "RES_0402-1.00K,1%,1/16W,CHIP,GA"
					( Origin gPackager )
				)
				( objectStatus "R3P36" )
			)
			( gate "@baseboard_fab2_lib.baseboard_fab2(sch_1):page96_i42"
				( attribute "BOM_COST" "PROC_SIDEBAND"
					( Origin gFrontEnd )
				)
				( attribute "CDS_LIB" "mstr_digital"
					( Origin gPackager )
				)
				( attribute "CDS_LOCATION" "U3P1"
					( Origin gPackager )
				)
				( attribute "CDS_SEC" "1"
					( Origin gPackager )
				)
				( attribute "LOCATION" "U3P1"
					( Origin gFrontEnd )
				)
				( attribute "MATERIAL" "IC"
					( Origin gFrontEnd )
				)
				( attribute "PACK_TYPE" "SM"
					( Origin gFrontEnd )
				)
				( attribute "PART_NUMBER" "D66151-001"
					( Origin gFrontEnd )
				)
				( attribute "PHYS_PAGE" "96"
					( Origin gFrontEnd )
				)
				( attribute "ROOM" "PROC_RSTS_PGOODS"
					( Origin gFrontEnd )
				)
				( attribute "ROT" "0"
					( Origin gFrontEnd )
				)
				( attribute "SEC" "1"
					( Origin gPackager )
				)
				( attribute "VER" "1"
					( Origin gFrontEnd )
				)
				( attribute "XY" "(-875,4100)"
					( Origin gFrontEnd )
				)
				( attribute "CHIPS_PART_NAME" "GTL2014"
					( Origin gPackager )
				)
				( attribute "CDS_PART_NAME" "GTL2014_SM-IC,D66151-001"
					( Origin gPackager )
				)
				( objectStatus "U3P1" )
			)
			( gate "@baseboard_fab2_lib.baseboard_fab2(sch_1):page96_i46"
				( attribute "BOM_COST" "PROC_SIDEBAND"
					( Origin gFrontEnd )
				)
				( attribute "CDS_LIB" "mstr_digital"
					( Origin gPackager )
				)
				( attribute "CDS_LOCATION" "U4C2"
					( Origin gPackager )
				)
				( attribute "CDS_SEC" "1"
					( Origin gPackager )
				)
				( attribute "LOCATION" "U4C2"
					( Origin gFrontEnd )
				)
				( attribute "MATERIAL" "IC"
					( Origin gFrontEnd )
				)
				( attribute "PACK_TYPE" "SM"
					( Origin gFrontEnd )
				)
				( attribute "PART_NUMBER" "D66151-001"
					( Origin gFrontEnd )
				)
				( attribute "PHYS_PAGE" "96"
					( Origin gFrontEnd )
				)
				( attribute "ROOM" "PROC_RSTS_PGOODS"
					( Origin gFrontEnd )
				)
				( attribute "ROT" "0"
					( Origin gFrontEnd )
				)
				( attribute "SEC" "1"
					( Origin gPackager )
				)
				( attribute "VER" "1"
					( Origin gFrontEnd )
				)
				( attribute "XY" "(-875,1800)"
					( Origin gFrontEnd )
				)
				( attribute "CHIPS_PART_NAME" "GTL2014"
					( Origin gPackager )
				)
				( attribute "CDS_PART_NAME" "GTL2014_SM-IC,D66151-001"
					( Origin gPackager )
				)
				( objectStatus "U4C2" )
			)
			( gate "@baseboard_fab2_lib.baseboard_fab2(sch_1):page96_i55"
				( attribute "BOM_COST" "PROC_SIDEBAND"
					( Origin gFrontEnd )
				)
				( attribute "CDS_LIB" "mstr_discrete"
					( Origin gPackager )
				)
				( attribute "CDS_LOCATION" "R4C8"
					( Origin gPackager )
				)
				( attribute "CDS_SEC" "1"
					( Origin gPackager )
				)
				( attribute "LOCATION" "R4C8"
					( Origin gFrontEnd )
				)
				( attribute "MATERIAL" "CHIP"
					( Origin gFrontEnd )
				)
				( attribute "PACK_TYPE" "0402"
					( Origin gFrontEnd )
				)
				( attribute "PART_NUMBER" "G21796-026"
					( Origin gFrontEnd )
				)
				( attribute "PHYS_PAGE" "96"
					( Origin gFrontEnd )
				)
				( attribute "ROOM" "PROC_RSTS_PGOODS"
					( Origin gFrontEnd )
				)
				( attribute "ROT" "0"
					( Origin gFrontEnd )
				)
				( attribute "SEC" "1"
					( Origin gPackager )
				)
				( attribute "TOLERANCE" "1%"
					( Origin gFrontEnd )
				)
				( attribute "VALUE" "1.00K"
					( Origin gFrontEnd )
				)
				( attribute "VER" "2"
					( Origin gFrontEnd )
				)
				( attribute "WATTAGE" "1/16W"
					( Origin gFrontEnd )
				)
				( attribute "XY" "(-2100,2350)"
					( Origin gFrontEnd )
				)
				( attribute "CHIPS_PART_NAME" "RES"
					( Origin gPackager )
				)
				( attribute "CDS_PART_NAME" "RES_0402-1.00K,1%,1/16W,CHIP,GA"
					( Origin gPackager )
				)
				( objectStatus "R4C8" )
			)
			( gate "@baseboard_fab2_lib.baseboard_fab2(sch_1):page96_i69"
				( attribute "BOM_COST" "PROC_SIDEBAND"
					( Origin gFrontEnd )
				)
				( attribute "CDS_LIB" "mstr_discrete"
					( Origin gPackager )
				)
				( attribute "CDS_LOCATION" "R4C9"
					( Origin gPackager )
				)
				( attribute "CDS_SEC" "1"
					( Origin gPackager )
				)
				( attribute "LOCATION" "R4C9"
					( Origin gFrontEnd )
				)
				( attribute "MATERIAL" "CHIP"
					( Origin gFrontEnd )
				)
				( attribute "PACK_TYPE" "0402"
					( Origin gFrontEnd )
				)
				( attribute "PART_NUMBER" "G21796-026"
					( Origin gFrontEnd )
				)
				( attribute "PHYS_PAGE" "96"
					( Origin gFrontEnd )
				)
				( attribute "ROOM" "PROC_RSTS_PGOODS"
					( Origin gFrontEnd )
				)
				( attribute "ROT" "0"
					( Origin gFrontEnd )
				)
				( attribute "SEC" "1"
					( Origin gFrontEnd )
				)
				( attribute "SEC_TYPE" "0402"
					( Origin gFrontEnd )
				)
				( attribute "TOLERANCE" "1%"
					( Origin gFrontEnd )
				)
				( attribute "VALUE" "1.00K"
					( Origin gFrontEnd )
				)
				( attribute "VER" "1"
					( Origin gFrontEnd )
				)
				( attribute "WATTAGE" "1/16W"
					( Origin gFrontEnd )
				)
				( attribute "XY" "(-2400,2050)"
					( Origin gFrontEnd )
				)
				( attribute "CHIPS_PART_NAME" "RES"
					( Origin gPackager )
				)
				( attribute "CDS_PART_NAME" "RES_0402-1.00K,1%,1/16W,CHIP,GA"
					( Origin gPackager )
				)
				( objectStatus "R4C9" )
			)
			( gate "@baseboard_fab2_lib.baseboard_fab2(sch_1):page96_i71"
				( attribute "BOM_COST" "PROC_SIDEBAND"
					( Origin gFrontEnd )
				)
				( attribute "CDS_LIB" "mstr_discrete"
					( Origin gPackager )
				)
				( attribute "CDS_LOCATION" "R3P32"
					( Origin gPackager )
				)
				( attribute "CDS_SEC" "1"
					( Origin gPackager )
				)
				( attribute "LOCATION" "R3P32"
					( Origin gFrontEnd )
				)
				( attribute "MATERIAL" "CHIP"
					( Origin gFrontEnd )
				)
				( attribute "PACK_TYPE" "0402"
					( Origin gFrontEnd )
				)
				( attribute "PART_NUMBER" "G21796-026"
					( Origin gFrontEnd )
				)
				( attribute "PHYS_PAGE" "96"
					( Origin gFrontEnd )
				)
				( attribute "ROOM" "PROC_RSTS_PGOODS"
					( Origin gFrontEnd )
				)
				( attribute "ROT" "0"
					( Origin gFrontEnd )
				)
				( attribute "SEC" "1"
					( Origin gFrontEnd )
				)
				( attribute "SEC_TYPE" "0402"
					( Origin gFrontEnd )
				)
				( attribute "TOLERANCE" "1%"
					( Origin gFrontEnd )
				)
				( attribute "VALUE" "1.00K"
					( Origin gFrontEnd )
				)
				( attribute "VER" "1"
					( Origin gFrontEnd )
				)
				( attribute "WATTAGE" "1/16W"
					( Origin gFrontEnd )
				)
				( attribute "XY" "(-2400,4350)"
					( Origin gFrontEnd )
				)
				( attribute "CHIPS_PART_NAME" "RES"
					( Origin gPackager )
				)
				( attribute "CDS_PART_NAME" "RES_0402-1.00K,1%,1/16W,CHIP,GA"
					( Origin gPackager )
				)
				( objectStatus "R3P32" )
			)
			( gate "@baseboard_fab2_lib.baseboard_fab2(sch_1):page96_i73"
				( attribute "BOM_COST" "PROC_SIDEBAND"
					( Origin gFrontEnd )
				)
				( attribute "CDS_LIB" "dev_discrete"
					( Origin gPackager )
				)
				( attribute "CDS_LOCATION" "C3P42"
					( Origin gPackager )
				)
				( attribute "CDS_SEC" "1"
					( Origin gPackager )
				)
				( attribute "LOCATION" "C3P42"
					( Origin gFrontEnd )
				)
				( attribute "MATERIAL" "X6S"
					( Origin gFrontEnd )
				)
				( attribute "PACK_TYPE" "0402V"
					( Origin gFrontEnd )
				)
				( attribute "PART_NUMBER" "D97712-004"
					( Origin gFrontEnd )
				)
				( attribute "PHYS_PAGE" "96"
					( Origin gFrontEnd )
				)
				( attribute "ROOM" "PROC_RSTS_PGOODS"
					( Origin gFrontEnd )
				)
				( attribute "ROT" "0"
					( Origin gFrontEnd )
				)
				( attribute "SEC" "1"
					( Origin gFrontEnd )
				)
				( attribute "SEC_TYPE" "0402V"
					( Origin gFrontEnd )
				)
				( attribute "TOLERANCE" "10%"
					( Origin gFrontEnd )
				)
				( attribute "VALUE" "1.0UF"
					( Origin gFrontEnd )
				)
				( attribute "VER" "1"
					( Origin gFrontEnd )
				)
				( attribute "VOLTAGE" "6.3V"
					( Units "uVoltage" "V" 1.000000)
					( Origin gFrontEnd )
				)
				( attribute "XY" "(-1650,4650)"
					( Origin gFrontEnd )
				)
				( attribute "CHIPS_PART_NAME" "CAP_A"
					( Origin gPackager )
				)
				( attribute "CDS_PART_NAME" "CAP_A_0402V-1.0UF,6.3V,10%,X6SA"
					( Origin gPackager )
				)
				( objectStatus "C3P42" )
			)
			( gate "@baseboard_fab2_lib.baseboard_fab2(sch_1):page96_i75"
				( attribute "BOM_COST" "PROC_SIDEBAND"
					( Origin gFrontEnd )
				)
				( attribute "CDS_LIB" "dev_discrete"
					( Origin gPackager )
				)
				( attribute "CDS_LOCATION" "C4C3"
					( Origin gPackager )
				)
				( attribute "CDS_SEC" "1"
					( Origin gPackager )
				)
				( attribute "LOCATION" "C4C3"
					( Origin gFrontEnd )
				)
				( attribute "MATERIAL" "X6S"
					( Origin gFrontEnd )
				)
				( attribute "PACK_TYPE" "0402V"
					( Origin gFrontEnd )
				)
				( attribute "PART_NUMBER" "D97712-004"
					( Origin gFrontEnd )
				)
				( attribute "PHYS_PAGE" "96"
					( Origin gFrontEnd )
				)
				( attribute "ROOM" "PROC_RSTS_PGOODS"
					( Origin gFrontEnd )
				)
				( attribute "ROT" "0"
					( Origin gFrontEnd )
				)
				( attribute "SEC" "1"
					( Origin gFrontEnd )
				)
				( attribute "SEC_TYPE" "0402V"
					( Origin gFrontEnd )
				)
				( attribute "TOLERANCE" "10%"
					( Origin gFrontEnd )
				)
				( attribute "VALUE" "1.0UF"
					( Origin gFrontEnd )
				)
				( attribute "VER" "1"
					( Origin gFrontEnd )
				)
				( attribute "VOLTAGE" "6.3V"
					( Units "uVoltage" "V" 1.000000)
					( Origin gFrontEnd )
				)
				( attribute "XY" "(-1725,2325)"
					( Origin gFrontEnd )
				)
				( attribute "CHIPS_PART_NAME" "CAP_A"
					( Origin gPackager )
				)
				( attribute "CDS_PART_NAME" "CAP_A_0402V-1.0UF,6.3V,10%,X6SA"
					( Origin gPackager )
				)
				( objectStatus "C4C3" )
			)
			( gate "@baseboard_fab2_lib.baseboard_fab2(sch_1):page97_i33"
				( attribute "BOM_COST" "PROC_SIDEBAND"
					( Origin gFrontEnd )
				)
				( attribute "CDS_LIB" "mstr_discrete"
					( Origin gPackager )
				)
				( attribute "CDS_LOCATION" "R3D18"
					( Origin gPackager )
				)
				( attribute "CDS_SEC" "1"
					( Origin gPackager )
				)
				( attribute "LOCATION" "R3D18"
					( Origin gFrontEnd )
				)
				( attribute "MATERIAL" "CHIP"
					( Origin gFrontEnd )
				)
				( attribute "PACK_TYPE" "0402"
					( Origin gFrontEnd )
				)
				( attribute "PART_NUMBER" "G21497-005"
					( Origin gFrontEnd )
				)
				( attribute "PHYS_PAGE" "97"
					( Origin gFrontEnd )
				)
				( attribute "ROOM" "PROC_SIDEBAND"
					( Origin gFrontEnd )
				)
				( attribute "ROT" "0"
					( Origin gFrontEnd )
				)
				( attribute "SEC" "1"
					( Origin gPackager )
				)
				( attribute "TOLERANCE" "5%"
					( Origin gFrontEnd )
				)
				( attribute "VALUE" "0.0"
					( Origin gFrontEnd )
				)
				( attribute "VER" "1"
					( Origin gFrontEnd )
				)
				( attribute "WATTAGE" "1/16W"
					( Origin gFrontEnd )
				)
				( attribute "XY" "(-2000,4225)"
					( Origin gFrontEnd )
				)
				( attribute "CHIPS_PART_NAME" "RES"
					( Origin gPackager )
				)
				( attribute "CDS_PART_NAME" "RES_0402-0.0,5%,1/16W,CHIP,G21A"
					( Origin gPackager )
				)
				( objectStatus "R3D18" )
			)
			( gate "@baseboard_fab2_lib.baseboard_fab2(sch_1):page97_i42"
				( attribute "CDS_LIB" "mstr_discrete"
					( Origin gPackager )
				)
				( attribute "CDS_LOCATION" "R4R4"
					( Origin gPackager )
				)
				( attribute "CDS_SEC" "1"
					( Origin gPackager )
				)
				( attribute "LOCATION" "R4R4"
					( Origin gFrontEnd )
				)
				( attribute "MATERIAL" "CHIP"
					( Origin gFrontEnd )
				)
				( attribute "PACK_TYPE" "0402"
					( Origin gFrontEnd )
				)
				( attribute "PART_NUMBER" "G21796-009"
					( Origin gFrontEnd )
				)
				( attribute "PHYS_PAGE" "97"
					( Origin gFrontEnd )
				)
				( attribute "ROOM" "PROC_SIDEBAND"
					( Origin gFrontEnd )
				)
				( attribute "ROT" "0"
					( Origin gFrontEnd )
				)
				( attribute "SEC" "1"
					( Origin gPackager )
				)
				( attribute "TOLERANCE" "1%"
					( Origin gFrontEnd )
				)
				( attribute "VALUE" "150.0"
					( Origin gFrontEnd )
				)
				( attribute "VER" "2"
					( Origin gFrontEnd )
				)
				( attribute "WATTAGE" "1/16W"
					( Origin gFrontEnd )
				)
				( attribute "XY" "(-2700,4525)"
					( Origin gFrontEnd )
				)
				( attribute "CHIPS_PART_NAME" "RES"
					( Origin gPackager )
				)
				( attribute "CDS_PART_NAME" "RES_0402-150.0,1%,1/16W,CHIP,GA"
					( Origin gPackager )
				)
				( objectStatus "R4R4" )
			)
			( gate "@baseboard_fab2_lib.baseboard_fab2(sch_1):page97_i44"
				( attribute "CDS_LIB" "mstr_discrete"
					( Origin gPackager )
				)
				( attribute "CDS_LOCATION" "R7P20"
					( Origin gPackager )
				)
				( attribute "CDS_SEC" "1"
					( Origin gPackager )
				)
				( attribute "LOCATION" "R7P20"
					( Origin gFrontEnd )
				)
				( attribute "MATERIAL" "CHIP"
					( Origin gFrontEnd )
				)
				( attribute "PACK_TYPE" "0402"
					( Origin gFrontEnd )
				)
				( attribute "PART_NUMBER" "G21796-009"
					( Origin gFrontEnd )
				)
				( attribute "PHYS_PAGE" "97"
					( Origin gFrontEnd )
				)
				( attribute "ROOM" "PROC_SIDEBAND"
					( Origin gFrontEnd )
				)
				( attribute "ROT" "0"
					( Origin gFrontEnd )
				)
				( attribute "SEC" "1"
					( Origin gPackager )
				)
				( attribute "TOLERANCE" "1%"
					( Origin gFrontEnd )
				)
				( attribute "VALUE" "150.0"
					( Origin gFrontEnd )
				)
				( attribute "VER" "2"
					( Origin gFrontEnd )
				)
				( attribute "WATTAGE" "1/16W"
					( Origin gFrontEnd )
				)
				( attribute "XY" "(-1200,4525)"
					( Origin gFrontEnd )
				)
				( attribute "CHIPS_PART_NAME" "RES"
					( Origin gPackager )
				)
				( attribute "CDS_PART_NAME" "RES_0402-150.0,1%,1/16W,CHIP,GA"
					( Origin gPackager )
				)
				( objectStatus "R7P20" )
			)
			( gate "@baseboard_fab2_lib.baseboard_fab2(sch_1):page97_i72"
				( attribute "BOM_COST" "PROC_SIDEBAND"
					( Origin gFrontEnd )
				)
				( attribute "CDS_LIB" "mstr_discrete"
					( Origin gPackager )
				)
				( attribute "CDS_LOCATION" "R4P21"
					( Origin gPackager )
				)
				( attribute "CDS_SEC" "1"
					( Origin gPackager )
				)
				( attribute "LOCATION" "R4P21"
					( Origin gFrontEnd )
				)
				( attribute "MATERIAL" "CHIP"
					( Origin gFrontEnd )
				)
				( attribute "PACK_TYPE" "0402"
					( Origin gFrontEnd )
				)
				( attribute "PART_NUMBER" "G21796-294"
					( Origin gFrontEnd )
				)
				( attribute "PHYS_PAGE" "97"
					( Origin gFrontEnd )
				)
				( attribute "ROOM" "PROC_SIDEBAND"
					( Origin gFrontEnd )
				)
				( attribute "ROT" "0"
					( Origin gFrontEnd )
				)
				( attribute "SEC" "1"
					( Origin gFrontEnd )
				)
				( attribute "SEC_TYPE" "0402"
					( Origin gFrontEnd )
				)
				( attribute "TOLERANCE" "1.0%"
					( Origin gFrontEnd )
				)
				( attribute "VALUE" "240"
					( Origin gFrontEnd )
				)
				( attribute "VER" "1"
					( Origin gFrontEnd )
				)
				( attribute "WATTAGE" "1/16W"
					( Origin gFrontEnd )
				)
				( attribute "XY" "(-2625,1425)"
					( Origin gFrontEnd )
				)
				( attribute "CHIPS_PART_NAME" "RES"
					( Origin gPackager )
				)
				( attribute "CDS_PART_NAME" "RES_0402-240,1.0%,1/16W,CHIP,GA"
					( Origin gPackager )
				)
				( objectStatus "R4P21" )
			)
			( gate "@baseboard_fab2_lib.baseboard_fab2(sch_1):page97_i76"
				( attribute "BOM_COST" "PROC_SIDEBAND"
					( Origin gFrontEnd )
				)
				( attribute "CDS_LIB" "mstr_discrete"
					( Origin gPackager )
				)
				( attribute "CDS_LOCATION" "R4C10"
					( Origin gPackager )
				)
				( attribute "CDS_SEC" "1"
					( Origin gPackager )
				)
				( attribute "LOCATION" "R4C10"
					( Origin gFrontEnd )
				)
				( attribute "MATERIAL" "CHIP"
					( Origin gFrontEnd )
				)
				( attribute "PACK_TYPE" "0402"
					( Origin gFrontEnd )
				)
				( attribute "PART_NUMBER" "G21796-294"
					( Origin gFrontEnd )
				)
				( attribute "PHYS_PAGE" "97"
					( Origin gFrontEnd )
				)
				( attribute "ROOM" "PROC_SIDEBAND"
					( Origin gFrontEnd )
				)
				( attribute "ROT" "0"
					( Origin gFrontEnd )
				)
				( attribute "SEC" "1"
					( Origin gFrontEnd )
				)
				( attribute "SEC_TYPE" "0402"
					( Origin gFrontEnd )
				)
				( attribute "TOLERANCE" "1.0%"
					( Origin gFrontEnd )
				)
				( attribute "VALUE" "240"
					( Origin gFrontEnd )
				)
				( attribute "VER" "1"
					( Origin gFrontEnd )
				)
				( attribute "WATTAGE" "1/16W"
					( Origin gFrontEnd )
				)
				( attribute "XY" "(-2600,800)"
					( Origin gFrontEnd )
				)
				( attribute "CHIPS_PART_NAME" "RES"
					( Origin gPackager )
				)
				( attribute "CDS_PART_NAME" "RES_0402-240,1.0%,1/16W,CHIP,GA"
					( Origin gPackager )
				)
				( objectStatus "R4C10" )
			)
			( gate "@baseboard_fab2_lib.baseboard_fab2(sch_1):page97_i80"
				( attribute "CDS_LIB" "mstr_discrete"
					( Origin gPackager )
				)
				( attribute "CDS_LOCATION" "R4P5"
					( Origin gPackager )
				)
				( attribute "CDS_SEC" "1"
					( Origin gPackager )
				)
				( attribute "LOCATION" "R4P5"
					( Origin gFrontEnd )
				)
				( attribute "MATERIAL" "CHIP"
					( Origin gFrontEnd )
				)
				( attribute "PACK_TYPE" "0402"
					( Origin gFrontEnd )
				)
				( attribute "PART_NUMBER" "G21796-016"
					( Origin gFrontEnd )
				)
				( attribute "PHYS_PAGE" "97"
					( Origin gFrontEnd )
				)
				( attribute "ROOM" "CPU0"
					( Origin gFrontEnd )
				)
				( attribute "ROT" "0"
					( Origin gFrontEnd )
				)
				( attribute "SEC" "1"
					( Origin gFrontEnd )
				)
				( attribute "SEC_TYPE" "0402"
					( Origin gFrontEnd )
				)
				( attribute "TOLERANCE" "1%"
					( Origin gFrontEnd )
				)
				( attribute "VALUE" "10.0K"
					( Origin gFrontEnd )
				)
				( attribute "VER" "1"
					( Origin gFrontEnd )
				)
				( attribute "WATTAGE" "1/16W"
					( Origin gFrontEnd )
				)
				( attribute "XY" "(-2375,3175)"
					( Origin gFrontEnd )
				)
				( attribute "CHIPS_PART_NAME" "RES"
					( Origin gPackager )
				)
				( attribute "CDS_PART_NAME" "RES_0402-10.0K,1%,1/16W,CHIP,GA"
					( Origin gPackager )
				)
				( objectStatus "R4P5" )
			)
			( gate "@baseboard_fab2_lib.baseboard_fab2(sch_1):page97_i81"
				( attribute "CDS_LIB" "mstr_discrete"
					( Origin gPackager )
				)
				( attribute "CDS_LOCATION" "R7P13"
					( Origin gPackager )
				)
				( attribute "CDS_SEC" "1"
					( Origin gPackager )
				)
				( attribute "LOCATION" "R7P13"
					( Origin gFrontEnd )
				)
				( attribute "MATERIAL" "CHIP"
					( Origin gFrontEnd )
				)
				( attribute "PACK_TYPE" "0402"
					( Origin gFrontEnd )
				)
				( attribute "PART_NUMBER" "G21796-016"
					( Origin gFrontEnd )
				)
				( attribute "PHYS_PAGE" "97"
					( Origin gFrontEnd )
				)
				( attribute "ROOM" "CPU1"
					( Origin gFrontEnd )
				)
				( attribute "ROT" "0"
					( Origin gFrontEnd )
				)
				( attribute "SEC" "1"
					( Origin gFrontEnd )
				)
				( attribute "SEC_TYPE" "0402"
					( Origin gFrontEnd )
				)
				( attribute "TOLERANCE" "1%"
					( Origin gFrontEnd )
				)
				( attribute "VALUE" "10.0K"
					( Origin gFrontEnd )
				)
				( attribute "VER" "1"
					( Origin gFrontEnd )
				)
				( attribute "WATTAGE" "1/16W"
					( Origin gFrontEnd )
				)
				( attribute "XY" "(-2375,2825)"
					( Origin gFrontEnd )
				)
				( attribute "CHIPS_PART_NAME" "RES"
					( Origin gPackager )
				)
				( attribute "CDS_PART_NAME" "RES_0402-10.0K,1%,1/16W,CHIP,GA"
					( Origin gPackager )
				)
				( objectStatus "R7P13" )
			)
			( gate "@baseboard_fab2_lib.baseboard_fab2(sch_1):page98_i4"
				( attribute "BOM_COST" "PROC_SOCKET"
					( Origin gFrontEnd )
				)
				( attribute "CDS_LIB" "mstr_discrete"
					( Origin gPackager )
				)
				( attribute "CDS_LOCATION" "R4F5"
					( Origin gPackager )
				)
				( attribute "CDS_SEC" "1"
					( Origin gPackager )
				)
				( attribute "LOCATION" "R4F5"
					( Origin gFrontEnd )
				)
				( attribute "MATERIAL" "CHIP"
					( Origin gFrontEnd )
				)
				( attribute "PACK_TYPE" "0402"
					( Origin gFrontEnd )
				)
				( attribute "PART_NUMBER" "G21796-026"
					( Origin gFrontEnd )
				)
				( attribute "PHYS_PAGE" "98"
					( Origin gFrontEnd )
				)
				( attribute "ROOM" "PROC"
					( Origin gFrontEnd )
				)
				( attribute "ROT" "2"
					( Origin gFrontEnd )
				)
				( attribute "SEC" "1"
					( Origin gFrontEnd )
				)
				( attribute "SEC_TYPE" "0402"
					( Origin gFrontEnd )
				)
				( attribute "TOLERANCE" "1%"
					( Origin gFrontEnd )
				)
				( attribute "VALUE" "1.00K"
					( Origin gFrontEnd )
				)
				( attribute "VER" "2"
					( Origin gFrontEnd )
				)
				( attribute "WATTAGE" "1/16W"
					( Origin gFrontEnd )
				)
				( attribute "XY" "(-1725,3700)"
					( Origin gFrontEnd )
				)
				( attribute "CHIPS_PART_NAME" "RES"
					( Origin gPackager )
				)
				( attribute "CDS_PART_NAME" "RES_0402-1.00K,1%,1/16W,CHIP,GA"
					( Origin gPackager )
				)
				( objectStatus "R4F5" )
			)
			( gate "@baseboard_fab2_lib.baseboard_fab2(sch_1):page98_i5"
				( attribute "BOM_COST" "PROC_SOCKET"
					( Origin gFrontEnd )
				)
				( attribute "CDS_LIB" "mstr_discrete"
					( Origin gPackager )
				)
				( attribute "CDS_LOCATION" "R4F3"
					( Origin gPackager )
				)
				( attribute "CDS_SEC" "1"
					( Origin gPackager )
				)
				( attribute "LOCATION" "R4F3"
					( Origin gFrontEnd )
				)
				( attribute "MATERIAL" "CHIP"
					( Origin gFrontEnd )
				)
				( attribute "PACK_TYPE" "0402"
					( Origin gFrontEnd )
				)
				( attribute "PART_NUMBER" "G21796-274"
					( Origin gFrontEnd )
				)
				( attribute "PHYS_PAGE" "98"
					( Origin gFrontEnd )
				)
				( attribute "ROOM" "PROC"
					( Origin gFrontEnd )
				)
				( attribute "ROT" "0"
					( Origin gFrontEnd )
				)
				( attribute "SEC" "1"
					( Origin gFrontEnd )
				)
				( attribute "SEC_TYPE" "0402"
					( Origin gFrontEnd )
				)
				( attribute "TOLERANCE" "1.0%"
					( Origin gFrontEnd )
				)
				( attribute "VALUE" "2"
					( Origin gFrontEnd )
				)
				( attribute "VER" "1"
					( Origin gFrontEnd )
				)
				( attribute "WATTAGE" "1/16W"
					( Origin gFrontEnd )
				)
				( attribute "XY" "(-2025,4025)"
					( Origin gFrontEnd )
				)
				( attribute "CHIPS_PART_NAME" "RES"
					( Origin gPackager )
				)
				( attribute "CDS_PART_NAME" "RES_0402-2,1.0%,1/16W,CHIP,G21A"
					( Origin gPackager )
				)
				( objectStatus "R4F3" )
			)
			( gate "@baseboard_fab2_lib.baseboard_fab2(sch_1):page98_i7"
				( attribute "BOM_COST" "SM_CONTROLLER"
					( Origin gFrontEnd )
				)
				( attribute "CDS_LIB" "dev_discrete"
					( Origin gPackager )
				)
				( attribute "CDS_LOCATION" "C4F9"
					( Origin gPackager )
				)
				( attribute "CDS_SEC" "1"
					( Origin gPackager )
				)
				( attribute "LOCATION" "C4F9"
					( Origin gFrontEnd )
				)
				( attribute "MATERIAL" "X7R"
					( Origin gFrontEnd )
				)
				( attribute "PACK_TYPE" "0402V"
					( Origin gFrontEnd )
				)
				( attribute "PART_NUMBER" "A36096-045"
					( Origin gFrontEnd )
				)
				( attribute "PHYS_PAGE" "98"
					( Origin gFrontEnd )
				)
				( attribute "ROOM" "MEM"
					( Origin gFrontEnd )
				)
				( attribute "ROT" "0"
					( Origin gFrontEnd )
				)
				( attribute "SEC" "1"
					( Origin gFrontEnd )
				)
				( attribute "SEC_TYPE" "0402V"
					( Origin gFrontEnd )
				)
				( attribute "TOLERANCE" "10%"
					( Origin gFrontEnd )
				)
				( attribute "VALUE" "0.01UF"
					( Origin gFrontEnd )
				)
				( attribute "VER" "1"
					( Origin gFrontEnd )
				)
				( attribute "VOLTAGE" "25V"
					( Units "uVoltage" "V" 1.000000)
					( Origin gFrontEnd )
				)
				( attribute "XY" "(-2250,3725)"
					( Origin gFrontEnd )
				)
				( attribute "CHIPS_PART_NAME" "CAP_A"
					( Origin gPackager )
				)
				( attribute "CDS_PART_NAME" "CAP_A_0402V-0.01UF,25V,10%,X7RA"
					( Origin gPackager )
				)
				( objectStatus "C4F9" )
			)
			( gate "@baseboard_fab2_lib.baseboard_fab2(sch_1):page98_i9"
				( attribute "BOM_COST" "PROC_SOCKET"
					( Origin gFrontEnd )
				)
				( attribute "CDS_LIB" "mstr_discrete"
					( Origin gPackager )
				)
				( attribute "CDS_LOCATION" "R6M1"
					( Origin gPackager )
				)
				( attribute "CDS_SEC" "1"
					( Origin gPackager )
				)
				( attribute "LOCATION" "R6M1"
					( Origin gFrontEnd )
				)
				( attribute "MATERIAL" "CHIP"
					( Origin gFrontEnd )
				)
				( attribute "PACK_TYPE" "0402"
					( Origin gFrontEnd )
				)
				( attribute "PART_NUMBER" "G21796-026"
					( Origin gFrontEnd )
				)
				( attribute "PHYS_PAGE" "98"
					( Origin gFrontEnd )
				)
				( attribute "ROOM" "MEM"
					( Origin gFrontEnd )
				)
				( attribute "ROT" "2"
					( Origin gFrontEnd )
				)
				( attribute "SEC" "1"
					( Origin gFrontEnd )
				)
				( attribute "SEC_TYPE" "0402"
					( Origin gFrontEnd )
				)
				( attribute "TOLERANCE" "1%"
					( Origin gFrontEnd )
				)
				( attribute "VALUE" "1.00K"
					( Origin gFrontEnd )
				)
				( attribute "VER" "2"
					( Origin gFrontEnd )
				)
				( attribute "WATTAGE" "1/16W"
					( Origin gFrontEnd )
				)
				( attribute "XY" "(-1800,2675)"
					( Origin gFrontEnd )
				)
				( attribute "CHIPS_PART_NAME" "RES"
					( Origin gPackager )
				)
				( attribute "CDS_PART_NAME" "RES_0402-1.00K,1%,1/16W,CHIP,GA"
					( Origin gPackager )
				)
				( objectStatus "R6M1" )
			)
			( gate "@baseboard_fab2_lib.baseboard_fab2(sch_1):page98_i12"
				( attribute "BOM_COST" "PROC_SOCKET"
					( Origin gFrontEnd )
				)
				( attribute "CDS_LIB" "mstr_discrete"
					( Origin gPackager )
				)
				( attribute "CDS_LOCATION" "R6L16"
					( Origin gPackager )
				)
				( attribute "CDS_SEC" "1"
					( Origin gPackager )
				)
				( attribute "LOCATION" "R6L16"
					( Origin gFrontEnd )
				)
				( attribute "MATERIAL" "CHIP"
					( Origin gFrontEnd )
				)
				( attribute "PACK_TYPE" "0402"
					( Origin gFrontEnd )
				)
				( attribute "PART_NUMBER" "G21796-026"
					( Origin gFrontEnd )
				)
				( attribute "PHYS_PAGE" "98"
					( Origin gFrontEnd )
				)
				( attribute "ROOM" "PROC"
					( Origin gFrontEnd )
				)
				( attribute "ROT" "2"
					( Origin gFrontEnd )
				)
				( attribute "SEC" "1"
					( Origin gFrontEnd )
				)
				( attribute "SEC_TYPE" "0402"
					( Origin gFrontEnd )
				)
				( attribute "TOLERANCE" "1%"
					( Origin gFrontEnd )
				)
				( attribute "VALUE" "1.00K"
					( Origin gFrontEnd )
				)
				( attribute "VER" "2"
					( Origin gFrontEnd )
				)
				( attribute "WATTAGE" "1/16W"
					( Origin gFrontEnd )
				)
				( attribute "XY" "(-1725,2025)"
					( Origin gFrontEnd )
				)
				( attribute "CHIPS_PART_NAME" "RES"
					( Origin gPackager )
				)
				( attribute "CDS_PART_NAME" "RES_0402-1.00K,1%,1/16W,CHIP,GA"
					( Origin gPackager )
				)
				( objectStatus "R6L16" )
			)
			( gate "@baseboard_fab2_lib.baseboard_fab2(sch_1):page98_i14"
				( attribute "BOM_COST" "PROC_SOCKET"
					( Origin gFrontEnd )
				)
				( attribute "CDS_LIB" "mstr_discrete"
					( Origin gPackager )
				)
				( attribute "CDS_LOCATION" "R6M2"
					( Origin gPackager )
				)
				( attribute "CDS_SEC" "1"
					( Origin gPackager )
				)
				( attribute "LOCATION" "R6M2"
					( Origin gFrontEnd )
				)
				( attribute "MATERIAL" "CHIP"
					( Origin gFrontEnd )
				)
				( attribute "PACK_TYPE" "0402"
					( Origin gFrontEnd )
				)
				( attribute "PART_NUMBER" "G21796-274"
					( Origin gFrontEnd )
				)
				( attribute "PHYS_PAGE" "98"
					( Origin gFrontEnd )
				)
				( attribute "ROOM" "PROC"
					( Origin gFrontEnd )
				)
				( attribute "ROT" "0"
					( Origin gFrontEnd )
				)
				( attribute "SEC" "1"
					( Origin gFrontEnd )
				)
				( attribute "SEC_TYPE" "0402"
					( Origin gFrontEnd )
				)
				( attribute "TOLERANCE" "1.0%"
					( Origin gFrontEnd )
				)
				( attribute "VALUE" "2"
					( Origin gFrontEnd )
				)
				( attribute "VER" "1"
					( Origin gFrontEnd )
				)
				( attribute "WATTAGE" "1/16W"
					( Origin gFrontEnd )
				)
				( attribute "XY" "(-2025,2350)"
					( Origin gFrontEnd )
				)
				( attribute "CHIPS_PART_NAME" "RES"
					( Origin gPackager )
				)
				( attribute "CDS_PART_NAME" "RES_0402-2,1.0%,1/16W,CHIP,G21A"
					( Origin gPackager )
				)
				( objectStatus "R6M2" )
			)
			( gate "@baseboard_fab2_lib.baseboard_fab2(sch_1):page98_i33"
				( attribute "BOM_COST" "SM_CONTROLLER"
					( Origin gFrontEnd )
				)
				( attribute "CDS_LIB" "dev_discrete"
					( Origin gPackager )
				)
				( attribute "CDS_LOCATION" "C6M2"
					( Origin gPackager )
				)
				( attribute "CDS_SEC" "1"
					( Origin gPackager )
				)
				( attribute "LOCATION" "C6M2"
					( Origin gFrontEnd )
				)
				( attribute "MATERIAL" "X7R"
					( Origin gFrontEnd )
				)
				( attribute "PACK_TYPE" "0402V"
					( Origin gFrontEnd )
				)
				( attribute "PART_NUMBER" "A36096-045"
					( Origin gFrontEnd )
				)
				( attribute "PHYS_PAGE" "98"
					( Origin gFrontEnd )
				)
				( attribute "ROOM" "MEM"
					( Origin gFrontEnd )
				)
				( attribute "ROT" "0"
					( Origin gFrontEnd )
				)
				( attribute "SEC" "1"
					( Origin gFrontEnd )
				)
				( attribute "SEC_TYPE" "0402V"
					( Origin gFrontEnd )
				)
				( attribute "TOLERANCE" "10%"
					( Origin gFrontEnd )
				)
				( attribute "VALUE" "0.01UF"
					( Origin gFrontEnd )
				)
				( attribute "VER" "1"
					( Origin gFrontEnd )
				)
				( attribute "VOLTAGE" "25V"
					( Units "uVoltage" "V" 1.000000)
					( Origin gFrontEnd )
				)
				( attribute "XY" "(-2250,2050)"
					( Origin gFrontEnd )
				)
				( attribute "CHIPS_PART_NAME" "CAP_A"
					( Origin gPackager )
				)
				( attribute "CDS_PART_NAME" "CAP_A_0402V-0.01UF,25V,10%,X7RA"
					( Origin gPackager )
				)
				( objectStatus "C6M2" )
			)
			( gate "@baseboard_fab2_lib.baseboard_fab2(sch_1):page98_i36"
				( attribute "BOM_COST" "SM_CONTROLLER"
					( Origin gFrontEnd )
				)
				( attribute "CDS_LIB" "mstr_discrete"
					( Origin gPackager )
				)
				( attribute "CDS_LOCATION" "R4F4"
					( Origin gPackager )
				)
				( attribute "CDS_SEC" "1"
					( Origin gPackager )
				)
				( attribute "LOCATION" "R4F4"
					( Origin gFrontEnd )
				)
				( attribute "MATERIAL" "CHIP"
					( Origin gFrontEnd )
				)
				( attribute "PACK_TYPE" "0402"
					( Origin gFrontEnd )
				)
				( attribute "PART_NUMBER" "G21796-026"
					( Origin gFrontEnd )
				)
				( attribute "PHYS_PAGE" "98"
					( Origin gFrontEnd )
				)
				( attribute "ROOM" "MEM"
					( Origin gFrontEnd )
				)
				( attribute "ROT" "2"
					( Origin gFrontEnd )
				)
				( attribute "SEC" "1"
					( Origin gFrontEnd )
				)
				( attribute "SEC_TYPE" "0402"
					( Origin gFrontEnd )
				)
				( attribute "TOLERANCE" "1%"
					( Origin gFrontEnd )
				)
				( attribute "VALUE" "1.00K"
					( Origin gFrontEnd )
				)
				( attribute "VER" "2"
					( Origin gFrontEnd )
				)
				( attribute "WATTAGE" "1/16W"
					( Origin gFrontEnd )
				)
				( attribute "XY" "(-1800,4350)"
					( Origin gFrontEnd )
				)
				( attribute "CHIPS_PART_NAME" "RES"
					( Origin gPackager )
				)
				( attribute "CDS_PART_NAME" "RES_0402-1.00K,1%,1/16W,CHIP,GA"
					( Origin gPackager )
				)
				( objectStatus "R4F4" )
			)
			( gate "@baseboard_fab2_lib.baseboard_fab2(sch_1):page98_i38"
				( attribute "BOM_COST" "SM_CONTROLLER"
					( Origin gFrontEnd )
				)
				( attribute "CDS_LIB" "mstr_discrete"
					( Origin gPackager )
				)
				( attribute "CDS_LOCATION" "R4G2"
					( Origin gPackager )
				)
				( attribute "CDS_SEC" "1"
					( Origin gPackager )
				)
				( attribute "LOCATION" "R4G2"
					( Origin gFrontEnd )
				)
				( attribute "MATERIAL" "CHIP"
					( Origin gFrontEnd )
				)
				( attribute "PACK_TYPE" "0402"
					( Origin gFrontEnd )
				)
				( attribute "PART_NUMBER" "G21796-026"
					( Origin gFrontEnd )
				)
				( attribute "PHYS_PAGE" "98"
					( Origin gFrontEnd )
				)
				( attribute "ROOM" "MEM"
					( Origin gFrontEnd )
				)
				( attribute "ROT" "2"
					( Origin gFrontEnd )
				)
				( attribute "SEC" "1"
					( Origin gFrontEnd )
				)
				( attribute "SEC_TYPE" "0402"
					( Origin gFrontEnd )
				)
				( attribute "TOLERANCE" "1%"
					( Origin gFrontEnd )
				)
				( attribute "VALUE" "1.00K"
					( Origin gFrontEnd )
				)
				( attribute "VER" "2"
					( Origin gFrontEnd )
				)
				( attribute "WATTAGE" "1/16W"
					( Origin gFrontEnd )
				)
				( attribute "XY" "(250,4350)"
					( Origin gFrontEnd )
				)
				( attribute "CHIPS_PART_NAME" "RES"
					( Origin gPackager )
				)
				( attribute "CDS_PART_NAME" "RES_0402-1.00K,1%,1/16W,CHIP,GA"
					( Origin gPackager )
				)
				( objectStatus "R4G2" )
			)
			( gate "@baseboard_fab2_lib.baseboard_fab2(sch_1):page98_i40"
				( attribute "BOM_COST" "PROC_SOCKET"
					( Origin gFrontEnd )
				)
				( attribute "CDS_LIB" "mstr_discrete"
					( Origin gPackager )
				)
				( attribute "CDS_LOCATION" "R4G3"
					( Origin gPackager )
				)
				( attribute "CDS_SEC" "1"
					( Origin gPackager )
				)
				( attribute "LOCATION" "R4G3"
					( Origin gFrontEnd )
				)
				( attribute "MATERIAL" "CHIP"
					( Origin gFrontEnd )
				)
				( attribute "PACK_TYPE" "0402"
					( Origin gFrontEnd )
				)
				( attribute "PART_NUMBER" "G21796-026"
					( Origin gFrontEnd )
				)
				( attribute "PHYS_PAGE" "98"
					( Origin gFrontEnd )
				)
				( attribute "ROOM" "PROC"
					( Origin gFrontEnd )
				)
				( attribute "ROT" "2"
					( Origin gFrontEnd )
				)
				( attribute "SEC" "1"
					( Origin gFrontEnd )
				)
				( attribute "SEC_TYPE" "0402"
					( Origin gFrontEnd )
				)
				( attribute "TOLERANCE" "1%"
					( Origin gFrontEnd )
				)
				( attribute "VALUE" "1.00K"
					( Origin gFrontEnd )
				)
				( attribute "VER" "2"
					( Origin gFrontEnd )
				)
				( attribute "WATTAGE" "1/16W"
					( Origin gFrontEnd )
				)
				( attribute "XY" "(325,3700)"
					( Origin gFrontEnd )
				)
				( attribute "CHIPS_PART_NAME" "RES"
					( Origin gPackager )
				)
				( attribute "CDS_PART_NAME" "RES_0402-1.00K,1%,1/16W,CHIP,GA"
					( Origin gPackager )
				)
				( objectStatus "R4G3" )
			)
			( gate "@baseboard_fab2_lib.baseboard_fab2(sch_1):page98_i42"
				( attribute "BOM_COST" "PROC_SOCKET"
					( Origin gFrontEnd )
				)
				( attribute "CDS_LIB" "mstr_discrete"
					( Origin gPackager )
				)
				( attribute "CDS_LOCATION" "R4G1"
					( Origin gPackager )
				)
				( attribute "CDS_SEC" "1"
					( Origin gPackager )
				)
				( attribute "LOCATION" "R4G1"
					( Origin gFrontEnd )
				)
				( attribute "MATERIAL" "CHIP"
					( Origin gFrontEnd )
				)
				( attribute "PACK_TYPE" "0402"
					( Origin gFrontEnd )
				)
				( attribute "PART_NUMBER" "G21796-274"
					( Origin gFrontEnd )
				)
				( attribute "PHYS_PAGE" "98"
					( Origin gFrontEnd )
				)
				( attribute "ROOM" "PROC"
					( Origin gFrontEnd )
				)
				( attribute "ROT" "0"
					( Origin gFrontEnd )
				)
				( attribute "SEC" "1"
					( Origin gFrontEnd )
				)
				( attribute "SEC_TYPE" "0402"
					( Origin gFrontEnd )
				)
				( attribute "TOLERANCE" "1.0%"
					( Origin gFrontEnd )
				)
				( attribute "VALUE" "2"
					( Origin gFrontEnd )
				)
				( attribute "VER" "1"
					( Origin gFrontEnd )
				)
				( attribute "WATTAGE" "1/16W"
					( Origin gFrontEnd )
				)
				( attribute "XY" "(25,4025)"
					( Origin gFrontEnd )
				)
				( attribute "CHIPS_PART_NAME" "RES"
					( Origin gPackager )
				)
				( attribute "CDS_PART_NAME" "RES_0402-2,1.0%,1/16W,CHIP,G21A"
					( Origin gPackager )
				)
				( objectStatus "R4G1" )
			)
			( gate "@baseboard_fab2_lib.baseboard_fab2(sch_1):page98_i43"
				( attribute "BOM_COST" "SM_CONTROLLER"
					( Origin gFrontEnd )
				)
				( attribute "CDS_LIB" "dev_discrete"
					( Origin gPackager )
				)
				( attribute "CDS_LOCATION" "C4G1"
					( Origin gPackager )
				)
				( attribute "CDS_SEC" "1"
					( Origin gPackager )
				)
				( attribute "LOCATION" "C4G1"
					( Origin gFrontEnd )
				)
				( attribute "MATERIAL" "X7R"
					( Origin gFrontEnd )
				)
				( attribute "PACK_TYPE" "0402V"
					( Origin gFrontEnd )
				)
				( attribute "PART_NUMBER" "A36096-045"
					( Origin gFrontEnd )
				)
				( attribute "PHYS_PAGE" "98"
					( Origin gFrontEnd )
				)
				( attribute "ROOM" "MEM"
					( Origin gFrontEnd )
				)
				( attribute "ROT" "0"
					( Origin gFrontEnd )
				)
				( attribute "SEC" "1"
					( Origin gFrontEnd )
				)
				( attribute "SEC_TYPE" "0402V"
					( Origin gFrontEnd )
				)
				( attribute "TOLERANCE" "10%"
					( Origin gFrontEnd )
				)
				( attribute "VALUE" "0.01UF"
					( Origin gFrontEnd )
				)
				( attribute "VER" "1"
					( Origin gFrontEnd )
				)
				( attribute "VOLTAGE" "25V"
					( Units "uVoltage" "V" 1.000000)
					( Origin gFrontEnd )
				)
				( attribute "XY" "(-200,3725)"
					( Origin gFrontEnd )
				)
				( attribute "CHIPS_PART_NAME" "CAP_A"
					( Origin gPackager )
				)
				( attribute "CDS_PART_NAME" "CAP_A_0402V-0.01UF,25V,10%,X7RA"
					( Origin gPackager )
				)
				( objectStatus "C4G1" )
			)
			( gate "@baseboard_fab2_lib.baseboard_fab2(sch_1):page98_i46"
				( attribute "BOM_COST" "SM_CONTROLLER"
					( Origin gFrontEnd )
				)
				( attribute "CDS_LIB" "mstr_discrete"
					( Origin gPackager )
				)
				( attribute "CDS_LOCATION" "R4G21"
					( Origin gPackager )
				)
				( attribute "CDS_SEC" "1"
					( Origin gPackager )
				)
				( attribute "LOCATION" "R4G21"
					( Origin gFrontEnd )
				)
				( attribute "MATERIAL" "CHIP"
					( Origin gFrontEnd )
				)
				( attribute "PACK_TYPE" "0402"
					( Origin gFrontEnd )
				)
				( attribute "PART_NUMBER" "G21796-026"
					( Origin gFrontEnd )
				)
				( attribute "PHYS_PAGE" "98"
					( Origin gFrontEnd )
				)
				( attribute "ROOM" "MEM"
					( Origin gFrontEnd )
				)
				( attribute "ROT" "2"
					( Origin gFrontEnd )
				)
				( attribute "SEC" "1"
					( Origin gFrontEnd )
				)
				( attribute "SEC_TYPE" "0402"
					( Origin gFrontEnd )
				)
				( attribute "TOLERANCE" "1%"
					( Origin gFrontEnd )
				)
				( attribute "VALUE" "1.00K"
					( Origin gFrontEnd )
				)
				( attribute "VER" "2"
					( Origin gFrontEnd )
				)
				( attribute "WATTAGE" "1/16W"
					( Origin gFrontEnd )
				)
				( attribute "XY" "(2400,4350)"
					( Origin gFrontEnd )
				)
				( attribute "CHIPS_PART_NAME" "RES"
					( Origin gPackager )
				)
				( attribute "CDS_PART_NAME" "RES_0402-1.00K,1%,1/16W,CHIP,GA"
					( Origin gPackager )
				)
				( objectStatus "R4G21" )
			)
			( gate "@baseboard_fab2_lib.baseboard_fab2(sch_1):page98_i48"
				( attribute "BOM_COST" "PROC_SOCKET"
					( Origin gFrontEnd )
				)
				( attribute "CDS_LIB" "mstr_discrete"
					( Origin gPackager )
				)
				( attribute "CDS_LOCATION" "R4G22"
					( Origin gPackager )
				)
				( attribute "CDS_SEC" "1"
					( Origin gPackager )
				)
				( attribute "LOCATION" "R4G22"
					( Origin gFrontEnd )
				)
				( attribute "MATERIAL" "CHIP"
					( Origin gFrontEnd )
				)
				( attribute "PACK_TYPE" "0402"
					( Origin gFrontEnd )
				)
				( attribute "PART_NUMBER" "G21796-026"
					( Origin gFrontEnd )
				)
				( attribute "PHYS_PAGE" "98"
					( Origin gFrontEnd )
				)
				( attribute "ROOM" "PROC"
					( Origin gFrontEnd )
				)
				( attribute "ROT" "2"
					( Origin gFrontEnd )
				)
				( attribute "SEC" "1"
					( Origin gFrontEnd )
				)
				( attribute "SEC_TYPE" "0402"
					( Origin gFrontEnd )
				)
				( attribute "TOLERANCE" "1%"
					( Origin gFrontEnd )
				)
				( attribute "VALUE" "1.00K"
					( Origin gFrontEnd )
				)
				( attribute "VER" "2"
					( Origin gFrontEnd )
				)
				( attribute "WATTAGE" "1/16W"
					( Origin gFrontEnd )
				)
				( attribute "XY" "(2475,3700)"
					( Origin gFrontEnd )
				)
				( attribute "CHIPS_PART_NAME" "RES"
					( Origin gPackager )
				)
				( attribute "CDS_PART_NAME" "RES_0402-1.00K,1%,1/16W,CHIP,GA"
					( Origin gPackager )
				)
				( objectStatus "R4G22" )
			)
			( gate "@baseboard_fab2_lib.baseboard_fab2(sch_1):page98_i50"
				( attribute "BOM_COST" "PROC_SOCKET"
					( Origin gFrontEnd )
				)
				( attribute "CDS_LIB" "mstr_discrete"
					( Origin gPackager )
				)
				( attribute "CDS_LOCATION" "R4G20"
					( Origin gPackager )
				)
				( attribute "CDS_SEC" "1"
					( Origin gPackager )
				)
				( attribute "LOCATION" "R4G20"
					( Origin gFrontEnd )
				)
				( attribute "MATERIAL" "CHIP"
					( Origin gFrontEnd )
				)
				( attribute "PACK_TYPE" "0402"
					( Origin gFrontEnd )
				)
				( attribute "PART_NUMBER" "G21796-274"
					( Origin gFrontEnd )
				)
				( attribute "PHYS_PAGE" "98"
					( Origin gFrontEnd )
				)
				( attribute "ROOM" "PROC"
					( Origin gFrontEnd )
				)
				( attribute "ROT" "0"
					( Origin gFrontEnd )
				)
				( attribute "SEC" "1"
					( Origin gFrontEnd )
				)
				( attribute "SEC_TYPE" "0402"
					( Origin gFrontEnd )
				)
				( attribute "TOLERANCE" "1.0%"
					( Origin gFrontEnd )
				)
				( attribute "VALUE" "2"
					( Origin gFrontEnd )
				)
				( attribute "VER" "1"
					( Origin gFrontEnd )
				)
				( attribute "WATTAGE" "1/16W"
					( Origin gFrontEnd )
				)
				( attribute "XY" "(2175,4025)"
					( Origin gFrontEnd )
				)
				( attribute "CHIPS_PART_NAME" "RES"
					( Origin gPackager )
				)
				( attribute "CDS_PART_NAME" "RES_0402-2,1.0%,1/16W,CHIP,G21A"
					( Origin gPackager )
				)
				( objectStatus "R4G20" )
			)
			( gate "@baseboard_fab2_lib.baseboard_fab2(sch_1):page98_i51"
				( attribute "BOM_COST" "SM_CONTROLLER"
					( Origin gFrontEnd )
				)
				( attribute "CDS_LIB" "dev_discrete"
					( Origin gPackager )
				)
				( attribute "CDS_LOCATION" "C4G17"
					( Origin gPackager )
				)
				( attribute "CDS_SEC" "1"
					( Origin gPackager )
				)
				( attribute "LOCATION" "C4G17"
					( Origin gFrontEnd )
				)
				( attribute "MATERIAL" "X7R"
					( Origin gFrontEnd )
				)
				( attribute "PACK_TYPE" "0402V"
					( Origin gFrontEnd )
				)
				( attribute "PART_NUMBER" "A36096-045"
					( Origin gFrontEnd )
				)
				( attribute "PHYS_PAGE" "98"
					( Origin gFrontEnd )
				)
				( attribute "ROOM" "MEM"
					( Origin gFrontEnd )
				)
				( attribute "ROT" "0"
					( Origin gFrontEnd )
				)
				( attribute "SEC" "1"
					( Origin gFrontEnd )
				)
				( attribute "SEC_TYPE" "0402V"
					( Origin gFrontEnd )
				)
				( attribute "TOLERANCE" "10%"
					( Origin gFrontEnd )
				)
				( attribute "VALUE" "0.01UF"
					( Origin gFrontEnd )
				)
				( attribute "VER" "1"
					( Origin gFrontEnd )
				)
				( attribute "VOLTAGE" "25V"
					( Units "uVoltage" "V" 1.000000)
					( Origin gFrontEnd )
				)
				( attribute "XY" "(1950,3725)"
					( Origin gFrontEnd )
				)
				( attribute "CHIPS_PART_NAME" "CAP_A"
					( Origin gPackager )
				)
				( attribute "CDS_PART_NAME" "CAP_A_0402V-0.01UF,25V,10%,X7RA"
					( Origin gPackager )
				)
				( objectStatus "C4G17" )
			)
			( gate "@baseboard_fab2_lib.baseboard_fab2(sch_1):page98_i54"
				( attribute "BOM_COST" "SM_CONTROLLER"
					( Origin gFrontEnd )
				)
				( attribute "CDS_LIB" "mstr_discrete"
					( Origin gPackager )
				)
				( attribute "CDS_LOCATION" "R6L13"
					( Origin gPackager )
				)
				( attribute "CDS_SEC" "1"
					( Origin gPackager )
				)
				( attribute "LOCATION" "R6L13"
					( Origin gFrontEnd )
				)
				( attribute "MATERIAL" "CHIP"
					( Origin gFrontEnd )
				)
				( attribute "PACK_TYPE" "0402"
					( Origin gFrontEnd )
				)
				( attribute "PART_NUMBER" "G21796-026"
					( Origin gFrontEnd )
				)
				( attribute "PHYS_PAGE" "98"
					( Origin gFrontEnd )
				)
				( attribute "ROOM" "MEM"
					( Origin gFrontEnd )
				)
				( attribute "ROT" "2"
					( Origin gFrontEnd )
				)
				( attribute "SEC" "1"
					( Origin gFrontEnd )
				)
				( attribute "SEC_TYPE" "0402"
					( Origin gFrontEnd )
				)
				( attribute "TOLERANCE" "1%"
					( Origin gFrontEnd )
				)
				( attribute "VALUE" "1.00K"
					( Origin gFrontEnd )
				)
				( attribute "VER" "2"
					( Origin gFrontEnd )
				)
				( attribute "WATTAGE" "1/16W"
					( Origin gFrontEnd )
				)
				( attribute "XY" "(225,2675)"
					( Origin gFrontEnd )
				)
				( attribute "CHIPS_PART_NAME" "RES"
					( Origin gPackager )
				)
				( attribute "CDS_PART_NAME" "RES_0402-1.00K,1%,1/16W,CHIP,GA"
					( Origin gPackager )
				)
				( objectStatus "R6L13" )
			)
			( gate "@baseboard_fab2_lib.baseboard_fab2(sch_1):page98_i56"
				( attribute "BOM_COST" "PROC_SOCKET"
					( Origin gFrontEnd )
				)
				( attribute "CDS_LIB" "mstr_discrete"
					( Origin gPackager )
				)
				( attribute "CDS_LOCATION" "R6L12"
					( Origin gPackager )
				)
				( attribute "CDS_SEC" "1"
					( Origin gPackager )
				)
				( attribute "LOCATION" "R6L12"
					( Origin gFrontEnd )
				)
				( attribute "MATERIAL" "CHIP"
					( Origin gFrontEnd )
				)
				( attribute "PACK_TYPE" "0402"
					( Origin gFrontEnd )
				)
				( attribute "PART_NUMBER" "G21796-026"
					( Origin gFrontEnd )
				)
				( attribute "PHYS_PAGE" "98"
					( Origin gFrontEnd )
				)
				( attribute "ROOM" "PROC"
					( Origin gFrontEnd )
				)
				( attribute "ROT" "2"
					( Origin gFrontEnd )
				)
				( attribute "SEC" "1"
					( Origin gFrontEnd )
				)
				( attribute "SEC_TYPE" "0402"
					( Origin gFrontEnd )
				)
				( attribute "TOLERANCE" "1%"
					( Origin gFrontEnd )
				)
				( attribute "VALUE" "1.00K"
					( Origin gFrontEnd )
				)
				( attribute "VER" "2"
					( Origin gFrontEnd )
				)
				( attribute "WATTAGE" "1/16W"
					( Origin gFrontEnd )
				)
				( attribute "XY" "(300,2025)"
					( Origin gFrontEnd )
				)
				( attribute "CHIPS_PART_NAME" "RES"
					( Origin gPackager )
				)
				( attribute "CDS_PART_NAME" "RES_0402-1.00K,1%,1/16W,CHIP,GA"
					( Origin gPackager )
				)
				( objectStatus "R6L12" )
			)
			( gate "@baseboard_fab2_lib.baseboard_fab2(sch_1):page98_i58"
				( attribute "BOM_COST" "PROC_SOCKET"
					( Origin gFrontEnd )
				)
				( attribute "CDS_LIB" "mstr_discrete"
					( Origin gPackager )
				)
				( attribute "CDS_LOCATION" "R6L14"
					( Origin gPackager )
				)
				( attribute "CDS_SEC" "1"
					( Origin gPackager )
				)
				( attribute "LOCATION" "R6L14"
					( Origin gFrontEnd )
				)
				( attribute "MATERIAL" "CHIP"
					( Origin gFrontEnd )
				)
				( attribute "PACK_TYPE" "0402"
					( Origin gFrontEnd )
				)
				( attribute "PART_NUMBER" "G21796-274"
					( Origin gFrontEnd )
				)
				( attribute "PHYS_PAGE" "98"
					( Origin gFrontEnd )
				)
				( attribute "ROOM" "PROC"
					( Origin gFrontEnd )
				)
				( attribute "ROT" "0"
					( Origin gFrontEnd )
				)
				( attribute "SEC" "1"
					( Origin gFrontEnd )
				)
				( attribute "SEC_TYPE" "0402"
					( Origin gFrontEnd )
				)
				( attribute "TOLERANCE" "1.0%"
					( Origin gFrontEnd )
				)
				( attribute "VALUE" "2"
					( Origin gFrontEnd )
				)
				( attribute "VER" "1"
					( Origin gFrontEnd )
				)
				( attribute "WATTAGE" "1/16W"
					( Origin gFrontEnd )
				)
				( attribute "XY" "(0,2350)"
					( Origin gFrontEnd )
				)
				( attribute "CHIPS_PART_NAME" "RES"
					( Origin gPackager )
				)
				( attribute "CDS_PART_NAME" "RES_0402-2,1.0%,1/16W,CHIP,G21A"
					( Origin gPackager )
				)
				( objectStatus "R6L14" )
			)
			( gate "@baseboard_fab2_lib.baseboard_fab2(sch_1):page98_i59"
				( attribute "BOM_COST" "SM_CONTROLLER"
					( Origin gFrontEnd )
				)
				( attribute "CDS_LIB" "dev_discrete"
					( Origin gPackager )
				)
				( attribute "CDS_LOCATION" "C6L7"
					( Origin gPackager )
				)
				( attribute "CDS_SEC" "1"
					( Origin gPackager )
				)
				( attribute "LOCATION" "C6L7"
					( Origin gFrontEnd )
				)
				( attribute "MATERIAL" "X7R"
					( Origin gFrontEnd )
				)
				( attribute "PACK_TYPE" "0402V"
					( Origin gFrontEnd )
				)
				( attribute "PART_NUMBER" "A36096-045"
					( Origin gFrontEnd )
				)
				( attribute "PHYS_PAGE" "98"
					( Origin gFrontEnd )
				)
				( attribute "ROOM" "MEM"
					( Origin gFrontEnd )
				)
				( attribute "ROT" "0"
					( Origin gFrontEnd )
				)
				( attribute "SEC" "1"
					( Origin gFrontEnd )
				)
				( attribute "SEC_TYPE" "0402V"
					( Origin gFrontEnd )
				)
				( attribute "TOLERANCE" "10%"
					( Origin gFrontEnd )
				)
				( attribute "VALUE" "0.01UF"
					( Origin gFrontEnd )
				)
				( attribute "VER" "1"
					( Origin gFrontEnd )
				)
				( attribute "VOLTAGE" "25V"
					( Units "uVoltage" "V" 1.000000)
					( Origin gFrontEnd )
				)
				( attribute "XY" "(-225,2050)"
					( Origin gFrontEnd )
				)
				( attribute "CHIPS_PART_NAME" "CAP_A"
					( Origin gPackager )
				)
				( attribute "CDS_PART_NAME" "CAP_A_0402V-0.01UF,25V,10%,X7RA"
					( Origin gPackager )
				)
				( objectStatus "C6L7" )
			)
			( gate "@baseboard_fab2_lib.baseboard_fab2(sch_1):page98_i62"
				( attribute "BOM_COST" "SM_CONTROLLER"
					( Origin gFrontEnd )
				)
				( attribute "CDS_LIB" "mstr_discrete"
					( Origin gPackager )
				)
				( attribute "CDS_LOCATION" "R6L2"
					( Origin gPackager )
				)
				( attribute "CDS_SEC" "1"
					( Origin gPackager )
				)
				( attribute "LOCATION" "R6L2"
					( Origin gFrontEnd )
				)
				( attribute "MATERIAL" "CHIP"
					( Origin gFrontEnd )
				)
				( attribute "PACK_TYPE" "0402"
					( Origin gFrontEnd )
				)
				( attribute "PART_NUMBER" "G21796-026"
					( Origin gFrontEnd )
				)
				( attribute "PHYS_PAGE" "98"
					( Origin gFrontEnd )
				)
				( attribute "ROOM" "MEM"
					( Origin gFrontEnd )
				)
				( attribute "ROT" "2"
					( Origin gFrontEnd )
				)
				( attribute "SEC" "1"
					( Origin gFrontEnd )
				)
				( attribute "SEC_TYPE" "0402"
					( Origin gFrontEnd )
				)
				( attribute "TOLERANCE" "1%"
					( Origin gFrontEnd )
				)
				( attribute "VALUE" "1.00K"
					( Origin gFrontEnd )
				)
				( attribute "VER" "2"
					( Origin gFrontEnd )
				)
				( attribute "WATTAGE" "1/16W"
					( Origin gFrontEnd )
				)
				( attribute "XY" "(2400,2650)"
					( Origin gFrontEnd )
				)
				( attribute "CHIPS_PART_NAME" "RES"
					( Origin gPackager )
				)
				( attribute "CDS_PART_NAME" "RES_0402-1.00K,1%,1/16W,CHIP,GA"
					( Origin gPackager )
				)
				( objectStatus "R6L2" )
			)
			( gate "@baseboard_fab2_lib.baseboard_fab2(sch_1):page98_i64"
				( attribute "BOM_COST" "PROC_SOCKET"
					( Origin gFrontEnd )
				)
				( attribute "CDS_LIB" "mstr_discrete"
					( Origin gPackager )
				)
				( attribute "CDS_LOCATION" "R6L1"
					( Origin gPackager )
				)
				( attribute "CDS_SEC" "1"
					( Origin gPackager )
				)
				( attribute "LOCATION" "R6L1"
					( Origin gFrontEnd )
				)
				( attribute "MATERIAL" "CHIP"
					( Origin gFrontEnd )
				)
				( attribute "PACK_TYPE" "0402"
					( Origin gFrontEnd )
				)
				( attribute "PART_NUMBER" "G21796-026"
					( Origin gFrontEnd )
				)
				( attribute "PHYS_PAGE" "98"
					( Origin gFrontEnd )
				)
				( attribute "ROOM" "PROC"
					( Origin gFrontEnd )
				)
				( attribute "ROT" "2"
					( Origin gFrontEnd )
				)
				( attribute "SEC" "1"
					( Origin gFrontEnd )
				)
				( attribute "SEC_TYPE" "0402"
					( Origin gFrontEnd )
				)
				( attribute "TOLERANCE" "1%"
					( Origin gFrontEnd )
				)
				( attribute "VALUE" "1.00K"
					( Origin gFrontEnd )
				)
				( attribute "VER" "2"
					( Origin gFrontEnd )
				)
				( attribute "WATTAGE" "1/16W"
					( Origin gFrontEnd )
				)
				( attribute "XY" "(2475,2000)"
					( Origin gFrontEnd )
				)
				( attribute "CHIPS_PART_NAME" "RES"
					( Origin gPackager )
				)
				( attribute "CDS_PART_NAME" "RES_0402-1.00K,1%,1/16W,CHIP,GA"
					( Origin gPackager )
				)
				( objectStatus "R6L1" )
			)
			( gate "@baseboard_fab2_lib.baseboard_fab2(sch_1):page98_i66"
				( attribute "BOM_COST" "PROC_SOCKET"
					( Origin gFrontEnd )
				)
				( attribute "CDS_LIB" "mstr_discrete"
					( Origin gPackager )
				)
				( attribute "CDS_LOCATION" "R6L3"
					( Origin gPackager )
				)
				( attribute "CDS_SEC" "1"
					( Origin gPackager )
				)
				( attribute "LOCATION" "R6L3"
					( Origin gFrontEnd )
				)
				( attribute "MATERIAL" "CHIP"
					( Origin gFrontEnd )
				)
				( attribute "PACK_TYPE" "0402"
					( Origin gFrontEnd )
				)
				( attribute "PART_NUMBER" "G21796-274"
					( Origin gFrontEnd )
				)
				( attribute "PHYS_PAGE" "98"
					( Origin gFrontEnd )
				)
				( attribute "ROOM" "PROC"
					( Origin gFrontEnd )
				)
				( attribute "ROT" "0"
					( Origin gFrontEnd )
				)
				( attribute "SEC" "1"
					( Origin gFrontEnd )
				)
				( attribute "SEC_TYPE" "0402"
					( Origin gFrontEnd )
				)
				( attribute "TOLERANCE" "1.0%"
					( Origin gFrontEnd )
				)
				( attribute "VALUE" "2"
					( Origin gFrontEnd )
				)
				( attribute "VER" "1"
					( Origin gFrontEnd )
				)
				( attribute "WATTAGE" "1/16W"
					( Origin gFrontEnd )
				)
				( attribute "XY" "(2175,2325)"
					( Origin gFrontEnd )
				)
				( attribute "CHIPS_PART_NAME" "RES"
					( Origin gPackager )
				)
				( attribute "CDS_PART_NAME" "RES_0402-2,1.0%,1/16W,CHIP,G21A"
					( Origin gPackager )
				)
				( objectStatus "R6L3" )
			)
			( gate "@baseboard_fab2_lib.baseboard_fab2(sch_1):page98_i67"
				( attribute "BOM_COST" "SM_CONTROLLER"
					( Origin gFrontEnd )
				)
				( attribute "CDS_LIB" "dev_discrete"
					( Origin gPackager )
				)
				( attribute "CDS_LOCATION" "C6L2"
					( Origin gPackager )
				)
				( attribute "CDS_SEC" "1"
					( Origin gPackager )
				)
				( attribute "LOCATION" "C6L2"
					( Origin gFrontEnd )
				)
				( attribute "MATERIAL" "X7R"
					( Origin gFrontEnd )
				)
				( attribute "PACK_TYPE" "0402V"
					( Origin gFrontEnd )
				)
				( attribute "PART_NUMBER" "A36096-045"
					( Origin gFrontEnd )
				)
				( attribute "PHYS_PAGE" "98"
					( Origin gFrontEnd )
				)
				( attribute "ROOM" "MEM"
					( Origin gFrontEnd )
				)
				( attribute "ROT" "0"
					( Origin gFrontEnd )
				)
				( attribute "SEC" "1"
					( Origin gFrontEnd )
				)
				( attribute "SEC_TYPE" "0402V"
					( Origin gFrontEnd )
				)
				( attribute "TOLERANCE" "10%"
					( Origin gFrontEnd )
				)
				( attribute "VALUE" "0.01UF"
					( Origin gFrontEnd )
				)
				( attribute "VER" "1"
					( Origin gFrontEnd )
				)
				( attribute "VOLTAGE" "25V"
					( Units "uVoltage" "V" 1.000000)
					( Origin gFrontEnd )
				)
				( attribute "XY" "(1950,2025)"
					( Origin gFrontEnd )
				)
				( attribute "CHIPS_PART_NAME" "CAP_A"
					( Origin gPackager )
				)
				( attribute "CDS_PART_NAME" "CAP_A_0402V-0.01UF,25V,10%,X7RA"
					( Origin gPackager )
				)
				( objectStatus "C6L2" )
			)
			( gate "@baseboard_fab2_lib.baseboard_fab2(sch_1):page99_i2"
				( attribute "BOM_COST" "SM_CONTROLLER"
					( Origin gFrontEnd )
				)
				( attribute "CDS_LIB" "dev_discrete"
					( Origin gPackager )
				)
				( attribute "CDS_LOCATION" "C6F2"
					( Origin gPackager )
				)
				( attribute "CDS_SEC" "1"
					( Origin gPackager )
				)
				( attribute "CD_SEC" "1"
					( Origin gFrontEnd )
				)
				( attribute "LOCATION" "C6F2"
					( Origin gFrontEnd )
				)
				( attribute "MATERIAL" "X7R"
					( Origin gFrontEnd )
				)
				( attribute "PACK_TYPE" "0402V"
					( Origin gFrontEnd )
				)
				( attribute "PART_NUMBER" "A36096-030"
					( Origin gFrontEnd )
				)
				( attribute "PHYS_PAGE" "99"
					( Origin gFrontEnd )
				)
				( attribute "ROOM" "MEM"
					( Origin gFrontEnd )
				)
				( attribute "ROT" "0"
					( Origin gFrontEnd )
				)
				( attribute "SEC" "1"
					( Origin gPackager )
				)
				( attribute "SIGNAL_MODEL" "DEFAULT_CAPACITOR_100000pF_2_1"
					( Origin gFrontEnd )
				)
				( attribute "TOLERANCE" "10%"
					( Origin gFrontEnd )
				)
				( attribute "VALUE" "0.1UF"
					( Origin gFrontEnd )
				)
				( attribute "VER" "1"
					( Origin gFrontEnd )
				)
				( attribute "VOLTAGE" "16V"
					( Units "uVoltage" "V" 1.000000)
					( Origin gFrontEnd )
				)
				( attribute "XY" "(1900,4925)"
					( Origin gFrontEnd )
				)
				( attribute "CHIPS_PART_NAME" "CAP_A"
					( Origin gPackager )
				)
				( attribute "CDS_PART_NAME" "CAP_A_0402V-0.1UF,16V,10%,X7R,A"
					( Origin gPackager )
				)
				( objectStatus "C6F2" )
			)
			( gate "@baseboard_fab2_lib.baseboard_fab2(sch_1):page99_i7"
				( attribute "BOM_COST" "SM_CONTROLLER"
					( Origin gFrontEnd )
				)
				( attribute "CDS_LIB" "dev_discrete"
					( Origin gPackager )
				)
				( attribute "CDS_LOCATION" "C6F3"
					( Origin gPackager )
				)
				( attribute "CDS_SEC" "1"
					( Origin gPackager )
				)
				( attribute "CD_SEC" "1"
					( Origin gFrontEnd )
				)
				( attribute "LOCATION" "C6F3"
					( Origin gFrontEnd )
				)
				( attribute "MATERIAL" "X7R"
					( Origin gFrontEnd )
				)
				( attribute "PACK_TYPE" "0402V"
					( Origin gFrontEnd )
				)
				( attribute "PART_NUMBER" "A36096-030"
					( Origin gFrontEnd )
				)
				( attribute "PHYS_PAGE" "99"
					( Origin gFrontEnd )
				)
				( attribute "ROOM" "MEM"
					( Origin gFrontEnd )
				)
				( attribute "ROT" "0"
					( Origin gFrontEnd )
				)
				( attribute "SEC" "1"
					( Origin gPackager )
				)
				( attribute "SIGNAL_MODEL" "DEFAULT_CAPACITOR_100000pF_2_1"
					( Origin gFrontEnd )
				)
				( attribute "TOLERANCE" "10%"
					( Origin gFrontEnd )
				)
				( attribute "VALUE" "0.1UF"
					( Origin gFrontEnd )
				)
				( attribute "VER" "1"
					( Origin gFrontEnd )
				)
				( attribute "VOLTAGE" "16V"
					( Units "uVoltage" "V" 1.000000)
					( Origin gFrontEnd )
				)
				( attribute "XY" "(1475,4900)"
					( Origin gFrontEnd )
				)
				( attribute "CHIPS_PART_NAME" "CAP_A"
					( Origin gPackager )
				)
				( attribute "CDS_PART_NAME" "CAP_A_0402V-0.1UF,16V,10%,X7R,A"
					( Origin gPackager )
				)
				( objectStatus "C6F3" )
			)
			( gate "@baseboard_fab2_lib.baseboard_fab2(sch_1):page99_i9"
				( attribute "CDS_LIB" "mstr_discrete"
					( Origin gPackager )
				)
				( attribute "CDS_LOCATION" "R4T9"
					( Origin gPackager )
				)
				( attribute "CDS_SEC" "1"
					( Origin gPackager )
				)
				( attribute "LOCATION" "R4T9"
					( Origin gFrontEnd )
				)
				( attribute "MATERIAL" "CHIP"
					( Origin gFrontEnd )
				)
				( attribute "PACK_TYPE" "0402"
					( Origin gFrontEnd )
				)
				( attribute "PART_NUMBER" "G21796-173"
					( Origin gFrontEnd )
				)
				( attribute "PHYS_PAGE" "99"
					( Origin gFrontEnd )
				)
				( attribute "ROOM" "MEM"
					( Origin gFrontEnd )
				)
				( attribute "ROT" "0"
					( Origin gFrontEnd )
				)
				( attribute "SEC" "1"
					( Origin gPackager )
				)
				( attribute "TOLERANCE" "1%"
					( Origin gFrontEnd )
				)
				( attribute "VALUE" "20.0"
					( Origin gFrontEnd )
				)
				( attribute "VER" "1"
					( Origin gFrontEnd )
				)
				( attribute "WATTAGE" "1/16W"
					( Origin gFrontEnd )
				)
				( attribute "XY" "(1600,4350)"
					( Origin gFrontEnd )
				)
				( attribute "CHIPS_PART_NAME" "RES"
					( Origin gPackager )
				)
				( attribute "CDS_PART_NAME" "RES_0402-20.0,1%,1/16W,CHIP,G2A"
					( Origin gPackager )
				)
				( objectStatus "R4T9" )
			)
			( gate "@baseboard_fab2_lib.baseboard_fab2(sch_1):page99_i10"
				( attribute "CDS_LIB" "mstr_discrete"
					( Origin gPackager )
				)
				( attribute "CDS_LOCATION" "R4T10"
					( Origin gPackager )
				)
				( attribute "CDS_SEC" "1"
					( Origin gPackager )
				)
				( attribute "LOCATION" "R4T10"
					( Origin gFrontEnd )
				)
				( attribute "MATERIAL" "CHIP"
					( Origin gFrontEnd )
				)
				( attribute "PACK_TYPE" "0402"
					( Origin gFrontEnd )
				)
				( attribute "PART_NUMBER" "G21796-173"
					( Origin gFrontEnd )
				)
				( attribute "PHYS_PAGE" "99"
					( Origin gFrontEnd )
				)
				( attribute "ROOM" "MEM"
					( Origin gFrontEnd )
				)
				( attribute "ROT" "0"
					( Origin gFrontEnd )
				)
				( attribute "SEC" "1"
					( Origin gPackager )
				)
				( attribute "TOLERANCE" "1%"
					( Origin gFrontEnd )
				)
				( attribute "VALUE" "20.0"
					( Origin gFrontEnd )
				)
				( attribute "VER" "1"
					( Origin gFrontEnd )
				)
				( attribute "WATTAGE" "1/16W"
					( Origin gFrontEnd )
				)
				( attribute "XY" "(1600,4300)"
					( Origin gFrontEnd )
				)
				( attribute "CHIPS_PART_NAME" "RES"
					( Origin gPackager )
				)
				( attribute "CDS_PART_NAME" "RES_0402-20.0,1%,1/16W,CHIP,G2A"
					( Origin gPackager )
				)
				( objectStatus "R4T10" )
			)
			( gate "@baseboard_fab2_lib.baseboard_fab2(sch_1):page99_i11"
				( attribute "BOM_COST" "SM_CONTROLLER"
					( Origin gFrontEnd )
				)
				( attribute "CDS_LIB" "mstr_discrete"
					( Origin gPackager )
				)
				( attribute "CDS_LOCATION" "R4T8"
					( Origin gPackager )
				)
				( attribute "CDS_SEC" "1"
					( Origin gPackager )
				)
				( attribute "LOCATION" "R4T8"
					( Origin gFrontEnd )
				)
				( attribute "MATERIAL" "CHIP"
					( Origin gFrontEnd )
				)
				( attribute "PACK_TYPE" "0402"
					( Origin gFrontEnd )
				)
				( attribute "PART_NUMBER" "G21796-235"
					( Origin gFrontEnd )
				)
				( attribute "PHYS_PAGE" "99"
					( Origin gFrontEnd )
				)
				( attribute "ROOM" "MEM"
					( Origin gFrontEnd )
				)
				( attribute "ROT" "0"
					( Origin gFrontEnd )
				)
				( attribute "SEC" "1"
					( Origin gFrontEnd )
				)
				( attribute "SEC_TYPE" "0402"
					( Origin gFrontEnd )
				)
				( attribute "TOLERANCE" "1.0%"
					( Origin gFrontEnd )
				)
				( attribute "VALUE" "665"
					( Origin gFrontEnd )
				)
				( attribute "VER" "2"
					( Origin gFrontEnd )
				)
				( attribute "WATTAGE" "1/16W"
					( Origin gFrontEnd )
				)
				( attribute "XY" "(1225,4650)"
					( Origin gFrontEnd )
				)
				( attribute "CHIPS_PART_NAME" "RES"
					( Origin gPackager )
				)
				( attribute "CDS_PART_NAME" "RES_0402-665,1.0%,1/16W,CHIP,GA"
					( Origin gPackager )
				)
				( objectStatus "R4T8" )
			)
			( gate "@baseboard_fab2_lib.baseboard_fab2(sch_1):page99_i13"
				( attribute "BOM_COST" "SM_CONTROLLER"
					( Origin gFrontEnd )
				)
				( attribute "CDS_LIB" "mstr_discrete"
					( Origin gPackager )
				)
				( attribute "CDS_LOCATION" "R4T7"
					( Origin gPackager )
				)
				( attribute "CDS_SEC" "1"
					( Origin gPackager )
				)
				( attribute "LOCATION" "R4T7"
					( Origin gFrontEnd )
				)
				( attribute "MATERIAL" "CHIP"
					( Origin gFrontEnd )
				)
				( attribute "PACK_TYPE" "0402"
					( Origin gFrontEnd )
				)
				( attribute "PART_NUMBER" "G21796-235"
					( Origin gFrontEnd )
				)
				( attribute "PHYS_PAGE" "99"
					( Origin gFrontEnd )
				)
				( attribute "ROOM" "MEM"
					( Origin gFrontEnd )
				)
				( attribute "ROT" "0"
					( Origin gFrontEnd )
				)
				( attribute "SEC" "1"
					( Origin gFrontEnd )
				)
				( attribute "SEC_TYPE" "0402"
					( Origin gFrontEnd )
				)
				( attribute "TOLERANCE" "1.0%"
					( Origin gFrontEnd )
				)
				( attribute "VALUE" "665"
					( Origin gFrontEnd )
				)
				( attribute "VER" "2"
					( Origin gFrontEnd )
				)
				( attribute "WATTAGE" "1/16W"
					( Origin gFrontEnd )
				)
				( attribute "XY" "(875,4650)"
					( Origin gFrontEnd )
				)
				( attribute "CHIPS_PART_NAME" "RES"
					( Origin gPackager )
				)
				( attribute "CDS_PART_NAME" "RES_0402-665,1.0%,1/16W,CHIP,GA"
					( Origin gPackager )
				)
				( objectStatus "R4T7" )
			)
			( gate "@baseboard_fab2_lib.baseboard_fab2(sch_1):page99_i15"
				( attribute "BOM_COST" "SM_CONTROLLER"
					( Origin gFrontEnd )
				)
				( attribute "CDS_LIB" "mstr_digital"
					( Origin gPackager )
				)
				( attribute "CDS_LOCATION" "U6F1"
					( Origin gPackager )
				)
				( attribute "CDS_SEC" "1"
					( Origin gPackager )
				)
				( attribute "LOCATION" "U6F1"
					( Origin gFrontEnd )
				)
				( attribute "MATERIAL" "IC"
					( Origin gFrontEnd )
				)
				( attribute "PACK_TYPE" "SSOP"
					( Origin gFrontEnd )
				)
				( attribute "PART_NUMBER" "G81764-001"
					( Origin gFrontEnd )
				)
				( attribute "PHYS_PAGE" "99"
					( Origin gFrontEnd )
				)
				( attribute "ROOM" "MEM"
					( Origin gFrontEnd )
				)
				( attribute "ROT" "0"
					( Origin gFrontEnd )
				)
				( attribute "SEC" "1"
					( Origin gPackager )
				)
				( attribute "VER" "1"
					( Origin gFrontEnd )
				)
				( attribute "XY" "(150,4300)"
					( Origin gFrontEnd )
				)
				( attribute "CHIPS_PART_NAME" "PCA9617"
					( Origin gPackager )
				)
				( attribute "CDS_PART_NAME" "PCA9617_SSOP-IC,G81764-001"
					( Origin gPackager )
				)
				( objectStatus "U6F1" )
			)
			( gate "@baseboard_fab2_lib.baseboard_fab2(sch_1):page99_i17"
				( attribute "BOM_COST" "SM_CONTROLLER"
					( Origin gFrontEnd )
				)
				( attribute "CDS_LIB" "mstr_discrete"
					( Origin gPackager )
				)
				( attribute "CDS_LOCATION" "R4T6"
					( Origin gPackager )
				)
				( attribute "CDS_SEC" "1"
					( Origin gPackager )
				)
				( attribute "CD_SEC" "1"
					( Origin gFrontEnd )
				)
				( attribute "LOCATION" "R4T6"
					( Origin gFrontEnd )
				)
				( attribute "MATERIAL" "CHIP"
					( Origin gFrontEnd )
				)
				( attribute "PACK_TYPE" "0402"
					( Origin gFrontEnd )
				)
				( attribute "PART_NUMBER" "G21796-294"
					( Origin gFrontEnd )
				)
				( attribute "PHYS_PAGE" "99"
					( Origin gFrontEnd )
				)
				( attribute "ROOM" "MEM"
					( Origin gFrontEnd )
				)
				( attribute "ROT" "2"
					( Origin gFrontEnd )
				)
				( attribute "SEC" "1"
					( Origin gPackager )
				)
				( attribute "SIGNAL_MODEL" "DEFAULT_RESISTOR_750OHM_2_1"
					( Origin gFrontEnd )
				)
				( attribute "TOLERANCE" "1.0%"
					( Origin gFrontEnd )
				)
				( attribute "VALUE" "240"
					( Origin gFrontEnd )
				)
				( attribute "VER" "2"
					( Origin gFrontEnd )
				)
				( attribute "WATTAGE" "1/16W"
					( Origin gFrontEnd )
				)
				( attribute "XY" "(-650,4650)"
					( Origin gFrontEnd )
				)
				( attribute "CHIPS_PART_NAME" "RES"
					( Origin gPackager )
				)
				( attribute "CDS_PART_NAME" "RES_0402-240,1.0%,1/16W,CHIP,GA"
					( Origin gPackager )
				)
				( objectStatus "R4T6" )
			)
			( gate "@baseboard_fab2_lib.baseboard_fab2(sch_1):page99_i19"
				( attribute "BOM_COST" "SM_CONTROLLER"
					( Origin gFrontEnd )
				)
				( attribute "CDS_LIB" "mstr_discrete"
					( Origin gPackager )
				)
				( attribute "CDS_LOCATION" "R4T5"
					( Origin gPackager )
				)
				( attribute "CDS_SEC" "1"
					( Origin gPackager )
				)
				( attribute "CD_SEC" "1"
					( Origin gFrontEnd )
				)
				( attribute "LOCATION" "R4T5"
					( Origin gFrontEnd )
				)
				( attribute "MATERIAL" "CHIP"
					( Origin gFrontEnd )
				)
				( attribute "PACK_TYPE" "0402"
					( Origin gFrontEnd )
				)
				( attribute "PART_NUMBER" "G21796-294"
					( Origin gFrontEnd )
				)
				( attribute "PHYS_PAGE" "99"
					( Origin gFrontEnd )
				)
				( attribute "ROOM" "MEM"
					( Origin gFrontEnd )
				)
				( attribute "ROT" "2"
					( Origin gFrontEnd )
				)
				( attribute "SEC" "1"
					( Origin gPackager )
				)
				( attribute "SIGNAL_MODEL" "DEFAULT_RESISTOR_750OHM_2_1"
					( Origin gFrontEnd )
				)
				( attribute "TOLERANCE" "1.0%"
					( Origin gFrontEnd )
				)
				( attribute "VALUE" "240"
					( Origin gFrontEnd )
				)
				( attribute "VER" "2"
					( Origin gFrontEnd )
				)
				( attribute "WATTAGE" "1/16W"
					( Origin gFrontEnd )
				)
				( attribute "XY" "(-1025,4650)"
					( Origin gFrontEnd )
				)
				( attribute "CHIPS_PART_NAME" "RES"
					( Origin gPackager )
				)
				( attribute "CDS_PART_NAME" "RES_0402-240,1.0%,1/16W,CHIP,GA"
					( Origin gPackager )
				)
				( objectStatus "R4T5" )
			)
			( gate "@baseboard_fab2_lib.baseboard_fab2(sch_1):page99_i20"
				( attribute "BOM_COST" "SM_CONTROLLER"
					( Origin gFrontEnd )
				)
				( attribute "CDS_LIB" "mstr_discrete"
					( Origin gPackager )
				)
				( attribute "CDS_LOCATION" "R4T4"
					( Origin gPackager )
				)
				( attribute "CDS_SEC" "1"
					( Origin gPackager )
				)
				( attribute "LOCATION" "R4T4"
					( Origin gFrontEnd )
				)
				( attribute "MATERIAL" "CHIP"
					( Origin gFrontEnd )
				)
				( attribute "PACK_TYPE" "0402"
					( Origin gFrontEnd )
				)
				( attribute "PART_NUMBER" "G21796-066"
					( Origin gFrontEnd )
				)
				( attribute "PHYS_PAGE" "99"
					( Origin gFrontEnd )
				)
				( attribute "ROOM" "MEM"
					( Origin gFrontEnd )
				)
				( attribute "ROT" "0"
					( Origin gFrontEnd )
				)
				( attribute "SEC" "1"
					( Origin gPackager )
				)
				( attribute "TOLERANCE" "1%"
					( Origin gFrontEnd )
				)
				( attribute "VALUE" "10.0"
					( Origin gFrontEnd )
				)
				( attribute "VER" "1"
					( Origin gFrontEnd )
				)
				( attribute "WATTAGE" "1/16W"
					( Origin gFrontEnd )
				)
				( attribute "XY" "(-1075,4300)"
					( Origin gFrontEnd )
				)
				( attribute "CHIPS_PART_NAME" "RES"
					( Origin gPackager )
				)
				( attribute "CDS_PART_NAME" "RES_0402-10.0,1%,1/16W,CHIP,G2A"
					( Origin gPackager )
				)
				( objectStatus "R4T4" )
			)
			( gate "@baseboard_fab2_lib.baseboard_fab2(sch_1):page99_i23"
				( attribute "BOM_COST" "SM_CONTROLLER"
					( Origin gFrontEnd )
				)
				( attribute "CDS_LIB" "dev_discrete"
					( Origin gPackager )
				)
				( attribute "CDS_LOCATION" "C7E1"
					( Origin gPackager )
				)
				( attribute "CDS_SEC" "1"
					( Origin gPackager )
				)
				( attribute "CD_SEC" "1"
					( Origin gFrontEnd )
				)
				( attribute "LOCATION" "C7E1"
					( Origin gFrontEnd )
				)
				( attribute "MATERIAL" "X7R"
					( Origin gFrontEnd )
				)
				( attribute "PACK_TYPE" "0402V"
					( Origin gFrontEnd )
				)
				( attribute "PART_NUMBER" "A36096-030"
					( Origin gFrontEnd )
				)
				( attribute "PHYS_PAGE" "99"
					( Origin gFrontEnd )
				)
				( attribute "ROOM" "MEM"
					( Origin gFrontEnd )
				)
				( attribute "ROT" "0"
					( Origin gFrontEnd )
				)
				( attribute "SEC" "1"
					( Origin gPackager )
				)
				( attribute "SIGNAL_MODEL" "DEFAULT_CAPACITOR_100000pF_2_1"
					( Origin gFrontEnd )
				)
				( attribute "TOLERANCE" "10%"
					( Origin gFrontEnd )
				)
				( attribute "VALUE" "0.1UF"
					( Origin gFrontEnd )
				)
				( attribute "VER" "1"
					( Origin gFrontEnd )
				)
				( attribute "VOLTAGE" "16V"
					( Units "uVoltage" "V" 1.000000)
					( Origin gFrontEnd )
				)
				( attribute "XY" "(2125,3775)"
					( Origin gFrontEnd )
				)
				( attribute "CHIPS_PART_NAME" "CAP_A"
					( Origin gPackager )
				)
				( attribute "CDS_PART_NAME" "CAP_A_0402V-0.1UF,16V,10%,X7R,A"
					( Origin gPackager )
				)
				( objectStatus "C7E1" )
			)
			( gate "@baseboard_fab2_lib.baseboard_fab2(sch_1):page99_i27"
				( attribute "BOM_COST" "SM_CONTROLLER"
					( Origin gFrontEnd )
				)
				( attribute "CDS_LIB" "dev_discrete"
					( Origin gPackager )
				)
				( attribute "CDS_LOCATION" "C4G22"
					( Origin gPackager )
				)
				( attribute "CDS_SEC" "1"
					( Origin gPackager )
				)
				( attribute "CD_SEC" "1"
					( Origin gFrontEnd )
				)
				( attribute "LOCATION" "C4G22"
					( Origin gFrontEnd )
				)
				( attribute "MATERIAL" "X7R"
					( Origin gFrontEnd )
				)
				( attribute "PACK_TYPE" "0402V"
					( Origin gFrontEnd )
				)
				( attribute "PART_NUMBER" "A36096-030"
					( Origin gFrontEnd )
				)
				( attribute "PHYS_PAGE" "99"
					( Origin gFrontEnd )
				)
				( attribute "ROOM" "MEM"
					( Origin gFrontEnd )
				)
				( attribute "ROT" "0"
					( Origin gFrontEnd )
				)
				( attribute "SEC" "1"
					( Origin gPackager )
				)
				( attribute "SIGNAL_MODEL" "DEFAULT_CAPACITOR_100000pF_2_1"
					( Origin gFrontEnd )
				)
				( attribute "TOLERANCE" "10%"
					( Origin gFrontEnd )
				)
				( attribute "VALUE" "0.1UF"
					( Origin gFrontEnd )
				)
				( attribute "VER" "1"
					( Origin gFrontEnd )
				)
				( attribute "VOLTAGE" "16V"
					( Units "uVoltage" "V" 1.000000)
					( Origin gFrontEnd )
				)
				( attribute "XY" "(2225,2700)"
					( Origin gFrontEnd )
				)
				( attribute "CHIPS_PART_NAME" "CAP_A"
					( Origin gPackager )
				)
				( attribute "CDS_PART_NAME" "CAP_A_0402V-0.1UF,16V,10%,X7R,A"
					( Origin gPackager )
				)
				( objectStatus "C4G22" )
			)
			( gate "@baseboard_fab2_lib.baseboard_fab2(sch_1):page99_i32"
				( attribute "BOM_COST" "SM_CONTROLLER"
					( Origin gFrontEnd )
				)
				( attribute "CDS_LIB" "dev_discrete"
					( Origin gPackager )
				)
				( attribute "CDS_LOCATION" "C7E2"
					( Origin gPackager )
				)
				( attribute "CDS_SEC" "1"
					( Origin gPackager )
				)
				( attribute "CD_SEC" "1"
					( Origin gFrontEnd )
				)
				( attribute "LOCATION" "C7E2"
					( Origin gFrontEnd )
				)
				( attribute "MATERIAL" "X7R"
					( Origin gFrontEnd )
				)
				( attribute "PACK_TYPE" "0402V"
					( Origin gFrontEnd )
				)
				( attribute "PART_NUMBER" "A36096-030"
					( Origin gFrontEnd )
				)
				( attribute "PHYS_PAGE" "99"
					( Origin gFrontEnd )
				)
				( attribute "ROOM" "MEM"
					( Origin gFrontEnd )
				)
				( attribute "ROT" "0"
					( Origin gFrontEnd )
				)
				( attribute "SEC" "1"
					( Origin gPackager )
				)
				( attribute "SIGNAL_MODEL" "DEFAULT_CAPACITOR_100000pF_2_1"
					( Origin gFrontEnd )
				)
				( attribute "TOLERANCE" "10%"
					( Origin gFrontEnd )
				)
				( attribute "VALUE" "0.1UF"
					( Origin gFrontEnd )
				)
				( attribute "VER" "1"
					( Origin gFrontEnd )
				)
				( attribute "VOLTAGE" "16V"
					( Units "uVoltage" "V" 1.000000)
					( Origin gFrontEnd )
				)
				( attribute "XY" "(1625,3750)"
					( Origin gFrontEnd )
				)
				( attribute "CHIPS_PART_NAME" "CAP_A"
					( Origin gPackager )
				)
				( attribute "CDS_PART_NAME" "CAP_A_0402V-0.1UF,16V,10%,X7R,A"
					( Origin gPackager )
				)
				( objectStatus "C7E2" )
			)
			( gate "@baseboard_fab2_lib.baseboard_fab2(sch_1):page99_i34"
				( attribute "CDS_LIB" "mstr_discrete"
					( Origin gPackager )
				)
				( attribute "CDS_LOCATION" "R3R9"
					( Origin gPackager )
				)
				( attribute "CDS_SEC" "1"
					( Origin gPackager )
				)
				( attribute "LOCATION" "R3R9"
					( Origin gFrontEnd )
				)
				( attribute "MATERIAL" "CHIP"
					( Origin gFrontEnd )
				)
				( attribute "PACK_TYPE" "0402"
					( Origin gFrontEnd )
				)
				( attribute "PART_NUMBER" "G21796-173"
					( Origin gFrontEnd )
				)
				( attribute "PHYS_PAGE" "99"
					( Origin gFrontEnd )
				)
				( attribute "ROOM" "MEM"
					( Origin gFrontEnd )
				)
				( attribute "ROT" "0"
					( Origin gFrontEnd )
				)
				( attribute "SEC" "1"
					( Origin gPackager )
				)
				( attribute "TOLERANCE" "1%"
					( Origin gFrontEnd )
				)
				( attribute "VALUE" "20.0"
					( Origin gFrontEnd )
				)
				( attribute "VER" "1"
					( Origin gFrontEnd )
				)
				( attribute "WATTAGE" "1/16W"
					( Origin gFrontEnd )
				)
				( attribute "XY" "(1600,3250)"
					( Origin gFrontEnd )
				)
				( attribute "CHIPS_PART_NAME" "RES"
					( Origin gPackager )
				)
				( attribute "CDS_PART_NAME" "RES_0402-20.0,1%,1/16W,CHIP,G2A"
					( Origin gPackager )
				)
				( objectStatus "R3R9" )
			)
			( gate "@baseboard_fab2_lib.baseboard_fab2(sch_1):page99_i35"
				( attribute "CDS_LIB" "mstr_discrete"
					( Origin gPackager )
				)
				( attribute "CDS_LOCATION" "R3R8"
					( Origin gPackager )
				)
				( attribute "CDS_SEC" "1"
					( Origin gPackager )
				)
				( attribute "LOCATION" "R3R8"
					( Origin gFrontEnd )
				)
				( attribute "MATERIAL" "CHIP"
					( Origin gFrontEnd )
				)
				( attribute "PACK_TYPE" "0402"
					( Origin gFrontEnd )
				)
				( attribute "PART_NUMBER" "G21796-173"
					( Origin gFrontEnd )
				)
				( attribute "PHYS_PAGE" "99"
					( Origin gFrontEnd )
				)
				( attribute "ROOM" "MEM"
					( Origin gFrontEnd )
				)
				( attribute "ROT" "0"
					( Origin gFrontEnd )
				)
				( attribute "SEC" "1"
					( Origin gPackager )
				)
				( attribute "TOLERANCE" "1%"
					( Origin gFrontEnd )
				)
				( attribute "VALUE" "20.0"
					( Origin gFrontEnd )
				)
				( attribute "VER" "1"
					( Origin gFrontEnd )
				)
				( attribute "WATTAGE" "1/16W"
					( Origin gFrontEnd )
				)
				( attribute "XY" "(1600,3300)"
					( Origin gFrontEnd )
				)
				( attribute "CHIPS_PART_NAME" "RES"
					( Origin gPackager )
				)
				( attribute "CDS_PART_NAME" "RES_0402-20.0,1%,1/16W,CHIP,G2A"
					( Origin gPackager )
				)
				( objectStatus "R3R8" )
			)
			( gate "@baseboard_fab2_lib.baseboard_fab2(sch_1):page99_i41"
				( attribute "BOM_COST" "SM_CONTROLLER"
					( Origin gFrontEnd )
				)
				( attribute "CDS_LIB" "dev_discrete"
					( Origin gPackager )
				)
				( attribute "CDS_LOCATION" "C4G25"
					( Origin gPackager )
				)
				( attribute "CDS_SEC" "1"
					( Origin gPackager )
				)
				( attribute "CD_SEC" "1"
					( Origin gFrontEnd )
				)
				( attribute "LOCATION" "C4G25"
					( Origin gFrontEnd )
				)
				( attribute "MATERIAL" "X7R"
					( Origin gFrontEnd )
				)
				( attribute "PACK_TYPE" "0402V"
					( Origin gFrontEnd )
				)
				( attribute "PART_NUMBER" "A36096-030"
					( Origin gFrontEnd )
				)
				( attribute "PHYS_PAGE" "99"
					( Origin gFrontEnd )
				)
				( attribute "ROOM" "MEM"
					( Origin gFrontEnd )
				)
				( attribute "ROT" "0"
					( Origin gFrontEnd )
				)
				( attribute "SEC" "1"
					( Origin gPackager )
				)
				( attribute "SIGNAL_MODEL" "DEFAULT_CAPACITOR_100000pF_2_1"
					( Origin gFrontEnd )
				)
				( attribute "TOLERANCE" "10%"
					( Origin gFrontEnd )
				)
				( attribute "VALUE" "0.1UF"
					( Origin gFrontEnd )
				)
				( attribute "VER" "1"
					( Origin gFrontEnd )
				)
				( attribute "VOLTAGE" "16V"
					( Units "uVoltage" "V" 1.000000)
					( Origin gFrontEnd )
				)
				( attribute "XY" "(1650,2675)"
					( Origin gFrontEnd )
				)
				( attribute "CHIPS_PART_NAME" "CAP_A"
					( Origin gPackager )
				)
				( attribute "CDS_PART_NAME" "CAP_A_0402V-0.1UF,16V,10%,X7R,A"
					( Origin gPackager )
				)
				( objectStatus "C4G25" )
			)
			( gate "@baseboard_fab2_lib.baseboard_fab2(sch_1):page99_i42"
				( attribute "CDS_LIB" "mstr_discrete"
					( Origin gPackager )
				)
				( attribute "CDS_LOCATION" "R6U13"
					( Origin gPackager )
				)
				( attribute "CDS_SEC" "1"
					( Origin gPackager )
				)
				( attribute "LOCATION" "R6U13"
					( Origin gFrontEnd )
				)
				( attribute "MATERIAL" "CHIP"
					( Origin gFrontEnd )
				)
				( attribute "PACK_TYPE" "0402"
					( Origin gFrontEnd )
				)
				( attribute "PART_NUMBER" "G21796-173"
					( Origin gFrontEnd )
				)
				( attribute "PHYS_PAGE" "99"
					( Origin gFrontEnd )
				)
				( attribute "ROOM" "MEM"
					( Origin gFrontEnd )
				)
				( attribute "ROT" "0"
					( Origin gFrontEnd )
				)
				( attribute "SEC" "1"
					( Origin gPackager )
				)
				( attribute "TOLERANCE" "1%"
					( Origin gFrontEnd )
				)
				( attribute "VALUE" "20.0"
					( Origin gFrontEnd )
				)
				( attribute "VER" "1"
					( Origin gFrontEnd )
				)
				( attribute "WATTAGE" "1/16W"
					( Origin gFrontEnd )
				)
				( attribute "XY" "(1600,2150)"
					( Origin gFrontEnd )
				)
				( attribute "CHIPS_PART_NAME" "RES"
					( Origin gPackager )
				)
				( attribute "CDS_PART_NAME" "RES_0402-20.0,1%,1/16W,CHIP,G2A"
					( Origin gPackager )
				)
				( objectStatus "R6U13" )
			)
			( gate "@baseboard_fab2_lib.baseboard_fab2(sch_1):page225_i307"
				( attribute "BOM_COST" "MEM_VRD_PVDDQ_CD"
					( Origin gFrontEnd )
				)
				( attribute "CDS_LIB" "mstr_discrete"
					( Origin gPackager )
				)
				( attribute "CDS_LOCATION" "C8U11"
					( Origin gPackager )
				)
				( attribute "CDS_SEC" "1"
					( Origin gPackager )
				)
				( attribute "LOCATION" "C8U11"
					( Origin gFrontEnd )
				)
				( attribute "MATERIAL" "X5R"
					( Origin gFrontEnd )
				)
				( attribute "NEW_MATERIAL" "X6S"
					( Origin gFrontEnd )
				)
				( attribute "PACK_TYPE" "0805"
					( Origin gFrontEnd )
				)
				( attribute "PART_NUMBER" "602433-112"
					( Origin gFrontEnd )
				)
				( attribute "PHYS_PAGE" "225"
					( Origin gFrontEnd )
				)
				( attribute "ROOM" "VDDQ_ABC_PWR_VR"
					( Origin gFrontEnd )
				)
				( attribute "ROT" "0"
					( Origin gFrontEnd )
				)
				( attribute "SEC" "1"
					( Origin gFrontEnd )
				)
				( attribute "SEC_TYPE" "0805"
					( Origin gFrontEnd )
				)
				( attribute "TOLERANCE" "20%"
					( Origin gFrontEnd )
				)
				( attribute "VALUE" "100UF"
					( Origin gFrontEnd )
				)
				( attribute "VER" "1"
					( Origin gFrontEnd )
				)
				( attribute "VOLTAGE" "4V"
					( Units "uVoltage" "V" 1.000000)
					( Origin gFrontEnd )
				)
				( attribute "XY" "(3850,2825)"
					( Origin gFrontEnd )
				)
				( attribute "CHIPS_PART_NAME" "CAP"
					( Origin gPackager )
				)
				( attribute "CDS_PART_NAME" "CAP_0805-100UF,4V,20%,X5R,6024A"
					( Origin gPackager )
				)
				( attribute "GROUP" "PWR_MLCC_CAP"
					( Origin gFrontEnd )
				)
				( attribute "NEW_PN" "078.1071T.M002"
					( Origin gFrontEnd )
				)
				( attribute "BOM_SS" "NOPOP"
					( Origin gFrontEnd )
				)
				( objectStatus "C8U11" )
			)
			( gate "@baseboard_fab2_lib.baseboard_fab2(sch_1):page99_i47"
				( attribute "BOM_COST" "SM_CONTROLLER"
					( Origin gFrontEnd )
				)
				( attribute "CDS_LIB" "dev_discrete"
					( Origin gPackager )
				)
				( attribute "CDS_LOCATION" "C3B4"
					( Origin gPackager )
				)
				( attribute "CDS_SEC" "1"
					( Origin gPackager )
				)
				( attribute "CD_SEC" "1"
					( Origin gFrontEnd )
				)
				( attribute "LOCATION" "C3B4"
					( Origin gFrontEnd )
				)
				( attribute "MATERIAL" "X7R"
					( Origin gFrontEnd )
				)
				( attribute "PACK_TYPE" "0402V"
					( Origin gFrontEnd )
				)
				( attribute "PART_NUMBER" "A36096-030"
					( Origin gFrontEnd )
				)
				( attribute "PHYS_PAGE" "99"
					( Origin gFrontEnd )
				)
				( attribute "ROOM" "MEM"
					( Origin gFrontEnd )
				)
				( attribute "ROT" "0"
					( Origin gFrontEnd )
				)
				( attribute "SEC" "1"
					( Origin gPackager )
				)
				( attribute "SIGNAL_MODEL" "DEFAULT_CAPACITOR_100000pF_2_1"
					( Origin gFrontEnd )
				)
				( attribute "TOLERANCE" "10%"
					( Origin gFrontEnd )
				)
				( attribute "VALUE" "0.1UF"
					( Origin gFrontEnd )
				)
				( attribute "VER" "1"
					( Origin gFrontEnd )
				)
				( attribute "VOLTAGE" "16V"
					( Units "uVoltage" "V" 1.000000)
					( Origin gFrontEnd )
				)
				( attribute "XY" "(2250,1525)"
					( Origin gFrontEnd )
				)
				( attribute "CHIPS_PART_NAME" "CAP_A"
					( Origin gPackager )
				)
				( attribute "CDS_PART_NAME" "CAP_A_0402V-0.1UF,16V,10%,X7R,A"
					( Origin gPackager )
				)
				( objectStatus "C3B4" )
			)
			( gate "@baseboard_fab2_lib.baseboard_fab2(sch_1):page99_i53"
				( attribute "BOM_COST" "SM_CONTROLLER"
					( Origin gFrontEnd )
				)
				( attribute "CDS_LIB" "dev_discrete"
					( Origin gPackager )
				)
				( attribute "CDS_LOCATION" "C3B5"
					( Origin gPackager )
				)
				( attribute "CDS_SEC" "1"
					( Origin gPackager )
				)
				( attribute "CD_SEC" "1"
					( Origin gFrontEnd )
				)
				( attribute "LOCATION" "C3B5"
					( Origin gFrontEnd )
				)
				( attribute "MATERIAL" "X7R"
					( Origin gFrontEnd )
				)
				( attribute "PACK_TYPE" "0402V"
					( Origin gFrontEnd )
				)
				( attribute "PART_NUMBER" "A36096-030"
					( Origin gFrontEnd )
				)
				( attribute "PHYS_PAGE" "99"
					( Origin gFrontEnd )
				)
				( attribute "ROOM" "MEM"
					( Origin gFrontEnd )
				)
				( attribute "ROT" "0"
					( Origin gFrontEnd )
				)
				( attribute "SEC" "1"
					( Origin gPackager )
				)
				( attribute "SIGNAL_MODEL" "DEFAULT_CAPACITOR_100000pF_2_1"
					( Origin gFrontEnd )
				)
				( attribute "TOLERANCE" "10%"
					( Origin gFrontEnd )
				)
				( attribute "VALUE" "0.1UF"
					( Origin gFrontEnd )
				)
				( attribute "VER" "1"
					( Origin gFrontEnd )
				)
				( attribute "VOLTAGE" "16V"
					( Units "uVoltage" "V" 1.000000)
					( Origin gFrontEnd )
				)
				( attribute "XY" "(1675,1500)"
					( Origin gFrontEnd )
				)
				( attribute "CHIPS_PART_NAME" "CAP_A"
					( Origin gPackager )
				)
				( attribute "CDS_PART_NAME" "CAP_A_0402V-0.1UF,16V,10%,X7R,A"
					( Origin gPackager )
				)
				( objectStatus "C3B5" )
			)
			( gate "@baseboard_fab2_lib.baseboard_fab2(sch_1):page99_i55"
				( attribute "CDS_LIB" "mstr_discrete"
					( Origin gPackager )
				)
				( attribute "CDS_LOCATION" "R7M5"
					( Origin gPackager )
				)
				( attribute "CDS_SEC" "1"
					( Origin gPackager )
				)
				( attribute "LOCATION" "R7M5"
					( Origin gFrontEnd )
				)
				( attribute "MATERIAL" "CHIP"
					( Origin gFrontEnd )
				)
				( attribute "PACK_TYPE" "0402"
					( Origin gFrontEnd )
				)
				( attribute "PART_NUMBER" "G21796-173"
					( Origin gFrontEnd )
				)
				( attribute "PHYS_PAGE" "99"
					( Origin gFrontEnd )
				)
				( attribute "ROOM" "MEM"
					( Origin gFrontEnd )
				)
				( attribute "ROT" "0"
					( Origin gFrontEnd )
				)
				( attribute "SEC" "1"
					( Origin gPackager )
				)
				( attribute "TOLERANCE" "1%"
					( Origin gFrontEnd )
				)
				( attribute "VALUE" "20.0"
					( Origin gFrontEnd )
				)
				( attribute "VER" "1"
					( Origin gFrontEnd )
				)
				( attribute "WATTAGE" "1/16W"
					( Origin gFrontEnd )
				)
				( attribute "XY" "(1600,900)"
					( Origin gFrontEnd )
				)
				( attribute "CHIPS_PART_NAME" "RES"
					( Origin gPackager )
				)
				( attribute "CDS_PART_NAME" "RES_0402-20.0,1%,1/16W,CHIP,G2A"
					( Origin gPackager )
				)
				( objectStatus "R7M5" )
			)
			( gate "@baseboard_fab2_lib.baseboard_fab2(sch_1):page99_i56"
				( attribute "CDS_LIB" "mstr_discrete"
					( Origin gPackager )
				)
				( attribute "CDS_LOCATION" "R7M4"
					( Origin gPackager )
				)
				( attribute "CDS_SEC" "1"
					( Origin gPackager )
				)
				( attribute "LOCATION" "R7M4"
					( Origin gFrontEnd )
				)
				( attribute "MATERIAL" "CHIP"
					( Origin gFrontEnd )
				)
				( attribute "PACK_TYPE" "0402"
					( Origin gFrontEnd )
				)
				( attribute "PART_NUMBER" "G21796-173"
					( Origin gFrontEnd )
				)
				( attribute "PHYS_PAGE" "99"
					( Origin gFrontEnd )
				)
				( attribute "ROOM" "MEM"
					( Origin gFrontEnd )
				)
				( attribute "ROT" "0"
					( Origin gFrontEnd )
				)
				( attribute "SEC" "1"
					( Origin gPackager )
				)
				( attribute "TOLERANCE" "1%"
					( Origin gFrontEnd )
				)
				( attribute "VALUE" "20.0"
					( Origin gFrontEnd )
				)
				( attribute "VER" "1"
					( Origin gFrontEnd )
				)
				( attribute "WATTAGE" "1/16W"
					( Origin gFrontEnd )
				)
				( attribute "XY" "(1600,950)"
					( Origin gFrontEnd )
				)
				( attribute "CHIPS_PART_NAME" "RES"
					( Origin gPackager )
				)
				( attribute "CDS_PART_NAME" "RES_0402-20.0,1%,1/16W,CHIP,G2A"
					( Origin gPackager )
				)
				( objectStatus "R7M4" )
			)
			( gate "@baseboard_fab2_lib.baseboard_fab2(sch_1):page99_i61"
				( attribute "BOM_COST" "SM_CONTROLLER"
					( Origin gFrontEnd )
				)
				( attribute "CDS_LIB" "mstr_digital"
					( Origin gPackager )
				)
				( attribute "CDS_LOCATION" "U7E1"
					( Origin gPackager )
				)
				( attribute "CDS_SEC" "1"
					( Origin gPackager )
				)
				( attribute "LOCATION" "U7E1"
					( Origin gFrontEnd )
				)
				( attribute "MATERIAL" "IC"
					( Origin gFrontEnd )
				)
				( attribute "PACK_TYPE" "SSOP"
					( Origin gFrontEnd )
				)
				( attribute "PART_NUMBER" "G81764-001"
					( Origin gFrontEnd )
				)
				( attribute "PHYS_PAGE" "99"
					( Origin gFrontEnd )
				)
				( attribute "ROOM" "MEM"
					( Origin gFrontEnd )
				)
				( attribute "ROT" "0"
					( Origin gFrontEnd )
				)
				( attribute "SEC" "1"
					( Origin gPackager )
				)
				( attribute "VER" "1"
					( Origin gFrontEnd )
				)
				( attribute "XY" "(150,3250)"
					( Origin gFrontEnd )
				)
				( attribute "CHIPS_PART_NAME" "PCA9617"
					( Origin gPackager )
				)
				( attribute "CDS_PART_NAME" "PCA9617_SSOP-IC,G81764-001"
					( Origin gPackager )
				)
				( objectStatus "U7E1" )
			)
			( gate "@baseboard_fab2_lib.baseboard_fab2(sch_1):page99_i63"
				( attribute "BOM_COST" "SM_CONTROLLER"
					( Origin gFrontEnd )
				)
				( attribute "CDS_LIB" "mstr_digital"
					( Origin gPackager )
				)
				( attribute "CDS_LOCATION" "U4G1"
					( Origin gPackager )
				)
				( attribute "CDS_SEC" "1"
					( Origin gPackager )
				)
				( attribute "LOCATION" "U4G1"
					( Origin gFrontEnd )
				)
				( attribute "MATERIAL" "IC"
					( Origin gFrontEnd )
				)
				( attribute "PACK_TYPE" "SSOP"
					( Origin gFrontEnd )
				)
				( attribute "PART_NUMBER" "G81764-001"
					( Origin gFrontEnd )
				)
				( attribute "PHYS_PAGE" "99"
					( Origin gFrontEnd )
				)
				( attribute "ROOM" "MEM"
					( Origin gFrontEnd )
				)
				( attribute "ROT" "0"
					( Origin gFrontEnd )
				)
				( attribute "SEC" "1"
					( Origin gPackager )
				)
				( attribute "VER" "1"
					( Origin gFrontEnd )
				)
				( attribute "XY" "(150,2100)"
					( Origin gFrontEnd )
				)
				( attribute "CHIPS_PART_NAME" "PCA9617"
					( Origin gPackager )
				)
				( attribute "CDS_PART_NAME" "PCA9617_SSOP-IC,G81764-001"
					( Origin gPackager )
				)
				( objectStatus "U4G1" )
			)
			( gate "@baseboard_fab2_lib.baseboard_fab2(sch_1):page99_i65"
				( attribute "BOM_COST" "SM_CONTROLLER"
					( Origin gFrontEnd )
				)
				( attribute "CDS_LIB" "mstr_discrete"
					( Origin gPackager )
				)
				( attribute "CDS_LOCATION" "R3R13"
					( Origin gPackager )
				)
				( attribute "CDS_SEC" "1"
					( Origin gPackager )
				)
				( attribute "CD_SEC" "1"
					( Origin gFrontEnd )
				)
				( attribute "LOCATION" "R3R13"
					( Origin gFrontEnd )
				)
				( attribute "MATERIAL" "CHIP"
					( Origin gFrontEnd )
				)
				( attribute "PACK_TYPE" "0402"
					( Origin gFrontEnd )
				)
				( attribute "PART_NUMBER" "G21796-294"
					( Origin gFrontEnd )
				)
				( attribute "PHYS_PAGE" "99"
					( Origin gFrontEnd )
				)
				( attribute "ROOM" "MEM"
					( Origin gFrontEnd )
				)
				( attribute "ROT" "2"
					( Origin gFrontEnd )
				)
				( attribute "SEC" "1"
					( Origin gPackager )
				)
				( attribute "SIGNAL_MODEL" "DEFAULT_RESISTOR_750OHM_2_1"
					( Origin gFrontEnd )
				)
				( attribute "TOLERANCE" "1.0%"
					( Origin gFrontEnd )
				)
				( attribute "VALUE" "240"
					( Origin gFrontEnd )
				)
				( attribute "VER" "2"
					( Origin gFrontEnd )
				)
				( attribute "WATTAGE" "1/16W"
					( Origin gFrontEnd )
				)
				( attribute "XY" "(-675,3600)"
					( Origin gFrontEnd )
				)
				( attribute "CHIPS_PART_NAME" "RES"
					( Origin gPackager )
				)
				( attribute "CDS_PART_NAME" "RES_0402-240,1.0%,1/16W,CHIP,GA"
					( Origin gPackager )
				)
				( objectStatus "R3R13" )
			)
			( gate "@baseboard_fab2_lib.baseboard_fab2(sch_1):page99_i67"
				( attribute "BOM_COST" "SM_CONTROLLER"
					( Origin gFrontEnd )
				)
				( attribute "CDS_LIB" "mstr_discrete"
					( Origin gPackager )
				)
				( attribute "CDS_LOCATION" "R3P60"
					( Origin gPackager )
				)
				( attribute "CDS_SEC" "1"
					( Origin gPackager )
				)
				( attribute "CD_SEC" "1"
					( Origin gFrontEnd )
				)
				( attribute "LOCATION" "R3P60"
					( Origin gFrontEnd )
				)
				( attribute "MATERIAL" "CHIP"
					( Origin gFrontEnd )
				)
				( attribute "PACK_TYPE" "0402"
					( Origin gFrontEnd )
				)
				( attribute "PART_NUMBER" "G21796-294"
					( Origin gFrontEnd )
				)
				( attribute "PHYS_PAGE" "99"
					( Origin gFrontEnd )
				)
				( attribute "ROOM" "MEM"
					( Origin gFrontEnd )
				)
				( attribute "ROT" "2"
					( Origin gFrontEnd )
				)
				( attribute "SEC" "1"
					( Origin gPackager )
				)
				( attribute "SIGNAL_MODEL" "DEFAULT_RESISTOR_750OHM_2_1"
					( Origin gFrontEnd )
				)
				( attribute "TOLERANCE" "1.0%"
					( Origin gFrontEnd )
				)
				( attribute "VALUE" "240"
					( Origin gFrontEnd )
				)
				( attribute "VER" "2"
					( Origin gFrontEnd )
				)
				( attribute "WATTAGE" "1/16W"
					( Origin gFrontEnd )
				)
				( attribute "XY" "(-1050,3600)"
					( Origin gFrontEnd )
				)
				( attribute "CHIPS_PART_NAME" "RES"
					( Origin gPackager )
				)
				( attribute "CDS_PART_NAME" "RES_0402-240,1.0%,1/16W,CHIP,GA"
					( Origin gPackager )
				)
				( objectStatus "R3P60" )
			)
			( gate "@baseboard_fab2_lib.baseboard_fab2(sch_1):page99_i70"
				( attribute "BOM_COST" "SM_CONTROLLER"
					( Origin gFrontEnd )
				)
				( attribute "CDS_LIB" "mstr_discrete"
					( Origin gPackager )
				)
				( attribute "CDS_LOCATION" "R6T1"
					( Origin gPackager )
				)
				( attribute "CDS_SEC" "1"
					( Origin gPackager )
				)
				( attribute "CD_SEC" "1"
					( Origin gFrontEnd )
				)
				( attribute "LOCATION" "R6T1"
					( Origin gFrontEnd )
				)
				( attribute "MATERIAL" "CHIP"
					( Origin gFrontEnd )
				)
				( attribute "PACK_TYPE" "0402"
					( Origin gFrontEnd )
				)
				( attribute "PART_NUMBER" "G21796-294"
					( Origin gFrontEnd )
				)
				( attribute "PHYS_PAGE" "99"
					( Origin gFrontEnd )
				)
				( attribute "ROOM" "MEM"
					( Origin gFrontEnd )
				)
				( attribute "ROT" "2"
					( Origin gFrontEnd )
				)
				( attribute "SEC" "1"
					( Origin gPackager )
				)
				( attribute "SIGNAL_MODEL" "DEFAULT_RESISTOR_750OHM_2_1"
					( Origin gFrontEnd )
				)
				( attribute "TOLERANCE" "1.0%"
					( Origin gFrontEnd )
				)
				( attribute "VALUE" "240"
					( Origin gFrontEnd )
				)
				( attribute "VER" "2"
					( Origin gFrontEnd )
				)
				( attribute "WATTAGE" "1/16W"
					( Origin gFrontEnd )
				)
				( attribute "XY" "(-700,2450)"
					( Origin gFrontEnd )
				)
				( attribute "CHIPS_PART_NAME" "RES"
					( Origin gPackager )
				)
				( attribute "CDS_PART_NAME" "RES_0402-240,1.0%,1/16W,CHIP,GA"
					( Origin gPackager )
				)
				( objectStatus "R6T1" )
			)
			( gate "@baseboard_fab2_lib.baseboard_fab2(sch_1):page99_i72"
				( attribute "BOM_COST" "SM_CONTROLLER"
					( Origin gFrontEnd )
				)
				( attribute "CDS_LIB" "mstr_discrete"
					( Origin gPackager )
				)
				( attribute "CDS_LOCATION" "R6T2"
					( Origin gPackager )
				)
				( attribute "CDS_SEC" "1"
					( Origin gPackager )
				)
				( attribute "CD_SEC" "1"
					( Origin gFrontEnd )
				)
				( attribute "LOCATION" "R6T2"
					( Origin gFrontEnd )
				)
				( attribute "MATERIAL" "CHIP"
					( Origin gFrontEnd )
				)
				( attribute "PACK_TYPE" "0402"
					( Origin gFrontEnd )
				)
				( attribute "PART_NUMBER" "G21796-294"
					( Origin gFrontEnd )
				)
				( attribute "PHYS_PAGE" "99"
					( Origin gFrontEnd )
				)
				( attribute "ROOM" "MEM"
					( Origin gFrontEnd )
				)
				( attribute "ROT" "2"
					( Origin gFrontEnd )
				)
				( attribute "SEC" "1"
					( Origin gPackager )
				)
				( attribute "SIGNAL_MODEL" "DEFAULT_RESISTOR_750OHM_2_1"
					( Origin gFrontEnd )
				)
				( attribute "TOLERANCE" "1.0%"
					( Origin gFrontEnd )
				)
				( attribute "VALUE" "240"
					( Origin gFrontEnd )
				)
				( attribute "VER" "2"
					( Origin gFrontEnd )
				)
				( attribute "WATTAGE" "1/16W"
					( Origin gFrontEnd )
				)
				( attribute "XY" "(-1075,2450)"
					( Origin gFrontEnd )
				)
				( attribute "CHIPS_PART_NAME" "RES"
					( Origin gPackager )
				)
				( attribute "CDS_PART_NAME" "RES_0402-240,1.0%,1/16W,CHIP,GA"
					( Origin gPackager )
				)
				( objectStatus "R6T2" )
			)
			( gate "@baseboard_fab2_lib.baseboard_fab2(sch_1):page99_i75"
				( attribute "BOM_COST" "SM_CONTROLLER"
					( Origin gFrontEnd )
				)
				( attribute "CDS_LIB" "mstr_digital"
					( Origin gPackager )
				)
				( attribute "CDS_LOCATION" "U3B1"
					( Origin gPackager )
				)
				( attribute "CDS_SEC" "1"
					( Origin gPackager )
				)
				( attribute "LOCATION" "U3B1"
					( Origin gFrontEnd )
				)
				( attribute "MATERIAL" "IC"
					( Origin gFrontEnd )
				)
				( attribute "PACK_TYPE" "SSOP"
					( Origin gFrontEnd )
				)
				( attribute "PART_NUMBER" "G81764-001"
					( Origin gFrontEnd )
				)
				( attribute "PHYS_PAGE" "99"
					( Origin gFrontEnd )
				)
				( attribute "ROOM" "MEM"
					( Origin gFrontEnd )
				)
				( attribute "ROT" "0"
					( Origin gFrontEnd )
				)
				( attribute "SEC" "1"
					( Origin gPackager )
				)
				( attribute "VER" "1"
					( Origin gFrontEnd )
				)
				( attribute "XY" "(150,900)"
					( Origin gFrontEnd )
				)
				( attribute "CHIPS_PART_NAME" "PCA9617"
					( Origin gPackager )
				)
				( attribute "CDS_PART_NAME" "PCA9617_SSOP-IC,G81764-001"
					( Origin gPackager )
				)
				( objectStatus "U3B1" )
			)
			( gate "@baseboard_fab2_lib.baseboard_fab2(sch_1):page99_i77"
				( attribute "BOM_COST" "SM_CONTROLLER"
					( Origin gFrontEnd )
				)
				( attribute "CDS_LIB" "mstr_discrete"
					( Origin gPackager )
				)
				( attribute "CDS_LOCATION" "R7M7"
					( Origin gPackager )
				)
				( attribute "CDS_SEC" "1"
					( Origin gPackager )
				)
				( attribute "CD_SEC" "1"
					( Origin gFrontEnd )
				)
				( attribute "LOCATION" "R7M7"
					( Origin gFrontEnd )
				)
				( attribute "MATERIAL" "CHIP"
					( Origin gFrontEnd )
				)
				( attribute "PACK_TYPE" "0402"
					( Origin gFrontEnd )
				)
				( attribute "PART_NUMBER" "G21796-294"
					( Origin gFrontEnd )
				)
				( attribute "PHYS_PAGE" "99"
					( Origin gFrontEnd )
				)
				( attribute "ROOM" "MEM"
					( Origin gFrontEnd )
				)
				( attribute "ROT" "2"
					( Origin gFrontEnd )
				)
				( attribute "SEC" "1"
					( Origin gPackager )
				)
				( attribute "SIGNAL_MODEL" "DEFAULT_RESISTOR_750OHM_2_1"
					( Origin gFrontEnd )
				)
				( attribute "TOLERANCE" "1.0%"
					( Origin gFrontEnd )
				)
				( attribute "VALUE" "240"
					( Origin gFrontEnd )
				)
				( attribute "VER" "2"
					( Origin gFrontEnd )
				)
				( attribute "WATTAGE" "1/16W"
					( Origin gFrontEnd )
				)
				( attribute "XY" "(-725,1250)"
					( Origin gFrontEnd )
				)
				( attribute "CHIPS_PART_NAME" "RES"
					( Origin gPackager )
				)
				( attribute "CDS_PART_NAME" "RES_0402-240,1.0%,1/16W,CHIP,GA"
					( Origin gPackager )
				)
				( objectStatus "R7M7" )
			)
			( gate "@baseboard_fab2_lib.baseboard_fab2(sch_1):page99_i79"
				( attribute "BOM_COST" "SM_CONTROLLER"
					( Origin gFrontEnd )
				)
				( attribute "CDS_LIB" "mstr_discrete"
					( Origin gPackager )
				)
				( attribute "CDS_LOCATION" "R7M2"
					( Origin gPackager )
				)
				( attribute "CDS_SEC" "1"
					( Origin gPackager )
				)
				( attribute "CD_SEC" "1"
					( Origin gFrontEnd )
				)
				( attribute "LOCATION" "R7M2"
					( Origin gFrontEnd )
				)
				( attribute "MATERIAL" "CHIP"
					( Origin gFrontEnd )
				)
				( attribute "PACK_TYPE" "0402"
					( Origin gFrontEnd )
				)
				( attribute "PART_NUMBER" "G21796-294"
					( Origin gFrontEnd )
				)
				( attribute "PHYS_PAGE" "99"
					( Origin gFrontEnd )
				)
				( attribute "ROOM" "MEM"
					( Origin gFrontEnd )
				)
				( attribute "ROT" "2"
					( Origin gFrontEnd )
				)
				( attribute "SEC" "1"
					( Origin gPackager )
				)
				( attribute "SIGNAL_MODEL" "DEFAULT_RESISTOR_750OHM_2_1"
					( Origin gFrontEnd )
				)
				( attribute "TOLERANCE" "1.0%"
					( Origin gFrontEnd )
				)
				( attribute "VALUE" "240"
					( Origin gFrontEnd )
				)
				( attribute "VER" "2"
					( Origin gFrontEnd )
				)
				( attribute "WATTAGE" "1/16W"
					( Origin gFrontEnd )
				)
				( attribute "XY" "(-1100,1250)"
					( Origin gFrontEnd )
				)
				( attribute "CHIPS_PART_NAME" "RES"
					( Origin gPackager )
				)
				( attribute "CDS_PART_NAME" "RES_0402-240,1.0%,1/16W,CHIP,GA"
					( Origin gPackager )
				)
				( objectStatus "R7M2" )
			)
			( gate "@baseboard_fab2_lib.baseboard_fab2(sch_1):page99_i83"
				( attribute "BOM_COST" "SM_CONTROLLER"
					( Origin gFrontEnd )
				)
				( attribute "CDS_LIB" "mstr_discrete"
					( Origin gPackager )
				)
				( attribute "CDS_LOCATION" "R4T3"
					( Origin gPackager )
				)
				( attribute "CDS_SEC" "1"
					( Origin gPackager )
				)
				( attribute "LOCATION" "R4T3"
					( Origin gFrontEnd )
				)
				( attribute "MATERIAL" "CHIP"
					( Origin gFrontEnd )
				)
				( attribute "PACK_TYPE" "0402"
					( Origin gFrontEnd )
				)
				( attribute "PART_NUMBER" "G21796-066"
					( Origin gFrontEnd )
				)
				( attribute "PHYS_PAGE" "99"
					( Origin gFrontEnd )
				)
				( attribute "ROOM" "MEM"
					( Origin gFrontEnd )
				)
				( attribute "ROT" "0"
					( Origin gFrontEnd )
				)
				( attribute "SEC" "1"
					( Origin gPackager )
				)
				( attribute "TOLERANCE" "1%"
					( Origin gFrontEnd )
				)
				( attribute "VALUE" "10.0"
					( Origin gFrontEnd )
				)
				( attribute "VER" "1"
					( Origin gFrontEnd )
				)
				( attribute "WATTAGE" "1/16W"
					( Origin gFrontEnd )
				)
				( attribute "XY" "(-1500,4350)"
					( Origin gFrontEnd )
				)
				( attribute "CHIPS_PART_NAME" "RES"
					( Origin gPackager )
				)
				( attribute "CDS_PART_NAME" "RES_0402-10.0,1%,1/16W,CHIP,G2A"
					( Origin gPackager )
				)
				( objectStatus "R4T3" )
			)
			( gate "@baseboard_fab2_lib.baseboard_fab2(sch_1):page99_i88"
				( attribute "BOM_COST" "SM_CONTROLLER"
					( Origin gFrontEnd )
				)
				( attribute "CDS_LIB" "mstr_discrete"
					( Origin gPackager )
				)
				( attribute "CDS_LOCATION" "R3R7"
					( Origin gPackager )
				)
				( attribute "CDS_SEC" "1"
					( Origin gPackager )
				)
				( attribute "LOCATION" "R3R7"
					( Origin gFrontEnd )
				)
				( attribute "MATERIAL" "CHIP"
					( Origin gFrontEnd )
				)
				( attribute "PACK_TYPE" "0402"
					( Origin gFrontEnd )
				)
				( attribute "PART_NUMBER" "G21796-066"
					( Origin gFrontEnd )
				)
				( attribute "PHYS_PAGE" "99"
					( Origin gFrontEnd )
				)
				( attribute "ROOM" "MEM"
					( Origin gFrontEnd )
				)
				( attribute "ROT" "0"
					( Origin gFrontEnd )
				)
				( attribute "SEC" "1"
					( Origin gPackager )
				)
				( attribute "TOLERANCE" "1%"
					( Origin gFrontEnd )
				)
				( attribute "VALUE" "10.0"
					( Origin gFrontEnd )
				)
				( attribute "VER" "1"
					( Origin gFrontEnd )
				)
				( attribute "WATTAGE" "1/16W"
					( Origin gFrontEnd )
				)
				( attribute "XY" "(-1575,3300)"
					( Origin gFrontEnd )
				)
				( attribute "CHIPS_PART_NAME" "RES"
					( Origin gPackager )
				)
				( attribute "CDS_PART_NAME" "RES_0402-10.0,1%,1/16W,CHIP,G2A"
					( Origin gPackager )
				)
				( objectStatus "R3R7" )
			)
			( gate "@baseboard_fab2_lib.baseboard_fab2(sch_1):page99_i92"
				( attribute "BOM_COST" "SM_CONTROLLER"
					( Origin gFrontEnd )
				)
				( attribute "CDS_LIB" "mstr_discrete"
					( Origin gPackager )
				)
				( attribute "CDS_LOCATION" "R6T3"
					( Origin gPackager )
				)
				( attribute "CDS_SEC" "1"
					( Origin gPackager )
				)
				( attribute "LOCATION" "R6T3"
					( Origin gFrontEnd )
				)
				( attribute "MATERIAL" "CHIP"
					( Origin gFrontEnd )
				)
				( attribute "PACK_TYPE" "0402"
					( Origin gFrontEnd )
				)
				( attribute "PART_NUMBER" "G21796-066"
					( Origin gFrontEnd )
				)
				( attribute "PHYS_PAGE" "99"
					( Origin gFrontEnd )
				)
				( attribute "ROOM" "MEM"
					( Origin gFrontEnd )
				)
				( attribute "ROT" "0"
					( Origin gFrontEnd )
				)
				( attribute "SEC" "1"
					( Origin gPackager )
				)
				( attribute "TOLERANCE" "1%"
					( Origin gFrontEnd )
				)
				( attribute "VALUE" "10.0"
					( Origin gFrontEnd )
				)
				( attribute "VER" "1"
					( Origin gFrontEnd )
				)
				( attribute "WATTAGE" "1/16W"
					( Origin gFrontEnd )
				)
				( attribute "XY" "(-1475,2150)"
					( Origin gFrontEnd )
				)
				( attribute "CHIPS_PART_NAME" "RES"
					( Origin gPackager )
				)
				( attribute "CDS_PART_NAME" "RES_0402-10.0,1%,1/16W,CHIP,G2A"
					( Origin gPackager )
				)
				( objectStatus "R6T3" )
			)
			( gate "@baseboard_fab2_lib.baseboard_fab2(sch_1):page99_i98"
				( attribute "BOM_COST" "SM_CONTROLLER"
					( Origin gFrontEnd )
				)
				( attribute "CDS_LIB" "mstr_discrete"
					( Origin gPackager )
				)
				( attribute "CDS_LOCATION" "R7M3"
					( Origin gPackager )
				)
				( attribute "CDS_SEC" "1"
					( Origin gPackager )
				)
				( attribute "LOCATION" "R7M3"
					( Origin gFrontEnd )
				)
				( attribute "MATERIAL" "CHIP"
					( Origin gFrontEnd )
				)
				( attribute "PACK_TYPE" "0402"
					( Origin gFrontEnd )
				)
				( attribute "PART_NUMBER" "G21796-066"
					( Origin gFrontEnd )
				)
				( attribute "PHYS_PAGE" "99"
					( Origin gFrontEnd )
				)
				( attribute "ROOM" "MEM"
					( Origin gFrontEnd )
				)
				( attribute "ROT" "0"
					( Origin gFrontEnd )
				)
				( attribute "SEC" "1"
					( Origin gPackager )
				)
				( attribute "TOLERANCE" "1%"
					( Origin gFrontEnd )
				)
				( attribute "VALUE" "10.0"
					( Origin gFrontEnd )
				)
				( attribute "VER" "1"
					( Origin gFrontEnd )
				)
				( attribute "WATTAGE" "1/16W"
					( Origin gFrontEnd )
				)
				( attribute "XY" "(-1575,950)"
					( Origin gFrontEnd )
				)
				( attribute "CHIPS_PART_NAME" "RES"
					( Origin gPackager )
				)
				( attribute "CDS_PART_NAME" "RES_0402-10.0,1%,1/16W,CHIP,G2A"
					( Origin gPackager )
				)
				( objectStatus "R7M3" )
			)
			( gate "@baseboard_fab2_lib.baseboard_fab2(sch_1):page99_i101"
				( attribute "BOM_COST" "SM_CONTROLLER"
					( Origin gFrontEnd )
				)
				( attribute "CDS_LIB" "mstr_discrete"
					( Origin gPackager )
				)
				( attribute "CDS_LOCATION" "R3R12"
					( Origin gPackager )
				)
				( attribute "CDS_SEC" "1"
					( Origin gPackager )
				)
				( attribute "LOCATION" "R3R12"
					( Origin gFrontEnd )
				)
				( attribute "MATERIAL" "CHIP"
					( Origin gFrontEnd )
				)
				( attribute "PACK_TYPE" "0402"
					( Origin gFrontEnd )
				)
				( attribute "PART_NUMBER" "G21796-235"
					( Origin gFrontEnd )
				)
				( attribute "PHYS_PAGE" "99"
					( Origin gFrontEnd )
				)
				( attribute "ROOM" "MEM"
					( Origin gFrontEnd )
				)
				( attribute "ROT" "0"
					( Origin gFrontEnd )
				)
				( attribute "SEC" "1"
					( Origin gFrontEnd )
				)
				( attribute "SEC_TYPE" "0402"
					( Origin gFrontEnd )
				)
				( attribute "TOLERANCE" "1.0%"
					( Origin gFrontEnd )
				)
				( attribute "VALUE" "665"
					( Origin gFrontEnd )
				)
				( attribute "VER" "2"
					( Origin gFrontEnd )
				)
				( attribute "WATTAGE" "1/16W"
					( Origin gFrontEnd )
				)
				( attribute "XY" "(1275,3600)"
					( Origin gFrontEnd )
				)
				( attribute "CHIPS_PART_NAME" "RES"
					( Origin gPackager )
				)
				( attribute "CDS_PART_NAME" "RES_0402-665,1.0%,1/16W,CHIP,GA"
					( Origin gPackager )
				)
				( objectStatus "R3R12" )
			)
			( gate "@baseboard_fab2_lib.baseboard_fab2(sch_1):page99_i103"
				( attribute "BOM_COST" "SM_CONTROLLER"
					( Origin gFrontEnd )
				)
				( attribute "CDS_LIB" "mstr_discrete"
					( Origin gPackager )
				)
				( attribute "CDS_LOCATION" "R3R5"
					( Origin gPackager )
				)
				( attribute "CDS_SEC" "1"
					( Origin gPackager )
				)
				( attribute "LOCATION" "R3R5"
					( Origin gFrontEnd )
				)
				( attribute "MATERIAL" "CHIP"
					( Origin gFrontEnd )
				)
				( attribute "PACK_TYPE" "0402"
					( Origin gFrontEnd )
				)
				( attribute "PART_NUMBER" "G21796-235"
					( Origin gFrontEnd )
				)
				( attribute "PHYS_PAGE" "99"
					( Origin gFrontEnd )
				)
				( attribute "ROOM" "MEM"
					( Origin gFrontEnd )
				)
				( attribute "ROT" "0"
					( Origin gFrontEnd )
				)
				( attribute "SEC" "1"
					( Origin gFrontEnd )
				)
				( attribute "SEC_TYPE" "0402"
					( Origin gFrontEnd )
				)
				( attribute "TOLERANCE" "1.0%"
					( Origin gFrontEnd )
				)
				( attribute "VALUE" "665"
					( Origin gFrontEnd )
				)
				( attribute "VER" "2"
					( Origin gFrontEnd )
				)
				( attribute "WATTAGE" "1/16W"
					( Origin gFrontEnd )
				)
				( attribute "XY" "(925,3600)"
					( Origin gFrontEnd )
				)
				( attribute "CHIPS_PART_NAME" "RES"
					( Origin gPackager )
				)
				( attribute "CDS_PART_NAME" "RES_0402-665,1.0%,1/16W,CHIP,GA"
					( Origin gPackager )
				)
				( objectStatus "R3R5" )
			)
			( gate "@baseboard_fab2_lib.baseboard_fab2(sch_1):page99_i104"
				( attribute "BOM_COST" "SM_CONTROLLER"
					( Origin gFrontEnd )
				)
				( attribute "CDS_LIB" "mstr_discrete"
					( Origin gPackager )
				)
				( attribute "CDS_LOCATION" "R6U18"
					( Origin gPackager )
				)
				( attribute "CDS_SEC" "1"
					( Origin gPackager )
				)
				( attribute "LOCATION" "R6U18"
					( Origin gFrontEnd )
				)
				( attribute "MATERIAL" "CHIP"
					( Origin gFrontEnd )
				)
				( attribute "PACK_TYPE" "0402"
					( Origin gFrontEnd )
				)
				( attribute "PART_NUMBER" "G21796-235"
					( Origin gFrontEnd )
				)
				( attribute "PHYS_PAGE" "99"
					( Origin gFrontEnd )
				)
				( attribute "ROOM" "MEM"
					( Origin gFrontEnd )
				)
				( attribute "ROT" "0"
					( Origin gFrontEnd )
				)
				( attribute "SEC" "1"
					( Origin gFrontEnd )
				)
				( attribute "SEC_TYPE" "0402"
					( Origin gFrontEnd )
				)
				( attribute "TOLERANCE" "1.0%"
					( Origin gFrontEnd )
				)
				( attribute "VALUE" "665"
					( Origin gFrontEnd )
				)
				( attribute "VER" "2"
					( Origin gFrontEnd )
				)
				( attribute "WATTAGE" "1/16W"
					( Origin gFrontEnd )
				)
				( attribute "XY" "(1225,2450)"
					( Origin gFrontEnd )
				)
				( attribute "CHIPS_PART_NAME" "RES"
					( Origin gPackager )
				)
				( attribute "CDS_PART_NAME" "RES_0402-665,1.0%,1/16W,CHIP,GA"
					( Origin gPackager )
				)
				( objectStatus "R6U18" )
			)
			( gate "@baseboard_fab2_lib.baseboard_fab2(sch_1):page99_i106"
				( attribute "BOM_COST" "SM_CONTROLLER"
					( Origin gFrontEnd )
				)
				( attribute "CDS_LIB" "mstr_discrete"
					( Origin gPackager )
				)
				( attribute "CDS_LOCATION" "R6U17"
					( Origin gPackager )
				)
				( attribute "CDS_SEC" "1"
					( Origin gPackager )
				)
				( attribute "LOCATION" "R6U17"
					( Origin gFrontEnd )
				)
				( attribute "MATERIAL" "CHIP"
					( Origin gFrontEnd )
				)
				( attribute "PACK_TYPE" "0402"
					( Origin gFrontEnd )
				)
				( attribute "PART_NUMBER" "G21796-235"
					( Origin gFrontEnd )
				)
				( attribute "PHYS_PAGE" "99"
					( Origin gFrontEnd )
				)
				( attribute "ROOM" "MEM"
					( Origin gFrontEnd )
				)
				( attribute "ROT" "0"
					( Origin gFrontEnd )
				)
				( attribute "SEC" "1"
					( Origin gFrontEnd )
				)
				( attribute "SEC_TYPE" "0402"
					( Origin gFrontEnd )
				)
				( attribute "TOLERANCE" "1.0%"
					( Origin gFrontEnd )
				)
				( attribute "VALUE" "665"
					( Origin gFrontEnd )
				)
				( attribute "VER" "2"
					( Origin gFrontEnd )
				)
				( attribute "WATTAGE" "1/16W"
					( Origin gFrontEnd )
				)
				( attribute "XY" "(875,2450)"
					( Origin gFrontEnd )
				)
				( attribute "CHIPS_PART_NAME" "RES"
					( Origin gPackager )
				)
				( attribute "CDS_PART_NAME" "RES_0402-665,1.0%,1/16W,CHIP,GA"
					( Origin gPackager )
				)
				( objectStatus "R6U17" )
			)
			( gate "@baseboard_fab2_lib.baseboard_fab2(sch_1):page99_i107"
				( attribute "BOM_COST" "SM_CONTROLLER"
					( Origin gFrontEnd )
				)
				( attribute "CDS_LIB" "mstr_discrete"
					( Origin gPackager )
				)
				( attribute "CDS_LOCATION" "R7M6"
					( Origin gPackager )
				)
				( attribute "CDS_SEC" "1"
					( Origin gPackager )
				)
				( attribute "LOCATION" "R7M6"
					( Origin gFrontEnd )
				)
				( attribute "MATERIAL" "CHIP"
					( Origin gFrontEnd )
				)
				( attribute "PACK_TYPE" "0402"
					( Origin gFrontEnd )
				)
				( attribute "PART_NUMBER" "G21796-235"
					( Origin gFrontEnd )
				)
				( attribute "PHYS_PAGE" "99"
					( Origin gFrontEnd )
				)
				( attribute "ROOM" "MEM"
					( Origin gFrontEnd )
				)
				( attribute "ROT" "0"
					( Origin gFrontEnd )
				)
				( attribute "SEC" "1"
					( Origin gFrontEnd )
				)
				( attribute "SEC_TYPE" "0402"
					( Origin gFrontEnd )
				)
				( attribute "TOLERANCE" "1.0%"
					( Origin gFrontEnd )
				)
				( attribute "VALUE" "665"
					( Origin gFrontEnd )
				)
				( attribute "VER" "2"
					( Origin gFrontEnd )
				)
				( attribute "WATTAGE" "1/16W"
					( Origin gFrontEnd )
				)
				( attribute "XY" "(1225,1250)"
					( Origin gFrontEnd )
				)
				( attribute "CHIPS_PART_NAME" "RES"
					( Origin gPackager )
				)
				( attribute "CDS_PART_NAME" "RES_0402-665,1.0%,1/16W,CHIP,GA"
					( Origin gPackager )
				)
				( objectStatus "R7M6" )
			)
			( gate "@baseboard_fab2_lib.baseboard_fab2(sch_1):page99_i109"
				( attribute "BOM_COST" "SM_CONTROLLER"
					( Origin gFrontEnd )
				)
				( attribute "CDS_LIB" "mstr_discrete"
					( Origin gPackager )
				)
				( attribute "CDS_LOCATION" "R7M1"
					( Origin gPackager )
				)
				( attribute "CDS_SEC" "1"
					( Origin gPackager )
				)
				( attribute "LOCATION" "R7M1"
					( Origin gFrontEnd )
				)
				( attribute "MATERIAL" "CHIP"
					( Origin gFrontEnd )
				)
				( attribute "PACK_TYPE" "0402"
					( Origin gFrontEnd )
				)
				( attribute "PART_NUMBER" "G21796-235"
					( Origin gFrontEnd )
				)
				( attribute "PHYS_PAGE" "99"
					( Origin gFrontEnd )
				)
				( attribute "ROOM" "MEM"
					( Origin gFrontEnd )
				)
				( attribute "ROT" "0"
					( Origin gFrontEnd )
				)
				( attribute "SEC" "1"
					( Origin gFrontEnd )
				)
				( attribute "SEC_TYPE" "0402"
					( Origin gFrontEnd )
				)
				( attribute "TOLERANCE" "1.0%"
					( Origin gFrontEnd )
				)
				( attribute "VALUE" "665"
					( Origin gFrontEnd )
				)
				( attribute "VER" "2"
					( Origin gFrontEnd )
				)
				( attribute "WATTAGE" "1/16W"
					( Origin gFrontEnd )
				)
				( attribute "XY" "(875,1250)"
					( Origin gFrontEnd )
				)
				( attribute "CHIPS_PART_NAME" "RES"
					( Origin gPackager )
				)
				( attribute "CDS_PART_NAME" "RES_0402-665,1.0%,1/16W,CHIP,GA"
					( Origin gPackager )
				)
				( objectStatus "R7M1" )
			)
			( gate "@baseboard_fab2_lib.baseboard_fab2(sch_1):page99_i110"
				( attribute "BOM_COST" "SM_CONTROLLER"
					( Origin gFrontEnd )
				)
				( attribute "CDS_LIB" "mstr_discrete"
					( Origin gPackager )
				)
				( attribute "CDS_LOCATION" "R3R14"
					( Origin gPackager )
				)
				( attribute "CDS_SEC" "1"
					( Origin gPackager )
				)
				( attribute "LOCATION" "R3R14"
					( Origin gFrontEnd )
				)
				( attribute "MATERIAL" "CHIP"
					( Origin gFrontEnd )
				)
				( attribute "PACK_TYPE" "0402"
					( Origin gFrontEnd )
				)
				( attribute "PART_NUMBER" "G21796-066"
					( Origin gFrontEnd )
				)
				( attribute "PHYS_PAGE" "99"
					( Origin gFrontEnd )
				)
				( attribute "ROOM" "MEM"
					( Origin gFrontEnd )
				)
				( attribute "ROT" "0"
					( Origin gFrontEnd )
				)
				( attribute "SEC" "1"
					( Origin gPackager )
				)
				( attribute "TOLERANCE" "1%"
					( Origin gFrontEnd )
				)
				( attribute "VALUE" "10.0"
					( Origin gFrontEnd )
				)
				( attribute "VER" "1"
					( Origin gFrontEnd )
				)
				( attribute "WATTAGE" "1/16W"
					( Origin gFrontEnd )
				)
				( attribute "XY" "(-1175,3250)"
					( Origin gFrontEnd )
				)
				( attribute "CHIPS_PART_NAME" "RES"
					( Origin gPackager )
				)
				( attribute "CDS_PART_NAME" "RES_0402-10.0,1%,1/16W,CHIP,G2A"
					( Origin gPackager )
				)
				( objectStatus "R3R14" )
			)
			( gate "@baseboard_fab2_lib.baseboard_fab2(sch_1):page99_i111"
				( attribute "BOM_COST" "SM_CONTROLLER"
					( Origin gFrontEnd )
				)
				( attribute "CDS_LIB" "mstr_discrete"
					( Origin gPackager )
				)
				( attribute "CDS_LOCATION" "R6T4"
					( Origin gPackager )
				)
				( attribute "CDS_SEC" "1"
					( Origin gPackager )
				)
				( attribute "LOCATION" "R6T4"
					( Origin gFrontEnd )
				)
				( attribute "MATERIAL" "CHIP"
					( Origin gFrontEnd )
				)
				( attribute "PACK_TYPE" "0402"
					( Origin gFrontEnd )
				)
				( attribute "PART_NUMBER" "G21796-066"
					( Origin gFrontEnd )
				)
				( attribute "PHYS_PAGE" "99"
					( Origin gFrontEnd )
				)
				( attribute "ROOM" "MEM"
					( Origin gFrontEnd )
				)
				( attribute "ROT" "0"
					( Origin gFrontEnd )
				)
				( attribute "SEC" "1"
					( Origin gPackager )
				)
				( attribute "TOLERANCE" "1%"
					( Origin gFrontEnd )
				)
				( attribute "VALUE" "10.0"
					( Origin gFrontEnd )
				)
				( attribute "VER" "1"
					( Origin gFrontEnd )
				)
				( attribute "WATTAGE" "1/16W"
					( Origin gFrontEnd )
				)
				( attribute "XY" "(-1100,2100)"
					( Origin gFrontEnd )
				)
				( attribute "CHIPS_PART_NAME" "RES"
					( Origin gPackager )
				)
				( attribute "CDS_PART_NAME" "RES_0402-10.0,1%,1/16W,CHIP,G2A"
					( Origin gPackager )
				)
				( objectStatus "R6T4" )
			)
			( gate "@baseboard_fab2_lib.baseboard_fab2(sch_1):page99_i112"
				( attribute "BOM_COST" "SM_CONTROLLER"
					( Origin gFrontEnd )
				)
				( attribute "CDS_LIB" "mstr_discrete"
					( Origin gPackager )
				)
				( attribute "CDS_LOCATION" "R7M8"
					( Origin gPackager )
				)
				( attribute "CDS_SEC" "1"
					( Origin gPackager )
				)
				( attribute "LOCATION" "R7M8"
					( Origin gFrontEnd )
				)
				( attribute "MATERIAL" "CHIP"
					( Origin gFrontEnd )
				)
				( attribute "PACK_TYPE" "0402"
					( Origin gFrontEnd )
				)
				( attribute "PART_NUMBER" "G21796-066"
					( Origin gFrontEnd )
				)
				( attribute "PHYS_PAGE" "99"
					( Origin gFrontEnd )
				)
				( attribute "ROOM" "MEM"
					( Origin gFrontEnd )
				)
				( attribute "ROT" "0"
					( Origin gFrontEnd )
				)
				( attribute "SEC" "1"
					( Origin gPackager )
				)
				( attribute "TOLERANCE" "1%"
					( Origin gFrontEnd )
				)
				( attribute "VALUE" "10.0"
					( Origin gFrontEnd )
				)
				( attribute "VER" "1"
					( Origin gFrontEnd )
				)
				( attribute "WATTAGE" "1/16W"
					( Origin gFrontEnd )
				)
				( attribute "XY" "(-1200,900)"
					( Origin gFrontEnd )
				)
				( attribute "CHIPS_PART_NAME" "RES"
					( Origin gPackager )
				)
				( attribute "CDS_PART_NAME" "RES_0402-10.0,1%,1/16W,CHIP,G2A"
					( Origin gPackager )
				)
				( objectStatus "R7M8" )
			)
			( gate "@baseboard_fab2_lib.baseboard_fab2(sch_1):page100_i2"
				( attribute "BOM_COST" "SM_CONTROLLER"
					( Origin gFrontEnd )
				)
				( attribute "CDS_LIB" "mstr_discrete"
					( Origin gPackager )
				)
				( attribute "CDS_LOCATION" "R1F6"
					( Origin gPackager )
				)
				( attribute "CDS_SEC" "1"
					( Origin gPackager )
				)
				( attribute "LOCATION" "R1F6"
					( Origin gFrontEnd )
				)
				( attribute "MATERIAL" "CHIP"
					( Origin gFrontEnd )
				)
				( attribute "PACK_TYPE" "0402"
					( Origin gFrontEnd )
				)
				( attribute "PART_NUMBER" "G21796-026"
					( Origin gFrontEnd )
				)
				( attribute "PHYS_PAGE" "100"
					( Origin gFrontEnd )
				)
				( attribute "ROOM" "MEM"
					( Origin gFrontEnd )
				)
				( attribute "ROT" "2"
					( Origin gFrontEnd )
				)
				( attribute "SEC" "1"
					( Origin gFrontEnd )
				)
				( attribute "SEC_TYPE" "0402"
					( Origin gFrontEnd )
				)
				( attribute "TOLERANCE" "1%"
					( Origin gFrontEnd )
				)
				( attribute "VALUE" "1.00K"
					( Origin gFrontEnd )
				)
				( attribute "VER" "2"
					( Origin gFrontEnd )
				)
				( attribute "WATTAGE" "1/16W"
					( Origin gFrontEnd )
				)
				( attribute "XY" "(-1825,3300)"
					( Origin gFrontEnd )
				)
				( attribute "CHIPS_PART_NAME" "RES"
					( Origin gPackager )
				)
				( attribute "CDS_PART_NAME" "RES_0402-1.00K,1%,1/16W,CHIP,GA"
					( Origin gPackager )
				)
				( objectStatus "R1F6" )
			)
			( gate "@baseboard_fab2_lib.baseboard_fab2(sch_1):page100_i4"
				( attribute "BOM_COST" "PROC_SOCKET"
					( Origin gFrontEnd )
				)
				( attribute "CDS_LIB" "mstr_discrete"
					( Origin gPackager )
				)
				( attribute "CDS_LOCATION" "R9L11"
					( Origin gPackager )
				)
				( attribute "CDS_SEC" "1"
					( Origin gPackager )
				)
				( attribute "LOCATION" "R9L11"
					( Origin gFrontEnd )
				)
				( attribute "MATERIAL" "CHIP"
					( Origin gFrontEnd )
				)
				( attribute "PACK_TYPE" "0402"
					( Origin gFrontEnd )
				)
				( attribute "PART_NUMBER" "G21796-026"
					( Origin gFrontEnd )
				)
				( attribute "PHYS_PAGE" "100"
					( Origin gFrontEnd )
				)
				( attribute "ROOM" "PROC"
					( Origin gFrontEnd )
				)
				( attribute "ROT" "2"
					( Origin gFrontEnd )
				)
				( attribute "SEC" "1"
					( Origin gFrontEnd )
				)
				( attribute "SEC_TYPE" "0402"
					( Origin gFrontEnd )
				)
				( attribute "TOLERANCE" "1%"
					( Origin gFrontEnd )
				)
				( attribute "VALUE" "1.00K"
					( Origin gFrontEnd )
				)
				( attribute "VER" "2"
					( Origin gFrontEnd )
				)
				( attribute "WATTAGE" "1/16W"
					( Origin gFrontEnd )
				)
				( attribute "XY" "(-1825,1625)"
					( Origin gFrontEnd )
				)
				( attribute "CHIPS_PART_NAME" "RES"
					( Origin gPackager )
				)
				( attribute "CDS_PART_NAME" "RES_0402-1.00K,1%,1/16W,CHIP,GA"
					( Origin gPackager )
				)
				( objectStatus "R9L11" )
			)
			( gate "@baseboard_fab2_lib.baseboard_fab2(sch_1):page100_i6"
				( attribute "BOM_COST" "SM_CONTROLLER"
					( Origin gFrontEnd )
				)
				( attribute "CDS_LIB" "mstr_discrete"
					( Origin gPackager )
				)
				( attribute "CDS_LOCATION" "R1F5"
					( Origin gPackager )
				)
				( attribute "CDS_SEC" "1"
					( Origin gPackager )
				)
				( attribute "LOCATION" "R1F5"
					( Origin gFrontEnd )
				)
				( attribute "MATERIAL" "CHIP"
					( Origin gFrontEnd )
				)
				( attribute "PACK_TYPE" "0402"
					( Origin gFrontEnd )
				)
				( attribute "PART_NUMBER" "G21796-026"
					( Origin gFrontEnd )
				)
				( attribute "PHYS_PAGE" "100"
					( Origin gFrontEnd )
				)
				( attribute "ROOM" "MEM"
					( Origin gFrontEnd )
				)
				( attribute "ROT" "2"
					( Origin gFrontEnd )
				)
				( attribute "SEC" "1"
					( Origin gFrontEnd )
				)
				( attribute "SEC_TYPE" "0402"
					( Origin gFrontEnd )
				)
				( attribute "TOLERANCE" "1%"
					( Origin gFrontEnd )
				)
				( attribute "VALUE" "1.00K"
					( Origin gFrontEnd )
				)
				( attribute "VER" "2"
					( Origin gFrontEnd )
				)
				( attribute "WATTAGE" "1/16W"
					( Origin gFrontEnd )
				)
				( attribute "XY" "(-1900,3950)"
					( Origin gFrontEnd )
				)
				( attribute "CHIPS_PART_NAME" "RES"
					( Origin gPackager )
				)
				( attribute "CDS_PART_NAME" "RES_0402-1.00K,1%,1/16W,CHIP,GA"
					( Origin gPackager )
				)
				( objectStatus "R1F5" )
			)
			( gate "@baseboard_fab2_lib.baseboard_fab2(sch_1):page100_i7"
				( attribute "BOM_COST" "PROC_SOCKET"
					( Origin gFrontEnd )
				)
				( attribute "CDS_LIB" "mstr_discrete"
					( Origin gPackager )
				)
				( attribute "CDS_LOCATION" "R1F4"
					( Origin gPackager )
				)
				( attribute "CDS_SEC" "1"
					( Origin gPackager )
				)
				( attribute "LOCATION" "R1F4"
					( Origin gFrontEnd )
				)
				( attribute "MATERIAL" "CHIP"
					( Origin gFrontEnd )
				)
				( attribute "PACK_TYPE" "0402"
					( Origin gFrontEnd )
				)
				( attribute "PART_NUMBER" "G21796-274"
					( Origin gFrontEnd )
				)
				( attribute "PHYS_PAGE" "100"
					( Origin gFrontEnd )
				)
				( attribute "ROOM" "PROC"
					( Origin gFrontEnd )
				)
				( attribute "ROT" "0"
					( Origin gFrontEnd )
				)
				( attribute "SEC" "1"
					( Origin gFrontEnd )
				)
				( attribute "SEC_TYPE" "0402"
					( Origin gFrontEnd )
				)
				( attribute "TOLERANCE" "1.0%"
					( Origin gFrontEnd )
				)
				( attribute "VALUE" "2"
					( Origin gFrontEnd )
				)
				( attribute "VER" "1"
					( Origin gFrontEnd )
				)
				( attribute "WATTAGE" "1/16W"
					( Origin gFrontEnd )
				)
				( attribute "XY" "(-2125,3625)"
					( Origin gFrontEnd )
				)
				( attribute "CHIPS_PART_NAME" "RES"
					( Origin gPackager )
				)
				( attribute "CDS_PART_NAME" "RES_0402-2,1.0%,1/16W,CHIP,G21A"
					( Origin gPackager )
				)
				( objectStatus "R1F4" )
			)
			( gate "@baseboard_fab2_lib.baseboard_fab2(sch_1):page100_i8"
				( attribute "BOM_COST" "PROC_SOCKET"
					( Origin gFrontEnd )
				)
				( attribute "CDS_LIB" "dev_discrete"
					( Origin gPackager )
				)
				( attribute "CDS_LOCATION" "C1F19"
					( Origin gPackager )
				)
				( attribute "CDS_SEC" "1"
					( Origin gPackager )
				)
				( attribute "LOCATION" "C1F19"
					( Origin gFrontEnd )
				)
				( attribute "MATERIAL" "X7R"
					( Origin gFrontEnd )
				)
				( attribute "PACK_TYPE" "0402V"
					( Origin gFrontEnd )
				)
				( attribute "PART_NUMBER" "A36096-045"
					( Origin gFrontEnd )
				)
				( attribute "PHYS_PAGE" "100"
					( Origin gFrontEnd )
				)
				( attribute "ROOM" "PROC"
					( Origin gFrontEnd )
				)
				( attribute "ROT" "0"
					( Origin gFrontEnd )
				)
				( attribute "SEC" "1"
					( Origin gFrontEnd )
				)
				( attribute "SEC_TYPE" "0402V"
					( Origin gFrontEnd )
				)
				( attribute "TOLERANCE" "10%"
					( Origin gFrontEnd )
				)
				( attribute "VALUE" "0.01UF"
					( Origin gFrontEnd )
				)
				( attribute "VER" "1"
					( Origin gFrontEnd )
				)
				( attribute "VOLTAGE" "25V"
					( Units "uVoltage" "V" 1.000000)
					( Origin gFrontEnd )
				)
				( attribute "XY" "(-2350,3325)"
					( Origin gFrontEnd )
				)
				( attribute "CHIPS_PART_NAME" "CAP_A"
					( Origin gPackager )
				)
				( attribute "CDS_PART_NAME" "CAP_A_0402V-0.01UF,25V,10%,X7RA"
					( Origin gPackager )
				)
				( objectStatus "C1F19" )
			)
			( gate "@baseboard_fab2_lib.baseboard_fab2(sch_1):page100_i11"
				( attribute "BOM_COST" "SM_CONTROLLER"
					( Origin gFrontEnd )
				)
				( attribute "CDS_LIB" "mstr_discrete"
					( Origin gPackager )
				)
				( attribute "CDS_LOCATION" "R9M1"
					( Origin gPackager )
				)
				( attribute "CDS_SEC" "1"
					( Origin gPackager )
				)
				( attribute "LOCATION" "R9M1"
					( Origin gFrontEnd )
				)
				( attribute "MATERIAL" "CHIP"
					( Origin gFrontEnd )
				)
				( attribute "PACK_TYPE" "0402"
					( Origin gFrontEnd )
				)
				( attribute "PART_NUMBER" "G21796-026"
					( Origin gFrontEnd )
				)
				( attribute "PHYS_PAGE" "100"
					( Origin gFrontEnd )
				)
				( attribute "ROOM" "MEM"
					( Origin gFrontEnd )
				)
				( attribute "ROT" "2"
					( Origin gFrontEnd )
				)
				( attribute "SEC" "1"
					( Origin gFrontEnd )
				)
				( attribute "SEC_TYPE" "0402"
					( Origin gFrontEnd )
				)
				( attribute "TOLERANCE" "1%"
					( Origin gFrontEnd )
				)
				( attribute "VALUE" "1.00K"
					( Origin gFrontEnd )
				)
				( attribute "VER" "2"
					( Origin gFrontEnd )
				)
				( attribute "WATTAGE" "1/16W"
					( Origin gFrontEnd )
				)
				( attribute "XY" "(-1900,2275)"
					( Origin gFrontEnd )
				)
				( attribute "CHIPS_PART_NAME" "RES"
					( Origin gPackager )
				)
				( attribute "CDS_PART_NAME" "RES_0402-1.00K,1%,1/16W,CHIP,GA"
					( Origin gPackager )
				)
				( objectStatus "R9M1" )
			)
			( gate "@baseboard_fab2_lib.baseboard_fab2(sch_1):page100_i13"
				( attribute "BOM_COST" "PROC_SOCKET"
					( Origin gFrontEnd )
				)
				( attribute "CDS_LIB" "mstr_discrete"
					( Origin gPackager )
				)
				( attribute "CDS_LOCATION" "R9M2"
					( Origin gPackager )
				)
				( attribute "CDS_SEC" "1"
					( Origin gPackager )
				)
				( attribute "LOCATION" "R9M2"
					( Origin gFrontEnd )
				)
				( attribute "MATERIAL" "CHIP"
					( Origin gFrontEnd )
				)
				( attribute "PACK_TYPE" "0402"
					( Origin gFrontEnd )
				)
				( attribute "PART_NUMBER" "G21796-274"
					( Origin gFrontEnd )
				)
				( attribute "PHYS_PAGE" "100"
					( Origin gFrontEnd )
				)
				( attribute "ROOM" "PROC"
					( Origin gFrontEnd )
				)
				( attribute "ROT" "0"
					( Origin gFrontEnd )
				)
				( attribute "SEC" "1"
					( Origin gFrontEnd )
				)
				( attribute "SEC_TYPE" "0402"
					( Origin gFrontEnd )
				)
				( attribute "TOLERANCE" "1.0%"
					( Origin gFrontEnd )
				)
				( attribute "VALUE" "2"
					( Origin gFrontEnd )
				)
				( attribute "VER" "1"
					( Origin gFrontEnd )
				)
				( attribute "WATTAGE" "1/16W"
					( Origin gFrontEnd )
				)
				( attribute "XY" "(-2125,1950)"
					( Origin gFrontEnd )
				)
				( attribute "CHIPS_PART_NAME" "RES"
					( Origin gPackager )
				)
				( attribute "CDS_PART_NAME" "RES_0402-2,1.0%,1/16W,CHIP,G21A"
					( Origin gPackager )
				)
				( objectStatus "R9M2" )
			)
			( gate "@baseboard_fab2_lib.baseboard_fab2(sch_1):page100_i15"
				( attribute "BOM_COST" "SM_CONTROLLER"
					( Origin gFrontEnd )
				)
				( attribute "CDS_LIB" "dev_discrete"
					( Origin gPackager )
				)
				( attribute "CDS_LOCATION" "C9M2"
					( Origin gPackager )
				)
				( attribute "CDS_SEC" "1"
					( Origin gPackager )
				)
				( attribute "LOCATION" "C9M2"
					( Origin gFrontEnd )
				)
				( attribute "MATERIAL" "X7R"
					( Origin gFrontEnd )
				)
				( attribute "PACK_TYPE" "0402V"
					( Origin gFrontEnd )
				)
				( attribute "PART_NUMBER" "A36096-045"
					( Origin gFrontEnd )
				)
				( attribute "PHYS_PAGE" "100"
					( Origin gFrontEnd )
				)
				( attribute "ROOM" "MEM"
					( Origin gFrontEnd )
				)
				( attribute "ROT" "0"
					( Origin gFrontEnd )
				)
				( attribute "SEC" "1"
					( Origin gFrontEnd )
				)
				( attribute "SEC_TYPE" "0402V"
					( Origin gFrontEnd )
				)
				( attribute "TOLERANCE" "10%"
					( Origin gFrontEnd )
				)
				( attribute "VALUE" "0.01UF"
					( Origin gFrontEnd )
				)
				( attribute "VER" "1"
					( Origin gFrontEnd )
				)
				( attribute "VOLTAGE" "25V"
					( Units "uVoltage" "V" 1.000000)
					( Origin gFrontEnd )
				)
				( attribute "XY" "(-2350,1650)"
					( Origin gFrontEnd )
				)
				( attribute "CHIPS_PART_NAME" "CAP_A"
					( Origin gPackager )
				)
				( attribute "CDS_PART_NAME" "CAP_A_0402V-0.01UF,25V,10%,X7RA"
					( Origin gPackager )
				)
				( objectStatus "C9M2" )
			)
			( gate "@baseboard_fab2_lib.baseboard_fab2(sch_1):page100_i19"
				( attribute "BOM_COST" "SM_CONTROLLER"
					( Origin gFrontEnd )
				)
				( attribute "CDS_LIB" "mstr_discrete"
					( Origin gPackager )
				)
				( attribute "CDS_LOCATION" "R1G2"
					( Origin gPackager )
				)
				( attribute "CDS_SEC" "1"
					( Origin gPackager )
				)
				( attribute "LOCATION" "R1G2"
					( Origin gFrontEnd )
				)
				( attribute "MATERIAL" "CHIP"
					( Origin gFrontEnd )
				)
				( attribute "PACK_TYPE" "0402"
					( Origin gFrontEnd )
				)
				( attribute "PART_NUMBER" "G21796-026"
					( Origin gFrontEnd )
				)
				( attribute "PHYS_PAGE" "100"
					( Origin gFrontEnd )
				)
				( attribute "ROOM" "MEM"
					( Origin gFrontEnd )
				)
				( attribute "ROT" "2"
					( Origin gFrontEnd )
				)
				( attribute "SEC" "1"
					( Origin gFrontEnd )
				)
				( attribute "SEC_TYPE" "0402"
					( Origin gFrontEnd )
				)
				( attribute "TOLERANCE" "1%"
					( Origin gFrontEnd )
				)
				( attribute "VALUE" "1.00K"
					( Origin gFrontEnd )
				)
				( attribute "VER" "2"
					( Origin gFrontEnd )
				)
				( attribute "WATTAGE" "1/16W"
					( Origin gFrontEnd )
				)
				( attribute "XY" "(450,3950)"
					( Origin gFrontEnd )
				)
				( attribute "CHIPS_PART_NAME" "RES"
					( Origin gPackager )
				)
				( attribute "CDS_PART_NAME" "RES_0402-1.00K,1%,1/16W,CHIP,GA"
					( Origin gPackager )
				)
				( objectStatus "R1G2" )
			)
			( gate "@baseboard_fab2_lib.baseboard_fab2(sch_1):page100_i20"
				( attribute "BOM_COST" "SM_CONTROLLER"
					( Origin gFrontEnd )
				)
				( attribute "CDS_LIB" "mstr_discrete"
					( Origin gPackager )
				)
				( attribute "CDS_LOCATION" "R1G3"
					( Origin gPackager )
				)
				( attribute "CDS_SEC" "1"
					( Origin gPackager )
				)
				( attribute "LOCATION" "R1G3"
					( Origin gFrontEnd )
				)
				( attribute "MATERIAL" "CHIP"
					( Origin gFrontEnd )
				)
				( attribute "PACK_TYPE" "0402"
					( Origin gFrontEnd )
				)
				( attribute "PART_NUMBER" "G21796-026"
					( Origin gFrontEnd )
				)
				( attribute "PHYS_PAGE" "100"
					( Origin gFrontEnd )
				)
				( attribute "ROOM" "MEM"
					( Origin gFrontEnd )
				)
				( attribute "ROT" "2"
					( Origin gFrontEnd )
				)
				( attribute "SEC" "1"
					( Origin gFrontEnd )
				)
				( attribute "SEC_TYPE" "0402"
					( Origin gFrontEnd )
				)
				( attribute "TOLERANCE" "1%"
					( Origin gFrontEnd )
				)
				( attribute "VALUE" "1.00K"
					( Origin gFrontEnd )
				)
				( attribute "VER" "2"
					( Origin gFrontEnd )
				)
				( attribute "WATTAGE" "1/16W"
					( Origin gFrontEnd )
				)
				( attribute "XY" "(525,3300)"
					( Origin gFrontEnd )
				)
				( attribute "CHIPS_PART_NAME" "RES"
					( Origin gPackager )
				)
				( attribute "CDS_PART_NAME" "RES_0402-1.00K,1%,1/16W,CHIP,GA"
					( Origin gPackager )
				)
				( objectStatus "R1G3" )
			)
			( gate "@baseboard_fab2_lib.baseboard_fab2(sch_1):page100_i22"
				( attribute "BOM_COST" "SM_CONTROLLER"
					( Origin gFrontEnd )
				)
				( attribute "CDS_LIB" "mstr_discrete"
					( Origin gPackager )
				)
				( attribute "CDS_LOCATION" "R9L7"
					( Origin gPackager )
				)
				( attribute "CDS_SEC" "1"
					( Origin gPackager )
				)
				( attribute "LOCATION" "R9L7"
					( Origin gFrontEnd )
				)
				( attribute "MATERIAL" "CHIP"
					( Origin gFrontEnd )
				)
				( attribute "PACK_TYPE" "0402"
					( Origin gFrontEnd )
				)
				( attribute "PART_NUMBER" "G21796-026"
					( Origin gFrontEnd )
				)
				( attribute "PHYS_PAGE" "100"
					( Origin gFrontEnd )
				)
				( attribute "ROOM" "MEM"
					( Origin gFrontEnd )
				)
				( attribute "ROT" "2"
					( Origin gFrontEnd )
				)
				( attribute "SEC" "1"
					( Origin gFrontEnd )
				)
				( attribute "SEC_TYPE" "0402"
					( Origin gFrontEnd )
				)
				( attribute "TOLERANCE" "1%"
					( Origin gFrontEnd )
				)
				( attribute "VALUE" "1.00K"
					( Origin gFrontEnd )
				)
				( attribute "VER" "2"
					( Origin gFrontEnd )
				)
				( attribute "WATTAGE" "1/16W"
					( Origin gFrontEnd )
				)
				( attribute "XY" "(450,2275)"
					( Origin gFrontEnd )
				)
				( attribute "CHIPS_PART_NAME" "RES"
					( Origin gPackager )
				)
				( attribute "CDS_PART_NAME" "RES_0402-1.00K,1%,1/16W,CHIP,GA"
					( Origin gPackager )
				)
				( objectStatus "R9L7" )
			)
			( gate "@baseboard_fab2_lib.baseboard_fab2(sch_1):page100_i24"
				( attribute "BOM_COST" "PROC_SOCKET"
					( Origin gFrontEnd )
				)
				( attribute "CDS_LIB" "mstr_discrete"
					( Origin gPackager )
				)
				( attribute "CDS_LOCATION" "R9L6"
					( Origin gPackager )
				)
				( attribute "CDS_SEC" "1"
					( Origin gPackager )
				)
				( attribute "LOCATION" "R9L6"
					( Origin gFrontEnd )
				)
				( attribute "MATERIAL" "CHIP"
					( Origin gFrontEnd )
				)
				( attribute "PACK_TYPE" "0402"
					( Origin gFrontEnd )
				)
				( attribute "PART_NUMBER" "G21796-026"
					( Origin gFrontEnd )
				)
				( attribute "PHYS_PAGE" "100"
					( Origin gFrontEnd )
				)
				( attribute "ROOM" "PROC"
					( Origin gFrontEnd )
				)
				( attribute "ROT" "2"
					( Origin gFrontEnd )
				)
				( attribute "SEC" "1"
					( Origin gFrontEnd )
				)
				( attribute "SEC_TYPE" "0402"
					( Origin gFrontEnd )
				)
				( attribute "TOLERANCE" "1%"
					( Origin gFrontEnd )
				)
				( attribute "VALUE" "1.00K"
					( Origin gFrontEnd )
				)
				( attribute "VER" "2"
					( Origin gFrontEnd )
				)
				( attribute "WATTAGE" "1/16W"
					( Origin gFrontEnd )
				)
				( attribute "XY" "(525,1625)"
					( Origin gFrontEnd )
				)
				( attribute "CHIPS_PART_NAME" "RES"
					( Origin gPackager )
				)
				( attribute "CDS_PART_NAME" "RES_0402-1.00K,1%,1/16W,CHIP,GA"
					( Origin gPackager )
				)
				( objectStatus "R9L6" )
			)
			( gate "@baseboard_fab2_lib.baseboard_fab2(sch_1):page100_i25"
				( attribute "BOM_COST" "PROC_SOCKET"
					( Origin gFrontEnd )
				)
				( attribute "CDS_LIB" "mstr_discrete"
					( Origin gPackager )
				)
				( attribute "CDS_LOCATION" "R1G1"
					( Origin gPackager )
				)
				( attribute "CDS_SEC" "1"
					( Origin gPackager )
				)
				( attribute "LOCATION" "R1G1"
					( Origin gFrontEnd )
				)
				( attribute "MATERIAL" "CHIP"
					( Origin gFrontEnd )
				)
				( attribute "PACK_TYPE" "0402"
					( Origin gFrontEnd )
				)
				( attribute "PART_NUMBER" "G21796-274"
					( Origin gFrontEnd )
				)
				( attribute "PHYS_PAGE" "100"
					( Origin gFrontEnd )
				)
				( attribute "ROOM" "PROC"
					( Origin gFrontEnd )
				)
				( attribute "ROT" "0"
					( Origin gFrontEnd )
				)
				( attribute "SEC" "1"
					( Origin gFrontEnd )
				)
				( attribute "SEC_TYPE" "0402"
					( Origin gFrontEnd )
				)
				( attribute "TOLERANCE" "1.0%"
					( Origin gFrontEnd )
				)
				( attribute "VALUE" "2"
					( Origin gFrontEnd )
				)
				( attribute "VER" "1"
					( Origin gFrontEnd )
				)
				( attribute "WATTAGE" "1/16W"
					( Origin gFrontEnd )
				)
				( attribute "XY" "(225,3625)"
					( Origin gFrontEnd )
				)
				( attribute "CHIPS_PART_NAME" "RES"
					( Origin gPackager )
				)
				( attribute "CDS_PART_NAME" "RES_0402-2,1.0%,1/16W,CHIP,G21A"
					( Origin gPackager )
				)
				( objectStatus "R1G1" )
			)
			( gate "@baseboard_fab2_lib.baseboard_fab2(sch_1):page100_i26"
				( attribute "BOM_COST" "PROC_SOCKET"
					( Origin gFrontEnd )
				)
				( attribute "CDS_LIB" "dev_discrete"
					( Origin gPackager )
				)
				( attribute "CDS_LOCATION" "C1G8"
					( Origin gPackager )
				)
				( attribute "CDS_SEC" "1"
					( Origin gPackager )
				)
				( attribute "LOCATION" "C1G8"
					( Origin gFrontEnd )
				)
				( attribute "MATERIAL" "X7R"
					( Origin gFrontEnd )
				)
				( attribute "PACK_TYPE" "0402V"
					( Origin gFrontEnd )
				)
				( attribute "PART_NUMBER" "A36096-045"
					( Origin gFrontEnd )
				)
				( attribute "PHYS_PAGE" "100"
					( Origin gFrontEnd )
				)
				( attribute "ROOM" "PROC"
					( Origin gFrontEnd )
				)
				( attribute "ROT" "0"
					( Origin gFrontEnd )
				)
				( attribute "SEC" "1"
					( Origin gFrontEnd )
				)
				( attribute "SEC_TYPE" "0402V"
					( Origin gFrontEnd )
				)
				( attribute "TOLERANCE" "10%"
					( Origin gFrontEnd )
				)
				( attribute "VALUE" "0.01UF"
					( Origin gFrontEnd )
				)
				( attribute "VER" "1"
					( Origin gFrontEnd )
				)
				( attribute "VOLTAGE" "25V"
					( Units "uVoltage" "V" 1.000000)
					( Origin gFrontEnd )
				)
				( attribute "XY" "(0,3325)"
					( Origin gFrontEnd )
				)
				( attribute "CHIPS_PART_NAME" "CAP_A"
					( Origin gPackager )
				)
				( attribute "CDS_PART_NAME" "CAP_A_0402V-0.01UF,25V,10%,X7RA"
					( Origin gPackager )
				)
				( objectStatus "C1G8" )
			)
			( gate "@baseboard_fab2_lib.baseboard_fab2(sch_1):page100_i29"
				( attribute "BOM_COST" "PROC_SOCKET"
					( Origin gFrontEnd )
				)
				( attribute "CDS_LIB" "mstr_discrete"
					( Origin gPackager )
				)
				( attribute "CDS_LOCATION" "R9L8"
					( Origin gPackager )
				)
				( attribute "CDS_SEC" "1"
					( Origin gPackager )
				)
				( attribute "LOCATION" "R9L8"
					( Origin gFrontEnd )
				)
				( attribute "MATERIAL" "CHIP"
					( Origin gFrontEnd )
				)
				( attribute "PACK_TYPE" "0402"
					( Origin gFrontEnd )
				)
				( attribute "PART_NUMBER" "G21796-274"
					( Origin gFrontEnd )
				)
				( attribute "PHYS_PAGE" "100"
					( Origin gFrontEnd )
				)
				( attribute "ROOM" "PROC"
					( Origin gFrontEnd )
				)
				( attribute "ROT" "0"
					( Origin gFrontEnd )
				)
				( attribute "SEC" "1"
					( Origin gFrontEnd )
				)
				( attribute "SEC_TYPE" "0402"
					( Origin gFrontEnd )
				)
				( attribute "TOLERANCE" "1.0%"
					( Origin gFrontEnd )
				)
				( attribute "VALUE" "2"
					( Origin gFrontEnd )
				)
				( attribute "VER" "1"
					( Origin gFrontEnd )
				)
				( attribute "WATTAGE" "1/16W"
					( Origin gFrontEnd )
				)
				( attribute "XY" "(225,1950)"
					( Origin gFrontEnd )
				)
				( attribute "CHIPS_PART_NAME" "RES"
					( Origin gPackager )
				)
				( attribute "CDS_PART_NAME" "RES_0402-2,1.0%,1/16W,CHIP,G21A"
					( Origin gPackager )
				)
				( objectStatus "R9L8" )
			)
			( gate "@baseboard_fab2_lib.baseboard_fab2(sch_1):page100_i30"
				( attribute "BOM_COST" "SM_CONTROLLER"
					( Origin gFrontEnd )
				)
				( attribute "CDS_LIB" "dev_discrete"
					( Origin gPackager )
				)
				( attribute "CDS_LOCATION" "C9L8"
					( Origin gPackager )
				)
				( attribute "CDS_SEC" "1"
					( Origin gPackager )
				)
				( attribute "LOCATION" "C9L8"
					( Origin gFrontEnd )
				)
				( attribute "MATERIAL" "X7R"
					( Origin gFrontEnd )
				)
				( attribute "PACK_TYPE" "0402V"
					( Origin gFrontEnd )
				)
				( attribute "PART_NUMBER" "A36096-045"
					( Origin gFrontEnd )
				)
				( attribute "PHYS_PAGE" "100"
					( Origin gFrontEnd )
				)
				( attribute "ROOM" "MEM"
					( Origin gFrontEnd )
				)
				( attribute "ROT" "0"
					( Origin gFrontEnd )
				)
				( attribute "SEC" "1"
					( Origin gFrontEnd )
				)
				( attribute "SEC_TYPE" "0402V"
					( Origin gFrontEnd )
				)
				( attribute "TOLERANCE" "10%"
					( Origin gFrontEnd )
				)
				( attribute "VALUE" "0.01UF"
					( Origin gFrontEnd )
				)
				( attribute "VER" "1"
					( Origin gFrontEnd )
				)
				( attribute "VOLTAGE" "25V"
					( Units "uVoltage" "V" 1.000000)
					( Origin gFrontEnd )
				)
				( attribute "XY" "(0,1650)"
					( Origin gFrontEnd )
				)
				( attribute "CHIPS_PART_NAME" "CAP_A"
					( Origin gPackager )
				)
				( attribute "CDS_PART_NAME" "CAP_A_0402V-0.01UF,25V,10%,X7RA"
					( Origin gPackager )
				)
				( objectStatus "C9L8" )
			)
			( gate "@baseboard_fab2_lib.baseboard_fab2(sch_1):page100_i35"
				( attribute "BOM_COST" "SM_CONTROLLER"
					( Origin gFrontEnd )
				)
				( attribute "CDS_LIB" "mstr_discrete"
					( Origin gPackager )
				)
				( attribute "CDS_LOCATION" "R1G15"
					( Origin gPackager )
				)
				( attribute "CDS_SEC" "1"
					( Origin gPackager )
				)
				( attribute "LOCATION" "R1G15"
					( Origin gFrontEnd )
				)
				( attribute "MATERIAL" "CHIP"
					( Origin gFrontEnd )
				)
				( attribute "PACK_TYPE" "0402"
					( Origin gFrontEnd )
				)
				( attribute "PART_NUMBER" "G21796-026"
					( Origin gFrontEnd )
				)
				( attribute "PHYS_PAGE" "100"
					( Origin gFrontEnd )
				)
				( attribute "ROOM" "MEM"
					( Origin gFrontEnd )
				)
				( attribute "ROT" "2"
					( Origin gFrontEnd )
				)
				( attribute "SEC" "1"
					( Origin gFrontEnd )
				)
				( attribute "SEC_TYPE" "0402"
					( Origin gFrontEnd )
				)
				( attribute "TOLERANCE" "1%"
					( Origin gFrontEnd )
				)
				( attribute "VALUE" "1.00K"
					( Origin gFrontEnd )
				)
				( attribute "VER" "2"
					( Origin gFrontEnd )
				)
				( attribute "WATTAGE" "1/16W"
					( Origin gFrontEnd )
				)
				( attribute "XY" "(2900,3950)"
					( Origin gFrontEnd )
				)
				( attribute "CHIPS_PART_NAME" "RES"
					( Origin gPackager )
				)
				( attribute "CDS_PART_NAME" "RES_0402-1.00K,1%,1/16W,CHIP,GA"
					( Origin gPackager )
				)
				( objectStatus "R1G15" )
			)
			( gate "@baseboard_fab2_lib.baseboard_fab2(sch_1):page100_i36"
				( attribute "BOM_COST" "SM_CONTROLLER"
					( Origin gFrontEnd )
				)
				( attribute "CDS_LIB" "mstr_discrete"
					( Origin gPackager )
				)
				( attribute "CDS_LOCATION" "R1G17"
					( Origin gPackager )
				)
				( attribute "CDS_SEC" "1"
					( Origin gPackager )
				)
				( attribute "LOCATION" "R1G17"
					( Origin gFrontEnd )
				)
				( attribute "MATERIAL" "CHIP"
					( Origin gFrontEnd )
				)
				( attribute "PACK_TYPE" "0402"
					( Origin gFrontEnd )
				)
				( attribute "PART_NUMBER" "G21796-026"
					( Origin gFrontEnd )
				)
				( attribute "PHYS_PAGE" "100"
					( Origin gFrontEnd )
				)
				( attribute "ROOM" "MEM"
					( Origin gFrontEnd )
				)
				( attribute "ROT" "2"
					( Origin gFrontEnd )
				)
				( attribute "SEC" "1"
					( Origin gFrontEnd )
				)
				( attribute "SEC_TYPE" "0402"
					( Origin gFrontEnd )
				)
				( attribute "TOLERANCE" "1%"
					( Origin gFrontEnd )
				)
				( attribute "VALUE" "1.00K"
					( Origin gFrontEnd )
				)
				( attribute "VER" "2"
					( Origin gFrontEnd )
				)
				( attribute "WATTAGE" "1/16W"
					( Origin gFrontEnd )
				)
				( attribute "XY" "(2975,3300)"
					( Origin gFrontEnd )
				)
				( attribute "CHIPS_PART_NAME" "RES"
					( Origin gPackager )
				)
				( attribute "CDS_PART_NAME" "RES_0402-1.00K,1%,1/16W,CHIP,GA"
					( Origin gPackager )
				)
				( objectStatus "R1G17" )
			)
			( gate "@baseboard_fab2_lib.baseboard_fab2(sch_1):page100_i38"
				( attribute "BOM_COST" "SM_CONTROLLER"
					( Origin gFrontEnd )
				)
				( attribute "CDS_LIB" "mstr_discrete"
					( Origin gPackager )
				)
				( attribute "CDS_LOCATION" "R9L2"
					( Origin gPackager )
				)
				( attribute "CDS_SEC" "1"
					( Origin gPackager )
				)
				( attribute "LOCATION" "R9L2"
					( Origin gFrontEnd )
				)
				( attribute "MATERIAL" "CHIP"
					( Origin gFrontEnd )
				)
				( attribute "PACK_TYPE" "0402"
					( Origin gFrontEnd )
				)
				( attribute "PART_NUMBER" "G21796-026"
					( Origin gFrontEnd )
				)
				( attribute "PHYS_PAGE" "100"
					( Origin gFrontEnd )
				)
				( attribute "ROOM" "MEM"
					( Origin gFrontEnd )
				)
				( attribute "ROT" "2"
					( Origin gFrontEnd )
				)
				( attribute "SEC" "1"
					( Origin gFrontEnd )
				)
				( attribute "SEC_TYPE" "0402"
					( Origin gFrontEnd )
				)
				( attribute "TOLERANCE" "1%"
					( Origin gFrontEnd )
				)
				( attribute "VALUE" "1.00K"
					( Origin gFrontEnd )
				)
				( attribute "VER" "2"
					( Origin gFrontEnd )
				)
				( attribute "WATTAGE" "1/16W"
					( Origin gFrontEnd )
				)
				( attribute "XY" "(2900,2275)"
					( Origin gFrontEnd )
				)
				( attribute "CHIPS_PART_NAME" "RES"
					( Origin gPackager )
				)
				( attribute "CDS_PART_NAME" "RES_0402-1.00K,1%,1/16W,CHIP,GA"
					( Origin gPackager )
				)
				( objectStatus "R9L2" )
			)
			( gate "@baseboard_fab2_lib.baseboard_fab2(sch_1):page100_i40"
				( attribute "BOM_COST" "PROC_SOCKET"
					( Origin gFrontEnd )
				)
				( attribute "CDS_LIB" "mstr_discrete"
					( Origin gPackager )
				)
				( attribute "CDS_LOCATION" "R9L1"
					( Origin gPackager )
				)
				( attribute "CDS_SEC" "1"
					( Origin gPackager )
				)
				( attribute "LOCATION" "R9L1"
					( Origin gFrontEnd )
				)
				( attribute "MATERIAL" "CHIP"
					( Origin gFrontEnd )
				)
				( attribute "PACK_TYPE" "0402"
					( Origin gFrontEnd )
				)
				( attribute "PART_NUMBER" "G21796-026"
					( Origin gFrontEnd )
				)
				( attribute "PHYS_PAGE" "100"
					( Origin gFrontEnd )
				)
				( attribute "ROOM" "PROC"
					( Origin gFrontEnd )
				)
				( attribute "ROT" "2"
					( Origin gFrontEnd )
				)
				( attribute "SEC" "1"
					( Origin gFrontEnd )
				)
				( attribute "SEC_TYPE" "0402"
					( Origin gFrontEnd )
				)
				( attribute "TOLERANCE" "1%"
					( Origin gFrontEnd )
				)
				( attribute "VALUE" "1.00K"
					( Origin gFrontEnd )
				)
				( attribute "VER" "2"
					( Origin gFrontEnd )
				)
				( attribute "WATTAGE" "1/16W"
					( Origin gFrontEnd )
				)
				( attribute "XY" "(2975,1625)"
					( Origin gFrontEnd )
				)
				( attribute "CHIPS_PART_NAME" "RES"
					( Origin gPackager )
				)
				( attribute "CDS_PART_NAME" "RES_0402-1.00K,1%,1/16W,CHIP,GA"
					( Origin gPackager )
				)
				( objectStatus "R9L1" )
			)
			( gate "@baseboard_fab2_lib.baseboard_fab2(sch_1):page100_i41"
				( attribute "BOM_COST" "PROC_SOCKET"
					( Origin gFrontEnd )
				)
				( attribute "CDS_LIB" "mstr_discrete"
					( Origin gPackager )
				)
				( attribute "CDS_LOCATION" "R1G14"
					( Origin gPackager )
				)
				( attribute "CDS_SEC" "1"
					( Origin gPackager )
				)
				( attribute "LOCATION" "R1G14"
					( Origin gFrontEnd )
				)
				( attribute "MATERIAL" "CHIP"
					( Origin gFrontEnd )
				)
				( attribute "PACK_TYPE" "0402"
					( Origin gFrontEnd )
				)
				( attribute "PART_NUMBER" "G21796-274"
					( Origin gFrontEnd )
				)
				( attribute "PHYS_PAGE" "100"
					( Origin gFrontEnd )
				)
				( attribute "ROOM" "PROC"
					( Origin gFrontEnd )
				)
				( attribute "ROT" "0"
					( Origin gFrontEnd )
				)
				( attribute "SEC" "1"
					( Origin gFrontEnd )
				)
				( attribute "SEC_TYPE" "0402"
					( Origin gFrontEnd )
				)
				( attribute "TOLERANCE" "1.0%"
					( Origin gFrontEnd )
				)
				( attribute "VALUE" "2"
					( Origin gFrontEnd )
				)
				( attribute "VER" "1"
					( Origin gFrontEnd )
				)
				( attribute "WATTAGE" "1/16W"
					( Origin gFrontEnd )
				)
				( attribute "XY" "(2675,3625)"
					( Origin gFrontEnd )
				)
				( attribute "CHIPS_PART_NAME" "RES"
					( Origin gPackager )
				)
				( attribute "CDS_PART_NAME" "RES_0402-2,1.0%,1/16W,CHIP,G21A"
					( Origin gPackager )
				)
				( objectStatus "R1G14" )
			)
			( gate "@baseboard_fab2_lib.baseboard_fab2(sch_1):page100_i42"
				( attribute "BOM_COST" "PROC_SOCKET"
					( Origin gFrontEnd )
				)
				( attribute "CDS_LIB" "dev_discrete"
					( Origin gPackager )
				)
				( attribute "CDS_LOCATION" "C1G18"
					( Origin gPackager )
				)
				( attribute "CDS_SEC" "1"
					( Origin gPackager )
				)
				( attribute "LOCATION" "C1G18"
					( Origin gFrontEnd )
				)
				( attribute "MATERIAL" "X7R"
					( Origin gFrontEnd )
				)
				( attribute "PACK_TYPE" "0402V"
					( Origin gFrontEnd )
				)
				( attribute "PART_NUMBER" "A36096-045"
					( Origin gFrontEnd )
				)
				( attribute "PHYS_PAGE" "100"
					( Origin gFrontEnd )
				)
				( attribute "ROOM" "PROC"
					( Origin gFrontEnd )
				)
				( attribute "ROT" "0"
					( Origin gFrontEnd )
				)
				( attribute "SEC" "1"
					( Origin gFrontEnd )
				)
				( attribute "SEC_TYPE" "0402V"
					( Origin gFrontEnd )
				)
				( attribute "TOLERANCE" "10%"
					( Origin gFrontEnd )
				)
				( attribute "VALUE" "0.01UF"
					( Origin gFrontEnd )
				)
				( attribute "VER" "1"
					( Origin gFrontEnd )
				)
				( attribute "VOLTAGE" "25V"
					( Units "uVoltage" "V" 1.000000)
					( Origin gFrontEnd )
				)
				( attribute "XY" "(2450,3325)"
					( Origin gFrontEnd )
				)
				( attribute "CHIPS_PART_NAME" "CAP_A"
					( Origin gPackager )
				)
				( attribute "CDS_PART_NAME" "CAP_A_0402V-0.01UF,25V,10%,X7RA"
					( Origin gPackager )
				)
				( objectStatus "C1G18" )
			)
			( gate "@baseboard_fab2_lib.baseboard_fab2(sch_1):page100_i45"
				( attribute "BOM_COST" "PROC_SOCKET"
					( Origin gFrontEnd )
				)
				( attribute "CDS_LIB" "mstr_discrete"
					( Origin gPackager )
				)
				( attribute "CDS_LOCATION" "R9L3"
					( Origin gPackager )
				)
				( attribute "CDS_SEC" "1"
					( Origin gPackager )
				)
				( attribute "LOCATION" "R9L3"
					( Origin gFrontEnd )
				)
				( attribute "MATERIAL" "CHIP"
					( Origin gFrontEnd )
				)
				( attribute "PACK_TYPE" "0402"
					( Origin gFrontEnd )
				)
				( attribute "PART_NUMBER" "G21796-274"
					( Origin gFrontEnd )
				)
				( attribute "PHYS_PAGE" "100"
					( Origin gFrontEnd )
				)
				( attribute "ROOM" "PROC"
					( Origin gFrontEnd )
				)
				( attribute "ROT" "0"
					( Origin gFrontEnd )
				)
				( attribute "SEC" "1"
					( Origin gFrontEnd )
				)
				( attribute "SEC_TYPE" "0402"
					( Origin gFrontEnd )
				)
				( attribute "TOLERANCE" "1.0%"
					( Origin gFrontEnd )
				)
				( attribute "VALUE" "2"
					( Origin gFrontEnd )
				)
				( attribute "VER" "1"
					( Origin gFrontEnd )
				)
				( attribute "WATTAGE" "1/16W"
					( Origin gFrontEnd )
				)
				( attribute "XY" "(2675,1950)"
					( Origin gFrontEnd )
				)
				( attribute "CHIPS_PART_NAME" "RES"
					( Origin gPackager )
				)
				( attribute "CDS_PART_NAME" "RES_0402-2,1.0%,1/16W,CHIP,G21A"
					( Origin gPackager )
				)
				( objectStatus "R9L3" )
			)
			( gate "@baseboard_fab2_lib.baseboard_fab2(sch_1):page100_i46"
				( attribute "BOM_COST" "SM_CONTROLLER"
					( Origin gFrontEnd )
				)
				( attribute "CDS_LIB" "dev_discrete"
					( Origin gPackager )
				)
				( attribute "CDS_LOCATION" "C9L3"
					( Origin gPackager )
				)
				( attribute "CDS_SEC" "1"
					( Origin gPackager )
				)
				( attribute "LOCATION" "C9L3"
					( Origin gFrontEnd )
				)
				( attribute "MATERIAL" "X7R"
					( Origin gFrontEnd )
				)
				( attribute "PACK_TYPE" "0402V"
					( Origin gFrontEnd )
				)
				( attribute "PART_NUMBER" "A36096-045"
					( Origin gFrontEnd )
				)
				( attribute "PHYS_PAGE" "100"
					( Origin gFrontEnd )
				)
				( attribute "ROOM" "MEM"
					( Origin gFrontEnd )
				)
				( attribute "ROT" "0"
					( Origin gFrontEnd )
				)
				( attribute "SEC" "1"
					( Origin gFrontEnd )
				)
				( attribute "SEC_TYPE" "0402V"
					( Origin gFrontEnd )
				)
				( attribute "TOLERANCE" "10%"
					( Origin gFrontEnd )
				)
				( attribute "VALUE" "0.01UF"
					( Origin gFrontEnd )
				)
				( attribute "VER" "1"
					( Origin gFrontEnd )
				)
				( attribute "VOLTAGE" "25V"
					( Units "uVoltage" "V" 1.000000)
					( Origin gFrontEnd )
				)
				( attribute "XY" "(2450,1650)"
					( Origin gFrontEnd )
				)
				( attribute "CHIPS_PART_NAME" "CAP_A"
					( Origin gPackager )
				)
				( attribute "CDS_PART_NAME" "CAP_A_0402V-0.01UF,25V,10%,X7RA"
					( Origin gPackager )
				)
				( objectStatus "C9L3" )
			)
			( gate "@baseboard_fab2_lib.baseboard_fab2(sch_1):page101_i20"
				( attribute "BOM_COST" "SM_CONTROLLER"
					( Origin gFrontEnd )
				)
				( attribute "CDS_LIB" "mstr_discrete"
					( Origin gPackager )
				)
				( attribute "CDS_LOCATION" "R8F29"
					( Origin gPackager )
				)
				( attribute "CDS_SEC" "1"
					( Origin gPackager )
				)
				( attribute "LOCATION" "R8F29"
					( Origin gFrontEnd )
				)
				( attribute "MATERIAL" "CHIP"
					( Origin gFrontEnd )
				)
				( attribute "PACK_TYPE" "0402"
					( Origin gFrontEnd )
				)
				( attribute "PART_NUMBER" "G21796-074"
					( Origin gFrontEnd )
				)
				( attribute "PHYS_PAGE" "101"
					( Origin gFrontEnd )
				)
				( attribute "ROOM" "SYS_CLOCK"
					( Origin gFrontEnd )
				)
				( attribute "ROT" "0"
					( Origin gFrontEnd )
				)
				( attribute "SEC" "1"
					( Origin gFrontEnd )
				)
				( attribute "SEC_TYPE" "0402"
					( Origin gFrontEnd )
				)
				( attribute "TOLERANCE" "1%"
					( Origin gFrontEnd )
				)
				( attribute "VALUE" "33.2"
					( Origin gFrontEnd )
				)
				( attribute "VER" "1"
					( Origin gFrontEnd )
				)
				( attribute "WATTAGE" "1/16W"
					( Origin gFrontEnd )
				)
				( attribute "XY" "(-3050,2450)"
					( Origin gFrontEnd )
				)
				( attribute "CHIPS_PART_NAME" "RES"
					( Origin gPackager )
				)
				( attribute "CDS_PART_NAME" "RES_0402-33.2,1%,1/16W,CHIP,G2A"
					( Origin gPackager )
				)
				( objectStatus "R8F29" )
			)
			( gate "@baseboard_fab2_lib.baseboard_fab2(sch_1):page101_i28"
				( attribute "BOM_COST" "SM_CONTROLLER"
					( Origin gFrontEnd )
				)
				( attribute "CDS_LIB" "mstr_discrete"
					( Origin gPackager )
				)
				( attribute "CDS_LOCATION" "R8F25"
					( Origin gPackager )
				)
				( attribute "CDS_SEC" "1"
					( Origin gPackager )
				)
				( attribute "LOCATION" "R8F25"
					( Origin gFrontEnd )
				)
				( attribute "MATERIAL" "CHIP"
					( Origin gFrontEnd )
				)
				( attribute "PACK_TYPE" "0402"
					( Origin gFrontEnd )
				)
				( attribute "PART_NUMBER" "G21796-077"
					( Origin gFrontEnd )
				)
				( attribute "PHYS_PAGE" "101"
					( Origin gFrontEnd )
				)
				( attribute "ROOM" "SYS_CLOCK"
					( Origin gFrontEnd )
				)
				( attribute "ROT" "2"
					( Origin gFrontEnd )
				)
				( attribute "SEC" "1"
					( Origin gPackager )
				)
				( attribute "TOLERANCE" "1%"
					( Origin gFrontEnd )
				)
				( attribute "VALUE" "475.0"
					( Origin gFrontEnd )
				)
				( attribute "VER" "2"
					( Origin gFrontEnd )
				)
				( attribute "WATTAGE" "1/16W"
					( Origin gFrontEnd )
				)
				( attribute "XY" "(-4375,3000)"
					( Origin gFrontEnd )
				)
				( attribute "CHIPS_PART_NAME" "RES"
					( Origin gPackager )
				)
				( attribute "CDS_PART_NAME" "RES_0402-475.0,1%,1/16W,CHIP,GA"
					( Origin gPackager )
				)
				( objectStatus "R8F25" )
			)
			( gate "@baseboard_fab2_lib.baseboard_fab2(sch_1):page101_i34"
				( attribute "BOM_COST" "SM_CONTROLLER"
					( Origin gFrontEnd )
				)
				( attribute "CDS_LIB" "mstr_clock"
					( Origin gPackager )
				)
				( attribute "CDS_LMAN_SYM_OUTLINE" "-600,900,600,-900"
					( Origin gPackager )
				)
				( attribute "CDS_LOCATION" "EU8F2"
					( Origin gPackager )
				)
				( attribute "CDS_SEC" "1"
					( Origin gPackager )
				)
				( attribute "LOCATION" "EU8F2"
					( Origin gFrontEnd )
				)
				( attribute "MATERIAL" "IC"
					( Origin gFrontEnd )
				)
				( attribute "PACK_TYPE" "MLFP"
					( Origin gFrontEnd )
				)
				( attribute "PART_NUMBER" "E95226-001"
					( Origin gFrontEnd )
				)
				( attribute "PHYS_PAGE" "101"
					( Origin gFrontEnd )
				)
				( attribute "ROOM" "SYS_CLOCK"
					( Origin gFrontEnd )
				)
				( attribute "ROT" "0"
					( Origin gFrontEnd )
				)
				( attribute "SEC" "1"
					( Origin gFrontEnd )
				)
				( attribute "SEC_TYPE" "MLFP"
					( Origin gFrontEnd )
				)
				( attribute "VER" "1"
					( Origin gFrontEnd )
				)
				( attribute "XY" "(-5500,1850)"
					( Origin gFrontEnd )
				)
				( attribute "CHIPS_PART_NAME" "ICS9FGP204"
					( Origin gPackager )
				)
				( attribute "CDS_PART_NAME" "ICS9FGP204_MLFP-IC,E95226-001"
					( Origin gPackager )
				)
				( objectStatus "EU8F2" )
			)
			( gate "@baseboard_fab2_lib.baseboard_fab2(sch_1):page101_i48"
				( attribute "BOM_COST" "SM_CONTROLLER"
					( Origin gFrontEnd )
				)
				( attribute "CDS_LIB" "mstr_discrete"
					( Origin gPackager )
				)
				( attribute "CDS_LOCATION" "R2T25"
					( Origin gPackager )
				)
				( attribute "CDS_SEC" "1"
					( Origin gPackager )
				)
				( attribute "LOCATION" "R2T25"
					( Origin gFrontEnd )
				)
				( attribute "MATERIAL" "CHIP"
					( Origin gFrontEnd )
				)
				( attribute "PACK_TYPE" "0402"
					( Origin gFrontEnd )
				)
				( attribute "PART_NUMBER" "G21796-026"
					( Origin gFrontEnd )
				)
				( attribute "PHYS_PAGE" "101"
					( Origin gFrontEnd )
				)
				( attribute "ROOM" "SYS_CLOCK"
					( Origin gFrontEnd )
				)
				( attribute "ROT" "0"
					( Origin gFrontEnd )
				)
				( attribute "SEC" "1"
					( Origin gFrontEnd )
				)
				( attribute "SEC_TYPE" "0402"
					( Origin gFrontEnd )
				)
				( attribute "TOLERANCE" "1%"
					( Origin gFrontEnd )
				)
				( attribute "VALUE" "1.00K"
					( Origin gFrontEnd )
				)
				( attribute "VER" "2"
					( Origin gFrontEnd )
				)
				( attribute "WATTAGE" "1/16W"
					( Origin gFrontEnd )
				)
				( attribute "XY" "(-7925,1225)"
					( Origin gFrontEnd )
				)
				( attribute "CHIPS_PART_NAME" "RES"
					( Origin gPackager )
				)
				( attribute "CDS_PART_NAME" "RES_0402-1.00K,1%,1/16W,CHIP,GA"
					( Origin gPackager )
				)
				( objectStatus "R2T25" )
			)
			( gate "@baseboard_fab2_lib.baseboard_fab2(sch_1):page101_i52"
				( attribute "BOM_COST" "SM_CONTROLLER"
					( Origin gFrontEnd )
				)
				( attribute "CDS_LIB" "mstr_discrete"
					( Origin gPackager )
				)
				( attribute "CDS_LOCATION" "Y8F1"
					( Origin gPackager )
				)
				( attribute "CDS_SEC" "1"
					( Origin gPackager )
				)
				( attribute "LOCATION" "Y8F1"
					( Origin gFrontEnd )
				)
				( attribute "MATERIAL" "IC"
					( Origin gFrontEnd )
				)
				( attribute "PACK_TYPE" "2013LF"
					( Origin gFrontEnd )
				)
				( attribute "PART_NUMBER" "D71700-033"
					( Origin gFrontEnd )
				)
				( attribute "PHYS_PAGE" "101"
					( Origin gFrontEnd )
				)
				( attribute "ROOM" "SYS_CLOCK"
					( Origin gFrontEnd )
				)
				( attribute "ROT" "2"
					( Origin gFrontEnd )
				)
				( attribute "SEC" "1"
					( Origin gPackager )
				)
				( attribute "VALUE" "25.000MHZ"
					( Origin gFrontEnd )
				)
				( attribute "VER" "3"
					( Origin gFrontEnd )
				)
				( attribute "XY" "(-7350,1050)"
					( Origin gFrontEnd )
				)
				( attribute "CHIPS_PART_NAME" "CRYSTAL"
					( Origin gPackager )
				)
				( attribute "CDS_PART_NAME" "CRYSTAL_2013LF-25.000MHZ,IC,D7A"
					( Origin gPackager )
				)
				( objectStatus "Y8F1" )
			)
			( gate "@baseboard_fab2_lib.baseboard_fab2(sch_1):page227_i153"
				( attribute "ATTRIBUTE" "120NH"
					( Origin gFrontEnd )
				)
				( attribute "BOM_DS" "068.9002N.1021"
					( Origin gFrontEnd )
				)
				( attribute "BOM_SS" "NOPOP"
					( Origin gFrontEnd )
				)
				( attribute "CDS_LIB" "w_hdl"
					( Origin gPackager )
				)
				( attribute "CDS_LMAN_SYM_OUTLINE" "-75,100,75,-100"
					( Origin gPackager )
				)
				( attribute "CDS_LOCATION" "L1A1"
					( Origin gPackager )
				)
				( attribute "CDS_SEC" "1"
					( Origin gPackager )
				)
				( attribute "DS_VALUE" "90NH"
					( Origin gFrontEnd )
				)
				( attribute "LOCATION" "L1A1"
					( Origin gFrontEnd )
				)
				( attribute "NEW_PACK_SIZE" "DCR=0.17MOHM"
					( Origin gFrontEnd )
				)
				( attribute "NEW_RATED" "DS_ISAT=134A@25C"
					( Origin gFrontEnd )
				)
				( attribute "NEW_TYPE" "IRMS=66A@DELTA_T<40C"
					( Origin gFrontEnd )
				)
				( attribute "PACK_SIZE" "DCR=0.17MOHM"
					( Origin gFrontEnd )
				)
				( attribute "PACK_TYPE" "DISCRET-GB2"
					( Origin gFrontEnd )
				)
				( attribute "PART_NUMBER" "068.1202N.M001"
					( Origin gFrontEnd )
				)
				( attribute "PHYS_PAGE" "227"
					( Origin gFrontEnd )
				)
				( attribute "RATED" "ISAT=94A@25C"
					( Origin gFrontEnd )
				)
				( attribute "ROT" "1"
					( Origin gFrontEnd )
				)
				( attribute "SEC" "1"
					( Origin gFrontEnd )
				)
				( attribute "SEC_TYPE" "DISCRET-GB2"
					( Origin gFrontEnd )
				)
				( attribute "TYPE" "IRMS=66A@DELTA_T<40C"
					( Origin gFrontEnd )
				)
				( attribute "VALUE" "IND-120NH-30-GP"
					( Origin gFrontEnd )
				)
				( attribute "VER" "1"
					( Origin gFrontEnd )
				)
				( attribute "XY" "(3775,-300)"
					( Origin gFrontEnd )
				)
				( attribute "CHIPS_PART_NAME" "IND-120NH-30-GP"
					( Origin gPackager )
				)
				( attribute "CDS_PART_NAME" "IND-120NH-30-GP_DISCRET-GB2-INA"
					( Origin gPackager )
				)
				( objectStatus "L1A1" )
			)
			( gate "@baseboard_fab2_lib.baseboard_fab2(sch_1):page101_i89"
				( attribute "BOM_COST" "SM_CONTROLLER"
					( Origin gFrontEnd )
				)
				( attribute "CDS_LIB" "dev_discrete"
					( Origin gPackager )
				)
				( attribute "CDS_LOCATION" "C2T31"
					( Origin gPackager )
				)
				( attribute "CDS_SEC" "1"
					( Origin gPackager )
				)
				( attribute "LOCATION" "C2T31"
					( Origin gFrontEnd )
				)
				( attribute "MATERIAL" "X6S"
					( Origin gFrontEnd )
				)
				( attribute "PACK_TYPE" "0402V"
					( Origin gFrontEnd )
				)
				( attribute "PART_NUMBER" "D97712-004"
					( Origin gFrontEnd )
				)
				( attribute "PHYS_PAGE" "101"
					( Origin gFrontEnd )
				)
				( attribute "ROOM" "SYS_CLOCK"
					( Origin gFrontEnd )
				)
				( attribute "ROT" "0"
					( Origin gFrontEnd )
				)
				( attribute "SEC" "1"
					( Origin gPackager )
				)
				( attribute "TOLERANCE" "10%"
					( Origin gFrontEnd )
				)
				( attribute "VALUE" "1.0UF"
					( Origin gFrontEnd )
				)
				( attribute "VER" "1"
					( Origin gFrontEnd )
				)
				( attribute "VOLTAGE" "6.3V"
					( Units "uVoltage" "V" 1.000000)
					( Origin gFrontEnd )
				)
				( attribute "XY" "(-3625,3925)"
					( Origin gFrontEnd )
				)
				( attribute "CHIPS_PART_NAME" "CAP_A"
					( Origin gPackager )
				)
				( attribute "CDS_PART_NAME" "CAP_A_0402V-1.0UF,6.3V,10%,X6SA"
					( Origin gPackager )
				)
				( objectStatus "C2T31" )
			)
			( gate "@baseboard_fab2_lib.baseboard_fab2(sch_1):page101_i90"
				( attribute "BOM_COST" "SM_CONTROLLER"
					( Origin gFrontEnd )
				)
				( attribute "CDS_LIB" "dev_discrete"
					( Origin gPackager )
				)
				( attribute "CDS_LOCATION" "C2T27"
					( Origin gPackager )
				)
				( attribute "CDS_SEC" "1"
					( Origin gPackager )
				)
				( attribute "LOCATION" "C2T27"
					( Origin gFrontEnd )
				)
				( attribute "MATERIAL" "X7R"
					( Origin gFrontEnd )
				)
				( attribute "PACK_TYPE" "0402V"
					( Origin gFrontEnd )
				)
				( attribute "PART_NUMBER" "A36096-045"
					( Origin gFrontEnd )
				)
				( attribute "PHYS_PAGE" "101"
					( Origin gFrontEnd )
				)
				( attribute "ROOM" "SYS_CLOCK"
					( Origin gFrontEnd )
				)
				( attribute "ROT" "0"
					( Origin gFrontEnd )
				)
				( attribute "SEC" "1"
					( Origin gPackager )
				)
				( attribute "TOLERANCE" "10%"
					( Origin gFrontEnd )
				)
				( attribute "VALUE" "0.01UF"
					( Origin gFrontEnd )
				)
				( attribute "VER" "1"
					( Origin gFrontEnd )
				)
				( attribute "VOLTAGE" "25V"
					( Units "uVoltage" "V" 1.000000)
					( Origin gFrontEnd )
				)
				( attribute "XY" "(-4050,3925)"
					( Origin gFrontEnd )
				)
				( attribute "CHIPS_PART_NAME" "CAP_A"
					( Origin gPackager )
				)
				( attribute "CDS_PART_NAME" "CAP_A_0402V-0.01UF,25V,10%,X7RA"
					( Origin gPackager )
				)
				( objectStatus "C2T27" )
			)
			( gate "@baseboard_fab2_lib.baseboard_fab2(sch_1):page101_i94"
				( attribute "BOM_COST" "SM_CONTROLLER"
					( Origin gFrontEnd )
				)
				( attribute "CDS_LIB" "mstr_discrete"
					( Origin gPackager )
				)
				( attribute "CDS_LOCATION" "R2T23"
					( Origin gPackager )
				)
				( attribute "CDS_SEC" "1"
					( Origin gPackager )
				)
				( attribute "LOCATION" "R2T23"
					( Origin gFrontEnd )
				)
				( attribute "MATERIAL" "CHIP"
					( Origin gFrontEnd )
				)
				( attribute "PACK_TYPE" "0603"
					( Origin gFrontEnd )
				)
				( attribute "PART_NUMBER" "G22026-127"
					( Origin gFrontEnd )
				)
				( attribute "PHYS_PAGE" "101"
					( Origin gFrontEnd )
				)
				( attribute "ROOM" "SYS_CLOCK"
					( Origin gFrontEnd )
				)
				( attribute "ROT" "0"
					( Origin gFrontEnd )
				)
				( attribute "SEC" "1"
					( Origin gPackager )
				)
				( attribute "TOLERANCE" "1.0%"
					( Origin gFrontEnd )
				)
				( attribute "VALUE" "2.2"
					( Origin gFrontEnd )
				)
				( attribute "VER" "1"
					( Origin gFrontEnd )
				)
				( attribute "WATTAGE" "1/10W"
					( Origin gFrontEnd )
				)
				( attribute "XY" "(-4325,4150)"
					( Origin gFrontEnd )
				)
				( attribute "CHIPS_PART_NAME" "RES"
					( Origin gPackager )
				)
				( attribute "CDS_PART_NAME" "RES_0603-2.2,1.0%,1/10W,CHIP,GA"
					( Origin gPackager )
				)
				( objectStatus "R2T23" )
			)
			( gate "@baseboard_fab2_lib.baseboard_fab2(sch_1):page101_i95"
				( attribute "BOM_COST" "SM_CONTROLLER"
					( Origin gFrontEnd )
				)
				( attribute "CDS_LIB" "mstr_discrete"
					( Origin gPackager )
				)
				( attribute "CDS_LOCATION" "R2T52"
					( Origin gPackager )
				)
				( attribute "CDS_SEC" "1"
					( Origin gPackager )
				)
				( attribute "LOCATION" "R2T52"
					( Origin gFrontEnd )
				)
				( attribute "MATERIAL" "CHIP"
					( Origin gFrontEnd )
				)
				( attribute "PACK_TYPE" "0603"
					( Origin gFrontEnd )
				)
				( attribute "PART_NUMBER" "G22026-127"
					( Origin gFrontEnd )
				)
				( attribute "PHYS_PAGE" "101"
					( Origin gFrontEnd )
				)
				( attribute "ROOM" "SYS_CLOCK"
					( Origin gFrontEnd )
				)
				( attribute "ROT" "0"
					( Origin gFrontEnd )
				)
				( attribute "SEC" "1"
					( Origin gPackager )
				)
				( attribute "TOLERANCE" "1.0%"
					( Origin gFrontEnd )
				)
				( attribute "VALUE" "2.2"
					( Origin gFrontEnd )
				)
				( attribute "VER" "1"
					( Origin gFrontEnd )
				)
				( attribute "WATTAGE" "1/10W"
					( Origin gFrontEnd )
				)
				( attribute "XY" "(-2825,4200)"
					( Origin gFrontEnd )
				)
				( attribute "CHIPS_PART_NAME" "RES"
					( Origin gPackager )
				)
				( attribute "CDS_PART_NAME" "RES_0603-2.2,1.0%,1/10W,CHIP,GA"
					( Origin gPackager )
				)
				( objectStatus "R2T52" )
			)
			( gate "@baseboard_fab2_lib.baseboard_fab2(sch_1):page101_i97"
				( attribute "BOM_COST" "SM_CONTROLLER"
					( Origin gFrontEnd )
				)
				( attribute "CDS_LIB" "dev_discrete"
					( Origin gPackager )
				)
				( attribute "CDS_LOCATION" "C2T38"
					( Origin gPackager )
				)
				( attribute "CDS_SEC" "1"
					( Origin gPackager )
				)
				( attribute "LOCATION" "C2T38"
					( Origin gFrontEnd )
				)
				( attribute "MATERIAL" "X6S"
					( Origin gFrontEnd )
				)
				( attribute "PACK_TYPE" "0402V"
					( Origin gFrontEnd )
				)
				( attribute "PART_NUMBER" "D97712-004"
					( Origin gFrontEnd )
				)
				( attribute "PHYS_PAGE" "101"
					( Origin gFrontEnd )
				)
				( attribute "ROOM" "SYS_CLOCK"
					( Origin gFrontEnd )
				)
				( attribute "ROT" "0"
					( Origin gFrontEnd )
				)
				( attribute "SEC" "1"
					( Origin gPackager )
				)
				( attribute "TOLERANCE" "10%"
					( Origin gFrontEnd )
				)
				( attribute "VALUE" "1.0UF"
					( Origin gFrontEnd )
				)
				( attribute "VER" "1"
					( Origin gFrontEnd )
				)
				( attribute "VOLTAGE" "6.3V"
					( Units "uVoltage" "V" 1.000000)
					( Origin gFrontEnd )
				)
				( attribute "XY" "(-2250,4000)"
					( Origin gFrontEnd )
				)
				( attribute "CHIPS_PART_NAME" "CAP_A"
					( Origin gPackager )
				)
				( attribute "CDS_PART_NAME" "CAP_A_0402V-1.0UF,6.3V,10%,X6SA"
					( Origin gPackager )
				)
				( objectStatus "C2T38" )
			)
			( gate "@baseboard_fab2_lib.baseboard_fab2(sch_1):page101_i99"
				( attribute "BOM_COST" "SM_CONTROLLER"
					( Origin gFrontEnd )
				)
				( attribute "CDS_LIB" "dev_discrete"
					( Origin gPackager )
				)
				( attribute "CDS_LOCATION" "C2T37"
					( Origin gPackager )
				)
				( attribute "CDS_SEC" "1"
					( Origin gPackager )
				)
				( attribute "LOCATION" "C2T37"
					( Origin gFrontEnd )
				)
				( attribute "MATERIAL" "X7R"
					( Origin gFrontEnd )
				)
				( attribute "PACK_TYPE" "0402V"
					( Origin gFrontEnd )
				)
				( attribute "PART_NUMBER" "A36096-045"
					( Origin gFrontEnd )
				)
				( attribute "PHYS_PAGE" "101"
					( Origin gFrontEnd )
				)
				( attribute "ROOM" "SYS_CLOCK"
					( Origin gFrontEnd )
				)
				( attribute "ROT" "0"
					( Origin gFrontEnd )
				)
				( attribute "SEC" "1"
					( Origin gPackager )
				)
				( attribute "TOLERANCE" "10%"
					( Origin gFrontEnd )
				)
				( attribute "VALUE" "0.01UF"
					( Origin gFrontEnd )
				)
				( attribute "VER" "1"
					( Origin gFrontEnd )
				)
				( attribute "VOLTAGE" "25V"
					( Units "uVoltage" "V" 1.000000)
					( Origin gFrontEnd )
				)
				( attribute "XY" "(-2625,4000)"
					( Origin gFrontEnd )
				)
				( attribute "CHIPS_PART_NAME" "CAP_A"
					( Origin gPackager )
				)
				( attribute "CDS_PART_NAME" "CAP_A_0402V-0.01UF,25V,10%,X7RA"
					( Origin gPackager )
				)
				( objectStatus "C2T37" )
			)
			( gate "@baseboard_fab2_lib.baseboard_fab2(sch_1):page101_i104"
				( attribute "BOM_COST" "SM_CONTROLLER"
					( Origin gFrontEnd )
				)
				( attribute "CDS_LIB" "dev_discrete"
					( Origin gPackager )
				)
				( attribute "CDS_LOCATION" "C2T18"
					( Origin gPackager )
				)
				( attribute "CDS_SEC" "1"
					( Origin gPackager )
				)
				( attribute "LOCATION" "C2T18"
					( Origin gFrontEnd )
				)
				( attribute "MATERIAL" "X7R"
					( Origin gFrontEnd )
				)
				( attribute "PACK_TYPE" "0402V"
					( Origin gFrontEnd )
				)
				( attribute "PART_NUMBER" "A36096-045"
					( Origin gFrontEnd )
				)
				( attribute "PHYS_PAGE" "101"
					( Origin gFrontEnd )
				)
				( attribute "ROOM" "SYS_CLOCK"
					( Origin gFrontEnd )
				)
				( attribute "ROT" "0"
					( Origin gFrontEnd )
				)
				( attribute "SEC" "1"
					( Origin gPackager )
				)
				( attribute "TOLERANCE" "10%"
					( Origin gFrontEnd )
				)
				( attribute "VALUE" "0.01UF"
					( Origin gFrontEnd )
				)
				( attribute "VER" "1"
					( Origin gFrontEnd )
				)
				( attribute "VOLTAGE" "25V"
					( Units "uVoltage" "V" 1.000000)
					( Origin gFrontEnd )
				)
				( attribute "XY" "(-5550,3975)"
					( Origin gFrontEnd )
				)
				( attribute "CHIPS_PART_NAME" "CAP_A"
					( Origin gPackager )
				)
				( attribute "CDS_PART_NAME" "CAP_A_0402V-0.01UF,25V,10%,X7RA"
					( Origin gPackager )
				)
				( objectStatus "C2T18" )
			)
			( gate "@baseboard_fab2_lib.baseboard_fab2(sch_1):page101_i105"
				( attribute "BOM_COST" "SM_CONTROLLER"
					( Origin gFrontEnd )
				)
				( attribute "CDS_LIB" "mstr_discrete"
					( Origin gPackager )
				)
				( attribute "CDS_LOCATION" "R2T21"
					( Origin gPackager )
				)
				( attribute "CDS_SEC" "1"
					( Origin gPackager )
				)
				( attribute "LOCATION" "R2T21"
					( Origin gFrontEnd )
				)
				( attribute "MATERIAL" "CHIP"
					( Origin gFrontEnd )
				)
				( attribute "PACK_TYPE" "0603"
					( Origin gFrontEnd )
				)
				( attribute "PART_NUMBER" "G22026-127"
					( Origin gFrontEnd )
				)
				( attribute "PHYS_PAGE" "101"
					( Origin gFrontEnd )
				)
				( attribute "ROOM" "SYS_CLOCK"
					( Origin gFrontEnd )
				)
				( attribute "ROT" "0"
					( Origin gFrontEnd )
				)
				( attribute "SEC" "1"
					( Origin gFrontEnd )
				)
				( attribute "SEC_TYPE" "0603"
					( Origin gFrontEnd )
				)
				( attribute "TOLERANCE" "1.0%"
					( Origin gFrontEnd )
				)
				( attribute "VALUE" "2.2"
					( Origin gFrontEnd )
				)
				( attribute "VER" "1"
					( Origin gFrontEnd )
				)
				( attribute "WATTAGE" "1/10W"
					( Origin gFrontEnd )
				)
				( attribute "XY" "(-5825,4150)"
					( Origin gFrontEnd )
				)
				( attribute "CHIPS_PART_NAME" "RES"
					( Origin gPackager )
				)
				( attribute "CDS_PART_NAME" "RES_0603-2.2,1.0%,1/10W,CHIP,GA"
					( Origin gPackager )
				)
				( objectStatus "R2T21" )
			)
			( gate "@baseboard_fab2_lib.baseboard_fab2(sch_1):page101_i106"
				( attribute "BOM_COST" "SM_CONTROLLER"
					( Origin gFrontEnd )
				)
				( attribute "CDS_LIB" "dev_discrete"
					( Origin gPackager )
				)
				( attribute "CDS_LOCATION" "C2T19"
					( Origin gPackager )
				)
				( attribute "CDS_SEC" "1"
					( Origin gPackager )
				)
				( attribute "LOCATION" "C2T19"
					( Origin gFrontEnd )
				)
				( attribute "MATERIAL" "X6S"
					( Origin gFrontEnd )
				)
				( attribute "PACK_TYPE" "0402V"
					( Origin gFrontEnd )
				)
				( attribute "PART_NUMBER" "D97712-004"
					( Origin gFrontEnd )
				)
				( attribute "PHYS_PAGE" "101"
					( Origin gFrontEnd )
				)
				( attribute "ROOM" "SYS_CLOCK"
					( Origin gFrontEnd )
				)
				( attribute "ROT" "0"
					( Origin gFrontEnd )
				)
				( attribute "SEC" "1"
					( Origin gPackager )
				)
				( attribute "TOLERANCE" "10%"
					( Origin gFrontEnd )
				)
				( attribute "VALUE" "1.0UF"
					( Origin gFrontEnd )
				)
				( attribute "VER" "1"
					( Origin gFrontEnd )
				)
				( attribute "VOLTAGE" "6.3V"
					( Units "uVoltage" "V" 1.000000)
					( Origin gFrontEnd )
				)
				( attribute "XY" "(-5150,3975)"
					( Origin gFrontEnd )
				)
				( attribute "CHIPS_PART_NAME" "CAP_A"
					( Origin gPackager )
				)
				( attribute "CDS_PART_NAME" "CAP_A_0402V-1.0UF,6.3V,10%,X6SA"
					( Origin gPackager )
				)
				( objectStatus "C2T19" )
			)
			( gate "@baseboard_fab2_lib.baseboard_fab2(sch_1):page101_i109"
				( attribute "BOM_COST" "SM_CONTROLLER"
					( Origin gFrontEnd )
				)
				( attribute "CDS_LIB" "dev_discrete"
					( Origin gPackager )
				)
				( attribute "CDS_LOCATION" "C2T34"
					( Origin gPackager )
				)
				( attribute "CDS_SEC" "1"
					( Origin gPackager )
				)
				( attribute "LOCATION" "C2T34"
					( Origin gFrontEnd )
				)
				( attribute "MATERIAL" "X7R"
					( Origin gFrontEnd )
				)
				( attribute "PACK_TYPE" "0402V"
					( Origin gFrontEnd )
				)
				( attribute "PART_NUMBER" "A36096-030"
					( Origin gFrontEnd )
				)
				( attribute "PHYS_PAGE" "101"
					( Origin gFrontEnd )
				)
				( attribute "ROOM" "SYS_CLOCK"
					( Origin gFrontEnd )
				)
				( attribute "ROT" "0"
					( Origin gFrontEnd )
				)
				( attribute "SEC" "1"
					( Origin gFrontEnd )
				)
				( attribute "SEC_TYPE" "0402V"
					( Origin gFrontEnd )
				)
				( attribute "TOLERANCE" "10%"
					( Origin gFrontEnd )
				)
				( attribute "VALUE" "0.1UF"
					( Origin gFrontEnd )
				)
				( attribute "VER" "1"
					( Origin gFrontEnd )
				)
				( attribute "VOLTAGE" "16V"
					( Units "uVoltage" "V" 1.000000)
					( Origin gFrontEnd )
				)
				( attribute "XY" "(-6600,3975)"
					( Origin gFrontEnd )
				)
				( attribute "CHIPS_PART_NAME" "CAP_A"
					( Origin gPackager )
				)
				( attribute "CDS_PART_NAME" "CAP_A_0402V-0.1UF,16V,10%,X7R,A"
					( Origin gPackager )
				)
				( objectStatus "C2T34" )
			)
			( gate "@baseboard_fab2_lib.baseboard_fab2(sch_1):page101_i110"
				( attribute "BOM_COST" "SM_CONTROLLER"
					( Origin gFrontEnd )
				)
				( attribute "CDS_LIB" "dev_discrete"
					( Origin gPackager )
				)
				( attribute "CDS_LOCATION" "C2T30"
					( Origin gPackager )
				)
				( attribute "CDS_SEC" "1"
					( Origin gPackager )
				)
				( attribute "LOCATION" "C2T30"
					( Origin gFrontEnd )
				)
				( attribute "MATERIAL" "X7R"
					( Origin gFrontEnd )
				)
				( attribute "PACK_TYPE" "0402V"
					( Origin gFrontEnd )
				)
				( attribute "PART_NUMBER" "A36096-030"
					( Origin gFrontEnd )
				)
				( attribute "PHYS_PAGE" "101"
					( Origin gFrontEnd )
				)
				( attribute "ROOM" "SYS_CLOCK"
					( Origin gFrontEnd )
				)
				( attribute "ROT" "0"
					( Origin gFrontEnd )
				)
				( attribute "SEC" "1"
					( Origin gPackager )
				)
				( attribute "TOLERANCE" "10%"
					( Origin gFrontEnd )
				)
				( attribute "VALUE" "0.1UF"
					( Origin gFrontEnd )
				)
				( attribute "VER" "1"
					( Origin gFrontEnd )
				)
				( attribute "VOLTAGE" "16V"
					( Units "uVoltage" "V" 1.000000)
					( Origin gFrontEnd )
				)
				( attribute "XY" "(-6900,3975)"
					( Origin gFrontEnd )
				)
				( attribute "CHIPS_PART_NAME" "CAP_A"
					( Origin gPackager )
				)
				( attribute "CDS_PART_NAME" "CAP_A_0402V-0.1UF,16V,10%,X7R,A"
					( Origin gPackager )
				)
				( objectStatus "C2T30" )
			)
			( gate "@baseboard_fab2_lib.baseboard_fab2(sch_1):page101_i111"
				( attribute "BOM_COST" "SM_CONTROLLER"
					( Origin gFrontEnd )
				)
				( attribute "CDS_LIB" "dev_discrete"
					( Origin gPackager )
				)
				( attribute "CDS_LOCATION" "C2T25"
					( Origin gPackager )
				)
				( attribute "CDS_SEC" "1"
					( Origin gPackager )
				)
				( attribute "LOCATION" "C2T25"
					( Origin gFrontEnd )
				)
				( attribute "MATERIAL" "X7R"
					( Origin gFrontEnd )
				)
				( attribute "PACK_TYPE" "0402V"
					( Origin gFrontEnd )
				)
				( attribute "PART_NUMBER" "A36096-030"
					( Origin gFrontEnd )
				)
				( attribute "PHYS_PAGE" "101"
					( Origin gFrontEnd )
				)
				( attribute "ROOM" "SYS_CLOCK"
					( Origin gFrontEnd )
				)
				( attribute "ROT" "0"
					( Origin gFrontEnd )
				)
				( attribute "SEC" "1"
					( Origin gPackager )
				)
				( attribute "TOLERANCE" "10%"
					( Origin gFrontEnd )
				)
				( attribute "VALUE" "0.1UF"
					( Origin gFrontEnd )
				)
				( attribute "VER" "1"
					( Origin gFrontEnd )
				)
				( attribute "VOLTAGE" "16V"
					( Units "uVoltage" "V" 1.000000)
					( Origin gFrontEnd )
				)
				( attribute "XY" "(-7300,3975)"
					( Origin gFrontEnd )
				)
				( attribute "CHIPS_PART_NAME" "CAP_A"
					( Origin gPackager )
				)
				( attribute "CDS_PART_NAME" "CAP_A_0402V-0.1UF,16V,10%,X7R,A"
					( Origin gPackager )
				)
				( objectStatus "C2T25" )
			)
			( gate "@baseboard_fab2_lib.baseboard_fab2(sch_1):page101_i112"
				( attribute "BOM_COST" "SM_CONTROLLER"
					( Origin gFrontEnd )
				)
				( attribute "CDS_LIB" "dev_discrete"
					( Origin gPackager )
				)
				( attribute "CDS_LOCATION" "C2T17"
					( Origin gPackager )
				)
				( attribute "CDS_SEC" "1"
					( Origin gPackager )
				)
				( attribute "LOCATION" "C2T17"
					( Origin gFrontEnd )
				)
				( attribute "MATERIAL" "X7R"
					( Origin gFrontEnd )
				)
				( attribute "PACK_TYPE" "0402V"
					( Origin gFrontEnd )
				)
				( attribute "PART_NUMBER" "A36096-030"
					( Origin gFrontEnd )
				)
				( attribute "PHYS_PAGE" "101"
					( Origin gFrontEnd )
				)
				( attribute "ROOM" "SYS_CLOCK"
					( Origin gFrontEnd )
				)
				( attribute "ROT" "0"
					( Origin gFrontEnd )
				)
				( attribute "SEC" "1"
					( Origin gPackager )
				)
				( attribute "TOLERANCE" "10%"
					( Origin gFrontEnd )
				)
				( attribute "VALUE" "0.1UF"
					( Origin gFrontEnd )
				)
				( attribute "VER" "1"
					( Origin gFrontEnd )
				)
				( attribute "VOLTAGE" "16V"
					( Units "uVoltage" "V" 1.000000)
					( Origin gFrontEnd )
				)
				( attribute "XY" "(-7600,3975)"
					( Origin gFrontEnd )
				)
				( attribute "CHIPS_PART_NAME" "CAP_A"
					( Origin gPackager )
				)
				( attribute "CDS_PART_NAME" "CAP_A_0402V-0.1UF,16V,10%,X7R,A"
					( Origin gPackager )
				)
				( objectStatus "C2T17" )
			)
			( gate "@baseboard_fab2_lib.baseboard_fab2(sch_1):page101_i113"
				( attribute "BOM_COST" "SM_CONTROLLER"
					( Origin gFrontEnd )
				)
				( attribute "CDS_LIB" "mstr_discrete"
					( Origin gPackager )
				)
				( attribute "CDS_LOCATION" "C2T22"
					( Origin gPackager )
				)
				( attribute "CDS_SEC" "1"
					( Origin gPackager )
				)
				( attribute "LOCATION" "C2T22"
					( Origin gFrontEnd )
				)
				( attribute "MATERIAL" "X6S"
					( Origin gFrontEnd )
				)
				( attribute "PACK_TYPE" "0805"
					( Origin gFrontEnd )
				)
				( attribute "PART_NUMBER" "C95333-007"
					( Origin gFrontEnd )
				)
				( attribute "PHYS_PAGE" "101"
					( Origin gFrontEnd )
				)
				( attribute "ROOM" "SYS_CLOCK"
					( Origin gFrontEnd )
				)
				( attribute "ROT" "0"
					( Origin gFrontEnd )
				)
				( attribute "SEC" "1"
					( Origin gFrontEnd )
				)
				( attribute "SEC_TYPE" "0805"
					( Origin gFrontEnd )
				)
				( attribute "TOLERANCE" "10%"
					( Origin gFrontEnd )
				)
				( attribute "VALUE" "10UF"
					( Origin gFrontEnd )
				)
				( attribute "VER" "1"
					( Origin gFrontEnd )
				)
				( attribute "VOLTAGE" "16V"
					( Units "uVoltage" "V" 1.000000)
					( Origin gFrontEnd )
				)
				( attribute "XY" "(-7900,3975)"
					( Origin gFrontEnd )
				)
				( attribute "CHIPS_PART_NAME" "CAP"
					( Origin gPackager )
				)
				( attribute "CDS_PART_NAME" "CAP_0805-10UF,16V,10%,X6S,C953A"
					( Origin gPackager )
				)
				( objectStatus "C2T22" )
			)
			( gate "@baseboard_fab2_lib.baseboard_fab2(sch_1):page101_i114"
				( attribute "BOM_COST" "SM_CONTROLLER"
					( Origin gFrontEnd )
				)
				( attribute "CDS_LIB" "mstr_discrete"
					( Origin gPackager )
				)
				( attribute "CDS_LOCATION" "FB2T2"
					( Origin gPackager )
				)
				( attribute "CDS_SEC" "1"
					( Origin gPackager )
				)
				( attribute "LOCATION" "FB2T2"
					( Origin gFrontEnd )
				)
				( attribute "MATERIAL" "FB"
					( Origin gFrontEnd )
				)
				( attribute "PACK_TYPE" "SMLF"
					( Origin gFrontEnd )
				)
				( attribute "PART_NUMBER" "656554-043"
					( Origin gFrontEnd )
				)
				( attribute "PHYS_PAGE" "101"
					( Origin gFrontEnd )
				)
				( attribute "ROOM" "SYS_CLOCK"
					( Origin gFrontEnd )
				)
				( attribute "ROT" "0"
					( Origin gFrontEnd )
				)
				( attribute "SEC" "1"
					( Origin gPackager )
				)
				( attribute "VALUE" "600"
					( Origin gFrontEnd )
				)
				( attribute "VER" "1"
					( Origin gFrontEnd )
				)
				( attribute "XY" "(-8125,4125)"
					( Origin gFrontEnd )
				)
				( attribute "CHIPS_PART_NAME" "FERRITE"
					( Origin gPackager )
				)
				( attribute "CDS_PART_NAME" "FERRITE_SMLF-600,FB,656554-043"
					( Origin gPackager )
				)
				( objectStatus "FB2T2" )
			)
			( gate "@baseboard_fab2_lib.baseboard_fab2(sch_1):page101_i116"
				( attribute "BOM_COST" "SM_CONTROLLER"
					( Origin gFrontEnd )
				)
				( attribute "CDS_LIB" "dev_discrete"
					( Origin gPackager )
				)
				( attribute "CDS_LOCATION" "C2T28"
					( Origin gPackager )
				)
				( attribute "CDS_SEC" "1"
					( Origin gPackager )
				)
				( attribute "LOCATION" "C2T28"
					( Origin gFrontEnd )
				)
				( attribute "MATERIAL" "X6S"
					( Origin gFrontEnd )
				)
				( attribute "PACK_TYPE" "0402V"
					( Origin gFrontEnd )
				)
				( attribute "PART_NUMBER" "D97712-004"
					( Origin gFrontEnd )
				)
				( attribute "PHYS_PAGE" "101"
					( Origin gFrontEnd )
				)
				( attribute "ROOM" "SYS_CLOCK"
					( Origin gFrontEnd )
				)
				( attribute "ROT" "0"
					( Origin gFrontEnd )
				)
				( attribute "SEC" "1"
					( Origin gPackager )
				)
				( attribute "TOLERANCE" "10%"
					( Origin gFrontEnd )
				)
				( attribute "VALUE" "1.0UF"
					( Origin gFrontEnd )
				)
				( attribute "VER" "1"
					( Origin gFrontEnd )
				)
				( attribute "VOLTAGE" "6.3V"
					( Units "uVoltage" "V" 1.000000)
					( Origin gFrontEnd )
				)
				( attribute "XY" "(-8475,3950)"
					( Origin gFrontEnd )
				)
				( attribute "CHIPS_PART_NAME" "CAP_A"
					( Origin gPackager )
				)
				( attribute "CDS_PART_NAME" "CAP_A_0402V-1.0UF,6.3V,10%,X6SA"
					( Origin gPackager )
				)
				( objectStatus "C2T28" )
			)
			( gate "@baseboard_fab2_lib.baseboard_fab2(sch_1):page101_i124"
				( attribute "BOM_COST" "SM_CONTROLLER"
					( Origin gFrontEnd )
				)
				( attribute "CDS_LIB" "mstr_discrete"
					( Origin gPackager )
				)
				( attribute "CDS_LOCATION" "R2T42"
					( Origin gPackager )
				)
				( attribute "CDS_SEC" "1"
					( Origin gPackager )
				)
				( attribute "LOCATION" "R2T42"
					( Origin gFrontEnd )
				)
				( attribute "MATERIAL" "CHIP"
					( Origin gFrontEnd )
				)
				( attribute "PACK_TYPE" "0402"
					( Origin gFrontEnd )
				)
				( attribute "PART_NUMBER" "G21796-250"
					( Origin gFrontEnd )
				)
				( attribute "PHYS_PAGE" "101"
					( Origin gFrontEnd )
				)
				( attribute "ROOM" "SYS_CLOCK"
					( Origin gFrontEnd )
				)
				( attribute "ROT" "0"
					( Origin gFrontEnd )
				)
				( attribute "SEC" "1"
					( Origin gFrontEnd )
				)
				( attribute "SEC_TYPE" "0402"
					( Origin gFrontEnd )
				)
				( attribute "TOLERANCE" "1.0%"
					( Origin gFrontEnd )
				)
				( attribute "VALUE" "22.1"
					( Origin gFrontEnd )
				)
				( attribute "VER" "1"
					( Origin gFrontEnd )
				)
				( attribute "WATTAGE" "1/16W"
					( Origin gFrontEnd )
				)
				( attribute "XY" "(-3050,1550)"
					( Origin gFrontEnd )
				)
				( attribute "CHIPS_PART_NAME" "RES"
					( Origin gPackager )
				)
				( attribute "CDS_PART_NAME" "RES_0402-22.1,1.0%,1/16W,CHIP,A"
					( Origin gPackager )
				)
				( objectStatus "R2T42" )
			)
			( gate "@baseboard_fab2_lib.baseboard_fab2(sch_1):page101_i125"
				( attribute "BOM_COST" "SM_CONTROLLER"
					( Origin gFrontEnd )
				)
				( attribute "CDS_LIB" "mstr_discrete"
					( Origin gPackager )
				)
				( attribute "CDS_LOCATION" "R2T46"
					( Origin gPackager )
				)
				( attribute "CDS_SEC" "1"
					( Origin gPackager )
				)
				( attribute "LOCATION" "R2T46"
					( Origin gFrontEnd )
				)
				( attribute "MATERIAL" "CHIP"
					( Origin gFrontEnd )
				)
				( attribute "PACK_TYPE" "0402"
					( Origin gFrontEnd )
				)
				( attribute "PART_NUMBER" "G21796-250"
					( Origin gFrontEnd )
				)
				( attribute "PHYS_PAGE" "101"
					( Origin gFrontEnd )
				)
				( attribute "ROOM" "SYS_CLOCK"
					( Origin gFrontEnd )
				)
				( attribute "ROT" "0"
					( Origin gFrontEnd )
				)
				( attribute "SEC" "1"
					( Origin gFrontEnd )
				)
				( attribute "SEC_TYPE" "0402"
					( Origin gFrontEnd )
				)
				( attribute "TOLERANCE" "1.0%"
					( Origin gFrontEnd )
				)
				( attribute "VALUE" "22.1"
					( Origin gFrontEnd )
				)
				( attribute "VER" "1"
					( Origin gFrontEnd )
				)
				( attribute "WATTAGE" "1/16W"
					( Origin gFrontEnd )
				)
				( attribute "XY" "(-3050,1700)"
					( Origin gFrontEnd )
				)
				( attribute "CHIPS_PART_NAME" "RES"
					( Origin gPackager )
				)
				( attribute "CDS_PART_NAME" "RES_0402-22.1,1.0%,1/16W,CHIP,A"
					( Origin gPackager )
				)
				( objectStatus "R2T46" )
			)
			( gate "@baseboard_fab2_lib.baseboard_fab2(sch_1):page101_i143"
				( attribute "BOM_COST" "SM_CONTROLLER"
					( Origin gFrontEnd )
				)
				( attribute "CDS_LIB" "mstr_discrete"
					( Origin gPackager )
				)
				( attribute "CDS_LOCATION" "R8G24"
					( Origin gPackager )
				)
				( attribute "CDS_SEC" "1"
					( Origin gPackager )
				)
				( attribute "LOCATION" "R8G24"
					( Origin gFrontEnd )
				)
				( attribute "MATERIAL" "CHIP"
					( Origin gFrontEnd )
				)
				( attribute "PACK_TYPE" "0402"
					( Origin gFrontEnd )
				)
				( attribute "PART_NUMBER" "G21796-250"
					( Origin gFrontEnd )
				)
				( attribute "PHYS_PAGE" "101"
					( Origin gFrontEnd )
				)
				( attribute "ROOM" "SYS_CLOCK"
					( Origin gFrontEnd )
				)
				( attribute "ROT" "0"
					( Origin gFrontEnd )
				)
				( attribute "SEC" "1"
					( Origin gFrontEnd )
				)
				( attribute "SEC_TYPE" "0402"
					( Origin gFrontEnd )
				)
				( attribute "TOLERANCE" "1.0%"
					( Origin gFrontEnd )
				)
				( attribute "VALUE" "22.1"
					( Origin gFrontEnd )
				)
				( attribute "VER" "1"
					( Origin gFrontEnd )
				)
				( attribute "WATTAGE" "1/16W"
					( Origin gFrontEnd )
				)
				( attribute "XY" "(-3050,2150)"
					( Origin gFrontEnd )
				)
				( attribute "CHIPS_PART_NAME" "RES"
					( Origin gPackager )
				)
				( attribute "CDS_PART_NAME" "RES_0402-22.1,1.0%,1/16W,CHIP,A"
					( Origin gPackager )
				)
				( objectStatus "R8G24" )
			)
			( gate "@baseboard_fab2_lib.baseboard_fab2(sch_1):page101_i130"
				( attribute "BOM_COST" "SM_CONTROLLER"
					( Origin gFrontEnd )
				)
				( attribute "CDS_LIB" "mstr_discrete"
					( Origin gPackager )
				)
				( attribute "CDS_LOCATION" "R2T47"
					( Origin gPackager )
				)
				( attribute "CDS_SEC" "1"
					( Origin gPackager )
				)
				( attribute "LOCATION" "R2T47"
					( Origin gFrontEnd )
				)
				( attribute "MATERIAL" "CHIP"
					( Origin gFrontEnd )
				)
				( attribute "PACK_TYPE" "0402"
					( Origin gFrontEnd )
				)
				( attribute "PART_NUMBER" "G21796-074"
					( Origin gFrontEnd )
				)
				( attribute "PHYS_PAGE" "101"
					( Origin gFrontEnd )
				)
				( attribute "ROOM" "SYS_CLOCK"
					( Origin gFrontEnd )
				)
				( attribute "ROT" "0"
					( Origin gFrontEnd )
				)
				( attribute "SEC" "1"
					( Origin gFrontEnd )
				)
				( attribute "SEC_TYPE" "0402"
					( Origin gFrontEnd )
				)
				( attribute "TOLERANCE" "1%"
					( Origin gFrontEnd )
				)
				( attribute "VALUE" "33.2"
					( Origin gFrontEnd )
				)
				( attribute "VER" "1"
					( Origin gFrontEnd )
				)
				( attribute "WATTAGE" "1/16W"
					( Origin gFrontEnd )
				)
				( attribute "XY" "(-3050,2600)"
					( Origin gFrontEnd )
				)
				( attribute "CHIPS_PART_NAME" "RES"
					( Origin gPackager )
				)
				( attribute "CDS_PART_NAME" "RES_0402-33.2,1%,1/16W,CHIP,G2A"
					( Origin gPackager )
				)
				( objectStatus "R2T47" )
			)
			( gate "@baseboard_fab2_lib.baseboard_fab2(sch_1):page102_i1"
				( attribute "BOM_COST" "SYS_CLOCK"
					( Origin gFrontEnd )
				)
				( attribute "CDS_LIB" "mstr_clock"
					( Origin gPackager )
				)
				( attribute "CDS_LMAN_SYM_OUTLINE" "-600,1000,600,-1000"
					( Origin gPackager )
				)
				( attribute "CDS_LOCATION" "EU4D2"
					( Origin gPackager )
				)
				( attribute "CDS_SEC" "1"
					( Origin gPackager )
				)
				( attribute "LOCATION" "EU4D2"
					( Origin gFrontEnd )
				)
				( attribute "MATERIAL" "IC"
					( Origin gFrontEnd )
				)
				( attribute "PACK_TYPE" "LCC"
					( Origin gFrontEnd )
				)
				( attribute "PART_NUMBER" "H13585-001"
					( Origin gFrontEnd )
				)
				( attribute "PHYS_PAGE" "102"
					( Origin gFrontEnd )
				)
				( attribute "ROOM" "DB1200ZL"
					( Origin gFrontEnd )
				)
				( attribute "ROT" "0"
					( Origin gFrontEnd )
				)
				( attribute "SEC" "1"
					( Origin gFrontEnd )
				)
				( attribute "SEC_TYPE" "LCC"
					( Origin gFrontEnd )
				)
				( attribute "VER" "1"
					( Origin gFrontEnd )
				)
				( attribute "XY" "(350,2900)"
					( Origin gFrontEnd )
				)
				( attribute "CHIPS_PART_NAME" "NB3W1200L"
					( Origin gPackager )
				)
				( attribute "CDS_PART_NAME" "NB3W1200L_LCC-IC,H13585-001"
					( Origin gPackager )
				)
				( objectStatus "EU4D2" )
			)
			( gate "@baseboard_fab2_lib.baseboard_fab2(sch_1):page102_i8"
				( attribute "BOM_COST" "SYS_CLOCK"
					( Origin gFrontEnd )
				)
				( attribute "CDS_LIB" "mstr_discrete"
					( Origin gPackager )
				)
				( attribute "CDS_LOCATION" "FB6P1"
					( Origin gPackager )
				)
				( attribute "CDS_SEC" "1"
					( Origin gPackager )
				)
				( attribute "LOCATION" "FB6P1"
					( Origin gFrontEnd )
				)
				( attribute "MATERIAL" "FB"
					( Origin gFrontEnd )
				)
				( attribute "PACK_TYPE" "SMLF"
					( Origin gFrontEnd )
				)
				( attribute "PART_NUMBER" "656554-043"
					( Origin gFrontEnd )
				)
				( attribute "PHYS_PAGE" "102"
					( Origin gFrontEnd )
				)
				( attribute "ROOM" "DB1200ZL"
					( Origin gFrontEnd )
				)
				( attribute "ROT" "0"
					( Origin gFrontEnd )
				)
				( attribute "SEC" "1"
					( Origin gFrontEnd )
				)
				( attribute "SEC_TYPE" "SMLF"
					( Origin gFrontEnd )
				)
				( attribute "VALUE" "600"
					( Origin gFrontEnd )
				)
				( attribute "VER" "1"
					( Origin gFrontEnd )
				)
				( attribute "XY" "(1700,1125)"
					( Origin gFrontEnd )
				)
				( attribute "CHIPS_PART_NAME" "FERRITE"
					( Origin gPackager )
				)
				( attribute "CDS_PART_NAME" "FERRITE_SMLF-600,FB,656554-043"
					( Origin gPackager )
				)
				( objectStatus "FB6P1" )
			)
			( gate "@baseboard_fab2_lib.baseboard_fab2(sch_1):page102_i10"
				( attribute "BOM_COST" "SYS_CLOCK"
					( Origin gFrontEnd )
				)
				( attribute "CDS_LIB" "mstr_discrete"
					( Origin gPackager )
				)
				( attribute "CDS_LOCATION" "C3D22"
					( Origin gPackager )
				)
				( attribute "CDS_SEC" "1"
					( Origin gPackager )
				)
				( attribute "LOCATION" "C3D22"
					( Origin gFrontEnd )
				)
				( attribute "MATERIAL" "X7R"
					( Origin gFrontEnd )
				)
				( attribute "PACK_TYPE" "0805"
					( Origin gFrontEnd )
				)
				( attribute "PART_NUMBER" "G10601-001"
					( Origin gFrontEnd )
				)
				( attribute "PHYS_PAGE" "102"
					( Origin gFrontEnd )
				)
				( attribute "ROOM" "DB1200ZL"
					( Origin gFrontEnd )
				)
				( attribute "ROT" "0"
					( Origin gFrontEnd )
				)
				( attribute "SEC" "1"
					( Origin gFrontEnd )
				)
				( attribute "SEC_TYPE" "0805"
					( Origin gFrontEnd )
				)
				( attribute "TOLERANCE" "10%"
					( Origin gFrontEnd )
				)
				( attribute "VALUE" "10UF"
					( Origin gFrontEnd )
				)
				( attribute "VER" "1"
					( Origin gFrontEnd )
				)
				( attribute "VOLTAGE" "16V"
					( Units "uVoltage" "V" 1.000000)
					( Origin gFrontEnd )
				)
				( attribute "XY" "(1975,900)"
					( Origin gFrontEnd )
				)
				( attribute "CHIPS_PART_NAME" "CAP"
					( Origin gPackager )
				)
				( attribute "CDS_PART_NAME" "CAP_0805-10UF,16V,10%,X7R,G106A"
					( Origin gPackager )
				)
				( objectStatus "C3D22" )
			)
			( gate "@baseboard_fab2_lib.baseboard_fab2(sch_1):page102_i11"
				( attribute "BOM_COST" "SYS_CLOCK"
					( Origin gFrontEnd )
				)
				( attribute "CDS_LIB" "dev_discrete"
					( Origin gPackager )
				)
				( attribute "CDS_LOCATION" "C6P4"
					( Origin gPackager )
				)
				( attribute "CDS_SEC" "1"
					( Origin gPackager )
				)
				( attribute "LOCATION" "C6P4"
					( Origin gFrontEnd )
				)
				( attribute "MATERIAL" "X7R"
					( Origin gFrontEnd )
				)
				( attribute "PACK_TYPE" "0402V"
					( Origin gFrontEnd )
				)
				( attribute "PART_NUMBER" "A36096-030"
					( Origin gFrontEnd )
				)
				( attribute "PHYS_PAGE" "102"
					( Origin gFrontEnd )
				)
				( attribute "ROOM" "DB1200ZL"
					( Origin gFrontEnd )
				)
				( attribute "ROT" "0"
					( Origin gFrontEnd )
				)
				( attribute "SEC" "1"
					( Origin gFrontEnd )
				)
				( attribute "SEC_TYPE" "0402V"
					( Origin gFrontEnd )
				)
				( attribute "TOLERANCE" "10%"
					( Origin gFrontEnd )
				)
				( attribute "VALUE" "0.1UF"
					( Origin gFrontEnd )
				)
				( attribute "VER" "1"
					( Origin gFrontEnd )
				)
				( attribute "VOLTAGE" "16V"
					( Units "uVoltage" "V" 1.000000)
					( Origin gFrontEnd )
				)
				( attribute "XY" "(2575,900)"
					( Origin gFrontEnd )
				)
				( attribute "CHIPS_PART_NAME" "CAP_A"
					( Origin gPackager )
				)
				( attribute "CDS_PART_NAME" "CAP_A_0402V-0.1UF,16V,10%,X7R,A"
					( Origin gPackager )
				)
				( objectStatus "C6P4" )
			)
			( gate "@baseboard_fab2_lib.baseboard_fab2(sch_1):page102_i12"
				( attribute "BOM_COST" "SYS_CLOCK"
					( Origin gFrontEnd )
				)
				( attribute "CDS_LIB" "dev_discrete"
					( Origin gPackager )
				)
				( attribute "CDS_LOCATION" "C6P6"
					( Origin gPackager )
				)
				( attribute "CDS_SEC" "1"
					( Origin gPackager )
				)
				( attribute "LOCATION" "C6P6"
					( Origin gFrontEnd )
				)
				( attribute "MATERIAL" "X7R"
					( Origin gFrontEnd )
				)
				( attribute "PACK_TYPE" "0402V"
					( Origin gFrontEnd )
				)
				( attribute "PART_NUMBER" "A36096-030"
					( Origin gFrontEnd )
				)
				( attribute "PHYS_PAGE" "102"
					( Origin gFrontEnd )
				)
				( attribute "ROOM" "DB1200ZL"
					( Origin gFrontEnd )
				)
				( attribute "ROT" "0"
					( Origin gFrontEnd )
				)
				( attribute "SEC" "1"
					( Origin gFrontEnd )
				)
				( attribute "SEC_TYPE" "0402V"
					( Origin gFrontEnd )
				)
				( attribute "TOLERANCE" "10%"
					( Origin gFrontEnd )
				)
				( attribute "VALUE" "0.1UF"
					( Origin gFrontEnd )
				)
				( attribute "VER" "1"
					( Origin gFrontEnd )
				)
				( attribute "VOLTAGE" "16V"
					( Units "uVoltage" "V" 1.000000)
					( Origin gFrontEnd )
				)
				( attribute "XY" "(2825,900)"
					( Origin gFrontEnd )
				)
				( attribute "CHIPS_PART_NAME" "CAP_A"
					( Origin gPackager )
				)
				( attribute "CDS_PART_NAME" "CAP_A_0402V-0.1UF,16V,10%,X7R,A"
					( Origin gPackager )
				)
				( objectStatus "C6P6" )
			)
			( gate "@baseboard_fab2_lib.baseboard_fab2(sch_1):page102_i13"
				( attribute "BOM_COST" "SYS_CLOCK"
					( Origin gFrontEnd )
				)
				( attribute "CDS_LIB" "dev_discrete"
					( Origin gPackager )
				)
				( attribute "CDS_LOCATION" "C6P10"
					( Origin gPackager )
				)
				( attribute "CDS_SEC" "1"
					( Origin gPackager )
				)
				( attribute "LOCATION" "C6P10"
					( Origin gFrontEnd )
				)
				( attribute "MATERIAL" "X7R"
					( Origin gFrontEnd )
				)
				( attribute "PACK_TYPE" "0402V"
					( Origin gFrontEnd )
				)
				( attribute "PART_NUMBER" "A36096-030"
					( Origin gFrontEnd )
				)
				( attribute "PHYS_PAGE" "102"
					( Origin gFrontEnd )
				)
				( attribute "ROOM" "DB1200ZL"
					( Origin gFrontEnd )
				)
				( attribute "ROT" "0"
					( Origin gFrontEnd )
				)
				( attribute "SEC" "1"
					( Origin gFrontEnd )
				)
				( attribute "SEC_TYPE" "0402V"
					( Origin gFrontEnd )
				)
				( attribute "TOLERANCE" "10%"
					( Origin gFrontEnd )
				)
				( attribute "VALUE" "0.1UF"
					( Origin gFrontEnd )
				)
				( attribute "VER" "1"
					( Origin gFrontEnd )
				)
				( attribute "VOLTAGE" "16V"
					( Units "uVoltage" "V" 1.000000)
					( Origin gFrontEnd )
				)
				( attribute "XY" "(3050,900)"
					( Origin gFrontEnd )
				)
				( attribute "CHIPS_PART_NAME" "CAP_A"
					( Origin gPackager )
				)
				( attribute "CDS_PART_NAME" "CAP_A_0402V-0.1UF,16V,10%,X7R,A"
					( Origin gPackager )
				)
				( objectStatus "C6P10" )
			)
			( gate "@baseboard_fab2_lib.baseboard_fab2(sch_1):page102_i14"
				( attribute "BOM_COST" "SYS_CLOCK"
					( Origin gFrontEnd )
				)
				( attribute "CDS_LIB" "dev_discrete"
					( Origin gPackager )
				)
				( attribute "CDS_LOCATION" "C6P5"
					( Origin gPackager )
				)
				( attribute "CDS_SEC" "1"
					( Origin gPackager )
				)
				( attribute "LOCATION" "C6P5"
					( Origin gFrontEnd )
				)
				( attribute "MATERIAL" "X7R"
					( Origin gFrontEnd )
				)
				( attribute "PACK_TYPE" "0402V"
					( Origin gFrontEnd )
				)
				( attribute "PART_NUMBER" "A36096-030"
					( Origin gFrontEnd )
				)
				( attribute "PHYS_PAGE" "102"
					( Origin gFrontEnd )
				)
				( attribute "ROOM" "DB1200ZL"
					( Origin gFrontEnd )
				)
				( attribute "ROT" "0"
					( Origin gFrontEnd )
				)
				( attribute "SEC" "1"
					( Origin gFrontEnd )
				)
				( attribute "SEC_TYPE" "0402V"
					( Origin gFrontEnd )
				)
				( attribute "TOLERANCE" "10%"
					( Origin gFrontEnd )
				)
				( attribute "VALUE" "0.1UF"
					( Origin gFrontEnd )
				)
				( attribute "VER" "1"
					( Origin gFrontEnd )
				)
				( attribute "VOLTAGE" "16V"
					( Units "uVoltage" "V" 1.000000)
					( Origin gFrontEnd )
				)
				( attribute "XY" "(3275,900)"
					( Origin gFrontEnd )
				)
				( attribute "CHIPS_PART_NAME" "CAP_A"
					( Origin gPackager )
				)
				( attribute "CDS_PART_NAME" "CAP_A_0402V-0.1UF,16V,10%,X7R,A"
					( Origin gPackager )
				)
				( objectStatus "C6P5" )
			)
			( gate "@baseboard_fab2_lib.baseboard_fab2(sch_1):page102_i15"
				( attribute "BOM_COST" "SYS_CLOCK"
					( Origin gFrontEnd )
				)
				( attribute "CDS_LIB" "dev_discrete"
					( Origin gPackager )
				)
				( attribute "CDS_LOCATION" "C6P12"
					( Origin gPackager )
				)
				( attribute "CDS_SEC" "1"
					( Origin gPackager )
				)
				( attribute "LOCATION" "C6P12"
					( Origin gFrontEnd )
				)
				( attribute "MATERIAL" "X7R"
					( Origin gFrontEnd )
				)
				( attribute "PACK_TYPE" "0402V"
					( Origin gFrontEnd )
				)
				( attribute "PART_NUMBER" "A36096-030"
					( Origin gFrontEnd )
				)
				( attribute "PHYS_PAGE" "102"
					( Origin gFrontEnd )
				)
				( attribute "ROOM" "DB1200ZL"
					( Origin gFrontEnd )
				)
				( attribute "ROT" "0"
					( Origin gFrontEnd )
				)
				( attribute "SEC" "1"
					( Origin gFrontEnd )
				)
				( attribute "SEC_TYPE" "0402V"
					( Origin gFrontEnd )
				)
				( attribute "TOLERANCE" "10%"
					( Origin gFrontEnd )
				)
				( attribute "VALUE" "0.1UF"
					( Origin gFrontEnd )
				)
				( attribute "VER" "1"
					( Origin gFrontEnd )
				)
				( attribute "VOLTAGE" "16V"
					( Units "uVoltage" "V" 1.000000)
					( Origin gFrontEnd )
				)
				( attribute "XY" "(3475,900)"
					( Origin gFrontEnd )
				)
				( attribute "CHIPS_PART_NAME" "CAP_A"
					( Origin gPackager )
				)
				( attribute "CDS_PART_NAME" "CAP_A_0402V-0.1UF,16V,10%,X7R,A"
					( Origin gPackager )
				)
				( objectStatus "C6P12" )
			)
			( gate "@baseboard_fab2_lib.baseboard_fab2(sch_1):page102_i16"
				( attribute "BOM_COST" "SYS_CLOCK"
					( Origin gFrontEnd )
				)
				( attribute "CDS_LIB" "dev_discrete"
					( Origin gPackager )
				)
				( attribute "CDS_LOCATION" "C6P11"
					( Origin gPackager )
				)
				( attribute "CDS_SEC" "1"
					( Origin gPackager )
				)
				( attribute "LOCATION" "C6P11"
					( Origin gFrontEnd )
				)
				( attribute "MATERIAL" "X7R"
					( Origin gFrontEnd )
				)
				( attribute "PACK_TYPE" "0402V"
					( Origin gFrontEnd )
				)
				( attribute "PART_NUMBER" "A36096-030"
					( Origin gFrontEnd )
				)
				( attribute "PHYS_PAGE" "102"
					( Origin gFrontEnd )
				)
				( attribute "ROOM" "DB1200ZL"
					( Origin gFrontEnd )
				)
				( attribute "ROT" "0"
					( Origin gFrontEnd )
				)
				( attribute "SEC" "1"
					( Origin gFrontEnd )
				)
				( attribute "SEC_TYPE" "0402V"
					( Origin gFrontEnd )
				)
				( attribute "TOLERANCE" "10%"
					( Origin gFrontEnd )
				)
				( attribute "VALUE" "0.1UF"
					( Origin gFrontEnd )
				)
				( attribute "VER" "1"
					( Origin gFrontEnd )
				)
				( attribute "VOLTAGE" "16V"
					( Units "uVoltage" "V" 1.000000)
					( Origin gFrontEnd )
				)
				( attribute "XY" "(3700,900)"
					( Origin gFrontEnd )
				)
				( attribute "CHIPS_PART_NAME" "CAP_A"
					( Origin gPackager )
				)
				( attribute "CDS_PART_NAME" "CAP_A_0402V-0.1UF,16V,10%,X7R,A"
					( Origin gPackager )
				)
				( objectStatus "C6P11" )
			)
			( gate "@baseboard_fab2_lib.baseboard_fab2(sch_1):page102_i18"
				( attribute "BOM_COST" "SYS_CLOCK"
					( Origin gFrontEnd )
				)
				( attribute "CDS_LIB" "dev_discrete"
					( Origin gPackager )
				)
				( attribute "CDS_LOCATION" "C4D24"
					( Origin gPackager )
				)
				( attribute "CDS_SEC" "1"
					( Origin gPackager )
				)
				( attribute "LOCATION" "C4D24"
					( Origin gFrontEnd )
				)
				( attribute "MATERIAL" "X7R"
					( Origin gFrontEnd )
				)
				( attribute "PACK_TYPE" "0402V"
					( Origin gFrontEnd )
				)
				( attribute "PART_NUMBER" "A36096-030"
					( Origin gFrontEnd )
				)
				( attribute "PHYS_PAGE" "102"
					( Origin gFrontEnd )
				)
				( attribute "ROOM" "DB1200ZL"
					( Origin gFrontEnd )
				)
				( attribute "ROT" "0"
					( Origin gFrontEnd )
				)
				( attribute "SEC" "1"
					( Origin gFrontEnd )
				)
				( attribute "SEC_TYPE" "0402V"
					( Origin gFrontEnd )
				)
				( attribute "TOLERANCE" "10%"
					( Origin gFrontEnd )
				)
				( attribute "VALUE" "0.1UF"
					( Origin gFrontEnd )
				)
				( attribute "VER" "1"
					( Origin gFrontEnd )
				)
				( attribute "VOLTAGE" "16V"
					( Units "uVoltage" "V" 1.000000)
					( Origin gFrontEnd )
				)
				( attribute "XY" "(-1550,3900)"
					( Origin gFrontEnd )
				)
				( attribute "CHIPS_PART_NAME" "CAP_A"
					( Origin gPackager )
				)
				( attribute "CDS_PART_NAME" "CAP_A_0402V-0.1UF,16V,10%,X7R,A"
					( Origin gPackager )
				)
				( objectStatus "C4D24" )
			)
			( gate "@baseboard_fab2_lib.baseboard_fab2(sch_1):page102_i19"
				( attribute "BOM_COST" "SYS_CLOCK"
					( Origin gFrontEnd )
				)
				( attribute "CDS_LIB" "dev_discrete"
					( Origin gPackager )
				)
				( attribute "CDS_LOCATION" "C4D23"
					( Origin gPackager )
				)
				( attribute "CDS_SEC" "1"
					( Origin gPackager )
				)
				( attribute "LOCATION" "C4D23"
					( Origin gFrontEnd )
				)
				( attribute "MATERIAL" "X6S"
					( Origin gFrontEnd )
				)
				( attribute "PACK_TYPE" "0402V"
					( Origin gFrontEnd )
				)
				( attribute "PART_NUMBER" "D97712-004"
					( Origin gFrontEnd )
				)
				( attribute "PHYS_PAGE" "102"
					( Origin gFrontEnd )
				)
				( attribute "ROOM" "DB1200ZL"
					( Origin gFrontEnd )
				)
				( attribute "ROT" "0"
					( Origin gFrontEnd )
				)
				( attribute "SEC" "1"
					( Origin gFrontEnd )
				)
				( attribute "SEC_TYPE" "0402V"
					( Origin gFrontEnd )
				)
				( attribute "TOLERANCE" "10%"
					( Origin gFrontEnd )
				)
				( attribute "VALUE" "1.0UF"
					( Origin gFrontEnd )
				)
				( attribute "VER" "1"
					( Origin gFrontEnd )
				)
				( attribute "VOLTAGE" "6.3V"
					( Units "uVoltage" "V" 1.000000)
					( Origin gFrontEnd )
				)
				( attribute "XY" "(-1800,3900)"
					( Origin gFrontEnd )
				)
				( attribute "CHIPS_PART_NAME" "CAP_A"
					( Origin gPackager )
				)
				( attribute "CDS_PART_NAME" "CAP_A_0402V-1.0UF,6.3V,10%,X6SA"
					( Origin gPackager )
				)
				( objectStatus "C4D23" )
			)
			( gate "@baseboard_fab2_lib.baseboard_fab2(sch_1):page102_i21"
				( attribute "BOM_COST" "SYS_CLOCK"
					( Origin gFrontEnd )
				)
				( attribute "CDS_LIB" "mstr_discrete"
					( Origin gPackager )
				)
				( attribute "CDS_LOCATION" "R3D14"
					( Origin gPackager )
				)
				( attribute "CDS_SEC" "1"
					( Origin gPackager )
				)
				( attribute "LOCATION" "R3D14"
					( Origin gFrontEnd )
				)
				( attribute "MATERIAL" "CHIP"
					( Origin gFrontEnd )
				)
				( attribute "PACK_TYPE" "0603"
					( Origin gFrontEnd )
				)
				( attribute "PART_NUMBER" "G22026-127"
					( Origin gFrontEnd )
				)
				( attribute "PHYS_PAGE" "102"
					( Origin gFrontEnd )
				)
				( attribute "ROOM" "DB1200ZL"
					( Origin gFrontEnd )
				)
				( attribute "ROT" "0"
					( Origin gFrontEnd )
				)
				( attribute "SEC" "1"
					( Origin gFrontEnd )
				)
				( attribute "SEC_TYPE" "0603"
					( Origin gFrontEnd )
				)
				( attribute "TOLERANCE" "1.0%"
					( Origin gFrontEnd )
				)
				( attribute "VALUE" "2.2"
					( Origin gFrontEnd )
				)
				( attribute "VER" "1"
					( Origin gFrontEnd )
				)
				( attribute "WATTAGE" "1/10W"
					( Origin gFrontEnd )
				)
				( attribute "XY" "(-2425,4125)"
					( Origin gFrontEnd )
				)
				( attribute "CHIPS_PART_NAME" "RES"
					( Origin gPackager )
				)
				( attribute "CDS_PART_NAME" "RES_0603-2.2,1.0%,1/10W,CHIP,GA"
					( Origin gPackager )
				)
				( objectStatus "R3D14" )
			)
			( gate "@baseboard_fab2_lib.baseboard_fab2(sch_1):page102_i26"
				( attribute "BOM_COST" "SYS_CLOCK"
					( Origin gFrontEnd )
				)
				( attribute "CDS_LIB" "mstr_discrete"
					( Origin gPackager )
				)
				( attribute "CDS_LOCATION" "R6P25"
					( Origin gPackager )
				)
				( attribute "CDS_SEC" "1"
					( Origin gPackager )
				)
				( attribute "LOCATION" "R6P25"
					( Origin gFrontEnd )
				)
				( attribute "MATERIAL" "CHIP"
					( Origin gFrontEnd )
				)
				( attribute "PACK_TYPE" "0603"
					( Origin gFrontEnd )
				)
				( attribute "PART_NUMBER" "G22026-127"
					( Origin gFrontEnd )
				)
				( attribute "PHYS_PAGE" "102"
					( Origin gFrontEnd )
				)
				( attribute "ROOM" "DB1200ZL"
					( Origin gFrontEnd )
				)
				( attribute "ROT" "0"
					( Origin gFrontEnd )
				)
				( attribute "SEC" "1"
					( Origin gFrontEnd )
				)
				( attribute "SEC_TYPE" "0603"
					( Origin gFrontEnd )
				)
				( attribute "TOLERANCE" "1.0%"
					( Origin gFrontEnd )
				)
				( attribute "VALUE" "2.2"
					( Origin gFrontEnd )
				)
				( attribute "VER" "1"
					( Origin gFrontEnd )
				)
				( attribute "WATTAGE" "1/10W"
					( Origin gFrontEnd )
				)
				( attribute "XY" "(-2825,3400)"
					( Origin gFrontEnd )
				)
				( attribute "CHIPS_PART_NAME" "RES"
					( Origin gPackager )
				)
				( attribute "CDS_PART_NAME" "RES_0603-2.2,1.0%,1/10W,CHIP,GA"
					( Origin gPackager )
				)
				( objectStatus "R6P25" )
			)
			( gate "@baseboard_fab2_lib.baseboard_fab2(sch_1):page102_i28"
				( attribute "BOM_COST" "SYS_CLOCK"
					( Origin gFrontEnd )
				)
				( attribute "CDS_LIB" "dev_discrete"
					( Origin gPackager )
				)
				( attribute "CDS_LOCATION" "C4D22"
					( Origin gPackager )
				)
				( attribute "CDS_SEC" "1"
					( Origin gPackager )
				)
				( attribute "LOCATION" "C4D22"
					( Origin gFrontEnd )
				)
				( attribute "MATERIAL" "X7R"
					( Origin gFrontEnd )
				)
				( attribute "PACK_TYPE" "0402V"
					( Origin gFrontEnd )
				)
				( attribute "PART_NUMBER" "A36096-030"
					( Origin gFrontEnd )
				)
				( attribute "PHYS_PAGE" "102"
					( Origin gFrontEnd )
				)
				( attribute "ROOM" "DB1200ZL"
					( Origin gFrontEnd )
				)
				( attribute "ROT" "0"
					( Origin gFrontEnd )
				)
				( attribute "SEC" "1"
					( Origin gFrontEnd )
				)
				( attribute "SEC_TYPE" "0402V"
					( Origin gFrontEnd )
				)
				( attribute "TOLERANCE" "10%"
					( Origin gFrontEnd )
				)
				( attribute "VALUE" "0.1UF"
					( Origin gFrontEnd )
				)
				( attribute "VER" "1"
					( Origin gFrontEnd )
				)
				( attribute "VOLTAGE" "16V"
					( Units "uVoltage" "V" 1.000000)
					( Origin gFrontEnd )
				)
				( attribute "XY" "(-2325,3225)"
					( Origin gFrontEnd )
				)
				( attribute "CHIPS_PART_NAME" "CAP_A"
					( Origin gPackager )
				)
				( attribute "CDS_PART_NAME" "CAP_A_0402V-0.1UF,16V,10%,X7R,A"
					( Origin gPackager )
				)
				( objectStatus "C4D22" )
			)
			( gate "@baseboard_fab2_lib.baseboard_fab2(sch_1):page102_i30"
				( attribute "BOM_COST" "SYS_CLOCK"
					( Origin gFrontEnd )
				)
				( attribute "CDS_LIB" "dev_discrete"
					( Origin gPackager )
				)
				( attribute "CDS_LOCATION" "C4D27"
					( Origin gPackager )
				)
				( attribute "CDS_SEC" "1"
					( Origin gPackager )
				)
				( attribute "LOCATION" "C4D27"
					( Origin gFrontEnd )
				)
				( attribute "MATERIAL" "X6S"
					( Origin gFrontEnd )
				)
				( attribute "PACK_TYPE" "0402V"
					( Origin gFrontEnd )
				)
				( attribute "PART_NUMBER" "D97712-004"
					( Origin gFrontEnd )
				)
				( attribute "PHYS_PAGE" "102"
					( Origin gFrontEnd )
				)
				( attribute "ROOM" "DB1200ZL"
					( Origin gFrontEnd )
				)
				( attribute "ROT" "0"
					( Origin gFrontEnd )
				)
				( attribute "SEC" "1"
					( Origin gFrontEnd )
				)
				( attribute "SEC_TYPE" "0402V"
					( Origin gFrontEnd )
				)
				( attribute "TOLERANCE" "10%"
					( Origin gFrontEnd )
				)
				( attribute "VALUE" "1.0UF"
					( Origin gFrontEnd )
				)
				( attribute "VER" "1"
					( Origin gFrontEnd )
				)
				( attribute "VOLTAGE" "6.3V"
					( Units "uVoltage" "V" 1.000000)
					( Origin gFrontEnd )
				)
				( attribute "XY" "(-2575,3225)"
					( Origin gFrontEnd )
				)
				( attribute "CHIPS_PART_NAME" "CAP_A"
					( Origin gPackager )
				)
				( attribute "CDS_PART_NAME" "CAP_A_0402V-1.0UF,6.3V,10%,X6SA"
					( Origin gPackager )
				)
				( objectStatus "C4D27" )
			)
			( gate "@baseboard_fab2_lib.baseboard_fab2(sch_1):page102_i37"
				( attribute "BOM_COST" "SYS_CLOCK"
					( Origin gFrontEnd )
				)
				( attribute "CDS_LIB" "mstr_discrete"
					( Origin gPackager )
				)
				( attribute "CDS_LOCATION" "R4D38"
					( Origin gPackager )
				)
				( attribute "CDS_SEC" "1"
					( Origin gPackager )
				)
				( attribute "LOCATION" "R4D38"
					( Origin gFrontEnd )
				)
				( attribute "MATERIAL" "EMPTY"
					( Origin gFrontEnd )
				)
				( attribute "PACK_TYPE" "0402"
					( Origin gFrontEnd )
				)
				( attribute "PART_NUMBER" "G21796-016"
					( Origin gFrontEnd )
				)
				( attribute "PHYS_PAGE" "102"
					( Origin gFrontEnd )
				)
				( attribute "ROOM" "DB1200ZL"
					( Origin gFrontEnd )
				)
				( attribute "ROT" "0"
					( Origin gFrontEnd )
				)
				( attribute "SEC" "1"
					( Origin gFrontEnd )
				)
				( attribute "SEC_TYPE" "0402"
					( Origin gFrontEnd )
				)
				( attribute "TOLERANCE" "1%"
					( Origin gFrontEnd )
				)
				( attribute "VALUE" "10.0K"
					( Origin gFrontEnd )
				)
				( attribute "VER" "2"
					( Origin gFrontEnd )
				)
				( attribute "WATTAGE" "1/16W"
					( Origin gFrontEnd )
				)
				( attribute "XY" "(-2850,2850)"
					( Origin gFrontEnd )
				)
				( attribute "CHIPS_PART_NAME" "RES"
					( Origin gPackager )
				)
				( attribute "CDS_PART_NAME" "RES_0402-10.0K,1%,1/16W,EMPTY,A"
					( Origin gPackager )
				)
				( objectStatus "R4D38" )
			)
			( gate "@baseboard_fab2_lib.baseboard_fab2(sch_1):page102_i38"
				( attribute "BOM_COST" "SYS_CLOCK"
					( Origin gFrontEnd )
				)
				( attribute "CDS_LIB" "mstr_discrete"
					( Origin gPackager )
				)
				( attribute "CDS_LOCATION" "R4D35"
					( Origin gPackager )
				)
				( attribute "CDS_SEC" "1"
					( Origin gPackager )
				)
				( attribute "LOCATION" "R4D35"
					( Origin gFrontEnd )
				)
				( attribute "MATERIAL" "EMPTY"
					( Origin gFrontEnd )
				)
				( attribute "PACK_TYPE" "0402"
					( Origin gFrontEnd )
				)
				( attribute "PART_NUMBER" "G21796-016"
					( Origin gFrontEnd )
				)
				( attribute "PHYS_PAGE" "102"
					( Origin gFrontEnd )
				)
				( attribute "ROOM" "DB1200ZL"
					( Origin gFrontEnd )
				)
				( attribute "ROT" "0"
					( Origin gFrontEnd )
				)
				( attribute "SEC" "1"
					( Origin gFrontEnd )
				)
				( attribute "SEC_TYPE" "0402"
					( Origin gFrontEnd )
				)
				( attribute "TOLERANCE" "1%"
					( Origin gFrontEnd )
				)
				( attribute "VALUE" "10.0K"
					( Origin gFrontEnd )
				)
				( attribute "VER" "2"
					( Origin gFrontEnd )
				)
				( attribute "WATTAGE" "1/16W"
					( Origin gFrontEnd )
				)
				( attribute "XY" "(-3225,2850)"
					( Origin gFrontEnd )
				)
				( attribute "CHIPS_PART_NAME" "RES"
					( Origin gPackager )
				)
				( attribute "CDS_PART_NAME" "RES_0402-10.0K,1%,1/16W,EMPTY,A"
					( Origin gPackager )
				)
				( objectStatus "R4D35" )
			)
			( gate "@baseboard_fab2_lib.baseboard_fab2(sch_1):page102_i45"
				( attribute "BOM_COST" "SYS_CLOCK"
					( Origin gFrontEnd )
				)
				( attribute "CDS_LIB" "mstr_discrete"
					( Origin gPackager )
				)
				( attribute "CDS_LOCATION" "R4D40"
					( Origin gPackager )
				)
				( attribute "CDS_SEC" "1"
					( Origin gPackager )
				)
				( attribute "LOCATION" "R4D40"
					( Origin gFrontEnd )
				)
				( attribute "MATERIAL" "CHIP"
					( Origin gFrontEnd )
				)
				( attribute "PACK_TYPE" "0402"
					( Origin gFrontEnd )
				)
				( attribute "PART_NUMBER" "G21796-072"
					( Origin gFrontEnd )
				)
				( attribute "PHYS_PAGE" "102"
					( Origin gFrontEnd )
				)
				( attribute "ROOM" "DB1200ZL"
					( Origin gFrontEnd )
				)
				( attribute "ROT" "0"
					( Origin gFrontEnd )
				)
				( attribute "SEC" "1"
					( Origin gFrontEnd )
				)
				( attribute "SEC_TYPE" "0402"
					( Origin gFrontEnd )
				)
				( attribute "TOLERANCE" "1%"
					( Origin gFrontEnd )
				)
				( attribute "VALUE" "4.75K"
					( Origin gFrontEnd )
				)
				( attribute "VER" "2"
					( Origin gFrontEnd )
				)
				( attribute "WATTAGE" "1/16W"
					( Origin gFrontEnd )
				)
				( attribute "XY" "(-2675,1425)"
					( Origin gFrontEnd )
				)
				( attribute "CHIPS_PART_NAME" "RES"
					( Origin gPackager )
				)
				( attribute "CDS_PART_NAME" "RES_0402-4.75K,1%,1/16W,CHIP,GA"
					( Origin gPackager )
				)
				( objectStatus "R4D40" )
			)
			( gate "@baseboard_fab2_lib.baseboard_fab2(sch_1):page102_i46"
				( attribute "BOM_COST" "SYS_CLOCK"
					( Origin gFrontEnd )
				)
				( attribute "CDS_LIB" "mstr_discrete"
					( Origin gPackager )
				)
				( attribute "CDS_LOCATION" "R6P23"
					( Origin gPackager )
				)
				( attribute "CDS_SEC" "1"
					( Origin gPackager )
				)
				( attribute "LOCATION" "R6P23"
					( Origin gFrontEnd )
				)
				( attribute "MATERIAL" "EMPTY"
					( Origin gFrontEnd )
				)
				( attribute "PACK_TYPE" "0402"
					( Origin gFrontEnd )
				)
				( attribute "PART_NUMBER" "G21796-072"
					( Origin gFrontEnd )
				)
				( attribute "PHYS_PAGE" "102"
					( Origin gFrontEnd )
				)
				( attribute "ROOM" "DB1200ZL"
					( Origin gFrontEnd )
				)
				( attribute "ROT" "0"
					( Origin gFrontEnd )
				)
				( attribute "SEC" "1"
					( Origin gFrontEnd )
				)
				( attribute "SEC_TYPE" "0402"
					( Origin gFrontEnd )
				)
				( attribute "TOLERANCE" "1%"
					( Origin gFrontEnd )
				)
				( attribute "VALUE" "4.75K"
					( Origin gFrontEnd )
				)
				( attribute "VER" "2"
					( Origin gFrontEnd )
				)
				( attribute "WATTAGE" "1/16W"
					( Origin gFrontEnd )
				)
				( attribute "XY" "(-2675,1025)"
					( Origin gFrontEnd )
				)
				( attribute "CHIPS_PART_NAME" "RES"
					( Origin gPackager )
				)
				( attribute "CDS_PART_NAME" "RES_0402-4.75K,1%,1/16W,EMPTY,A"
					( Origin gPackager )
				)
				( objectStatus "R6P23" )
			)
			( gate "@baseboard_fab2_lib.baseboard_fab2(sch_1):page102_i47"
				( attribute "BOM_COST" "SYS_CLOCK"
					( Origin gFrontEnd )
				)
				( attribute "CDS_LIB" "mstr_discrete"
					( Origin gPackager )
				)
				( attribute "CDS_LOCATION" "R6P22"
					( Origin gPackager )
				)
				( attribute "CDS_SEC" "1"
					( Origin gPackager )
				)
				( attribute "LOCATION" "R6P22"
					( Origin gFrontEnd )
				)
				( attribute "MATERIAL" "EMPTY"
					( Origin gFrontEnd )
				)
				( attribute "PACK_TYPE" "0402"
					( Origin gFrontEnd )
				)
				( attribute "PART_NUMBER" "G21796-072"
					( Origin gFrontEnd )
				)
				( attribute "PHYS_PAGE" "102"
					( Origin gFrontEnd )
				)
				( attribute "ROOM" "DB1200ZL"
					( Origin gFrontEnd )
				)
				( attribute "ROT" "2"
					( Origin gFrontEnd )
				)
				( attribute "SEC" "1"
					( Origin gFrontEnd )
				)
				( attribute "SEC_TYPE" "0402"
					( Origin gFrontEnd )
				)
				( attribute "TOLERANCE" "1%"
					( Origin gFrontEnd )
				)
				( attribute "VALUE" "4.75K"
					( Origin gFrontEnd )
				)
				( attribute "VER" "2"
					( Origin gFrontEnd )
				)
				( attribute "WATTAGE" "1/16W"
					( Origin gFrontEnd )
				)
				( attribute "XY" "(-2925,1025)"
					( Origin gFrontEnd )
				)
				( attribute "CHIPS_PART_NAME" "RES"
					( Origin gPackager )
				)
				( attribute "CDS_PART_NAME" "RES_0402-4.75K,1%,1/16W,EMPTY,A"
					( Origin gPackager )
				)
				( objectStatus "R6P22" )
			)
			( gate "@baseboard_fab2_lib.baseboard_fab2(sch_1):page102_i53"
				( attribute "BOM_COST" "SYS_CLOCK"
					( Origin gFrontEnd )
				)
				( attribute "CDS_LIB" "mstr_discrete"
					( Origin gPackager )
				)
				( attribute "CDS_LOCATION" "R4D41"
					( Origin gPackager )
				)
				( attribute "CDS_SEC" "1"
					( Origin gPackager )
				)
				( attribute "LOCATION" "R4D41"
					( Origin gFrontEnd )
				)
				( attribute "MATERIAL" "CHIP"
					( Origin gFrontEnd )
				)
				( attribute "PACK_TYPE" "0402"
					( Origin gFrontEnd )
				)
				( attribute "PART_NUMBER" "G21796-072"
					( Origin gFrontEnd )
				)
				( attribute "PHYS_PAGE" "102"
					( Origin gFrontEnd )
				)
				( attribute "ROOM" "DB1200ZL"
					( Origin gFrontEnd )
				)
				( attribute "ROT" "2"
					( Origin gFrontEnd )
				)
				( attribute "SEC" "1"
					( Origin gFrontEnd )
				)
				( attribute "SEC_TYPE" "0402"
					( Origin gFrontEnd )
				)
				( attribute "TOLERANCE" "1%"
					( Origin gFrontEnd )
				)
				( attribute "VALUE" "4.75K"
					( Origin gFrontEnd )
				)
				( attribute "VER" "2"
					( Origin gFrontEnd )
				)
				( attribute "WATTAGE" "1/16W"
					( Origin gFrontEnd )
				)
				( attribute "XY" "(-2925,1425)"
					( Origin gFrontEnd )
				)
				( attribute "CHIPS_PART_NAME" "RES"
					( Origin gPackager )
				)
				( attribute "CDS_PART_NAME" "RES_0402-4.75K,1%,1/16W,CHIP,GA"
					( Origin gPackager )
				)
				( objectStatus "R4D41" )
			)
			( gate "@baseboard_fab2_lib.baseboard_fab2(sch_1):page102_i79"
				( attribute "BOM_COST" "SYS_CLOCK"
					( Origin gFrontEnd )
				)
				( attribute "CDS_LIB" "dev_discrete"
					( Origin gPackager )
				)
				( attribute "CDS_LOCATION" "C6P9"
					( Origin gPackager )
				)
				( attribute "CDS_SEC" "1"
					( Origin gPackager )
				)
				( attribute "LOCATION" "C6P9"
					( Origin gFrontEnd )
				)
				( attribute "MATERIAL" "X7R"
					( Origin gFrontEnd )
				)
				( attribute "PACK_TYPE" "0402V"
					( Origin gFrontEnd )
				)
				( attribute "PART_NUMBER" "A36096-030"
					( Origin gFrontEnd )
				)
				( attribute "PHYS_PAGE" "102"
					( Origin gFrontEnd )
				)
				( attribute "ROOM" "DB1200ZL"
					( Origin gFrontEnd )
				)
				( attribute "ROT" "0"
					( Origin gFrontEnd )
				)
				( attribute "SEC" "1"
					( Origin gFrontEnd )
				)
				( attribute "SEC_TYPE" "0402V"
					( Origin gFrontEnd )
				)
				( attribute "TOLERANCE" "10%"
					( Origin gFrontEnd )
				)
				( attribute "VALUE" "0.1UF"
					( Origin gFrontEnd )
				)
				( attribute "VER" "1"
					( Origin gFrontEnd )
				)
				( attribute "VOLTAGE" "16V"
					( Units "uVoltage" "V" 1.000000)
					( Origin gFrontEnd )
				)
				( attribute "XY" "(2275,900)"
					( Origin gFrontEnd )
				)
				( attribute "CHIPS_PART_NAME" "CAP_A"
					( Origin gPackager )
				)
				( attribute "CDS_PART_NAME" "CAP_A_0402V-0.1UF,16V,10%,X7R,A"
					( Origin gPackager )
				)
				( objectStatus "C6P9" )
			)
			( gate "@baseboard_fab2_lib.baseboard_fab2(sch_1):page102_i80"
				( attribute "BOM_COST" "SYS_CLOCK"
					( Origin gFrontEnd )
				)
				( attribute "CDS_LIB" "mstr_discrete"
					( Origin gPackager )
				)
				( attribute "CDS_LOCATION" "R6P21"
					( Origin gPackager )
				)
				( attribute "CDS_SEC" "1"
					( Origin gPackager )
				)
				( attribute "LOCATION" "R6P21"
					( Origin gFrontEnd )
				)
				( attribute "MATERIAL" "CHIP"
					( Origin gFrontEnd )
				)
				( attribute "PACK_TYPE" "0402"
					( Origin gFrontEnd )
				)
				( attribute "PART_NUMBER" "G21796-026"
					( Origin gFrontEnd )
				)
				( attribute "PHYS_PAGE" "102"
					( Origin gFrontEnd )
				)
				( attribute "ROOM" "DB1200ZL"
					( Origin gFrontEnd )
				)
				( attribute "ROT" "0"
					( Origin gFrontEnd )
				)
				( attribute "SEC" "1"
					( Origin gFrontEnd )
				)
				( attribute "SEC_TYPE" "0402"
					( Origin gFrontEnd )
				)
				( attribute "TOLERANCE" "1%"
					( Origin gFrontEnd )
				)
				( attribute "VALUE" "1.00K"
					( Origin gFrontEnd )
				)
				( attribute "VER" "2"
					( Origin gFrontEnd )
				)
				( attribute "WATTAGE" "1/16W"
					( Origin gFrontEnd )
				)
				( attribute "XY" "(-3225,2475)"
					( Origin gFrontEnd )
				)
				( attribute "CHIPS_PART_NAME" "RES"
					( Origin gPackager )
				)
				( attribute "CDS_PART_NAME" "RES_0402-1.00K,1%,1/16W,CHIP,GA"
					( Origin gPackager )
				)
				( objectStatus "R6P21" )
			)
			( gate "@baseboard_fab2_lib.baseboard_fab2(sch_1):page102_i81"
				( attribute "BOM_COST" "SYS_CLOCK"
					( Origin gFrontEnd )
				)
				( attribute "CDS_LIB" "mstr_discrete"
					( Origin gPackager )
				)
				( attribute "CDS_LOCATION" "R6P20"
					( Origin gPackager )
				)
				( attribute "CDS_SEC" "1"
					( Origin gPackager )
				)
				( attribute "LOCATION" "R6P20"
					( Origin gFrontEnd )
				)
				( attribute "MATERIAL" "CHIP"
					( Origin gFrontEnd )
				)
				( attribute "PACK_TYPE" "0402"
					( Origin gFrontEnd )
				)
				( attribute "PART_NUMBER" "G21796-026"
					( Origin gFrontEnd )
				)
				( attribute "PHYS_PAGE" "102"
					( Origin gFrontEnd )
				)
				( attribute "ROOM" "DB1200ZL"
					( Origin gFrontEnd )
				)
				( attribute "ROT" "0"
					( Origin gFrontEnd )
				)
				( attribute "SEC" "1"
					( Origin gFrontEnd )
				)
				( attribute "SEC_TYPE" "0402"
					( Origin gFrontEnd )
				)
				( attribute "TOLERANCE" "1%"
					( Origin gFrontEnd )
				)
				( attribute "VALUE" "1.00K"
					( Origin gFrontEnd )
				)
				( attribute "VER" "2"
					( Origin gFrontEnd )
				)
				( attribute "WATTAGE" "1/16W"
					( Origin gFrontEnd )
				)
				( attribute "XY" "(-2850,2475)"
					( Origin gFrontEnd )
				)
				( attribute "CHIPS_PART_NAME" "RES"
					( Origin gPackager )
				)
				( attribute "CDS_PART_NAME" "RES_0402-1.00K,1%,1/16W,CHIP,GA"
					( Origin gPackager )
				)
				( objectStatus "R6P20" )
			)
			( gate "@baseboard_fab2_lib.baseboard_fab2(sch_1):page102_i105"
				( attribute "CDS_LIB" "mstr_discrete"
					( Origin gPackager )
				)
				( attribute "CDS_LOCATION" "R4W3"
					( Origin gPackager )
				)
				( attribute "CDS_SEC" "1"
					( Origin gPackager )
				)
				( attribute "LOCATION" "R4W3"
					( Origin gFrontEnd )
				)
				( attribute "MATERIAL" "CHIP"
					( Origin gFrontEnd )
				)
				( attribute "PACK_TYPE" "0402"
					( Origin gFrontEnd )
				)
				( attribute "PART_NUMBER" "G21497-013"
					( Origin gFrontEnd )
				)
				( attribute "PHYS_PAGE" "102"
					( Origin gFrontEnd )
				)
				( attribute "ROT" "5"
					( Origin gFrontEnd )
				)
				( attribute "SEC" "1"
					( Origin gFrontEnd )
				)
				( attribute "SEC_TYPE" "0402"
					( Origin gFrontEnd )
				)
				( attribute "TOLERANCE" "5%"
					( Origin gFrontEnd )
				)
				( attribute "VALUE" "3.3K"
					( Origin gFrontEnd )
				)
				( attribute "VER" "1"
					( Origin gFrontEnd )
				)
				( attribute "WATTAGE" "1/16W"
					( Origin gFrontEnd )
				)
				( attribute "XY" "(3300,4750)"
					( Origin gFrontEnd )
				)
				( attribute "CHIPS_PART_NAME" "RES"
					( Origin gPackager )
				)
				( attribute "CDS_PART_NAME" "RES_0402-3.3K,5%,1/16W,CHIP,G2A"
					( Origin gPackager )
				)
				( objectStatus "R4W3" )
			)
			( gate "@baseboard_fab2_lib.baseboard_fab2(sch_1):page102_i102"
				( attribute "BOM_COST" "DEBUG"
					( Origin gFrontEnd )
				)
				( attribute "CDS_LIB" "mstr_discrete"
					( Origin gPackager )
				)
				( attribute "CDS_LOCATION" "Q4W1"
					( Origin gPackager )
				)
				( attribute "CDS_SEC" "1"
					( Origin gPackager )
				)
				( attribute "LOCATION" "Q4W1"
					( Origin gFrontEnd )
				)
				( attribute "MATERIAL" "FET"
					( Origin gFrontEnd )
				)
				( attribute "PACK_TYPE" "SMLF"
					( Origin gFrontEnd )
				)
				( attribute "PART_NUMBER" "D24280-001"
					( Origin gFrontEnd )
				)
				( attribute "PHYS_PAGE" "102"
					( Origin gFrontEnd )
				)
				( attribute "ROOM" "UART_MUX"
					( Origin gFrontEnd )
				)
				( attribute "ROT" "3"
					( Origin gFrontEnd )
				)
				( attribute "SEC" "1"
					( Origin gFrontEnd )
				)
				( attribute "SEC_TYPE" "SMLF"
					( Origin gFrontEnd )
				)
				( attribute "VALUE" "2N7002DW"
					( Origin gFrontEnd )
				)
				( attribute "VER" "5"
					( Origin gFrontEnd )
				)
				( attribute "XY" "(2350,4500)"
					( Origin gFrontEnd )
				)
				( attribute "CHIPS_PART_NAME" "FET_N_DUAL"
					( Origin gPackager )
				)
				( attribute "CDS_PART_NAME" "FET_N_DUAL_SMLF-2N7002DW,FET,DA"
					( Origin gPackager )
				)
				( objectStatus "Q4W1" )
			)
			( gate "@baseboard_fab2_lib.baseboard_fab2(sch_1):page102_i93"
				( attribute "BOM_COST" "SYS_CLOCK"
					( Origin gFrontEnd )
				)
				( attribute "CDS_LIB" "mstr_discrete"
					( Origin gPackager )
				)
				( attribute "CDS_LOCATION" "R4D69"
					( Origin gPackager )
				)
				( attribute "CDS_SEC" "1"
					( Origin gPackager )
				)
				( attribute "LOCATION" "R4D69"
					( Origin gFrontEnd )
				)
				( attribute "MATERIAL" "CHIP"
					( Origin gFrontEnd )
				)
				( attribute "PACK_TYPE" "0402"
					( Origin gFrontEnd )
				)
				( attribute "PART_NUMBER" "G21796-072"
					( Origin gFrontEnd )
				)
				( attribute "PHYS_PAGE" "102"
					( Origin gFrontEnd )
				)
				( attribute "ROOM" "DB1200ZL"
					( Origin gFrontEnd )
				)
				( attribute "ROT" "2"
					( Origin gFrontEnd )
				)
				( attribute "SEC" "1"
					( Origin gFrontEnd )
				)
				( attribute "SEC_TYPE" "0402"
					( Origin gFrontEnd )
				)
				( attribute "SIGNAL_MODEL" "DEFAULT_RESISTOR_47000OHM_2_1"
					( Origin gFrontEnd )
				)
				( attribute "TOLERANCE" "1%"
					( Origin gFrontEnd )
				)
				( attribute "VALUE" "4.75K"
					( Origin gFrontEnd )
				)
				( attribute "VER" "2"
					( Origin gFrontEnd )
				)
				( attribute "WATTAGE" "1/16W"
					( Origin gFrontEnd )
				)
				( attribute "XY" "(-125,1075)"
					( Origin gFrontEnd )
				)
				( attribute "CHIPS_PART_NAME" "RES"
					( Origin gPackager )
				)
				( attribute "CDS_PART_NAME" "RES_0402-4.75K,1%,1/16W,CHIP,GA"
					( Origin gPackager )
				)
				( objectStatus "R4D69" )
			)
			( gate "@baseboard_fab2_lib.baseboard_fab2(sch_1):page102_i94"
				( attribute "BOM_COST" "SYS_CLOCK"
					( Origin gFrontEnd )
				)
				( attribute "CDS_LIB" "mstr_discrete"
					( Origin gPackager )
				)
				( attribute "CDS_LOCATION" "R4D70"
					( Origin gPackager )
				)
				( attribute "CDS_SEC" "1"
					( Origin gPackager )
				)
				( attribute "LOCATION" "R4D70"
					( Origin gFrontEnd )
				)
				( attribute "MATERIAL" "CHIP"
					( Origin gFrontEnd )
				)
				( attribute "PACK_TYPE" "0402"
					( Origin gFrontEnd )
				)
				( attribute "PART_NUMBER" "G21796-072"
					( Origin gFrontEnd )
				)
				( attribute "PHYS_PAGE" "102"
					( Origin gFrontEnd )
				)
				( attribute "ROOM" "DB1200ZL"
					( Origin gFrontEnd )
				)
				( attribute "ROT" "2"
					( Origin gFrontEnd )
				)
				( attribute "SEC" "1"
					( Origin gFrontEnd )
				)
				( attribute "SEC_TYPE" "0402"
					( Origin gFrontEnd )
				)
				( attribute "SIGNAL_MODEL" "DEFAULT_RESISTOR_47000OHM_2_1"
					( Origin gFrontEnd )
				)
				( attribute "TOLERANCE" "1%"
					( Origin gFrontEnd )
				)
				( attribute "VALUE" "4.75K"
					( Origin gFrontEnd )
				)
				( attribute "VER" "2"
					( Origin gFrontEnd )
				)
				( attribute "WATTAGE" "1/16W"
					( Origin gFrontEnd )
				)
				( attribute "XY" "(200,1075)"
					( Origin gFrontEnd )
				)
				( attribute "CHIPS_PART_NAME" "RES"
					( Origin gPackager )
				)
				( attribute "CDS_PART_NAME" "RES_0402-4.75K,1%,1/16W,CHIP,GA"
					( Origin gPackager )
				)
				( objectStatus "R4D70" )
			)
			( gate "@baseboard_fab2_lib.baseboard_fab2(sch_1):page103_i1"
				( attribute "BOM_COST" "SYS_CLOCK"
					( Origin gFrontEnd )
				)
				( attribute "CDS_LIB" "mstr_discrete"
					( Origin gPackager )
				)
				( attribute "CDS_LOCATION" "R4D25"
					( Origin gPackager )
				)
				( attribute "CDS_SEC" "1"
					( Origin gPackager )
				)
				( attribute "LOCATION" "R4D25"
					( Origin gFrontEnd )
				)
				( attribute "MATERIAL" "CHIP"
					( Origin gFrontEnd )
				)
				( attribute "PACK_TYPE" "0402"
					( Origin gFrontEnd )
				)
				( attribute "PART_NUMBER" "G21796-182"
					( Origin gFrontEnd )
				)
				( attribute "PHYS_PAGE" "103"
					( Origin gFrontEnd )
				)
				( attribute "ROOM" "DB1200Z"
					( Origin gFrontEnd )
				)
				( attribute "ROT" "0"
					( Origin gFrontEnd )
				)
				( attribute "SEC" "1"
					( Origin gFrontEnd )
				)
				( attribute "SEC_TYPE" "0402"
					( Origin gFrontEnd )
				)
				( attribute "TOLERANCE" "1%"
					( Origin gFrontEnd )
				)
				( attribute "VALUE" "27.4"
					( Origin gFrontEnd )
				)
				( attribute "VER" "1"
					( Origin gFrontEnd )
				)
				( attribute "WATTAGE" "1/16W"
					( Origin gFrontEnd )
				)
				( attribute "XY" "(300,1250)"
					( Origin gFrontEnd )
				)
				( attribute "CHIPS_PART_NAME" "RES"
					( Origin gPackager )
				)
				( attribute "CDS_PART_NAME" "RES_0402-27.4,1%,1/16W,CHIP,G2A"
					( Origin gPackager )
				)
				( objectStatus "R4D25" )
			)
			( gate "@baseboard_fab2_lib.baseboard_fab2(sch_1):page103_i9"
				( attribute "BOM_COST" "SYS_CLOCK"
					( Origin gFrontEnd )
				)
				( attribute "CDS_LIB" "mstr_discrete"
					( Origin gPackager )
				)
				( attribute "CDS_LOCATION" "R4D23"
					( Origin gPackager )
				)
				( attribute "CDS_SEC" "1"
					( Origin gPackager )
				)
				( attribute "LOCATION" "R4D23"
					( Origin gFrontEnd )
				)
				( attribute "MATERIAL" "CHIP"
					( Origin gFrontEnd )
				)
				( attribute "PACK_TYPE" "0402"
					( Origin gFrontEnd )
				)
				( attribute "PART_NUMBER" "G21796-182"
					( Origin gFrontEnd )
				)
				( attribute "PHYS_PAGE" "103"
					( Origin gFrontEnd )
				)
				( attribute "ROOM" "DB1200Z"
					( Origin gFrontEnd )
				)
				( attribute "ROT" "0"
					( Origin gFrontEnd )
				)
				( attribute "SEC" "1"
					( Origin gFrontEnd )
				)
				( attribute "SEC_TYPE" "0402"
					( Origin gFrontEnd )
				)
				( attribute "TOLERANCE" "1%"
					( Origin gFrontEnd )
				)
				( attribute "VALUE" "27.4"
					( Origin gFrontEnd )
				)
				( attribute "VER" "1"
					( Origin gFrontEnd )
				)
				( attribute "WATTAGE" "1/16W"
					( Origin gFrontEnd )
				)
				( attribute "XY" "(-3925,4900)"
					( Origin gFrontEnd )
				)
				( attribute "CHIPS_PART_NAME" "RES"
					( Origin gPackager )
				)
				( attribute "CDS_PART_NAME" "RES_0402-27.4,1%,1/16W,CHIP,G2A"
					( Origin gPackager )
				)
				( objectStatus "R4D23" )
			)
			( gate "@baseboard_fab2_lib.baseboard_fab2(sch_1):page103_i14"
				( attribute "BOM_COST" "SYS_CLOCK"
					( Origin gFrontEnd )
				)
				( attribute "CDS_LIB" "mstr_discrete"
					( Origin gPackager )
				)
				( attribute "CDS_LOCATION" "R4D28"
					( Origin gPackager )
				)
				( attribute "CDS_SEC" "1"
					( Origin gPackager )
				)
				( attribute "LOCATION" "R4D28"
					( Origin gFrontEnd )
				)
				( attribute "MATERIAL" "CHIP"
					( Origin gFrontEnd )
				)
				( attribute "PACK_TYPE" "0402"
					( Origin gFrontEnd )
				)
				( attribute "PART_NUMBER" "G21796-182"
					( Origin gFrontEnd )
				)
				( attribute "PHYS_PAGE" "103"
					( Origin gFrontEnd )
				)
				( attribute "ROOM" "DB1200Z"
					( Origin gFrontEnd )
				)
				( attribute "ROT" "0"
					( Origin gFrontEnd )
				)
				( attribute "SEC" "1"
					( Origin gFrontEnd )
				)
				( attribute "SEC_TYPE" "0402"
					( Origin gFrontEnd )
				)
				( attribute "TOLERANCE" "1%"
					( Origin gFrontEnd )
				)
				( attribute "VALUE" "27.4"
					( Origin gFrontEnd )
				)
				( attribute "VER" "1"
					( Origin gFrontEnd )
				)
				( attribute "WATTAGE" "1/16W"
					( Origin gFrontEnd )
				)
				( attribute "XY" "(-3925,4525)"
					( Origin gFrontEnd )
				)
				( attribute "CHIPS_PART_NAME" "RES"
					( Origin gPackager )
				)
				( attribute "CDS_PART_NAME" "RES_0402-27.4,1%,1/16W,CHIP,G2A"
					( Origin gPackager )
				)
				( objectStatus "R4D28" )
			)
			( gate "@baseboard_fab2_lib.baseboard_fab2(sch_1):page103_i19"
				( attribute "BOM_COST" "SYS_CLOCK"
					( Origin gFrontEnd )
				)
				( attribute "CDS_LIB" "mstr_discrete"
					( Origin gPackager )
				)
				( attribute "CDS_LOCATION" "R4D19"
					( Origin gPackager )
				)
				( attribute "CDS_SEC" "1"
					( Origin gPackager )
				)
				( attribute "LOCATION" "R4D19"
					( Origin gFrontEnd )
				)
				( attribute "MATERIAL" "CHIP"
					( Origin gFrontEnd )
				)
				( attribute "PACK_TYPE" "0402"
					( Origin gFrontEnd )
				)
				( attribute "PART_NUMBER" "G21796-182"
					( Origin gFrontEnd )
				)
				( attribute "PHYS_PAGE" "103"
					( Origin gFrontEnd )
				)
				( attribute "ROOM" "DB1200Z"
					( Origin gFrontEnd )
				)
				( attribute "ROT" "0"
					( Origin gFrontEnd )
				)
				( attribute "SEC" "1"
					( Origin gFrontEnd )
				)
				( attribute "SEC_TYPE" "0402"
					( Origin gFrontEnd )
				)
				( attribute "TOLERANCE" "1%"
					( Origin gFrontEnd )
				)
				( attribute "VALUE" "27.4"
					( Origin gFrontEnd )
				)
				( attribute "VER" "1"
					( Origin gFrontEnd )
				)
				( attribute "WATTAGE" "1/16W"
					( Origin gFrontEnd )
				)
				( attribute "XY" "(-3925,4175)"
					( Origin gFrontEnd )
				)
				( attribute "CHIPS_PART_NAME" "RES"
					( Origin gPackager )
				)
				( attribute "CDS_PART_NAME" "RES_0402-27.4,1%,1/16W,CHIP,G2A"
					( Origin gPackager )
				)
				( objectStatus "R4D19" )
			)
			( gate "@baseboard_fab2_lib.baseboard_fab2(sch_1):page103_i24"
				( attribute "BOM_COST" "SYS_CLOCK"
					( Origin gFrontEnd )
				)
				( attribute "CDS_LIB" "mstr_discrete"
					( Origin gPackager )
				)
				( attribute "CDS_LOCATION" "R4D21"
					( Origin gPackager )
				)
				( attribute "CDS_SEC" "1"
					( Origin gPackager )
				)
				( attribute "LOCATION" "R4D21"
					( Origin gFrontEnd )
				)
				( attribute "MATERIAL" "CHIP"
					( Origin gFrontEnd )
				)
				( attribute "PACK_TYPE" "0402"
					( Origin gFrontEnd )
				)
				( attribute "PART_NUMBER" "G21796-182"
					( Origin gFrontEnd )
				)
				( attribute "PHYS_PAGE" "103"
					( Origin gFrontEnd )
				)
				( attribute "ROOM" "DB1200Z"
					( Origin gFrontEnd )
				)
				( attribute "ROT" "0"
					( Origin gFrontEnd )
				)
				( attribute "SEC" "1"
					( Origin gFrontEnd )
				)
				( attribute "SEC_TYPE" "0402"
					( Origin gFrontEnd )
				)
				( attribute "TOLERANCE" "1%"
					( Origin gFrontEnd )
				)
				( attribute "VALUE" "27.4"
					( Origin gFrontEnd )
				)
				( attribute "VER" "1"
					( Origin gFrontEnd )
				)
				( attribute "WATTAGE" "1/16W"
					( Origin gFrontEnd )
				)
				( attribute "XY" "(-3925,3850)"
					( Origin gFrontEnd )
				)
				( attribute "CHIPS_PART_NAME" "RES"
					( Origin gPackager )
				)
				( attribute "CDS_PART_NAME" "RES_0402-27.4,1%,1/16W,CHIP,G2A"
					( Origin gPackager )
				)
				( objectStatus "R4D21" )
			)
			( gate "@baseboard_fab2_lib.baseboard_fab2(sch_1):page103_i29"
				( attribute "BOM_COST" "SYS_CLOCK"
					( Origin gFrontEnd )
				)
				( attribute "CDS_LIB" "mstr_discrete"
					( Origin gPackager )
				)
				( attribute "CDS_LOCATION" "R4D13"
					( Origin gPackager )
				)
				( attribute "CDS_SEC" "1"
					( Origin gPackager )
				)
				( attribute "LOCATION" "R4D13"
					( Origin gFrontEnd )
				)
				( attribute "MATERIAL" "CHIP"
					( Origin gFrontEnd )
				)
				( attribute "PACK_TYPE" "0402"
					( Origin gFrontEnd )
				)
				( attribute "PART_NUMBER" "G21796-182"
					( Origin gFrontEnd )
				)
				( attribute "PHYS_PAGE" "103"
					( Origin gFrontEnd )
				)
				( attribute "ROOM" "DB1200Z"
					( Origin gFrontEnd )
				)
				( attribute "ROT" "0"
					( Origin gFrontEnd )
				)
				( attribute "SEC" "1"
					( Origin gFrontEnd )
				)
				( attribute "SEC_TYPE" "0402"
					( Origin gFrontEnd )
				)
				( attribute "TOLERANCE" "1%"
					( Origin gFrontEnd )
				)
				( attribute "VALUE" "27.4"
					( Origin gFrontEnd )
				)
				( attribute "VER" "1"
					( Origin gFrontEnd )
				)
				( attribute "WATTAGE" "1/16W"
					( Origin gFrontEnd )
				)
				( attribute "XY" "(-3925,3525)"
					( Origin gFrontEnd )
				)
				( attribute "CHIPS_PART_NAME" "RES"
					( Origin gPackager )
				)
				( attribute "CDS_PART_NAME" "RES_0402-27.4,1%,1/16W,CHIP,G2A"
					( Origin gPackager )
				)
				( objectStatus "R4D13" )
			)
			( gate "@baseboard_fab2_lib.baseboard_fab2(sch_1):page103_i34"
				( attribute "BOM_COST" "SYS_CLOCK"
					( Origin gFrontEnd )
				)
				( attribute "CDS_LIB" "mstr_discrete"
					( Origin gPackager )
				)
				( attribute "CDS_LOCATION" "R4D16"
					( Origin gPackager )
				)
				( attribute "CDS_SEC" "1"
					( Origin gPackager )
				)
				( attribute "LOCATION" "R4D16"
					( Origin gFrontEnd )
				)
				( attribute "MATERIAL" "CHIP"
					( Origin gFrontEnd )
				)
				( attribute "PACK_TYPE" "0402"
					( Origin gFrontEnd )
				)
				( attribute "PART_NUMBER" "G21796-182"
					( Origin gFrontEnd )
				)
				( attribute "PHYS_PAGE" "103"
					( Origin gFrontEnd )
				)
				( attribute "ROOM" "DB1200Z"
					( Origin gFrontEnd )
				)
				( attribute "ROT" "0"
					( Origin gFrontEnd )
				)
				( attribute "SEC" "1"
					( Origin gFrontEnd )
				)
				( attribute "SEC_TYPE" "0402"
					( Origin gFrontEnd )
				)
				( attribute "TOLERANCE" "1%"
					( Origin gFrontEnd )
				)
				( attribute "VALUE" "27.4"
					( Origin gFrontEnd )
				)
				( attribute "VER" "1"
					( Origin gFrontEnd )
				)
				( attribute "WATTAGE" "1/16W"
					( Origin gFrontEnd )
				)
				( attribute "XY" "(-3925,3200)"
					( Origin gFrontEnd )
				)
				( attribute "CHIPS_PART_NAME" "RES"
					( Origin gPackager )
				)
				( attribute "CDS_PART_NAME" "RES_0402-27.4,1%,1/16W,CHIP,G2A"
					( Origin gPackager )
				)
				( objectStatus "R4D16" )
			)
			( gate "@baseboard_fab2_lib.baseboard_fab2(sch_1):page103_i39"
				( attribute "BOM_COST" "SYS_CLOCK"
					( Origin gFrontEnd )
				)
				( attribute "CDS_LIB" "mstr_discrete"
					( Origin gPackager )
				)
				( attribute "CDS_LOCATION" "R4D9"
					( Origin gPackager )
				)
				( attribute "CDS_SEC" "1"
					( Origin gPackager )
				)
				( attribute "LOCATION" "R4D9"
					( Origin gFrontEnd )
				)
				( attribute "MATERIAL" "CHIP"
					( Origin gFrontEnd )
				)
				( attribute "PACK_TYPE" "0402"
					( Origin gFrontEnd )
				)
				( attribute "PART_NUMBER" "G21796-182"
					( Origin gFrontEnd )
				)
				( attribute "PHYS_PAGE" "103"
					( Origin gFrontEnd )
				)
				( attribute "ROOM" "DB1200Z"
					( Origin gFrontEnd )
				)
				( attribute "ROT" "0"
					( Origin gFrontEnd )
				)
				( attribute "SEC" "1"
					( Origin gFrontEnd )
				)
				( attribute "SEC_TYPE" "0402"
					( Origin gFrontEnd )
				)
				( attribute "TOLERANCE" "1%"
					( Origin gFrontEnd )
				)
				( attribute "VALUE" "27.4"
					( Origin gFrontEnd )
				)
				( attribute "VER" "1"
					( Origin gFrontEnd )
				)
				( attribute "WATTAGE" "1/16W"
					( Origin gFrontEnd )
				)
				( attribute "XY" "(-3925,2875)"
					( Origin gFrontEnd )
				)
				( attribute "CHIPS_PART_NAME" "RES"
					( Origin gPackager )
				)
				( attribute "CDS_PART_NAME" "RES_0402-27.4,1%,1/16W,CHIP,G2A"
					( Origin gPackager )
				)
				( objectStatus "R4D9" )
			)
			( gate "@baseboard_fab2_lib.baseboard_fab2(sch_1):page103_i44"
				( attribute "BOM_COST" "SYS_CLOCK"
					( Origin gFrontEnd )
				)
				( attribute "CDS_LIB" "mstr_discrete"
					( Origin gPackager )
				)
				( attribute "CDS_LOCATION" "R4D11"
					( Origin gPackager )
				)
				( attribute "CDS_SEC" "1"
					( Origin gPackager )
				)
				( attribute "LOCATION" "R4D11"
					( Origin gFrontEnd )
				)
				( attribute "MATERIAL" "CHIP"
					( Origin gFrontEnd )
				)
				( attribute "PACK_TYPE" "0402"
					( Origin gFrontEnd )
				)
				( attribute "PART_NUMBER" "G21796-182"
					( Origin gFrontEnd )
				)
				( attribute "PHYS_PAGE" "103"
					( Origin gFrontEnd )
				)
				( attribute "ROOM" "DB1200Z"
					( Origin gFrontEnd )
				)
				( attribute "ROT" "0"
					( Origin gFrontEnd )
				)
				( attribute "SEC" "1"
					( Origin gFrontEnd )
				)
				( attribute "SEC_TYPE" "0402"
					( Origin gFrontEnd )
				)
				( attribute "TOLERANCE" "1%"
					( Origin gFrontEnd )
				)
				( attribute "VALUE" "27.4"
					( Origin gFrontEnd )
				)
				( attribute "VER" "1"
					( Origin gFrontEnd )
				)
				( attribute "WATTAGE" "1/16W"
					( Origin gFrontEnd )
				)
				( attribute "XY" "(-3925,2550)"
					( Origin gFrontEnd )
				)
				( attribute "CHIPS_PART_NAME" "RES"
					( Origin gPackager )
				)
				( attribute "CDS_PART_NAME" "RES_0402-27.4,1%,1/16W,CHIP,G2A"
					( Origin gPackager )
				)
				( objectStatus "R4D11" )
			)
			( gate "@baseboard_fab2_lib.baseboard_fab2(sch_1):page103_i49"
				( attribute "BOM_COST" "SYS_CLOCK"
					( Origin gFrontEnd )
				)
				( attribute "CDS_LIB" "mstr_discrete"
					( Origin gPackager )
				)
				( attribute "CDS_LOCATION" "R4D2"
					( Origin gPackager )
				)
				( attribute "CDS_SEC" "1"
					( Origin gPackager )
				)
				( attribute "LOCATION" "R4D2"
					( Origin gFrontEnd )
				)
				( attribute "MATERIAL" "CHIP"
					( Origin gFrontEnd )
				)
				( attribute "PACK_TYPE" "0402"
					( Origin gFrontEnd )
				)
				( attribute "PART_NUMBER" "G21796-182"
					( Origin gFrontEnd )
				)
				( attribute "PHYS_PAGE" "103"
					( Origin gFrontEnd )
				)
				( attribute "ROOM" "DB1200Z"
					( Origin gFrontEnd )
				)
				( attribute "ROT" "0"
					( Origin gFrontEnd )
				)
				( attribute "SEC" "1"
					( Origin gPackager )
				)
				( attribute "TOLERANCE" "1%"
					( Origin gFrontEnd )
				)
				( attribute "VALUE" "27.4"
					( Origin gFrontEnd )
				)
				( attribute "VER" "1"
					( Origin gFrontEnd )
				)
				( attribute "WATTAGE" "1/16W"
					( Origin gFrontEnd )
				)
				( attribute "XY" "(-3925,2225)"
					( Origin gFrontEnd )
				)
				( attribute "CHIPS_PART_NAME" "RES"
					( Origin gPackager )
				)
				( attribute "CDS_PART_NAME" "RES_0402-27.4,1%,1/16W,CHIP,G2A"
					( Origin gPackager )
				)
				( objectStatus "R4D2" )
			)
			( gate "@baseboard_fab2_lib.baseboard_fab2(sch_1):page103_i54"
				( attribute "BOM_COST" "SYS_CLOCK"
					( Origin gFrontEnd )
				)
				( attribute "CDS_LIB" "mstr_discrete"
					( Origin gPackager )
				)
				( attribute "CDS_LOCATION" "R4D1"
					( Origin gPackager )
				)
				( attribute "CDS_SEC" "1"
					( Origin gPackager )
				)
				( attribute "LOCATION" "R4D1"
					( Origin gFrontEnd )
				)
				( attribute "MATERIAL" "CHIP"
					( Origin gFrontEnd )
				)
				( attribute "PACK_TYPE" "0402"
					( Origin gFrontEnd )
				)
				( attribute "PART_NUMBER" "G21796-182"
					( Origin gFrontEnd )
				)
				( attribute "PHYS_PAGE" "103"
					( Origin gFrontEnd )
				)
				( attribute "ROOM" "DB1200Z"
					( Origin gFrontEnd )
				)
				( attribute "ROT" "0"
					( Origin gFrontEnd )
				)
				( attribute "SEC" "1"
					( Origin gFrontEnd )
				)
				( attribute "SEC_TYPE" "0402"
					( Origin gFrontEnd )
				)
				( attribute "TOLERANCE" "1%"
					( Origin gFrontEnd )
				)
				( attribute "VALUE" "27.4"
					( Origin gFrontEnd )
				)
				( attribute "VER" "1"
					( Origin gFrontEnd )
				)
				( attribute "WATTAGE" "1/16W"
					( Origin gFrontEnd )
				)
				( attribute "XY" "(-3925,1900)"
					( Origin gFrontEnd )
				)
				( attribute "CHIPS_PART_NAME" "RES"
					( Origin gPackager )
				)
				( attribute "CDS_PART_NAME" "RES_0402-27.4,1%,1/16W,CHIP,G2A"
					( Origin gPackager )
				)
				( objectStatus "R4D1" )
			)
			( gate "@baseboard_fab2_lib.baseboard_fab2(sch_1):page103_i59"
				( attribute "BOM_COST" "SYS_CLOCK"
					( Origin gFrontEnd )
				)
				( attribute "CDS_LIB" "mstr_discrete"
					( Origin gPackager )
				)
				( attribute "CDS_LOCATION" "R4D4"
					( Origin gPackager )
				)
				( attribute "CDS_SEC" "1"
					( Origin gPackager )
				)
				( attribute "LOCATION" "R4D4"
					( Origin gFrontEnd )
				)
				( attribute "MATERIAL" "CHIP"
					( Origin gFrontEnd )
				)
				( attribute "PACK_TYPE" "0402"
					( Origin gFrontEnd )
				)
				( attribute "PART_NUMBER" "G21796-182"
					( Origin gFrontEnd )
				)
				( attribute "PHYS_PAGE" "103"
					( Origin gFrontEnd )
				)
				( attribute "ROOM" "DB1200Z"
					( Origin gFrontEnd )
				)
				( attribute "ROT" "0"
					( Origin gFrontEnd )
				)
				( attribute "SEC" "1"
					( Origin gFrontEnd )
				)
				( attribute "SEC_TYPE" "0402"
					( Origin gFrontEnd )
				)
				( attribute "TOLERANCE" "1%"
					( Origin gFrontEnd )
				)
				( attribute "VALUE" "27.4"
					( Origin gFrontEnd )
				)
				( attribute "VER" "1"
					( Origin gFrontEnd )
				)
				( attribute "WATTAGE" "1/16W"
					( Origin gFrontEnd )
				)
				( attribute "XY" "(-3925,1575)"
					( Origin gFrontEnd )
				)
				( attribute "CHIPS_PART_NAME" "RES"
					( Origin gPackager )
				)
				( attribute "CDS_PART_NAME" "RES_0402-27.4,1%,1/16W,CHIP,G2A"
					( Origin gPackager )
				)
				( objectStatus "R4D4" )
			)
			( gate "@baseboard_fab2_lib.baseboard_fab2(sch_1):page103_i64"
				( attribute "BOM_COST" "SYS_CLOCK"
					( Origin gFrontEnd )
				)
				( attribute "CDS_LIB" "mstr_discrete"
					( Origin gPackager )
				)
				( attribute "CDS_LOCATION" "R4D3"
					( Origin gPackager )
				)
				( attribute "CDS_SEC" "1"
					( Origin gPackager )
				)
				( attribute "LOCATION" "R4D3"
					( Origin gFrontEnd )
				)
				( attribute "MATERIAL" "CHIP"
					( Origin gFrontEnd )
				)
				( attribute "PACK_TYPE" "0402"
					( Origin gFrontEnd )
				)
				( attribute "PART_NUMBER" "G21796-182"
					( Origin gFrontEnd )
				)
				( attribute "PHYS_PAGE" "103"
					( Origin gFrontEnd )
				)
				( attribute "ROOM" "DB1200Z"
					( Origin gFrontEnd )
				)
				( attribute "ROT" "0"
					( Origin gFrontEnd )
				)
				( attribute "SEC" "1"
					( Origin gFrontEnd )
				)
				( attribute "SEC_TYPE" "0402"
					( Origin gFrontEnd )
				)
				( attribute "TOLERANCE" "1%"
					( Origin gFrontEnd )
				)
				( attribute "VALUE" "27.4"
					( Origin gFrontEnd )
				)
				( attribute "VER" "1"
					( Origin gFrontEnd )
				)
				( attribute "WATTAGE" "1/16W"
					( Origin gFrontEnd )
				)
				( attribute "XY" "(-3925,1250)"
					( Origin gFrontEnd )
				)
				( attribute "CHIPS_PART_NAME" "RES"
					( Origin gPackager )
				)
				( attribute "CDS_PART_NAME" "RES_0402-27.4,1%,1/16W,CHIP,G2A"
					( Origin gPackager )
				)
				( objectStatus "R4D3" )
			)
			( gate "@baseboard_fab2_lib.baseboard_fab2(sch_1):page103_i69"
				( attribute "BOM_COST" "SYS_CLOCK"
					( Origin gFrontEnd )
				)
				( attribute "CDS_LIB" "mstr_discrete"
					( Origin gPackager )
				)
				( attribute "CDS_LOCATION" "R4D29"
					( Origin gPackager )
				)
				( attribute "CDS_SEC" "1"
					( Origin gPackager )
				)
				( attribute "LOCATION" "R4D29"
					( Origin gFrontEnd )
				)
				( attribute "MATERIAL" "CHIP"
					( Origin gFrontEnd )
				)
				( attribute "PACK_TYPE" "0402"
					( Origin gFrontEnd )
				)
				( attribute "PART_NUMBER" "G21796-182"
					( Origin gFrontEnd )
				)
				( attribute "PHYS_PAGE" "103"
					( Origin gFrontEnd )
				)
				( attribute "ROOM" "DB1200Z"
					( Origin gFrontEnd )
				)
				( attribute "ROT" "0"
					( Origin gFrontEnd )
				)
				( attribute "SEC" "1"
					( Origin gFrontEnd )
				)
				( attribute "SEC_TYPE" "0402"
					( Origin gFrontEnd )
				)
				( attribute "TOLERANCE" "1%"
					( Origin gFrontEnd )
				)
				( attribute "VALUE" "27.4"
					( Origin gFrontEnd )
				)
				( attribute "VER" "1"
					( Origin gFrontEnd )
				)
				( attribute "WATTAGE" "1/16W"
					( Origin gFrontEnd )
				)
				( attribute "XY" "(300,1575)"
					( Origin gFrontEnd )
				)
				( attribute "CHIPS_PART_NAME" "RES"
					( Origin gPackager )
				)
				( attribute "CDS_PART_NAME" "RES_0402-27.4,1%,1/16W,CHIP,G2A"
					( Origin gPackager )
				)
				( objectStatus "R4D29" )
			)
			( gate "@baseboard_fab2_lib.baseboard_fab2(sch_1):page103_i74"
				( attribute "BOM_COST" "SYS_CLOCK"
					( Origin gFrontEnd )
				)
				( attribute "CDS_LIB" "mstr_discrete"
					( Origin gPackager )
				)
				( attribute "CDS_LOCATION" "R4D6"
					( Origin gPackager )
				)
				( attribute "CDS_SEC" "1"
					( Origin gPackager )
				)
				( attribute "LOCATION" "R4D6"
					( Origin gFrontEnd )
				)
				( attribute "MATERIAL" "CHIP"
					( Origin gFrontEnd )
				)
				( attribute "PACK_TYPE" "0402"
					( Origin gFrontEnd )
				)
				( attribute "PART_NUMBER" "G21796-182"
					( Origin gFrontEnd )
				)
				( attribute "PHYS_PAGE" "103"
					( Origin gFrontEnd )
				)
				( attribute "ROOM" "DB1200Z"
					( Origin gFrontEnd )
				)
				( attribute "ROT" "0"
					( Origin gFrontEnd )
				)
				( attribute "SEC" "1"
					( Origin gFrontEnd )
				)
				( attribute "SEC_TYPE" "0402"
					( Origin gFrontEnd )
				)
				( attribute "TOLERANCE" "1%"
					( Origin gFrontEnd )
				)
				( attribute "VALUE" "27.4"
					( Origin gFrontEnd )
				)
				( attribute "VER" "1"
					( Origin gFrontEnd )
				)
				( attribute "WATTAGE" "1/16W"
					( Origin gFrontEnd )
				)
				( attribute "XY" "(300,4825)"
					( Origin gFrontEnd )
				)
				( attribute "CHIPS_PART_NAME" "RES"
					( Origin gPackager )
				)
				( attribute "CDS_PART_NAME" "RES_0402-27.4,1%,1/16W,CHIP,G2A"
					( Origin gPackager )
				)
				( objectStatus "R4D6" )
			)
			( gate "@baseboard_fab2_lib.baseboard_fab2(sch_1):page103_i79"
				( attribute "BOM_COST" "SYS_CLOCK"
					( Origin gFrontEnd )
				)
				( attribute "CDS_LIB" "mstr_discrete"
					( Origin gPackager )
				)
				( attribute "CDS_LOCATION" "R4D5"
					( Origin gPackager )
				)
				( attribute "CDS_SEC" "1"
					( Origin gPackager )
				)
				( attribute "LOCATION" "R4D5"
					( Origin gFrontEnd )
				)
				( attribute "MATERIAL" "CHIP"
					( Origin gFrontEnd )
				)
				( attribute "PACK_TYPE" "0402"
					( Origin gFrontEnd )
				)
				( attribute "PART_NUMBER" "G21796-182"
					( Origin gFrontEnd )
				)
				( attribute "PHYS_PAGE" "103"
					( Origin gFrontEnd )
				)
				( attribute "ROOM" "DB1200Z"
					( Origin gFrontEnd )
				)
				( attribute "ROT" "0"
					( Origin gFrontEnd )
				)
				( attribute "SEC" "1"
					( Origin gFrontEnd )
				)
				( attribute "SEC_TYPE" "0402"
					( Origin gFrontEnd )
				)
				( attribute "TOLERANCE" "1%"
					( Origin gFrontEnd )
				)
				( attribute "VALUE" "27.4"
					( Origin gFrontEnd )
				)
				( attribute "VER" "1"
					( Origin gFrontEnd )
				)
				( attribute "WATTAGE" "1/16W"
					( Origin gFrontEnd )
				)
				( attribute "XY" "(300,4500)"
					( Origin gFrontEnd )
				)
				( attribute "CHIPS_PART_NAME" "RES"
					( Origin gPackager )
				)
				( attribute "CDS_PART_NAME" "RES_0402-27.4,1%,1/16W,CHIP,G2A"
					( Origin gPackager )
				)
				( objectStatus "R4D5" )
			)
			( gate "@baseboard_fab2_lib.baseboard_fab2(sch_1):page103_i84"
				( attribute "BOM_COST" "SYS_CLOCK"
					( Origin gFrontEnd )
				)
				( attribute "CDS_LIB" "mstr_discrete"
					( Origin gPackager )
				)
				( attribute "CDS_LOCATION" "R4D8"
					( Origin gPackager )
				)
				( attribute "CDS_SEC" "1"
					( Origin gPackager )
				)
				( attribute "LOCATION" "R4D8"
					( Origin gFrontEnd )
				)
				( attribute "MATERIAL" "CHIP"
					( Origin gFrontEnd )
				)
				( attribute "PACK_TYPE" "0402"
					( Origin gFrontEnd )
				)
				( attribute "PART_NUMBER" "G21796-182"
					( Origin gFrontEnd )
				)
				( attribute "PHYS_PAGE" "103"
					( Origin gFrontEnd )
				)
				( attribute "ROOM" "DB1200Z"
					( Origin gFrontEnd )
				)
				( attribute "ROT" "0"
					( Origin gFrontEnd )
				)
				( attribute "SEC" "1"
					( Origin gFrontEnd )
				)
				( attribute "SEC_TYPE" "0402"
					( Origin gFrontEnd )
				)
				( attribute "TOLERANCE" "1%"
					( Origin gFrontEnd )
				)
				( attribute "VALUE" "27.4"
					( Origin gFrontEnd )
				)
				( attribute "VER" "1"
					( Origin gFrontEnd )
				)
				( attribute "WATTAGE" "1/16W"
					( Origin gFrontEnd )
				)
				( attribute "XY" "(300,4175)"
					( Origin gFrontEnd )
				)
				( attribute "CHIPS_PART_NAME" "RES"
					( Origin gPackager )
				)
				( attribute "CDS_PART_NAME" "RES_0402-27.4,1%,1/16W,CHIP,G2A"
					( Origin gPackager )
				)
				( objectStatus "R4D8" )
			)
			( gate "@baseboard_fab2_lib.baseboard_fab2(sch_1):page103_i89"
				( attribute "BOM_COST" "SYS_CLOCK"
					( Origin gFrontEnd )
				)
				( attribute "CDS_LIB" "mstr_discrete"
					( Origin gPackager )
				)
				( attribute "CDS_LOCATION" "R4D7"
					( Origin gPackager )
				)
				( attribute "CDS_SEC" "1"
					( Origin gPackager )
				)
				( attribute "LOCATION" "R4D7"
					( Origin gFrontEnd )
				)
				( attribute "MATERIAL" "CHIP"
					( Origin gFrontEnd )
				)
				( attribute "PACK_TYPE" "0402"
					( Origin gFrontEnd )
				)
				( attribute "PART_NUMBER" "G21796-182"
					( Origin gFrontEnd )
				)
				( attribute "PHYS_PAGE" "103"
					( Origin gFrontEnd )
				)
				( attribute "ROOM" "DB1200Z"
					( Origin gFrontEnd )
				)
				( attribute "ROT" "0"
					( Origin gFrontEnd )
				)
				( attribute "SEC" "1"
					( Origin gFrontEnd )
				)
				( attribute "SEC_TYPE" "0402"
					( Origin gFrontEnd )
				)
				( attribute "TOLERANCE" "1%"
					( Origin gFrontEnd )
				)
				( attribute "VALUE" "27.4"
					( Origin gFrontEnd )
				)
				( attribute "VER" "1"
					( Origin gFrontEnd )
				)
				( attribute "WATTAGE" "1/16W"
					( Origin gFrontEnd )
				)
				( attribute "XY" "(300,3850)"
					( Origin gFrontEnd )
				)
				( attribute "CHIPS_PART_NAME" "RES"
					( Origin gPackager )
				)
				( attribute "CDS_PART_NAME" "RES_0402-27.4,1%,1/16W,CHIP,G2A"
					( Origin gPackager )
				)
				( objectStatus "R4D7" )
			)
			( gate "@baseboard_fab2_lib.baseboard_fab2(sch_1):page103_i94"
				( attribute "BOM_COST" "SYS_CLOCK"
					( Origin gFrontEnd )
				)
				( attribute "CDS_LIB" "mstr_discrete"
					( Origin gPackager )
				)
				( attribute "CDS_LOCATION" "R4D12"
					( Origin gPackager )
				)
				( attribute "CDS_SEC" "1"
					( Origin gPackager )
				)
				( attribute "LOCATION" "R4D12"
					( Origin gFrontEnd )
				)
				( attribute "MATERIAL" "CHIP"
					( Origin gFrontEnd )
				)
				( attribute "PACK_TYPE" "0402"
					( Origin gFrontEnd )
				)
				( attribute "PART_NUMBER" "G21796-182"
					( Origin gFrontEnd )
				)
				( attribute "PHYS_PAGE" "103"
					( Origin gFrontEnd )
				)
				( attribute "ROOM" "DB1200Z"
					( Origin gFrontEnd )
				)
				( attribute "ROT" "0"
					( Origin gFrontEnd )
				)
				( attribute "SEC" "1"
					( Origin gFrontEnd )
				)
				( attribute "SEC_TYPE" "0402"
					( Origin gFrontEnd )
				)
				( attribute "TOLERANCE" "1%"
					( Origin gFrontEnd )
				)
				( attribute "VALUE" "27.4"
					( Origin gFrontEnd )
				)
				( attribute "VER" "1"
					( Origin gFrontEnd )
				)
				( attribute "WATTAGE" "1/16W"
					( Origin gFrontEnd )
				)
				( attribute "XY" "(300,3525)"
					( Origin gFrontEnd )
				)
				( attribute "CHIPS_PART_NAME" "RES"
					( Origin gPackager )
				)
				( attribute "CDS_PART_NAME" "RES_0402-27.4,1%,1/16W,CHIP,G2A"
					( Origin gPackager )
				)
				( objectStatus "R4D12" )
			)
			( gate "@baseboard_fab2_lib.baseboard_fab2(sch_1):page103_i99"
				( attribute "BOM_COST" "SYS_CLOCK"
					( Origin gFrontEnd )
				)
				( attribute "CDS_LIB" "mstr_discrete"
					( Origin gPackager )
				)
				( attribute "CDS_LOCATION" "R4D10"
					( Origin gPackager )
				)
				( attribute "CDS_SEC" "1"
					( Origin gPackager )
				)
				( attribute "LOCATION" "R4D10"
					( Origin gFrontEnd )
				)
				( attribute "MATERIAL" "CHIP"
					( Origin gFrontEnd )
				)
				( attribute "PACK_TYPE" "0402"
					( Origin gFrontEnd )
				)
				( attribute "PART_NUMBER" "G21796-182"
					( Origin gFrontEnd )
				)
				( attribute "PHYS_PAGE" "103"
					( Origin gFrontEnd )
				)
				( attribute "ROOM" "DB1200Z"
					( Origin gFrontEnd )
				)
				( attribute "ROT" "0"
					( Origin gFrontEnd )
				)
				( attribute "SEC" "1"
					( Origin gFrontEnd )
				)
				( attribute "SEC_TYPE" "0402"
					( Origin gFrontEnd )
				)
				( attribute "TOLERANCE" "1%"
					( Origin gFrontEnd )
				)
				( attribute "VALUE" "27.4"
					( Origin gFrontEnd )
				)
				( attribute "VER" "1"
					( Origin gFrontEnd )
				)
				( attribute "WATTAGE" "1/16W"
					( Origin gFrontEnd )
				)
				( attribute "XY" "(300,3200)"
					( Origin gFrontEnd )
				)
				( attribute "CHIPS_PART_NAME" "RES"
					( Origin gPackager )
				)
				( attribute "CDS_PART_NAME" "RES_0402-27.4,1%,1/16W,CHIP,G2A"
					( Origin gPackager )
				)
				( objectStatus "R4D10" )
			)
			( gate "@baseboard_fab2_lib.baseboard_fab2(sch_1):page103_i104"
				( attribute "BOM_COST" "SYS_CLOCK"
					( Origin gFrontEnd )
				)
				( attribute "CDS_LIB" "mstr_discrete"
					( Origin gPackager )
				)
				( attribute "CDS_LOCATION" "R4D17"
					( Origin gPackager )
				)
				( attribute "CDS_SEC" "1"
					( Origin gPackager )
				)
				( attribute "LOCATION" "R4D17"
					( Origin gFrontEnd )
				)
				( attribute "MATERIAL" "CHIP"
					( Origin gFrontEnd )
				)
				( attribute "PACK_TYPE" "0402"
					( Origin gFrontEnd )
				)
				( attribute "PART_NUMBER" "G21796-182"
					( Origin gFrontEnd )
				)
				( attribute "PHYS_PAGE" "103"
					( Origin gFrontEnd )
				)
				( attribute "ROOM" "DB1200Z"
					( Origin gFrontEnd )
				)
				( attribute "ROT" "0"
					( Origin gFrontEnd )
				)
				( attribute "SEC" "1"
					( Origin gFrontEnd )
				)
				( attribute "SEC_TYPE" "0402"
					( Origin gFrontEnd )
				)
				( attribute "TOLERANCE" "1%"
					( Origin gFrontEnd )
				)
				( attribute "VALUE" "27.4"
					( Origin gFrontEnd )
				)
				( attribute "VER" "1"
					( Origin gFrontEnd )
				)
				( attribute "WATTAGE" "1/16W"
					( Origin gFrontEnd )
				)
				( attribute "XY" "(300,2875)"
					( Origin gFrontEnd )
				)
				( attribute "CHIPS_PART_NAME" "RES"
					( Origin gPackager )
				)
				( attribute "CDS_PART_NAME" "RES_0402-27.4,1%,1/16W,CHIP,G2A"
					( Origin gPackager )
				)
				( objectStatus "R4D17" )
			)
			( gate "@baseboard_fab2_lib.baseboard_fab2(sch_1):page103_i109"
				( attribute "BOM_COST" "SYS_CLOCK"
					( Origin gFrontEnd )
				)
				( attribute "CDS_LIB" "mstr_discrete"
					( Origin gPackager )
				)
				( attribute "CDS_LOCATION" "R4D14"
					( Origin gPackager )
				)
				( attribute "CDS_SEC" "1"
					( Origin gPackager )
				)
				( attribute "LOCATION" "R4D14"
					( Origin gFrontEnd )
				)
				( attribute "MATERIAL" "CHIP"
					( Origin gFrontEnd )
				)
				( attribute "PACK_TYPE" "0402"
					( Origin gFrontEnd )
				)
				( attribute "PART_NUMBER" "G21796-182"
					( Origin gFrontEnd )
				)
				( attribute "PHYS_PAGE" "103"
					( Origin gFrontEnd )
				)
				( attribute "ROOM" "DB1200Z"
					( Origin gFrontEnd )
				)
				( attribute "ROT" "0"
					( Origin gFrontEnd )
				)
				( attribute "SEC" "1"
					( Origin gFrontEnd )
				)
				( attribute "SEC_TYPE" "0402"
					( Origin gFrontEnd )
				)
				( attribute "TOLERANCE" "1%"
					( Origin gFrontEnd )
				)
				( attribute "VALUE" "27.4"
					( Origin gFrontEnd )
				)
				( attribute "VER" "1"
					( Origin gFrontEnd )
				)
				( attribute "WATTAGE" "1/16W"
					( Origin gFrontEnd )
				)
				( attribute "XY" "(300,2550)"
					( Origin gFrontEnd )
				)
				( attribute "CHIPS_PART_NAME" "RES"
					( Origin gPackager )
				)
				( attribute "CDS_PART_NAME" "RES_0402-27.4,1%,1/16W,CHIP,G2A"
					( Origin gPackager )
				)
				( objectStatus "R4D14" )
			)
			( gate "@baseboard_fab2_lib.baseboard_fab2(sch_1):page103_i114"
				( attribute "BOM_COST" "SYS_CLOCK"
					( Origin gFrontEnd )
				)
				( attribute "CDS_LIB" "mstr_discrete"
					( Origin gPackager )
				)
				( attribute "CDS_LOCATION" "R4D22"
					( Origin gPackager )
				)
				( attribute "CDS_SEC" "1"
					( Origin gPackager )
				)
				( attribute "LOCATION" "R4D22"
					( Origin gFrontEnd )
				)
				( attribute "MATERIAL" "CHIP"
					( Origin gFrontEnd )
				)
				( attribute "PACK_TYPE" "0402"
					( Origin gFrontEnd )
				)
				( attribute "PART_NUMBER" "G21796-182"
					( Origin gFrontEnd )
				)
				( attribute "PHYS_PAGE" "103"
					( Origin gFrontEnd )
				)
				( attribute "ROOM" "DB1200Z"
					( Origin gFrontEnd )
				)
				( attribute "ROT" "0"
					( Origin gFrontEnd )
				)
				( attribute "SEC" "1"
					( Origin gFrontEnd )
				)
				( attribute "SEC_TYPE" "0402"
					( Origin gFrontEnd )
				)
				( attribute "TOLERANCE" "1%"
					( Origin gFrontEnd )
				)
				( attribute "VALUE" "27.4"
					( Origin gFrontEnd )
				)
				( attribute "VER" "1"
					( Origin gFrontEnd )
				)
				( attribute "WATTAGE" "1/16W"
					( Origin gFrontEnd )
				)
				( attribute "XY" "(300,2225)"
					( Origin gFrontEnd )
				)
				( attribute "CHIPS_PART_NAME" "RES"
					( Origin gPackager )
				)
				( attribute "CDS_PART_NAME" "RES_0402-27.4,1%,1/16W,CHIP,G2A"
					( Origin gPackager )
				)
				( objectStatus "R4D22" )
			)
			( gate "@baseboard_fab2_lib.baseboard_fab2(sch_1):page103_i119"
				( attribute "BOM_COST" "SYS_CLOCK"
					( Origin gFrontEnd )
				)
				( attribute "CDS_LIB" "mstr_discrete"
					( Origin gPackager )
				)
				( attribute "CDS_LOCATION" "R4D20"
					( Origin gPackager )
				)
				( attribute "CDS_SEC" "1"
					( Origin gPackager )
				)
				( attribute "LOCATION" "R4D20"
					( Origin gFrontEnd )
				)
				( attribute "MATERIAL" "CHIP"
					( Origin gFrontEnd )
				)
				( attribute "PACK_TYPE" "0402"
					( Origin gFrontEnd )
				)
				( attribute "PART_NUMBER" "G21796-182"
					( Origin gFrontEnd )
				)
				( attribute "PHYS_PAGE" "103"
					( Origin gFrontEnd )
				)
				( attribute "ROOM" "DB1200Z"
					( Origin gFrontEnd )
				)
				( attribute "ROT" "0"
					( Origin gFrontEnd )
				)
				( attribute "SEC" "1"
					( Origin gFrontEnd )
				)
				( attribute "SEC_TYPE" "0402"
					( Origin gFrontEnd )
				)
				( attribute "TOLERANCE" "1%"
					( Origin gFrontEnd )
				)
				( attribute "VALUE" "27.4"
					( Origin gFrontEnd )
				)
				( attribute "VER" "1"
					( Origin gFrontEnd )
				)
				( attribute "WATTAGE" "1/16W"
					( Origin gFrontEnd )
				)
				( attribute "XY" "(300,1900)"
					( Origin gFrontEnd )
				)
				( attribute "CHIPS_PART_NAME" "RES"
					( Origin gPackager )
				)
				( attribute "CDS_PART_NAME" "RES_0402-27.4,1%,1/16W,CHIP,G2A"
					( Origin gPackager )
				)
				( objectStatus "R4D20" )
			)
			( gate "@baseboard_fab2_lib.baseboard_fab2(sch_1):page103_i121"
				( attribute "BOM_COST" "SYS_CLOCK"
					( Origin gFrontEnd )
				)
				( attribute "CDS_LIB" "mstr_discrete"
					( Origin gPackager )
				)
				( attribute "CDS_LOCATION" "R7P9"
					( Origin gPackager )
				)
				( attribute "CDS_SEC" "1"
					( Origin gPackager )
				)
				( attribute "LOCATION" "R7P9"
					( Origin gFrontEnd )
				)
				( attribute "MATERIAL" "EMPTY"
					( Origin gFrontEnd )
				)
				( attribute "PACK_TYPE" "0402"
					( Origin gFrontEnd )
				)
				( attribute "PART_NUMBER" "G21796-259"
					( Origin gFrontEnd )
				)
				( attribute "PHYS_PAGE" "103"
					( Origin gFrontEnd )
				)
				( attribute "ROOM" "DB1200Z"
					( Origin gFrontEnd )
				)
				( attribute "ROT" "0"
					( Origin gFrontEnd )
				)
				( attribute "SEC" "1"
					( Origin gFrontEnd )
				)
				( attribute "SEC_TYPE" "0402"
					( Origin gFrontEnd )
				)
				( attribute "TOLERANCE" "1.0%"
					( Origin gFrontEnd )
				)
				( attribute "VALUE" "42.2"
					( Origin gFrontEnd )
				)
				( attribute "VER" "1"
					( Origin gFrontEnd )
				)
				( attribute "WATTAGE" "1/16W"
					( Origin gFrontEnd )
				)
				( attribute "XY" "(-3325,4800)"
					( Origin gFrontEnd )
				)
				( attribute "CHIPS_PART_NAME" "RES"
					( Origin gPackager )
				)
				( attribute "CDS_PART_NAME" "RES_0402-42.2,1.0%,1/16W,EMPTYA"
					( Origin gPackager )
				)
				( objectStatus "R7P9" )
			)
			( gate "@baseboard_fab2_lib.baseboard_fab2(sch_1):page103_i123"
				( attribute "BOM_COST" "SYS_CLOCK"
					( Origin gFrontEnd )
				)
				( attribute "CDS_LIB" "mstr_discrete"
					( Origin gPackager )
				)
				( attribute "CDS_LOCATION" "R7P12"
					( Origin gPackager )
				)
				( attribute "CDS_SEC" "1"
					( Origin gPackager )
				)
				( attribute "LOCATION" "R7P12"
					( Origin gFrontEnd )
				)
				( attribute "MATERIAL" "EMPTY"
					( Origin gFrontEnd )
				)
				( attribute "PACK_TYPE" "0402"
					( Origin gFrontEnd )
				)
				( attribute "PART_NUMBER" "G21796-259"
					( Origin gFrontEnd )
				)
				( attribute "PHYS_PAGE" "103"
					( Origin gFrontEnd )
				)
				( attribute "ROOM" "DB1200Z"
					( Origin gFrontEnd )
				)
				( attribute "ROT" "0"
					( Origin gFrontEnd )
				)
				( attribute "SEC" "1"
					( Origin gFrontEnd )
				)
				( attribute "SEC_TYPE" "0402"
					( Origin gFrontEnd )
				)
				( attribute "TOLERANCE" "1.0%"
					( Origin gFrontEnd )
				)
				( attribute "VALUE" "42.2"
					( Origin gFrontEnd )
				)
				( attribute "VER" "1"
					( Origin gFrontEnd )
				)
				( attribute "WATTAGE" "1/16W"
					( Origin gFrontEnd )
				)
				( attribute "XY" "(-3300,4425)"
					( Origin gFrontEnd )
				)
				( attribute "CHIPS_PART_NAME" "RES"
					( Origin gPackager )
				)
				( attribute "CDS_PART_NAME" "RES_0402-42.2,1.0%,1/16W,EMPTYA"
					( Origin gPackager )
				)
				( objectStatus "R7P12" )
			)
			( gate "@baseboard_fab2_lib.baseboard_fab2(sch_1):page103_i125"
				( attribute "BOM_COST" "SYS_CLOCK"
					( Origin gFrontEnd )
				)
				( attribute "CDS_LIB" "mstr_discrete"
					( Origin gPackager )
				)
				( attribute "CDS_LOCATION" "R7P6"
					( Origin gPackager )
				)
				( attribute "CDS_SEC" "1"
					( Origin gPackager )
				)
				( attribute "LOCATION" "R7P6"
					( Origin gFrontEnd )
				)
				( attribute "MATERIAL" "EMPTY"
					( Origin gFrontEnd )
				)
				( attribute "PACK_TYPE" "0402"
					( Origin gFrontEnd )
				)
				( attribute "PART_NUMBER" "G21796-259"
					( Origin gFrontEnd )
				)
				( attribute "PHYS_PAGE" "103"
					( Origin gFrontEnd )
				)
				( attribute "ROOM" "DB1200Z"
					( Origin gFrontEnd )
				)
				( attribute "ROT" "0"
					( Origin gFrontEnd )
				)
				( attribute "SEC" "1"
					( Origin gFrontEnd )
				)
				( attribute "SEC_TYPE" "0402"
					( Origin gFrontEnd )
				)
				( attribute "TOLERANCE" "1.0%"
					( Origin gFrontEnd )
				)
				( attribute "VALUE" "42.2"
					( Origin gFrontEnd )
				)
				( attribute "VER" "1"
					( Origin gFrontEnd )
				)
				( attribute "WATTAGE" "1/16W"
					( Origin gFrontEnd )
				)
				( attribute "XY" "(-3325,4075)"
					( Origin gFrontEnd )
				)
				( attribute "CHIPS_PART_NAME" "RES"
					( Origin gPackager )
				)
				( attribute "CDS_PART_NAME" "RES_0402-42.2,1.0%,1/16W,EMPTYA"
					( Origin gPackager )
				)
				( objectStatus "R7P6" )
			)
			( gate "@baseboard_fab2_lib.baseboard_fab2(sch_1):page103_i127"
				( attribute "BOM_COST" "SYS_CLOCK"
					( Origin gFrontEnd )
				)
				( attribute "CDS_LIB" "mstr_discrete"
					( Origin gPackager )
				)
				( attribute "CDS_LOCATION" "R7P7"
					( Origin gPackager )
				)
				( attribute "CDS_SEC" "1"
					( Origin gPackager )
				)
				( attribute "LOCATION" "R7P7"
					( Origin gFrontEnd )
				)
				( attribute "MATERIAL" "EMPTY"
					( Origin gFrontEnd )
				)
				( attribute "PACK_TYPE" "0402"
					( Origin gFrontEnd )
				)
				( attribute "PART_NUMBER" "G21796-259"
					( Origin gFrontEnd )
				)
				( attribute "PHYS_PAGE" "103"
					( Origin gFrontEnd )
				)
				( attribute "ROOM" "DB1200Z"
					( Origin gFrontEnd )
				)
				( attribute "ROT" "0"
					( Origin gFrontEnd )
				)
				( attribute "SEC" "1"
					( Origin gPackager )
				)
				( attribute "TOLERANCE" "1.0%"
					( Origin gFrontEnd )
				)
				( attribute "VALUE" "42.2"
					( Origin gFrontEnd )
				)
				( attribute "VER" "1"
					( Origin gFrontEnd )
				)
				( attribute "WATTAGE" "1/16W"
					( Origin gFrontEnd )
				)
				( attribute "XY" "(-3325,3750)"
					( Origin gFrontEnd )
				)
				( attribute "CHIPS_PART_NAME" "RES"
					( Origin gPackager )
				)
				( attribute "CDS_PART_NAME" "RES_0402-42.2,1.0%,1/16W,EMPTYA"
					( Origin gPackager )
				)
				( objectStatus "R7P7" )
			)
			( gate "@baseboard_fab2_lib.baseboard_fab2(sch_1):page103_i129"
				( attribute "BOM_COST" "SYS_CLOCK"
					( Origin gFrontEnd )
				)
				( attribute "CDS_LIB" "mstr_discrete"
					( Origin gPackager )
				)
				( attribute "CDS_LOCATION" "R7P3"
					( Origin gPackager )
				)
				( attribute "CDS_SEC" "1"
					( Origin gPackager )
				)
				( attribute "LOCATION" "R7P3"
					( Origin gFrontEnd )
				)
				( attribute "MATERIAL" "EMPTY"
					( Origin gFrontEnd )
				)
				( attribute "PACK_TYPE" "0402"
					( Origin gFrontEnd )
				)
				( attribute "PART_NUMBER" "G21796-259"
					( Origin gFrontEnd )
				)
				( attribute "PHYS_PAGE" "103"
					( Origin gFrontEnd )
				)
				( attribute "ROOM" "DB1200Z"
					( Origin gFrontEnd )
				)
				( attribute "ROT" "0"
					( Origin gFrontEnd )
				)
				( attribute "SEC" "1"
					( Origin gFrontEnd )
				)
				( attribute "SEC_TYPE" "0402"
					( Origin gFrontEnd )
				)
				( attribute "TOLERANCE" "1.0%"
					( Origin gFrontEnd )
				)
				( attribute "VALUE" "42.2"
					( Origin gFrontEnd )
				)
				( attribute "VER" "1"
					( Origin gFrontEnd )
				)
				( attribute "WATTAGE" "1/16W"
					( Origin gFrontEnd )
				)
				( attribute "XY" "(-3325,3425)"
					( Origin gFrontEnd )
				)
				( attribute "CHIPS_PART_NAME" "RES"
					( Origin gPackager )
				)
				( attribute "CDS_PART_NAME" "RES_0402-42.2,1.0%,1/16W,EMPTYA"
					( Origin gPackager )
				)
				( objectStatus "R7P3" )
			)
			( gate "@baseboard_fab2_lib.baseboard_fab2(sch_1):page103_i131"
				( attribute "BOM_COST" "SYS_CLOCK"
					( Origin gFrontEnd )
				)
				( attribute "CDS_LIB" "mstr_discrete"
					( Origin gPackager )
				)
				( attribute "CDS_LOCATION" "R7P4"
					( Origin gPackager )
				)
				( attribute "CDS_SEC" "1"
					( Origin gPackager )
				)
				( attribute "LOCATION" "R7P4"
					( Origin gFrontEnd )
				)
				( attribute "MATERIAL" "EMPTY"
					( Origin gFrontEnd )
				)
				( attribute "PACK_TYPE" "0402"
					( Origin gFrontEnd )
				)
				( attribute "PART_NUMBER" "G21796-259"
					( Origin gFrontEnd )
				)
				( attribute "PHYS_PAGE" "103"
					( Origin gFrontEnd )
				)
				( attribute "ROOM" "DB1200Z"
					( Origin gFrontEnd )
				)
				( attribute "ROT" "0"
					( Origin gFrontEnd )
				)
				( attribute "SEC" "1"
					( Origin gFrontEnd )
				)
				( attribute "SEC_TYPE" "0402"
					( Origin gFrontEnd )
				)
				( attribute "TOLERANCE" "1.0%"
					( Origin gFrontEnd )
				)
				( attribute "VALUE" "42.2"
					( Origin gFrontEnd )
				)
				( attribute "VER" "1"
					( Origin gFrontEnd )
				)
				( attribute "WATTAGE" "1/16W"
					( Origin gFrontEnd )
				)
				( attribute "XY" "(-3325,3100)"
					( Origin gFrontEnd )
				)
				( attribute "CHIPS_PART_NAME" "RES"
					( Origin gPackager )
				)
				( attribute "CDS_PART_NAME" "RES_0402-42.2,1.0%,1/16W,EMPTYA"
					( Origin gPackager )
				)
				( objectStatus "R7P4" )
			)
			( gate "@baseboard_fab2_lib.baseboard_fab2(sch_1):page103_i133"
				( attribute "BOM_COST" "SYS_CLOCK"
					( Origin gFrontEnd )
				)
				( attribute "CDS_LIB" "mstr_discrete"
					( Origin gPackager )
				)
				( attribute "CDS_LOCATION" "R7P1"
					( Origin gPackager )
				)
				( attribute "CDS_SEC" "1"
					( Origin gPackager )
				)
				( attribute "LOCATION" "R7P1"
					( Origin gFrontEnd )
				)
				( attribute "MATERIAL" "EMPTY"
					( Origin gFrontEnd )
				)
				( attribute "PACK_TYPE" "0402"
					( Origin gFrontEnd )
				)
				( attribute "PART_NUMBER" "G21796-259"
					( Origin gFrontEnd )
				)
				( attribute "PHYS_PAGE" "103"
					( Origin gFrontEnd )
				)
				( attribute "ROOM" "DB1200Z"
					( Origin gFrontEnd )
				)
				( attribute "ROT" "0"
					( Origin gFrontEnd )
				)
				( attribute "SEC" "1"
					( Origin gFrontEnd )
				)
				( attribute "SEC_TYPE" "0402"
					( Origin gFrontEnd )
				)
				( attribute "TOLERANCE" "1.0%"
					( Origin gFrontEnd )
				)
				( attribute "VALUE" "42.2"
					( Origin gFrontEnd )
				)
				( attribute "VER" "1"
					( Origin gFrontEnd )
				)
				( attribute "WATTAGE" "1/16W"
					( Origin gFrontEnd )
				)
				( attribute "XY" "(-3325,2775)"
					( Origin gFrontEnd )
				)
				( attribute "CHIPS_PART_NAME" "RES"
					( Origin gPackager )
				)
				( attribute "CDS_PART_NAME" "RES_0402-42.2,1.0%,1/16W,EMPTYA"
					( Origin gPackager )
				)
				( objectStatus "R7P1" )
			)
			( gate "@baseboard_fab2_lib.baseboard_fab2(sch_1):page103_i135"
				( attribute "BOM_COST" "SYS_CLOCK"
					( Origin gFrontEnd )
				)
				( attribute "CDS_LIB" "mstr_discrete"
					( Origin gPackager )
				)
				( attribute "CDS_LOCATION" "R7P2"
					( Origin gPackager )
				)
				( attribute "CDS_SEC" "1"
					( Origin gPackager )
				)
				( attribute "LOCATION" "R7P2"
					( Origin gFrontEnd )
				)
				( attribute "MATERIAL" "EMPTY"
					( Origin gFrontEnd )
				)
				( attribute "PACK_TYPE" "0402"
					( Origin gFrontEnd )
				)
				( attribute "PART_NUMBER" "G21796-259"
					( Origin gFrontEnd )
				)
				( attribute "PHYS_PAGE" "103"
					( Origin gFrontEnd )
				)
				( attribute "ROOM" "DB1200Z"
					( Origin gFrontEnd )
				)
				( attribute "ROT" "0"
					( Origin gFrontEnd )
				)
				( attribute "SEC" "1"
					( Origin gFrontEnd )
				)
				( attribute "SEC_TYPE" "0402"
					( Origin gFrontEnd )
				)
				( attribute "TOLERANCE" "1.0%"
					( Origin gFrontEnd )
				)
				( attribute "VALUE" "42.2"
					( Origin gFrontEnd )
				)
				( attribute "VER" "1"
					( Origin gFrontEnd )
				)
				( attribute "WATTAGE" "1/16W"
					( Origin gFrontEnd )
				)
				( attribute "XY" "(-3325,2450)"
					( Origin gFrontEnd )
				)
				( attribute "CHIPS_PART_NAME" "RES"
					( Origin gPackager )
				)
				( attribute "CDS_PART_NAME" "RES_0402-42.2,1.0%,1/16W,EMPTYA"
					( Origin gPackager )
				)
				( objectStatus "R7P2" )
			)
			( gate "@baseboard_fab2_lib.baseboard_fab2(sch_1):page103_i137"
				( attribute "BOM_COST" "SYS_CLOCK"
					( Origin gFrontEnd )
				)
				( attribute "CDS_LIB" "mstr_discrete"
					( Origin gPackager )
				)
				( attribute "CDS_LOCATION" "R6P7"
					( Origin gPackager )
				)
				( attribute "CDS_SEC" "1"
					( Origin gPackager )
				)
				( attribute "LOCATION" "R6P7"
					( Origin gFrontEnd )
				)
				( attribute "MATERIAL" "EMPTY"
					( Origin gFrontEnd )
				)
				( attribute "PACK_TYPE" "0402"
					( Origin gFrontEnd )
				)
				( attribute "PART_NUMBER" "G21796-259"
					( Origin gFrontEnd )
				)
				( attribute "PHYS_PAGE" "103"
					( Origin gFrontEnd )
				)
				( attribute "ROOM" "DB1200Z"
					( Origin gFrontEnd )
				)
				( attribute "ROT" "0"
					( Origin gFrontEnd )
				)
				( attribute "SEC" "1"
					( Origin gFrontEnd )
				)
				( attribute "SEC_TYPE" "0402"
					( Origin gFrontEnd )
				)
				( attribute "TOLERANCE" "1.0%"
					( Origin gFrontEnd )
				)
				( attribute "VALUE" "42.2"
					( Origin gFrontEnd )
				)
				( attribute "VER" "1"
					( Origin gFrontEnd )
				)
				( attribute "WATTAGE" "1/16W"
					( Origin gFrontEnd )
				)
				( attribute "XY" "(-3325,2125)"
					( Origin gFrontEnd )
				)
				( attribute "CHIPS_PART_NAME" "RES"
					( Origin gPackager )
				)
				( attribute "CDS_PART_NAME" "RES_0402-42.2,1.0%,1/16W,EMPTYA"
					( Origin gPackager )
				)
				( objectStatus "R6P7" )
			)
			( gate "@baseboard_fab2_lib.baseboard_fab2(sch_1):page103_i139"
				( attribute "BOM_COST" "SYS_CLOCK"
					( Origin gFrontEnd )
				)
				( attribute "CDS_LIB" "mstr_discrete"
					( Origin gPackager )
				)
				( attribute "CDS_LOCATION" "R6P8"
					( Origin gPackager )
				)
				( attribute "CDS_SEC" "1"
					( Origin gPackager )
				)
				( attribute "LOCATION" "R6P8"
					( Origin gFrontEnd )
				)
				( attribute "MATERIAL" "EMPTY"
					( Origin gFrontEnd )
				)
				( attribute "PACK_TYPE" "0402"
					( Origin gFrontEnd )
				)
				( attribute "PART_NUMBER" "G21796-259"
					( Origin gFrontEnd )
				)
				( attribute "PHYS_PAGE" "103"
					( Origin gFrontEnd )
				)
				( attribute "ROOM" "DB1200Z"
					( Origin gFrontEnd )
				)
				( attribute "ROT" "0"
					( Origin gFrontEnd )
				)
				( attribute "SEC" "1"
					( Origin gFrontEnd )
				)
				( attribute "SEC_TYPE" "0402"
					( Origin gFrontEnd )
				)
				( attribute "TOLERANCE" "1.0%"
					( Origin gFrontEnd )
				)
				( attribute "VALUE" "42.2"
					( Origin gFrontEnd )
				)
				( attribute "VER" "1"
					( Origin gFrontEnd )
				)
				( attribute "WATTAGE" "1/16W"
					( Origin gFrontEnd )
				)
				( attribute "XY" "(-3325,1800)"
					( Origin gFrontEnd )
				)
				( attribute "CHIPS_PART_NAME" "RES"
					( Origin gPackager )
				)
				( attribute "CDS_PART_NAME" "RES_0402-42.2,1.0%,1/16W,EMPTYA"
					( Origin gPackager )
				)
				( objectStatus "R6P8" )
			)
			( gate "@baseboard_fab2_lib.baseboard_fab2(sch_1):page103_i141"
				( attribute "BOM_COST" "SYS_CLOCK"
					( Origin gFrontEnd )
				)
				( attribute "CDS_LIB" "mstr_discrete"
					( Origin gPackager )
				)
				( attribute "CDS_LOCATION" "R6P5"
					( Origin gPackager )
				)
				( attribute "CDS_SEC" "1"
					( Origin gPackager )
				)
				( attribute "LOCATION" "R6P5"
					( Origin gFrontEnd )
				)
				( attribute "MATERIAL" "EMPTY"
					( Origin gFrontEnd )
				)
				( attribute "PACK_TYPE" "0402"
					( Origin gFrontEnd )
				)
				( attribute "PART_NUMBER" "G21796-259"
					( Origin gFrontEnd )
				)
				( attribute "PHYS_PAGE" "103"
					( Origin gFrontEnd )
				)
				( attribute "ROOM" "DB1200Z"
					( Origin gFrontEnd )
				)
				( attribute "ROT" "0"
					( Origin gFrontEnd )
				)
				( attribute "SEC" "1"
					( Origin gFrontEnd )
				)
				( attribute "SEC_TYPE" "0402"
					( Origin gFrontEnd )
				)
				( attribute "TOLERANCE" "1.0%"
					( Origin gFrontEnd )
				)
				( attribute "VALUE" "42.2"
					( Origin gFrontEnd )
				)
				( attribute "VER" "1"
					( Origin gFrontEnd )
				)
				( attribute "WATTAGE" "1/16W"
					( Origin gFrontEnd )
				)
				( attribute "XY" "(-3325,1475)"
					( Origin gFrontEnd )
				)
				( attribute "CHIPS_PART_NAME" "RES"
					( Origin gPackager )
				)
				( attribute "CDS_PART_NAME" "RES_0402-42.2,1.0%,1/16W,EMPTYA"
					( Origin gPackager )
				)
				( objectStatus "R6P5" )
			)
			( gate "@baseboard_fab2_lib.baseboard_fab2(sch_1):page103_i143"
				( attribute "BOM_COST" "SYS_CLOCK"
					( Origin gFrontEnd )
				)
				( attribute "CDS_LIB" "mstr_discrete"
					( Origin gPackager )
				)
				( attribute "CDS_LOCATION" "R6P6"
					( Origin gPackager )
				)
				( attribute "CDS_SEC" "1"
					( Origin gPackager )
				)
				( attribute "LOCATION" "R6P6"
					( Origin gFrontEnd )
				)
				( attribute "MATERIAL" "EMPTY"
					( Origin gFrontEnd )
				)
				( attribute "PACK_TYPE" "0402"
					( Origin gFrontEnd )
				)
				( attribute "PART_NUMBER" "G21796-259"
					( Origin gFrontEnd )
				)
				( attribute "PHYS_PAGE" "103"
					( Origin gFrontEnd )
				)
				( attribute "ROOM" "DB1200Z"
					( Origin gFrontEnd )
				)
				( attribute "ROT" "0"
					( Origin gFrontEnd )
				)
				( attribute "SEC" "1"
					( Origin gFrontEnd )
				)
				( attribute "SEC_TYPE" "0402"
					( Origin gFrontEnd )
				)
				( attribute "TOLERANCE" "1.0%"
					( Origin gFrontEnd )
				)
				( attribute "VALUE" "42.2"
					( Origin gFrontEnd )
				)
				( attribute "VER" "1"
					( Origin gFrontEnd )
				)
				( attribute "WATTAGE" "1/16W"
					( Origin gFrontEnd )
				)
				( attribute "XY" "(-3325,1150)"
					( Origin gFrontEnd )
				)
				( attribute "CHIPS_PART_NAME" "RES"
					( Origin gPackager )
				)
				( attribute "CDS_PART_NAME" "RES_0402-42.2,1.0%,1/16W,EMPTYA"
					( Origin gPackager )
				)
				( objectStatus "R6P6" )
			)
			( gate "@baseboard_fab2_lib.baseboard_fab2(sch_1):page103_i145"
				( attribute "BOM_COST" "SYS_CLOCK"
					( Origin gFrontEnd )
				)
				( attribute "CDS_LIB" "mstr_discrete"
					( Origin gPackager )
				)
				( attribute "CDS_LOCATION" "R6P3"
					( Origin gPackager )
				)
				( attribute "CDS_SEC" "1"
					( Origin gPackager )
				)
				( attribute "LOCATION" "R6P3"
					( Origin gFrontEnd )
				)
				( attribute "MATERIAL" "EMPTY"
					( Origin gFrontEnd )
				)
				( attribute "PACK_TYPE" "0402"
					( Origin gFrontEnd )
				)
				( attribute "PART_NUMBER" "G21796-259"
					( Origin gFrontEnd )
				)
				( attribute "PHYS_PAGE" "103"
					( Origin gFrontEnd )
				)
				( attribute "ROOM" "DB1200Z"
					( Origin gFrontEnd )
				)
				( attribute "ROT" "0"
					( Origin gFrontEnd )
				)
				( attribute "SEC" "1"
					( Origin gFrontEnd )
				)
				( attribute "SEC_TYPE" "0402"
					( Origin gFrontEnd )
				)
				( attribute "TOLERANCE" "1.0%"
					( Origin gFrontEnd )
				)
				( attribute "VALUE" "42.2"
					( Origin gFrontEnd )
				)
				( attribute "VER" "1"
					( Origin gFrontEnd )
				)
				( attribute "WATTAGE" "1/16W"
					( Origin gFrontEnd )
				)
				( attribute "XY" "(1025,4725)"
					( Origin gFrontEnd )
				)
				( attribute "CHIPS_PART_NAME" "RES"
					( Origin gPackager )
				)
				( attribute "CDS_PART_NAME" "RES_0402-42.2,1.0%,1/16W,EMPTYA"
					( Origin gPackager )
				)
				( objectStatus "R6P3" )
			)
			( gate "@baseboard_fab2_lib.baseboard_fab2(sch_1):page103_i147"
				( attribute "BOM_COST" "SYS_CLOCK"
					( Origin gFrontEnd )
				)
				( attribute "CDS_LIB" "mstr_discrete"
					( Origin gPackager )
				)
				( attribute "CDS_LOCATION" "R6P4"
					( Origin gPackager )
				)
				( attribute "CDS_SEC" "1"
					( Origin gPackager )
				)
				( attribute "LOCATION" "R6P4"
					( Origin gFrontEnd )
				)
				( attribute "MATERIAL" "EMPTY"
					( Origin gFrontEnd )
				)
				( attribute "PACK_TYPE" "0402"
					( Origin gFrontEnd )
				)
				( attribute "PART_NUMBER" "G21796-259"
					( Origin gFrontEnd )
				)
				( attribute "PHYS_PAGE" "103"
					( Origin gFrontEnd )
				)
				( attribute "ROOM" "DB1200Z"
					( Origin gFrontEnd )
				)
				( attribute "ROT" "0"
					( Origin gFrontEnd )
				)
				( attribute "SEC" "1"
					( Origin gFrontEnd )
				)
				( attribute "SEC_TYPE" "0402"
					( Origin gFrontEnd )
				)
				( attribute "TOLERANCE" "1.0%"
					( Origin gFrontEnd )
				)
				( attribute "VALUE" "42.2"
					( Origin gFrontEnd )
				)
				( attribute "VER" "1"
					( Origin gFrontEnd )
				)
				( attribute "WATTAGE" "1/16W"
					( Origin gFrontEnd )
				)
				( attribute "XY" "(1050,4400)"
					( Origin gFrontEnd )
				)
				( attribute "CHIPS_PART_NAME" "RES"
					( Origin gPackager )
				)
				( attribute "CDS_PART_NAME" "RES_0402-42.2,1.0%,1/16W,EMPTYA"
					( Origin gPackager )
				)
				( objectStatus "R6P4" )
			)
			( gate "@baseboard_fab2_lib.baseboard_fab2(sch_1):page103_i149"
				( attribute "BOM_COST" "SYS_CLOCK"
					( Origin gFrontEnd )
				)
				( attribute "CDS_LIB" "mstr_discrete"
					( Origin gPackager )
				)
				( attribute "CDS_LOCATION" "R6P1"
					( Origin gPackager )
				)
				( attribute "CDS_SEC" "1"
					( Origin gPackager )
				)
				( attribute "LOCATION" "R6P1"
					( Origin gFrontEnd )
				)
				( attribute "MATERIAL" "EMPTY"
					( Origin gFrontEnd )
				)
				( attribute "PACK_TYPE" "0402"
					( Origin gFrontEnd )
				)
				( attribute "PART_NUMBER" "G21796-259"
					( Origin gFrontEnd )
				)
				( attribute "PHYS_PAGE" "103"
					( Origin gFrontEnd )
				)
				( attribute "ROOM" "DB1200Z"
					( Origin gFrontEnd )
				)
				( attribute "ROT" "0"
					( Origin gFrontEnd )
				)
				( attribute "SEC" "1"
					( Origin gFrontEnd )
				)
				( attribute "SEC_TYPE" "0402"
					( Origin gFrontEnd )
				)
				( attribute "TOLERANCE" "1.0%"
					( Origin gFrontEnd )
				)
				( attribute "VALUE" "42.2"
					( Origin gFrontEnd )
				)
				( attribute "VER" "1"
					( Origin gFrontEnd )
				)
				( attribute "WATTAGE" "1/16W"
					( Origin gFrontEnd )
				)
				( attribute "XY" "(1025,4075)"
					( Origin gFrontEnd )
				)
				( attribute "CHIPS_PART_NAME" "RES"
					( Origin gPackager )
				)
				( attribute "CDS_PART_NAME" "RES_0402-42.2,1.0%,1/16W,EMPTYA"
					( Origin gPackager )
				)
				( objectStatus "R6P1" )
			)
			( gate "@baseboard_fab2_lib.baseboard_fab2(sch_1):page103_i151"
				( attribute "BOM_COST" "SYS_CLOCK"
					( Origin gFrontEnd )
				)
				( attribute "CDS_LIB" "mstr_discrete"
					( Origin gPackager )
				)
				( attribute "CDS_LOCATION" "R6P2"
					( Origin gPackager )
				)
				( attribute "CDS_SEC" "1"
					( Origin gPackager )
				)
				( attribute "LOCATION" "R6P2"
					( Origin gFrontEnd )
				)
				( attribute "MATERIAL" "EMPTY"
					( Origin gFrontEnd )
				)
				( attribute "PACK_TYPE" "0402"
					( Origin gFrontEnd )
				)
				( attribute "PART_NUMBER" "G21796-259"
					( Origin gFrontEnd )
				)
				( attribute "PHYS_PAGE" "103"
					( Origin gFrontEnd )
				)
				( attribute "ROOM" "DB1200Z"
					( Origin gFrontEnd )
				)
				( attribute "ROT" "0"
					( Origin gFrontEnd )
				)
				( attribute "SEC" "1"
					( Origin gFrontEnd )
				)
				( attribute "SEC_TYPE" "0402"
					( Origin gFrontEnd )
				)
				( attribute "TOLERANCE" "1.0%"
					( Origin gFrontEnd )
				)
				( attribute "VALUE" "42.2"
					( Origin gFrontEnd )
				)
				( attribute "VER" "1"
					( Origin gFrontEnd )
				)
				( attribute "WATTAGE" "1/16W"
					( Origin gFrontEnd )
				)
				( attribute "XY" "(1050,3750)"
					( Origin gFrontEnd )
				)
				( attribute "CHIPS_PART_NAME" "RES"
					( Origin gPackager )
				)
				( attribute "CDS_PART_NAME" "RES_0402-42.2,1.0%,1/16W,EMPTYA"
					( Origin gPackager )
				)
				( objectStatus "R6P2" )
			)
			( gate "@baseboard_fab2_lib.baseboard_fab2(sch_1):page103_i153"
				( attribute "BOM_COST" "SYS_CLOCK"
					( Origin gFrontEnd )
				)
				( attribute "CDS_LIB" "mstr_discrete"
					( Origin gPackager )
				)
				( attribute "CDS_LOCATION" "R6P11"
					( Origin gPackager )
				)
				( attribute "CDS_SEC" "1"
					( Origin gPackager )
				)
				( attribute "LOCATION" "R6P11"
					( Origin gFrontEnd )
				)
				( attribute "MATERIAL" "EMPTY"
					( Origin gFrontEnd )
				)
				( attribute "PACK_TYPE" "0402"
					( Origin gFrontEnd )
				)
				( attribute "PART_NUMBER" "G21796-259"
					( Origin gFrontEnd )
				)
				( attribute "PHYS_PAGE" "103"
					( Origin gFrontEnd )
				)
				( attribute "ROOM" "DB1200Z"
					( Origin gFrontEnd )
				)
				( attribute "ROT" "0"
					( Origin gFrontEnd )
				)
				( attribute "SEC" "1"
					( Origin gFrontEnd )
				)
				( attribute "SEC_TYPE" "0402"
					( Origin gFrontEnd )
				)
				( attribute "TOLERANCE" "1.0%"
					( Origin gFrontEnd )
				)
				( attribute "VALUE" "42.2"
					( Origin gFrontEnd )
				)
				( attribute "VER" "1"
					( Origin gFrontEnd )
				)
				( attribute "WATTAGE" "1/16W"
					( Origin gFrontEnd )
				)
				( attribute "XY" "(1050,3425)"
					( Origin gFrontEnd )
				)
				( attribute "CHIPS_PART_NAME" "RES"
					( Origin gPackager )
				)
				( attribute "CDS_PART_NAME" "RES_0402-42.2,1.0%,1/16W,EMPTYA"
					( Origin gPackager )
				)
				( objectStatus "R6P11" )
			)
			( gate "@baseboard_fab2_lib.baseboard_fab2(sch_1):page103_i155"
				( attribute "BOM_COST" "SYS_CLOCK"
					( Origin gFrontEnd )
				)
				( attribute "CDS_LIB" "mstr_discrete"
					( Origin gPackager )
				)
				( attribute "CDS_LOCATION" "R6P9"
					( Origin gPackager )
				)
				( attribute "CDS_SEC" "1"
					( Origin gPackager )
				)
				( attribute "LOCATION" "R6P9"
					( Origin gFrontEnd )
				)
				( attribute "MATERIAL" "EMPTY"
					( Origin gFrontEnd )
				)
				( attribute "PACK_TYPE" "0402"
					( Origin gFrontEnd )
				)
				( attribute "PART_NUMBER" "G21796-259"
					( Origin gFrontEnd )
				)
				( attribute "PHYS_PAGE" "103"
					( Origin gFrontEnd )
				)
				( attribute "ROOM" "DB1200Z"
					( Origin gFrontEnd )
				)
				( attribute "ROT" "0"
					( Origin gFrontEnd )
				)
				( attribute "SEC" "1"
					( Origin gFrontEnd )
				)
				( attribute "SEC_TYPE" "0402"
					( Origin gFrontEnd )
				)
				( attribute "TOLERANCE" "1.0%"
					( Origin gFrontEnd )
				)
				( attribute "VALUE" "42.2"
					( Origin gFrontEnd )
				)
				( attribute "VER" "1"
					( Origin gFrontEnd )
				)
				( attribute "WATTAGE" "1/16W"
					( Origin gFrontEnd )
				)
				( attribute "XY" "(1075,3100)"
					( Origin gFrontEnd )
				)
				( attribute "CHIPS_PART_NAME" "RES"
					( Origin gPackager )
				)
				( attribute "CDS_PART_NAME" "RES_0402-42.2,1.0%,1/16W,EMPTYA"
					( Origin gPackager )
				)
				( objectStatus "R6P9" )
			)
			( gate "@baseboard_fab2_lib.baseboard_fab2(sch_1):page103_i157"
				( attribute "BOM_COST" "SYS_CLOCK"
					( Origin gFrontEnd )
				)
				( attribute "CDS_LIB" "mstr_discrete"
					( Origin gPackager )
				)
				( attribute "CDS_LOCATION" "R6P13"
					( Origin gPackager )
				)
				( attribute "CDS_SEC" "1"
					( Origin gPackager )
				)
				( attribute "LOCATION" "R6P13"
					( Origin gFrontEnd )
				)
				( attribute "MATERIAL" "EMPTY"
					( Origin gFrontEnd )
				)
				( attribute "PACK_TYPE" "0402"
					( Origin gFrontEnd )
				)
				( attribute "PART_NUMBER" "G21796-259"
					( Origin gFrontEnd )
				)
				( attribute "PHYS_PAGE" "103"
					( Origin gFrontEnd )
				)
				( attribute "ROOM" "DB1200Z"
					( Origin gFrontEnd )
				)
				( attribute "ROT" "0"
					( Origin gFrontEnd )
				)
				( attribute "SEC" "1"
					( Origin gFrontEnd )
				)
				( attribute "SEC_TYPE" "0402"
					( Origin gFrontEnd )
				)
				( attribute "TOLERANCE" "1.0%"
					( Origin gFrontEnd )
				)
				( attribute "VALUE" "42.2"
					( Origin gFrontEnd )
				)
				( attribute "VER" "1"
					( Origin gFrontEnd )
				)
				( attribute "WATTAGE" "1/16W"
					( Origin gFrontEnd )
				)
				( attribute "XY" "(1050,2775)"
					( Origin gFrontEnd )
				)
				( attribute "CHIPS_PART_NAME" "RES"
					( Origin gPackager )
				)
				( attribute "CDS_PART_NAME" "RES_0402-42.2,1.0%,1/16W,EMPTYA"
					( Origin gPackager )
				)
				( objectStatus "R6P13" )
			)
			( gate "@baseboard_fab2_lib.baseboard_fab2(sch_1):page103_i159"
				( attribute "BOM_COST" "SYS_CLOCK"
					( Origin gFrontEnd )
				)
				( attribute "CDS_LIB" "mstr_discrete"
					( Origin gPackager )
				)
				( attribute "CDS_LOCATION" "R6P12"
					( Origin gPackager )
				)
				( attribute "CDS_SEC" "1"
					( Origin gPackager )
				)
				( attribute "LOCATION" "R6P12"
					( Origin gFrontEnd )
				)
				( attribute "MATERIAL" "EMPTY"
					( Origin gFrontEnd )
				)
				( attribute "PACK_TYPE" "0402"
					( Origin gFrontEnd )
				)
				( attribute "PART_NUMBER" "G21796-259"
					( Origin gFrontEnd )
				)
				( attribute "PHYS_PAGE" "103"
					( Origin gFrontEnd )
				)
				( attribute "ROOM" "DB1200Z"
					( Origin gFrontEnd )
				)
				( attribute "ROT" "0"
					( Origin gFrontEnd )
				)
				( attribute "SEC" "1"
					( Origin gFrontEnd )
				)
				( attribute "SEC_TYPE" "0402"
					( Origin gFrontEnd )
				)
				( attribute "TOLERANCE" "1.0%"
					( Origin gFrontEnd )
				)
				( attribute "VALUE" "42.2"
					( Origin gFrontEnd )
				)
				( attribute "VER" "1"
					( Origin gFrontEnd )
				)
				( attribute "WATTAGE" "1/16W"
					( Origin gFrontEnd )
				)
				( attribute "XY" "(1050,2450)"
					( Origin gFrontEnd )
				)
				( attribute "CHIPS_PART_NAME" "RES"
					( Origin gPackager )
				)
				( attribute "CDS_PART_NAME" "RES_0402-42.2,1.0%,1/16W,EMPTYA"
					( Origin gPackager )
				)
				( objectStatus "R6P12" )
			)
			( gate "@baseboard_fab2_lib.baseboard_fab2(sch_1):page103_i161"
				( attribute "BOM_COST" "SYS_CLOCK"
					( Origin gFrontEnd )
				)
				( attribute "CDS_LIB" "mstr_discrete"
					( Origin gPackager )
				)
				( attribute "CDS_LOCATION" "R4D24"
					( Origin gPackager )
				)
				( attribute "CDS_SEC" "1"
					( Origin gPackager )
				)
				( attribute "LOCATION" "R4D24"
					( Origin gFrontEnd )
				)
				( attribute "MATERIAL" "EMPTY"
					( Origin gFrontEnd )
				)
				( attribute "PACK_TYPE" "0402"
					( Origin gFrontEnd )
				)
				( attribute "PART_NUMBER" "G21796-259"
					( Origin gFrontEnd )
				)
				( attribute "PHYS_PAGE" "103"
					( Origin gFrontEnd )
				)
				( attribute "ROOM" "DB1200Z"
					( Origin gFrontEnd )
				)
				( attribute "ROT" "0"
					( Origin gFrontEnd )
				)
				( attribute "SEC" "1"
					( Origin gFrontEnd )
				)
				( attribute "SEC_TYPE" "0402"
					( Origin gFrontEnd )
				)
				( attribute "TOLERANCE" "1.0%"
					( Origin gFrontEnd )
				)
				( attribute "VALUE" "42.2"
					( Origin gFrontEnd )
				)
				( attribute "VER" "1"
					( Origin gFrontEnd )
				)
				( attribute "WATTAGE" "1/16W"
					( Origin gFrontEnd )
				)
				( attribute "XY" "(1050,2125)"
					( Origin gFrontEnd )
				)
				( attribute "CHIPS_PART_NAME" "RES"
					( Origin gPackager )
				)
				( attribute "CDS_PART_NAME" "RES_0402-42.2,1.0%,1/16W,EMPTYA"
					( Origin gPackager )
				)
				( objectStatus "R4D24" )
			)
			( gate "@baseboard_fab2_lib.baseboard_fab2(sch_1):page103_i163"
				( attribute "BOM_COST" "SYS_CLOCK"
					( Origin gFrontEnd )
				)
				( attribute "CDS_LIB" "mstr_discrete"
					( Origin gPackager )
				)
				( attribute "CDS_LOCATION" "R4D18"
					( Origin gPackager )
				)
				( attribute "CDS_SEC" "1"
					( Origin gPackager )
				)
				( attribute "LOCATION" "R4D18"
					( Origin gFrontEnd )
				)
				( attribute "MATERIAL" "EMPTY"
					( Origin gFrontEnd )
				)
				( attribute "PACK_TYPE" "0402"
					( Origin gFrontEnd )
				)
				( attribute "PART_NUMBER" "G21796-259"
					( Origin gFrontEnd )
				)
				( attribute "PHYS_PAGE" "103"
					( Origin gFrontEnd )
				)
				( attribute "ROOM" "DB1200Z"
					( Origin gFrontEnd )
				)
				( attribute "ROT" "0"
					( Origin gFrontEnd )
				)
				( attribute "SEC" "1"
					( Origin gFrontEnd )
				)
				( attribute "SEC_TYPE" "0402"
					( Origin gFrontEnd )
				)
				( attribute "TOLERANCE" "1.0%"
					( Origin gFrontEnd )
				)
				( attribute "VALUE" "42.2"
					( Origin gFrontEnd )
				)
				( attribute "VER" "1"
					( Origin gFrontEnd )
				)
				( attribute "WATTAGE" "1/16W"
					( Origin gFrontEnd )
				)
				( attribute "XY" "(1050,1800)"
					( Origin gFrontEnd )
				)
				( attribute "CHIPS_PART_NAME" "RES"
					( Origin gPackager )
				)
				( attribute "CDS_PART_NAME" "RES_0402-42.2,1.0%,1/16W,EMPTYA"
					( Origin gPackager )
				)
				( objectStatus "R4D18" )
			)
			( gate "@baseboard_fab2_lib.baseboard_fab2(sch_1):page103_i165"
				( attribute "BOM_COST" "SYS_CLOCK"
					( Origin gFrontEnd )
				)
				( attribute "CDS_LIB" "mstr_discrete"
					( Origin gPackager )
				)
				( attribute "CDS_LOCATION" "R6P17"
					( Origin gPackager )
				)
				( attribute "CDS_SEC" "1"
					( Origin gPackager )
				)
				( attribute "LOCATION" "R6P17"
					( Origin gFrontEnd )
				)
				( attribute "MATERIAL" "EMPTY"
					( Origin gFrontEnd )
				)
				( attribute "PACK_TYPE" "0402"
					( Origin gFrontEnd )
				)
				( attribute "PART_NUMBER" "G21796-259"
					( Origin gFrontEnd )
				)
				( attribute "PHYS_PAGE" "103"
					( Origin gFrontEnd )
				)
				( attribute "ROOM" "DB1200Z"
					( Origin gFrontEnd )
				)
				( attribute "ROT" "0"
					( Origin gFrontEnd )
				)
				( attribute "SEC" "1"
					( Origin gFrontEnd )
				)
				( attribute "SEC_TYPE" "0402"
					( Origin gFrontEnd )
				)
				( attribute "TOLERANCE" "1.0%"
					( Origin gFrontEnd )
				)
				( attribute "VALUE" "42.2"
					( Origin gFrontEnd )
				)
				( attribute "VER" "1"
					( Origin gFrontEnd )
				)
				( attribute "WATTAGE" "1/16W"
					( Origin gFrontEnd )
				)
				( attribute "XY" "(1050,1475)"
					( Origin gFrontEnd )
				)
				( attribute "CHIPS_PART_NAME" "RES"
					( Origin gPackager )
				)
				( attribute "CDS_PART_NAME" "RES_0402-42.2,1.0%,1/16W,EMPTYA"
					( Origin gPackager )
				)
				( objectStatus "R6P17" )
			)
			( gate "@baseboard_fab2_lib.baseboard_fab2(sch_1):page103_i167"
				( attribute "BOM_COST" "SYS_CLOCK"
					( Origin gFrontEnd )
				)
				( attribute "CDS_LIB" "mstr_discrete"
					( Origin gPackager )
				)
				( attribute "CDS_LOCATION" "R6P15"
					( Origin gPackager )
				)
				( attribute "CDS_SEC" "1"
					( Origin gPackager )
				)
				( attribute "LOCATION" "R6P15"
					( Origin gFrontEnd )
				)
				( attribute "MATERIAL" "EMPTY"
					( Origin gFrontEnd )
				)
				( attribute "PACK_TYPE" "0402"
					( Origin gFrontEnd )
				)
				( attribute "PART_NUMBER" "G21796-259"
					( Origin gFrontEnd )
				)
				( attribute "PHYS_PAGE" "103"
					( Origin gFrontEnd )
				)
				( attribute "ROOM" "DB1200Z"
					( Origin gFrontEnd )
				)
				( attribute "ROT" "0"
					( Origin gFrontEnd )
				)
				( attribute "SEC" "1"
					( Origin gFrontEnd )
				)
				( attribute "SEC_TYPE" "0402"
					( Origin gFrontEnd )
				)
				( attribute "TOLERANCE" "1.0%"
					( Origin gFrontEnd )
				)
				( attribute "VALUE" "42.2"
					( Origin gFrontEnd )
				)
				( attribute "VER" "1"
					( Origin gFrontEnd )
				)
				( attribute "WATTAGE" "1/16W"
					( Origin gFrontEnd )
				)
				( attribute "XY" "(1050,1150)"
					( Origin gFrontEnd )
				)
				( attribute "CHIPS_PART_NAME" "RES"
					( Origin gPackager )
				)
				( attribute "CDS_PART_NAME" "RES_0402-42.2,1.0%,1/16W,EMPTYA"
					( Origin gPackager )
				)
				( objectStatus "R6P15" )
			)
			( gate "@baseboard_fab2_lib.baseboard_fab2(sch_1):page104_i25"
				( attribute "CDS_LIB" "dev_discrete"
					( Origin gPackager )
				)
				( attribute "CDS_LOCATION" "C6F1"
					( Origin gPackager )
				)
				( attribute "CDS_SEC" "1"
					( Origin gPackager )
				)
				( attribute "LOCATION" "C6F1"
					( Origin gFrontEnd )
				)
				( attribute "MATERIAL" "X7R"
					( Origin gFrontEnd )
				)
				( attribute "PACK_TYPE" "0402V"
					( Origin gFrontEnd )
				)
				( attribute "PART_NUMBER" "A36096-030"
					( Origin gFrontEnd )
				)
				( attribute "PHYS_PAGE" "104"
					( Origin gFrontEnd )
				)
				( attribute "ROOM" "CLOCK_CPU0_OSC"
					( Origin gFrontEnd )
				)
				( attribute "ROT" "0"
					( Origin gFrontEnd )
				)
				( attribute "SEC" "1"
					( Origin gFrontEnd )
				)
				( attribute "SEC_TYPE" "0402V"
					( Origin gFrontEnd )
				)
				( attribute "TOLERANCE" "10%"
					( Origin gFrontEnd )
				)
				( attribute "VALUE" "0.1UF"
					( Origin gFrontEnd )
				)
				( attribute "VER" "1"
					( Origin gFrontEnd )
				)
				( attribute "VOLTAGE" "16V"
					( Units "uVoltage" "V" 1.000000)
					( Origin gFrontEnd )
				)
				( attribute "XY" "(-4250,5100)"
					( Origin gFrontEnd )
				)
				( attribute "CHIPS_PART_NAME" "CAP_A"
					( Origin gPackager )
				)
				( attribute "CDS_PART_NAME" "CAP_A_0402V-0.1UF,16V,10%,X7R,A"
					( Origin gPackager )
				)
				( objectStatus "C6F1" )
			)
			( gate "@baseboard_fab2_lib.baseboard_fab2(sch_1):page104_i34"
				( attribute "CDS_LIB" "dev_discrete"
					( Origin gPackager )
				)
				( attribute "CDS_LOCATION" "C3F2"
					( Origin gPackager )
				)
				( attribute "CDS_SEC" "1"
					( Origin gPackager )
				)
				( attribute "LOCATION" "C3F2"
					( Origin gFrontEnd )
				)
				( attribute "MATERIAL" "X7R"
					( Origin gFrontEnd )
				)
				( attribute "PACK_TYPE" "0402V"
					( Origin gFrontEnd )
				)
				( attribute "PART_NUMBER" "A36096-030"
					( Origin gFrontEnd )
				)
				( attribute "PHYS_PAGE" "104"
					( Origin gFrontEnd )
				)
				( attribute "ROOM" "CLOCK_CPU1_OSC"
					( Origin gFrontEnd )
				)
				( attribute "ROT" "0"
					( Origin gFrontEnd )
				)
				( attribute "SEC" "1"
					( Origin gFrontEnd )
				)
				( attribute "SEC_TYPE" "0402V"
					( Origin gFrontEnd )
				)
				( attribute "TOLERANCE" "10%"
					( Origin gFrontEnd )
				)
				( attribute "VALUE" "0.1UF"
					( Origin gFrontEnd )
				)
				( attribute "VER" "1"
					( Origin gFrontEnd )
				)
				( attribute "VOLTAGE" "16V"
					( Units "uVoltage" "V" 1.000000)
					( Origin gFrontEnd )
				)
				( attribute "XY" "(-4575,4225)"
					( Origin gFrontEnd )
				)
				( attribute "CHIPS_PART_NAME" "CAP_A"
					( Origin gPackager )
				)
				( attribute "CDS_PART_NAME" "CAP_A_0402V-0.1UF,16V,10%,X7R,A"
					( Origin gPackager )
				)
				( objectStatus "C3F2" )
			)
			( gate "@baseboard_fab2_lib.baseboard_fab2(sch_1):page104_i37"
				( attribute "CDS_LIB" "mstr_discrete"
					( Origin gPackager )
				)
				( attribute "CDS_LOCATION" "R6F8"
					( Origin gPackager )
				)
				( attribute "LOCATION" "R6F8"
					( Origin gFrontEnd )
				)
				( attribute "MATERIAL" "EMPTY"
					( Origin gFrontEnd )
				)
				( attribute "NO_XNET_CONNECTION" "1"
					( Origin gFrontEnd )
				)
				( attribute "PACK_TYPE" "0402"
					( Origin gFrontEnd )
				)
				( attribute "PART_NUMBER" "G21497-005"
					( Origin gFrontEnd )
				)
				( attribute "PHYS_PAGE" "104"
					( Origin gFrontEnd )
				)
				( attribute "ROOM" "CLOCK_CPU0_OSC"
					( Origin gFrontEnd )
				)
				( attribute "ROT" "0"
					( Origin gFrontEnd )
				)
				( attribute "SEC" "1"
					( Origin gFrontEnd )
				)
				( attribute "SEC_TYPE" "0402"
					( Origin gFrontEnd )
				)
				( attribute "TOLERANCE" "5%"
					( Origin gFrontEnd )
				)
				( attribute "VALUE" "0.0"
					( Origin gFrontEnd )
				)
				( attribute "VER" "1"
					( Origin gFrontEnd )
				)
				( attribute "WATTAGE" "1/16W"
					( Origin gFrontEnd )
				)
				( attribute "XY" "(525,4325)"
					( Origin gFrontEnd )
				)
				( attribute "CHIPS_PART_NAME" "RES"
					( Origin gPackager )
				)
				( attribute "CDS_PART_NAME" "RES_0402-0.0,5%,1/16W,EMPTY,G2A"
					( Origin gPackager )
				)
				( attribute "CDS_SEC" "1"
					( Origin gPackager )
				)
				( objectStatus "R6F8" )
			)
			( gate "@baseboard_fab2_lib.baseboard_fab2(sch_1):page104_i41"
				( attribute "CDS_LIB" "mstr_discrete"
					( Origin gPackager )
				)
				( attribute "CDS_LOCATION" "R6F6"
					( Origin gPackager )
				)
				( attribute "CDS_SEC" "1"
					( Origin gPackager )
				)
				( attribute "LOCATION" "R6F6"
					( Origin gFrontEnd )
				)
				( attribute "MATERIAL" "EMPTY"
					( Origin gFrontEnd )
				)
				( attribute "NO_XNET_CONNECTION" "1"
					( Origin gFrontEnd )
				)
				( attribute "PACK_TYPE" "0402"
					( Origin gFrontEnd )
				)
				( attribute "PART_NUMBER" "G21497-005"
					( Origin gFrontEnd )
				)
				( attribute "PHYS_PAGE" "104"
					( Origin gFrontEnd )
				)
				( attribute "ROOM" "CLOCK_CPU0_OSC"
					( Origin gFrontEnd )
				)
				( attribute "ROT" "0"
					( Origin gFrontEnd )
				)
				( attribute "SEC" "1"
					( Origin gFrontEnd )
				)
				( attribute "SEC_TYPE" "0402"
					( Origin gFrontEnd )
				)
				( attribute "TOLERANCE" "5%"
					( Origin gFrontEnd )
				)
				( attribute "VALUE" "0.0"
					( Origin gFrontEnd )
				)
				( attribute "VER" "1"
					( Origin gFrontEnd )
				)
				( attribute "WATTAGE" "1/16W"
					( Origin gFrontEnd )
				)
				( attribute "XY" "(525,5025)"
					( Origin gFrontEnd )
				)
				( attribute "CHIPS_PART_NAME" "RES"
					( Origin gPackager )
				)
				( attribute "CDS_PART_NAME" "RES_0402-0.0,5%,1/16W,EMPTY,G2A"
					( Origin gPackager )
				)
				( objectStatus "R6F6" )
			)
			( gate "@baseboard_fab2_lib.baseboard_fab2(sch_1):page104_i51"
				( attribute "CDS_LIB" "mstr_discrete"
					( Origin gPackager )
				)
				( attribute "CDS_LOCATION" "R3F1"
					( Origin gPackager )
				)
				( attribute "CDS_SEC" "1"
					( Origin gPackager )
				)
				( attribute "LOCATION" "R3F1"
					( Origin gFrontEnd )
				)
				( attribute "MATERIAL" "EMPTY"
					( Origin gFrontEnd )
				)
				( attribute "NO_XNET_CONNECTION" "1"
					( Origin gFrontEnd )
				)
				( attribute "PACK_TYPE" "0402"
					( Origin gFrontEnd )
				)
				( attribute "PART_NUMBER" "G21497-005"
					( Origin gFrontEnd )
				)
				( attribute "PHYS_PAGE" "104"
					( Origin gFrontEnd )
				)
				( attribute "ROOM" "CLOCK_CPU1_OSC"
					( Origin gFrontEnd )
				)
				( attribute "ROT" "0"
					( Origin gFrontEnd )
				)
				( attribute "SEC" "1"
					( Origin gFrontEnd )
				)
				( attribute "SEC_TYPE" "0402"
					( Origin gFrontEnd )
				)
				( attribute "TOLERANCE" "5%"
					( Origin gFrontEnd )
				)
				( attribute "VALUE" "0.0"
					( Origin gFrontEnd )
				)
				( attribute "VER" "1"
					( Origin gFrontEnd )
				)
				( attribute "WATTAGE" "1/16W"
					( Origin gFrontEnd )
				)
				( attribute "XY" "(525,3625)"
					( Origin gFrontEnd )
				)
				( attribute "CHIPS_PART_NAME" "RES"
					( Origin gPackager )
				)
				( attribute "CDS_PART_NAME" "RES_0402-0.0,5%,1/16W,EMPTY,G2A"
					( Origin gPackager )
				)
				( objectStatus "R3F1" )
			)
			( gate "@baseboard_fab2_lib.baseboard_fab2(sch_1):page104_i53"
				( attribute "CDS_LIB" "mstr_discrete"
					( Origin gPackager )
				)
				( attribute "CDS_LOCATION" "R3F3"
					( Origin gPackager )
				)
				( attribute "CDS_SEC" "1"
					( Origin gPackager )
				)
				( attribute "LOCATION" "R3F3"
					( Origin gFrontEnd )
				)
				( attribute "MATERIAL" "EMPTY"
					( Origin gFrontEnd )
				)
				( attribute "NO_XNET_CONNECTION" "1"
					( Origin gFrontEnd )
				)
				( attribute "PACK_TYPE" "0402"
					( Origin gFrontEnd )
				)
				( attribute "PART_NUMBER" "G21497-005"
					( Origin gFrontEnd )
				)
				( attribute "PHYS_PAGE" "104"
					( Origin gFrontEnd )
				)
				( attribute "ROOM" "CLOCK_CPU1_OSC"
					( Origin gFrontEnd )
				)
				( attribute "ROT" "0"
					( Origin gFrontEnd )
				)
				( attribute "SEC" "1"
					( Origin gFrontEnd )
				)
				( attribute "SEC_TYPE" "0402"
					( Origin gFrontEnd )
				)
				( attribute "TOLERANCE" "5%"
					( Origin gFrontEnd )
				)
				( attribute "VALUE" "0.0"
					( Origin gFrontEnd )
				)
				( attribute "VER" "1"
					( Origin gFrontEnd )
				)
				( attribute "WATTAGE" "1/16W"
					( Origin gFrontEnd )
				)
				( attribute "XY" "(525,2925)"
					( Origin gFrontEnd )
				)
				( attribute "CHIPS_PART_NAME" "RES"
					( Origin gPackager )
				)
				( attribute "CDS_PART_NAME" "RES_0402-0.0,5%,1/16W,EMPTY,G2A"
					( Origin gPackager )
				)
				( objectStatus "R3F3" )
			)
			( gate "@baseboard_fab2_lib.baseboard_fab2(sch_1):page104_i67"
				( attribute "CDS_LIB" "mstr_discrete"
					( Origin gPackager )
				)
				( attribute "CDS_LOCATION" "R6F7"
					( Origin gPackager )
				)
				( attribute "CDS_SEC" "1"
					( Origin gPackager )
				)
				( attribute "LOCATION" "R6F7"
					( Origin gFrontEnd )
				)
				( attribute "MATERIAL" "CHIP"
					( Origin gFrontEnd )
				)
				( attribute "NO_XNET_CONNECTION" "1"
					( Origin gFrontEnd )
				)
				( attribute "PACK_TYPE" "0402"
					( Origin gFrontEnd )
				)
				( attribute "PART_NUMBER" "G21497-005"
					( Origin gFrontEnd )
				)
				( attribute "PHYS_PAGE" "104"
					( Origin gFrontEnd )
				)
				( attribute "ROOM" "CLOCK_CPU0_OSC"
					( Origin gFrontEnd )
				)
				( attribute "ROT" "0"
					( Origin gFrontEnd )
				)
				( attribute "SEC" "1"
					( Origin gFrontEnd )
				)
				( attribute "SEC_TYPE" "0402"
					( Origin gFrontEnd )
				)
				( attribute "TOLERANCE" "5%"
					( Origin gFrontEnd )
				)
				( attribute "VALUE" "0.0"
					( Origin gFrontEnd )
				)
				( attribute "VER" "1"
					( Origin gFrontEnd )
				)
				( attribute "WATTAGE" "1/16W"
					( Origin gFrontEnd )
				)
				( attribute "XY" "(525,5175)"
					( Origin gFrontEnd )
				)
				( attribute "CHIPS_PART_NAME" "RES"
					( Origin gPackager )
				)
				( attribute "CDS_PART_NAME" "RES_0402-0.0,5%,1/16W,CHIP,G21A"
					( Origin gPackager )
				)
				( objectStatus "R6F7" )
			)
			( gate "@baseboard_fab2_lib.baseboard_fab2(sch_1):page104_i68"
				( attribute "CDS_LIB" "mstr_discrete"
					( Origin gPackager )
				)
				( attribute "CDS_LOCATION" "R6F9"
					( Origin gPackager )
				)
				( attribute "LOCATION" "R6F9"
					( Origin gFrontEnd )
				)
				( attribute "MATERIAL" "CHIP"
					( Origin gFrontEnd )
				)
				( attribute "NO_XNET_CONNECTION" "1"
					( Origin gFrontEnd )
				)
				( attribute "PACK_TYPE" "0402"
					( Origin gFrontEnd )
				)
				( attribute "PART_NUMBER" "G21497-005"
					( Origin gFrontEnd )
				)
				( attribute "PHYS_PAGE" "104"
					( Origin gFrontEnd )
				)
				( attribute "ROOM" "CLOCK_CPU0_OSC"
					( Origin gFrontEnd )
				)
				( attribute "ROT" "0"
					( Origin gFrontEnd )
				)
				( attribute "SEC" "1"
					( Origin gFrontEnd )
				)
				( attribute "SEC_TYPE" "0402"
					( Origin gFrontEnd )
				)
				( attribute "TOLERANCE" "5%"
					( Origin gFrontEnd )
				)
				( attribute "VALUE" "0.0"
					( Origin gFrontEnd )
				)
				( attribute "VER" "1"
					( Origin gFrontEnd )
				)
				( attribute "WATTAGE" "1/16W"
					( Origin gFrontEnd )
				)
				( attribute "XY" "(525,4475)"
					( Origin gFrontEnd )
				)
				( attribute "CHIPS_PART_NAME" "RES"
					( Origin gPackager )
				)
				( attribute "CDS_PART_NAME" "RES_0402-0.0,5%,1/16W,CHIP,G21A"
					( Origin gPackager )
				)
				( attribute "CDS_SEC" "1"
					( Origin gPackager )
				)
				( objectStatus "R6F9" )
			)
			( gate "@baseboard_fab2_lib.baseboard_fab2(sch_1):page104_i69"
				( attribute "CDS_LIB" "mstr_discrete"
					( Origin gPackager )
				)
				( attribute "CDS_LOCATION" "R3F2"
					( Origin gPackager )
				)
				( attribute "CDS_SEC" "1"
					( Origin gPackager )
				)
				( attribute "LOCATION" "R3F2"
					( Origin gFrontEnd )
				)
				( attribute "MATERIAL" "CHIP"
					( Origin gFrontEnd )
				)
				( attribute "NO_XNET_CONNECTION" "1"
					( Origin gFrontEnd )
				)
				( attribute "PACK_TYPE" "0402"
					( Origin gFrontEnd )
				)
				( attribute "PART_NUMBER" "G21497-005"
					( Origin gFrontEnd )
				)
				( attribute "PHYS_PAGE" "104"
					( Origin gFrontEnd )
				)
				( attribute "ROOM" "CLOCK_CPU1_OSC"
					( Origin gFrontEnd )
				)
				( attribute "ROT" "0"
					( Origin gFrontEnd )
				)
				( attribute "SEC" "1"
					( Origin gFrontEnd )
				)
				( attribute "SEC_TYPE" "0402"
					( Origin gFrontEnd )
				)
				( attribute "TOLERANCE" "5%"
					( Origin gFrontEnd )
				)
				( attribute "VALUE" "0.0"
					( Origin gFrontEnd )
				)
				( attribute "VER" "1"
					( Origin gFrontEnd )
				)
				( attribute "WATTAGE" "1/16W"
					( Origin gFrontEnd )
				)
				( attribute "XY" "(525,3775)"
					( Origin gFrontEnd )
				)
				( attribute "CHIPS_PART_NAME" "RES"
					( Origin gPackager )
				)
				( attribute "CDS_PART_NAME" "RES_0402-0.0,5%,1/16W,CHIP,G21A"
					( Origin gPackager )
				)
				( objectStatus "R3F2" )
			)
			( gate "@baseboard_fab2_lib.baseboard_fab2(sch_1):page104_i70"
				( attribute "CDS_LIB" "mstr_discrete"
					( Origin gPackager )
				)
				( attribute "CDS_LOCATION" "R3F4"
					( Origin gPackager )
				)
				( attribute "CDS_SEC" "1"
					( Origin gPackager )
				)
				( attribute "LOCATION" "R3F4"
					( Origin gFrontEnd )
				)
				( attribute "MATERIAL" "CHIP"
					( Origin gFrontEnd )
				)
				( attribute "NO_XNET_CONNECTION" "1"
					( Origin gFrontEnd )
				)
				( attribute "PACK_TYPE" "0402"
					( Origin gFrontEnd )
				)
				( attribute "PART_NUMBER" "G21497-005"
					( Origin gFrontEnd )
				)
				( attribute "PHYS_PAGE" "104"
					( Origin gFrontEnd )
				)
				( attribute "ROOM" "CLOCK_CPU1_OSC"
					( Origin gFrontEnd )
				)
				( attribute "ROT" "0"
					( Origin gFrontEnd )
				)
				( attribute "SEC" "1"
					( Origin gFrontEnd )
				)
				( attribute "SEC_TYPE" "0402"
					( Origin gFrontEnd )
				)
				( attribute "TOLERANCE" "5%"
					( Origin gFrontEnd )
				)
				( attribute "VALUE" "0.0"
					( Origin gFrontEnd )
				)
				( attribute "VER" "1"
					( Origin gFrontEnd )
				)
				( attribute "WATTAGE" "1/16W"
					( Origin gFrontEnd )
				)
				( attribute "XY" "(525,3075)"
					( Origin gFrontEnd )
				)
				( attribute "CHIPS_PART_NAME" "RES"
					( Origin gPackager )
				)
				( attribute "CDS_PART_NAME" "RES_0402-0.0,5%,1/16W,CHIP,G21A"
					( Origin gPackager )
				)
				( objectStatus "R3F4" )
			)
			( gate "@baseboard_fab2_lib.baseboard_fab2(sch_1):page104_i71"
				( attribute "CDS_LIB" "mstr_discrete"
					( Origin gPackager )
				)
				( attribute "CDS_LMAN_SYM_OUTLINE" "-450,200,450,-200"
					( Origin gPackager )
				)
				( attribute "CDS_LOCATION" "Y6F1"
					( Origin gPackager )
				)
				( attribute "CDS_SEC" "1"
					( Origin gPackager )
				)
				( attribute "LOCATION" "Y6F1"
					( Origin gFrontEnd )
				)
				( attribute "MATERIAL" "OSC"
					( Origin gFrontEnd )
				)
				( attribute "PACK_TYPE" "6P10"
					( Origin gFrontEnd )
				)
				( attribute "PART_NUMBER" "G63831-004"
					( Origin gFrontEnd )
				)
				( attribute "PHYS_PAGE" "104"
					( Origin gFrontEnd )
				)
				( attribute "ROT" "0"
					( Origin gFrontEnd )
				)
				( attribute "SEC" "1"
					( Origin gFrontEnd )
				)
				( attribute "SEC_TYPE" "6P10"
					( Origin gFrontEnd )
				)
				( attribute "VALUE" "156.25MHZ"
					( Origin gFrontEnd )
				)
				( attribute "VER" "17"
					( Origin gFrontEnd )
				)
				( attribute "XY" "(-3400,4775)"
					( Origin gFrontEnd )
				)
				( attribute "CHIPS_PART_NAME" "OSC_C"
					( Origin gPackager )
				)
				( attribute "CDS_PART_NAME" "OSC_C_6P10-156.25MHZ,OSC,G6383A"
					( Origin gPackager )
				)
				( objectStatus "Y6F1" )
			)
			( gate "@baseboard_fab2_lib.baseboard_fab2(sch_1):page104_i72"
				( attribute "CDS_LIB" "mstr_discrete"
					( Origin gPackager )
				)
				( attribute "CDS_LMAN_SYM_OUTLINE" "-450,200,450,-200"
					( Origin gPackager )
				)
				( attribute "CDS_LOCATION" "Y3F1"
					( Origin gPackager )
				)
				( attribute "CDS_SEC" "1"
					( Origin gPackager )
				)
				( attribute "LOCATION" "Y3F1"
					( Origin gFrontEnd )
				)
				( attribute "MATERIAL" "OSC"
					( Origin gFrontEnd )
				)
				( attribute "PACK_TYPE" "6P10"
					( Origin gFrontEnd )
				)
				( attribute "PART_NUMBER" "G63831-004"
					( Origin gFrontEnd )
				)
				( attribute "PHYS_PAGE" "104"
					( Origin gFrontEnd )
				)
				( attribute "ROT" "0"
					( Origin gFrontEnd )
				)
				( attribute "SEC" "1"
					( Origin gFrontEnd )
				)
				( attribute "SEC_TYPE" "6P10"
					( Origin gFrontEnd )
				)
				( attribute "VALUE" "156.25MHZ"
					( Origin gFrontEnd )
				)
				( attribute "VER" "17"
					( Origin gFrontEnd )
				)
				( attribute "XY" "(-3700,3925)"
					( Origin gFrontEnd )
				)
				( attribute "CHIPS_PART_NAME" "OSC_C"
					( Origin gPackager )
				)
				( attribute "CDS_PART_NAME" "OSC_C_6P10-156.25MHZ,OSC,G6383A"
					( Origin gPackager )
				)
				( objectStatus "Y3F1" )
			)
			( gate "@baseboard_fab2_lib.baseboard_fab2(sch_1):page104_i78"
				( attribute "CDS_LIB" "mstr_discrete"
					( Origin gPackager )
				)
				( attribute "CDS_LOCATION" "R6F10"
					( Origin gPackager )
				)
				( attribute "CDS_SEC" "1"
					( Origin gPackager )
				)
				( attribute "LOCATION" "R6F10"
					( Origin gFrontEnd )
				)
				( attribute "MATERIAL" "EMPTY"
					( Origin gFrontEnd )
				)
				( attribute "PACK_TYPE" "0402"
					( Origin gFrontEnd )
				)
				( attribute "PART_NUMBER" "G21497-005"
					( Origin gFrontEnd )
				)
				( attribute "PHYS_PAGE" "104"
					( Origin gFrontEnd )
				)
				( attribute "ROT" "0"
					( Origin gFrontEnd )
				)
				( attribute "SEC" "1"
					( Origin gFrontEnd )
				)
				( attribute "SEC_TYPE" "0402"
					( Origin gFrontEnd )
				)
				( attribute "TOLERANCE" "5%"
					( Origin gFrontEnd )
				)
				( attribute "VALUE" "0.0"
					( Origin gFrontEnd )
				)
				( attribute "VER" "1"
					( Origin gFrontEnd )
				)
				( attribute "WATTAGE" "1/16W"
					( Origin gFrontEnd )
				)
				( attribute "XY" "(525,4825)"
					( Origin gFrontEnd )
				)
				( attribute "CHIPS_PART_NAME" "RES"
					( Origin gPackager )
				)
				( attribute "CDS_PART_NAME" "RES_0402-0.0,5%,1/16W,EMPTY,G2A"
					( Origin gPackager )
				)
				( objectStatus "R6F10" )
			)
			( gate "@baseboard_fab2_lib.baseboard_fab2(sch_1):page104_i79"
				( attribute "CDS_LIB" "mstr_discrete"
					( Origin gPackager )
				)
				( attribute "LOCATION" "R6F11"
					( Origin gFrontEnd )
				)
				( attribute "MATERIAL" "EMPTY"
					( Origin gFrontEnd )
				)
				( attribute "PACK_TYPE" "0402"
					( Origin gFrontEnd )
				)
				( attribute "PART_NUMBER" "G21497-005"
					( Origin gFrontEnd )
				)
				( attribute "PHYS_PAGE" "104"
					( Origin gFrontEnd )
				)
				( attribute "ROT" "0"
					( Origin gFrontEnd )
				)
				( attribute "SEC" "1"
					( Origin gFrontEnd )
				)
				( attribute "SEC_TYPE" "0402"
					( Origin gFrontEnd )
				)
				( attribute "TOLERANCE" "5%"
					( Origin gFrontEnd )
				)
				( attribute "VALUE" "0.0"
					( Origin gFrontEnd )
				)
				( attribute "VER" "1"
					( Origin gFrontEnd )
				)
				( attribute "WATTAGE" "1/16W"
					( Origin gFrontEnd )
				)
				( attribute "XY" "(525,4125)"
					( Origin gFrontEnd )
				)
				( attribute "CHIPS_PART_NAME" "RES"
					( Origin gPackager )
				)
				( attribute "CDS_PART_NAME" "RES_0402-0.0,5%,1/16W,EMPTY,G2A"
					( Origin gPackager )
				)
				( attribute "CDS_LOCATION" "R6F11"
					( Origin gPackager )
				)
				( attribute "CDS_SEC" "1"
					( Origin gPackager )
				)
				( objectStatus "R6F11" )
			)
			( gate "@baseboard_fab2_lib.baseboard_fab2(sch_1):page104_i84"
				( attribute "CDS_LIB" "mstr_discrete"
					( Origin gPackager )
				)
				( attribute "CDS_LOCATION" "R3F5"
					( Origin gPackager )
				)
				( attribute "CDS_SEC" "1"
					( Origin gPackager )
				)
				( attribute "LOCATION" "R3F5"
					( Origin gFrontEnd )
				)
				( attribute "MATERIAL" "EMPTY"
					( Origin gFrontEnd )
				)
				( attribute "PACK_TYPE" "0402"
					( Origin gFrontEnd )
				)
				( attribute "PART_NUMBER" "G21497-005"
					( Origin gFrontEnd )
				)
				( attribute "PHYS_PAGE" "104"
					( Origin gFrontEnd )
				)
				( attribute "ROT" "0"
					( Origin gFrontEnd )
				)
				( attribute "SEC" "1"
					( Origin gFrontEnd )
				)
				( attribute "SEC_TYPE" "0402"
					( Origin gFrontEnd )
				)
				( attribute "TOLERANCE" "5%"
					( Origin gFrontEnd )
				)
				( attribute "VALUE" "0.0"
					( Origin gFrontEnd )
				)
				( attribute "VER" "1"
					( Origin gFrontEnd )
				)
				( attribute "WATTAGE" "1/16W"
					( Origin gFrontEnd )
				)
				( attribute "XY" "(525,3425)"
					( Origin gFrontEnd )
				)
				( attribute "CHIPS_PART_NAME" "RES"
					( Origin gPackager )
				)
				( attribute "CDS_PART_NAME" "RES_0402-0.0,5%,1/16W,EMPTY,G2A"
					( Origin gPackager )
				)
				( objectStatus "R3F5" )
			)
			( gate "@baseboard_fab2_lib.baseboard_fab2(sch_1):page104_i88"
				( attribute "CDS_LIB" "mstr_discrete"
					( Origin gPackager )
				)
				( attribute "CDS_LOCATION" "R3F6"
					( Origin gPackager )
				)
				( attribute "CDS_SEC" "1"
					( Origin gPackager )
				)
				( attribute "LOCATION" "R3F6"
					( Origin gFrontEnd )
				)
				( attribute "MATERIAL" "EMPTY"
					( Origin gFrontEnd )
				)
				( attribute "PACK_TYPE" "0402"
					( Origin gFrontEnd )
				)
				( attribute "PART_NUMBER" "G21497-005"
					( Origin gFrontEnd )
				)
				( attribute "PHYS_PAGE" "104"
					( Origin gFrontEnd )
				)
				( attribute "ROT" "0"
					( Origin gFrontEnd )
				)
				( attribute "SEC" "1"
					( Origin gFrontEnd )
				)
				( attribute "SEC_TYPE" "0402"
					( Origin gFrontEnd )
				)
				( attribute "TOLERANCE" "5%"
					( Origin gFrontEnd )
				)
				( attribute "VALUE" "0.0"
					( Origin gFrontEnd )
				)
				( attribute "VER" "1"
					( Origin gFrontEnd )
				)
				( attribute "WATTAGE" "1/16W"
					( Origin gFrontEnd )
				)
				( attribute "XY" "(525,2725)"
					( Origin gFrontEnd )
				)
				( attribute "CHIPS_PART_NAME" "RES"
					( Origin gPackager )
				)
				( attribute "CDS_PART_NAME" "RES_0402-0.0,5%,1/16W,EMPTY,G2A"
					( Origin gPackager )
				)
				( objectStatus "R3F6" )
			)
			( gate "@baseboard_fab2_lib.baseboard_fab2(sch_1):page104_i93"
				( attribute "CDS_LIB" "mstr_discrete"
					( Origin gPackager )
				)
				( attribute "CDS_LOCATION" "R8D43"
					( Origin gPackager )
				)
				( attribute "CDS_SEC" "1"
					( Origin gPackager )
				)
				( attribute "LOCATION" "R8D43"
					( Origin gFrontEnd )
				)
				( attribute "MATERIAL" "CHIP"
					( Origin gFrontEnd )
				)
				( attribute "PACK_TYPE" "0402"
					( Origin gFrontEnd )
				)
				( attribute "PART_NUMBER" "G21497-005"
					( Origin gFrontEnd )
				)
				( attribute "PHYS_PAGE" "104"
					( Origin gFrontEnd )
				)
				( attribute "ROOM" "CLOCK_CPU1_OSC"
					( Origin gFrontEnd )
				)
				( attribute "ROT" "0"
					( Origin gFrontEnd )
				)
				( attribute "SEC" "1"
					( Origin gFrontEnd )
				)
				( attribute "SEC_TYPE" "0402"
					( Origin gFrontEnd )
				)
				( attribute "TOLERANCE" "5%"
					( Origin gFrontEnd )
				)
				( attribute "VALUE" "0.0"
					( Origin gFrontEnd )
				)
				( attribute "VER" "1"
					( Origin gFrontEnd )
				)
				( attribute "WATTAGE" "1/16W"
					( Origin gFrontEnd )
				)
				( attribute "XY" "(550,2200)"
					( Origin gFrontEnd )
				)
				( attribute "CHIPS_PART_NAME" "RES"
					( Origin gPackager )
				)
				( attribute "CDS_PART_NAME" "RES_0402-0.0,5%,1/16W,CHIP,G21A"
					( Origin gPackager )
				)
				( objectStatus "R8D43" )
			)
			( gate "@baseboard_fab2_lib.baseboard_fab2(sch_1):page104_i94"
				( attribute "CDS_LIB" "mstr_discrete"
					( Origin gPackager )
				)
				( attribute "CDS_LOCATION" "R7D40"
					( Origin gPackager )
				)
				( attribute "CDS_SEC" "1"
					( Origin gPackager )
				)
				( attribute "LOCATION" "R7D40"
					( Origin gFrontEnd )
				)
				( attribute "MATERIAL" "EMPTY"
					( Origin gFrontEnd )
				)
				( attribute "PACK_TYPE" "0402"
					( Origin gFrontEnd )
				)
				( attribute "PART_NUMBER" "G21497-005"
					( Origin gFrontEnd )
				)
				( attribute "PHYS_PAGE" "104"
					( Origin gFrontEnd )
				)
				( attribute "ROOM" "CLOCK_CPU1_OSC"
					( Origin gFrontEnd )
				)
				( attribute "ROT" "0"
					( Origin gFrontEnd )
				)
				( attribute "SEC" "1"
					( Origin gFrontEnd )
				)
				( attribute "SEC_TYPE" "0402"
					( Origin gFrontEnd )
				)
				( attribute "TOLERANCE" "5%"
					( Origin gFrontEnd )
				)
				( attribute "VALUE" "0.0"
					( Origin gFrontEnd )
				)
				( attribute "VER" "1"
					( Origin gFrontEnd )
				)
				( attribute "WATTAGE" "1/16W"
					( Origin gFrontEnd )
				)
				( attribute "XY" "(550,2000)"
					( Origin gFrontEnd )
				)
				( attribute "CHIPS_PART_NAME" "RES"
					( Origin gPackager )
				)
				( attribute "CDS_PART_NAME" "RES_0402-0.0,5%,1/16W,EMPTY,G2A"
					( Origin gPackager )
				)
				( objectStatus "R7D40" )
			)
			( gate "@baseboard_fab2_lib.baseboard_fab2(sch_1):page104_i96"
				( attribute "CDS_LIB" "mstr_discrete"
					( Origin gPackager )
				)
				( attribute "CDS_LOCATION" "R7D36"
					( Origin gPackager )
				)
				( attribute "CDS_SEC" "1"
					( Origin gPackager )
				)
				( attribute "LOCATION" "R7D36"
					( Origin gFrontEnd )
				)
				( attribute "MATERIAL" "CHIP"
					( Origin gFrontEnd )
				)
				( attribute "PACK_TYPE" "0402"
					( Origin gFrontEnd )
				)
				( attribute "PART_NUMBER" "G21497-005"
					( Origin gFrontEnd )
				)
				( attribute "PHYS_PAGE" "104"
					( Origin gFrontEnd )
				)
				( attribute "ROOM" "CLOCK_CPU1_OSC"
					( Origin gFrontEnd )
				)
				( attribute "ROT" "0"
					( Origin gFrontEnd )
				)
				( attribute "SEC" "1"
					( Origin gFrontEnd )
				)
				( attribute "SEC_TYPE" "0402"
					( Origin gFrontEnd )
				)
				( attribute "TOLERANCE" "5%"
					( Origin gFrontEnd )
				)
				( attribute "VALUE" "0.0"
					( Origin gFrontEnd )
				)
				( attribute "VER" "1"
					( Origin gFrontEnd )
				)
				( attribute "WATTAGE" "1/16W"
					( Origin gFrontEnd )
				)
				( attribute "XY" "(550,1500)"
					( Origin gFrontEnd )
				)
				( attribute "CHIPS_PART_NAME" "RES"
					( Origin gPackager )
				)
				( attribute "CDS_PART_NAME" "RES_0402-0.0,5%,1/16W,CHIP,G21A"
					( Origin gPackager )
				)
				( objectStatus "R7D36" )
			)
			( gate "@baseboard_fab2_lib.baseboard_fab2(sch_1):page104_i97"
				( attribute "CDS_LIB" "mstr_discrete"
					( Origin gPackager )
				)
				( attribute "CDS_LOCATION" "R7D38"
					( Origin gPackager )
				)
				( attribute "CDS_SEC" "1"
					( Origin gPackager )
				)
				( attribute "LOCATION" "R7D38"
					( Origin gFrontEnd )
				)
				( attribute "MATERIAL" "EMPTY"
					( Origin gFrontEnd )
				)
				( attribute "PACK_TYPE" "0402"
					( Origin gFrontEnd )
				)
				( attribute "PART_NUMBER" "G21497-005"
					( Origin gFrontEnd )
				)
				( attribute "PHYS_PAGE" "104"
					( Origin gFrontEnd )
				)
				( attribute "ROOM" "CLOCK_CPU1_OSC"
					( Origin gFrontEnd )
				)
				( attribute "ROT" "0"
					( Origin gFrontEnd )
				)
				( attribute "SEC" "1"
					( Origin gFrontEnd )
				)
				( attribute "SEC_TYPE" "0402"
					( Origin gFrontEnd )
				)
				( attribute "TOLERANCE" "5%"
					( Origin gFrontEnd )
				)
				( attribute "VALUE" "0.0"
					( Origin gFrontEnd )
				)
				( attribute "VER" "1"
					( Origin gFrontEnd )
				)
				( attribute "WATTAGE" "1/16W"
					( Origin gFrontEnd )
				)
				( attribute "XY" "(550,1300)"
					( Origin gFrontEnd )
				)
				( attribute "CHIPS_PART_NAME" "RES"
					( Origin gPackager )
				)
				( attribute "CDS_PART_NAME" "RES_0402-0.0,5%,1/16W,EMPTY,G2A"
					( Origin gPackager )
				)
				( objectStatus "R7D38" )
			)
			( gate "@baseboard_fab2_lib.baseboard_fab2(sch_1):page105_i1"
				( attribute "CDS_LIB" "mstr_discrete"
					( Origin gPackager )
				)
				( attribute "CDS_LOCATION" "C7G24"
					( Origin gPackager )
				)
				( attribute "CDS_SEC" "1"
					( Origin gPackager )
				)
				( attribute "LOCATION" "C7G24"
					( Origin gFrontEnd )
				)
				( attribute "MATERIAL" "X7R"
					( Origin gFrontEnd )
				)
				( attribute "PACK_TYPE" "0402"
					( Origin gFrontEnd )
				)
				( attribute "PART_NUMBER" "A36096-155"
					( Origin gFrontEnd )
				)
				( attribute "PHYS_PAGE" "105"
					( Origin gFrontEnd )
				)
				( attribute "ROOM" "OCP_STEERING"
					( Origin gFrontEnd )
				)
				( attribute "ROT" "2"
					( Origin gFrontEnd )
				)
				( attribute "SEC" "1"
					( Origin gFrontEnd )
				)
				( attribute "SEC_TYPE" "0402"
					( Origin gFrontEnd )
				)
				( attribute "TOLERANCE" "10%"
					( Origin gFrontEnd )
				)
				( attribute "VALUE" "0.22UF"
					( Origin gFrontEnd )
				)
				( attribute "VER" "1"
					( Origin gFrontEnd )
				)
				( attribute "VOLTAGE" "16V"
					( Units "uVoltage" "V" 1.000000)
					( Origin gFrontEnd )
				)
				( attribute "XY" "(1125,3650)"
					( Origin gFrontEnd )
				)
				( attribute "CHIPS_PART_NAME" "CAP"
					( Origin gPackager )
				)
				( attribute "CDS_PART_NAME" "CAP_0402-0.22UF,16V,10%,X7R,A3A"
					( Origin gPackager )
				)
				( objectStatus "C7G24" )
			)
			( gate "@baseboard_fab2_lib.baseboard_fab2(sch_1):page105_i6"
				( attribute "CDS_LIB" "mstr_discrete"
					( Origin gPackager )
				)
				( attribute "CDS_LOCATION" "C7G6"
					( Origin gPackager )
				)
				( attribute "CDS_SEC" "1"
					( Origin gPackager )
				)
				( attribute "LOCATION" "C7G6"
					( Origin gFrontEnd )
				)
				( attribute "MATERIAL" "X7R"
					( Origin gFrontEnd )
				)
				( attribute "PACK_TYPE" "0402"
					( Origin gFrontEnd )
				)
				( attribute "PART_NUMBER" "A36096-155"
					( Origin gFrontEnd )
				)
				( attribute "PHYS_PAGE" "105"
					( Origin gFrontEnd )
				)
				( attribute "ROOM" "OCP_STEERING"
					( Origin gFrontEnd )
				)
				( attribute "ROT" "2"
					( Origin gFrontEnd )
				)
				( attribute "SEC" "1"
					( Origin gPackager )
				)
				( attribute "TOLERANCE" "10%"
					( Origin gFrontEnd )
				)
				( attribute "VALUE" "0.22UF"
					( Origin gFrontEnd )
				)
				( attribute "VER" "1"
					( Origin gFrontEnd )
				)
				( attribute "VOLTAGE" "16V"
					( Units "uVoltage" "V" 1.000000)
					( Origin gFrontEnd )
				)
				( attribute "XY" "(-700,3350)"
					( Origin gFrontEnd )
				)
				( attribute "CHIPS_PART_NAME" "CAP"
					( Origin gPackager )
				)
				( attribute "CDS_PART_NAME" "CAP_0402-0.22UF,16V,10%,X7R,A3A"
					( Origin gPackager )
				)
				( objectStatus "C7G6" )
			)
			( gate "@baseboard_fab2_lib.baseboard_fab2(sch_1):page105_i7"
				( attribute "CDS_LIB" "mstr_discrete"
					( Origin gPackager )
				)
				( attribute "CDS_LOCATION" "C7G7"
					( Origin gPackager )
				)
				( attribute "CDS_SEC" "1"
					( Origin gPackager )
				)
				( attribute "LOCATION" "C7G7"
					( Origin gFrontEnd )
				)
				( attribute "MATERIAL" "X7R"
					( Origin gFrontEnd )
				)
				( attribute "PACK_TYPE" "0402"
					( Origin gFrontEnd )
				)
				( attribute "PART_NUMBER" "A36096-155"
					( Origin gFrontEnd )
				)
				( attribute "PHYS_PAGE" "105"
					( Origin gFrontEnd )
				)
				( attribute "ROOM" "OCP_STEERING"
					( Origin gFrontEnd )
				)
				( attribute "ROT" "2"
					( Origin gFrontEnd )
				)
				( attribute "SEC" "1"
					( Origin gFrontEnd )
				)
				( attribute "SEC_TYPE" "0402"
					( Origin gFrontEnd )
				)
				( attribute "TOLERANCE" "10%"
					( Origin gFrontEnd )
				)
				( attribute "VALUE" "0.22UF"
					( Origin gFrontEnd )
				)
				( attribute "VER" "1"
					( Origin gFrontEnd )
				)
				( attribute "VOLTAGE" "16V"
					( Units "uVoltage" "V" 1.000000)
					( Origin gFrontEnd )
				)
				( attribute "XY" "(-500,3650)"
					( Origin gFrontEnd )
				)
				( attribute "CHIPS_PART_NAME" "CAP"
					( Origin gPackager )
				)
				( attribute "CDS_PART_NAME" "CAP_0402-0.22UF,16V,10%,X7R,A3A"
					( Origin gPackager )
				)
				( objectStatus "C7G7" )
			)
			( gate "@baseboard_fab2_lib.baseboard_fab2(sch_1):page105_i8"
				( attribute "CDS_LIB" "mstr_discrete"
					( Origin gPackager )
				)
				( attribute "CDS_LOCATION" "C7G10"
					( Origin gPackager )
				)
				( attribute "CDS_SEC" "1"
					( Origin gPackager )
				)
				( attribute "LOCATION" "C7G10"
					( Origin gFrontEnd )
				)
				( attribute "MATERIAL" "X7R"
					( Origin gFrontEnd )
				)
				( attribute "PACK_TYPE" "0402"
					( Origin gFrontEnd )
				)
				( attribute "PART_NUMBER" "A36096-155"
					( Origin gFrontEnd )
				)
				( attribute "PHYS_PAGE" "105"
					( Origin gFrontEnd )
				)
				( attribute "ROOM" "OCP_STEERING"
					( Origin gFrontEnd )
				)
				( attribute "ROT" "2"
					( Origin gFrontEnd )
				)
				( attribute "SEC" "1"
					( Origin gFrontEnd )
				)
				( attribute "SEC_TYPE" "0402"
					( Origin gFrontEnd )
				)
				( attribute "TOLERANCE" "10%"
					( Origin gFrontEnd )
				)
				( attribute "VALUE" "0.22UF"
					( Origin gFrontEnd )
				)
				( attribute "VER" "1"
					( Origin gFrontEnd )
				)
				( attribute "VOLTAGE" "16V"
					( Units "uVoltage" "V" 1.000000)
					( Origin gFrontEnd )
				)
				( attribute "XY" "(-300,3350)"
					( Origin gFrontEnd )
				)
				( attribute "CHIPS_PART_NAME" "CAP"
					( Origin gPackager )
				)
				( attribute "CDS_PART_NAME" "CAP_0402-0.22UF,16V,10%,X7R,A3A"
					( Origin gPackager )
				)
				( objectStatus "C7G10" )
			)
			( gate "@baseboard_fab2_lib.baseboard_fab2(sch_1):page105_i12"
				( attribute "CDS_LIB" "mstr_discrete"
					( Origin gPackager )
				)
				( attribute "CDS_LOCATION" "C7G12"
					( Origin gPackager )
				)
				( attribute "CDS_SEC" "1"
					( Origin gPackager )
				)
				( attribute "LOCATION" "C7G12"
					( Origin gFrontEnd )
				)
				( attribute "MATERIAL" "X7R"
					( Origin gFrontEnd )
				)
				( attribute "PACK_TYPE" "0402"
					( Origin gFrontEnd )
				)
				( attribute "PART_NUMBER" "A36096-155"
					( Origin gFrontEnd )
				)
				( attribute "PHYS_PAGE" "105"
					( Origin gFrontEnd )
				)
				( attribute "ROOM" "OCP_STEERING"
					( Origin gFrontEnd )
				)
				( attribute "ROT" "2"
					( Origin gFrontEnd )
				)
				( attribute "SEC" "1"
					( Origin gFrontEnd )
				)
				( attribute "SEC_TYPE" "0402"
					( Origin gFrontEnd )
				)
				( attribute "TOLERANCE" "10%"
					( Origin gFrontEnd )
				)
				( attribute "VALUE" "0.22UF"
					( Origin gFrontEnd )
				)
				( attribute "VER" "1"
					( Origin gFrontEnd )
				)
				( attribute "VOLTAGE" "16V"
					( Units "uVoltage" "V" 1.000000)
					( Origin gFrontEnd )
				)
				( attribute "XY" "(-100,3650)"
					( Origin gFrontEnd )
				)
				( attribute "CHIPS_PART_NAME" "CAP"
					( Origin gPackager )
				)
				( attribute "CDS_PART_NAME" "CAP_0402-0.22UF,16V,10%,X7R,A3A"
					( Origin gPackager )
				)
				( objectStatus "C7G12" )
			)
			( gate "@baseboard_fab2_lib.baseboard_fab2(sch_1):page105_i13"
				( attribute "CDS_LIB" "mstr_discrete"
					( Origin gPackager )
				)
				( attribute "CDS_LOCATION" "C7G13"
					( Origin gPackager )
				)
				( attribute "CDS_SEC" "1"
					( Origin gPackager )
				)
				( attribute "LOCATION" "C7G13"
					( Origin gFrontEnd )
				)
				( attribute "MATERIAL" "X7R"
					( Origin gFrontEnd )
				)
				( attribute "PACK_TYPE" "0402"
					( Origin gFrontEnd )
				)
				( attribute "PART_NUMBER" "A36096-155"
					( Origin gFrontEnd )
				)
				( attribute "PHYS_PAGE" "105"
					( Origin gFrontEnd )
				)
				( attribute "ROOM" "OCP_STEERING"
					( Origin gFrontEnd )
				)
				( attribute "ROT" "2"
					( Origin gFrontEnd )
				)
				( attribute "SEC" "1"
					( Origin gFrontEnd )
				)
				( attribute "SEC_TYPE" "0402"
					( Origin gFrontEnd )
				)
				( attribute "TOLERANCE" "10%"
					( Origin gFrontEnd )
				)
				( attribute "VALUE" "0.22UF"
					( Origin gFrontEnd )
				)
				( attribute "VER" "1"
					( Origin gFrontEnd )
				)
				( attribute "VOLTAGE" "16V"
					( Units "uVoltage" "V" 1.000000)
					( Origin gFrontEnd )
				)
				( attribute "XY" "(100,3350)"
					( Origin gFrontEnd )
				)
				( attribute "CHIPS_PART_NAME" "CAP"
					( Origin gPackager )
				)
				( attribute "CDS_PART_NAME" "CAP_0402-0.22UF,16V,10%,X7R,A3A"
					( Origin gPackager )
				)
				( objectStatus "C7G13" )
			)
			( gate "@baseboard_fab2_lib.baseboard_fab2(sch_1):page105_i20"
				( attribute "CDS_LIB" "mstr_discrete"
					( Origin gPackager )
				)
				( attribute "CDS_LOCATION" "C7G5"
					( Origin gPackager )
				)
				( attribute "CDS_SEC" "1"
					( Origin gPackager )
				)
				( attribute "LOCATION" "C7G5"
					( Origin gFrontEnd )
				)
				( attribute "MATERIAL" "X7R"
					( Origin gFrontEnd )
				)
				( attribute "PACK_TYPE" "0402"
					( Origin gFrontEnd )
				)
				( attribute "PART_NUMBER" "A36096-155"
					( Origin gFrontEnd )
				)
				( attribute "PHYS_PAGE" "105"
					( Origin gFrontEnd )
				)
				( attribute "ROOM" "OCP_STEERING"
					( Origin gFrontEnd )
				)
				( attribute "ROT" "2"
					( Origin gFrontEnd )
				)
				( attribute "SEC" "1"
					( Origin gFrontEnd )
				)
				( attribute "SEC_TYPE" "0402"
					( Origin gFrontEnd )
				)
				( attribute "TOLERANCE" "10%"
					( Origin gFrontEnd )
				)
				( attribute "VALUE" "0.22UF"
					( Origin gFrontEnd )
				)
				( attribute "VER" "1"
					( Origin gFrontEnd )
				)
				( attribute "VOLTAGE" "16V"
					( Units "uVoltage" "V" 1.000000)
					( Origin gFrontEnd )
				)
				( attribute "XY" "(-750,4350)"
					( Origin gFrontEnd )
				)
				( attribute "CHIPS_PART_NAME" "CAP"
					( Origin gPackager )
				)
				( attribute "CDS_PART_NAME" "CAP_0402-0.22UF,16V,10%,X7R,A3A"
					( Origin gPackager )
				)
				( objectStatus "C7G5" )
			)
			( gate "@baseboard_fab2_lib.baseboard_fab2(sch_1):page105_i21"
				( attribute "CDS_LIB" "mstr_discrete"
					( Origin gPackager )
				)
				( attribute "CDS_LOCATION" "C7G9"
					( Origin gPackager )
				)
				( attribute "CDS_SEC" "1"
					( Origin gPackager )
				)
				( attribute "LOCATION" "C7G9"
					( Origin gFrontEnd )
				)
				( attribute "MATERIAL" "X7R"
					( Origin gFrontEnd )
				)
				( attribute "PACK_TYPE" "0402"
					( Origin gFrontEnd )
				)
				( attribute "PART_NUMBER" "A36096-155"
					( Origin gFrontEnd )
				)
				( attribute "PHYS_PAGE" "105"
					( Origin gFrontEnd )
				)
				( attribute "ROOM" "OCP_STEERING"
					( Origin gFrontEnd )
				)
				( attribute "ROT" "2"
					( Origin gFrontEnd )
				)
				( attribute "SEC" "1"
					( Origin gFrontEnd )
				)
				( attribute "SEC_TYPE" "0402"
					( Origin gFrontEnd )
				)
				( attribute "TOLERANCE" "10%"
					( Origin gFrontEnd )
				)
				( attribute "VALUE" "0.22UF"
					( Origin gFrontEnd )
				)
				( attribute "VER" "1"
					( Origin gFrontEnd )
				)
				( attribute "VOLTAGE" "16V"
					( Units "uVoltage" "V" 1.000000)
					( Origin gFrontEnd )
				)
				( attribute "XY" "(-350,4350)"
					( Origin gFrontEnd )
				)
				( attribute "CHIPS_PART_NAME" "CAP"
					( Origin gPackager )
				)
				( attribute "CDS_PART_NAME" "CAP_0402-0.22UF,16V,10%,X7R,A3A"
					( Origin gPackager )
				)
				( objectStatus "C7G9" )
			)
			( gate "@baseboard_fab2_lib.baseboard_fab2(sch_1):page105_i22"
				( attribute "CDS_LIB" "mstr_discrete"
					( Origin gPackager )
				)
				( attribute "CDS_LOCATION" "C7G8"
					( Origin gPackager )
				)
				( attribute "CDS_SEC" "1"
					( Origin gPackager )
				)
				( attribute "LOCATION" "C7G8"
					( Origin gFrontEnd )
				)
				( attribute "MATERIAL" "X7R"
					( Origin gFrontEnd )
				)
				( attribute "PACK_TYPE" "0402"
					( Origin gFrontEnd )
				)
				( attribute "PART_NUMBER" "A36096-155"
					( Origin gFrontEnd )
				)
				( attribute "PHYS_PAGE" "105"
					( Origin gFrontEnd )
				)
				( attribute "ROOM" "OCP_STEERING"
					( Origin gFrontEnd )
				)
				( attribute "ROT" "2"
					( Origin gFrontEnd )
				)
				( attribute "SEC" "1"
					( Origin gFrontEnd )
				)
				( attribute "SEC_TYPE" "0402"
					( Origin gFrontEnd )
				)
				( attribute "TOLERANCE" "10%"
					( Origin gFrontEnd )
				)
				( attribute "VALUE" "0.22UF"
					( Origin gFrontEnd )
				)
				( attribute "VER" "1"
					( Origin gFrontEnd )
				)
				( attribute "VOLTAGE" "16V"
					( Units "uVoltage" "V" 1.000000)
					( Origin gFrontEnd )
				)
				( attribute "XY" "(-550,4650)"
					( Origin gFrontEnd )
				)
				( attribute "CHIPS_PART_NAME" "CAP"
					( Origin gPackager )
				)
				( attribute "CDS_PART_NAME" "CAP_0402-0.22UF,16V,10%,X7R,A3A"
					( Origin gPackager )
				)
				( objectStatus "C7G8" )
			)
			( gate "@baseboard_fab2_lib.baseboard_fab2(sch_1):page105_i27"
				( attribute "CDS_LIB" "mstr_discrete"
					( Origin gPackager )
				)
				( attribute "CDS_LOCATION" "C7G11"
					( Origin gPackager )
				)
				( attribute "CDS_SEC" "1"
					( Origin gPackager )
				)
				( attribute "LOCATION" "C7G11"
					( Origin gFrontEnd )
				)
				( attribute "MATERIAL" "X7R"
					( Origin gFrontEnd )
				)
				( attribute "PACK_TYPE" "0402"
					( Origin gFrontEnd )
				)
				( attribute "PART_NUMBER" "A36096-155"
					( Origin gFrontEnd )
				)
				( attribute "PHYS_PAGE" "105"
					( Origin gFrontEnd )
				)
				( attribute "ROOM" "OCP_STEERING"
					( Origin gFrontEnd )
				)
				( attribute "ROT" "2"
					( Origin gFrontEnd )
				)
				( attribute "SEC" "1"
					( Origin gFrontEnd )
				)
				( attribute "SEC_TYPE" "0402"
					( Origin gFrontEnd )
				)
				( attribute "TOLERANCE" "10%"
					( Origin gFrontEnd )
				)
				( attribute "VALUE" "0.22UF"
					( Origin gFrontEnd )
				)
				( attribute "VER" "1"
					( Origin gFrontEnd )
				)
				( attribute "VOLTAGE" "16V"
					( Units "uVoltage" "V" 1.000000)
					( Origin gFrontEnd )
				)
				( attribute "XY" "(-150,4650)"
					( Origin gFrontEnd )
				)
				( attribute "CHIPS_PART_NAME" "CAP"
					( Origin gPackager )
				)
				( attribute "CDS_PART_NAME" "CAP_0402-0.22UF,16V,10%,X7R,A3A"
					( Origin gPackager )
				)
				( objectStatus "C7G11" )
			)
			( gate "@baseboard_fab2_lib.baseboard_fab2(sch_1):page105_i28"
				( attribute "CDS_LIB" "mstr_discrete"
					( Origin gPackager )
				)
				( attribute "CDS_LOCATION" "C7G14"
					( Origin gPackager )
				)
				( attribute "CDS_SEC" "1"
					( Origin gPackager )
				)
				( attribute "LOCATION" "C7G14"
					( Origin gFrontEnd )
				)
				( attribute "MATERIAL" "X7R"
					( Origin gFrontEnd )
				)
				( attribute "PACK_TYPE" "0402"
					( Origin gFrontEnd )
				)
				( attribute "PART_NUMBER" "A36096-155"
					( Origin gFrontEnd )
				)
				( attribute "PHYS_PAGE" "105"
					( Origin gFrontEnd )
				)
				( attribute "ROOM" "OCP_STEERING"
					( Origin gFrontEnd )
				)
				( attribute "ROT" "2"
					( Origin gFrontEnd )
				)
				( attribute "SEC" "1"
					( Origin gFrontEnd )
				)
				( attribute "SEC_TYPE" "0402"
					( Origin gFrontEnd )
				)
				( attribute "TOLERANCE" "10%"
					( Origin gFrontEnd )
				)
				( attribute "VALUE" "0.22UF"
					( Origin gFrontEnd )
				)
				( attribute "VER" "1"
					( Origin gFrontEnd )
				)
				( attribute "VOLTAGE" "16V"
					( Units "uVoltage" "V" 1.000000)
					( Origin gFrontEnd )
				)
				( attribute "XY" "(50,4350)"
					( Origin gFrontEnd )
				)
				( attribute "CHIPS_PART_NAME" "CAP"
					( Origin gPackager )
				)
				( attribute "CDS_PART_NAME" "CAP_0402-0.22UF,16V,10%,X7R,A3A"
					( Origin gPackager )
				)
				( objectStatus "C7G14" )
			)
			( gate "@baseboard_fab2_lib.baseboard_fab2(sch_1):page105_i31"
				( attribute "CDS_LIB" "mstr_discrete"
					( Origin gPackager )
				)
				( attribute "CDS_LOCATION" "C7G16"
					( Origin gPackager )
				)
				( attribute "CDS_SEC" "1"
					( Origin gPackager )
				)
				( attribute "LOCATION" "C7G16"
					( Origin gFrontEnd )
				)
				( attribute "MATERIAL" "X7R"
					( Origin gFrontEnd )
				)
				( attribute "PACK_TYPE" "0402"
					( Origin gFrontEnd )
				)
				( attribute "PART_NUMBER" "A36096-155"
					( Origin gFrontEnd )
				)
				( attribute "PHYS_PAGE" "105"
					( Origin gFrontEnd )
				)
				( attribute "ROOM" "OCP_STEERING"
					( Origin gFrontEnd )
				)
				( attribute "ROT" "2"
					( Origin gFrontEnd )
				)
				( attribute "SEC" "1"
					( Origin gFrontEnd )
				)
				( attribute "SEC_TYPE" "0402"
					( Origin gFrontEnd )
				)
				( attribute "TOLERANCE" "10%"
					( Origin gFrontEnd )
				)
				( attribute "VALUE" "0.22UF"
					( Origin gFrontEnd )
				)
				( attribute "VER" "1"
					( Origin gFrontEnd )
				)
				( attribute "VOLTAGE" "16V"
					( Units "uVoltage" "V" 1.000000)
					( Origin gFrontEnd )
				)
				( attribute "XY" "(300,3650)"
					( Origin gFrontEnd )
				)
				( attribute "CHIPS_PART_NAME" "CAP"
					( Origin gPackager )
				)
				( attribute "CDS_PART_NAME" "CAP_0402-0.22UF,16V,10%,X7R,A3A"
					( Origin gPackager )
				)
				( objectStatus "C7G16" )
			)
			( gate "@baseboard_fab2_lib.baseboard_fab2(sch_1):page105_i32"
				( attribute "CDS_LIB" "mstr_discrete"
					( Origin gPackager )
				)
				( attribute "CDS_LOCATION" "C7G18"
					( Origin gPackager )
				)
				( attribute "CDS_SEC" "1"
					( Origin gPackager )
				)
				( attribute "LOCATION" "C7G18"
					( Origin gFrontEnd )
				)
				( attribute "MATERIAL" "X7R"
					( Origin gFrontEnd )
				)
				( attribute "PACK_TYPE" "0402"
					( Origin gFrontEnd )
				)
				( attribute "PART_NUMBER" "A36096-155"
					( Origin gFrontEnd )
				)
				( attribute "PHYS_PAGE" "105"
					( Origin gFrontEnd )
				)
				( attribute "ROOM" "OCP_STEERING"
					( Origin gFrontEnd )
				)
				( attribute "ROT" "2"
					( Origin gFrontEnd )
				)
				( attribute "SEC" "1"
					( Origin gFrontEnd )
				)
				( attribute "SEC_TYPE" "0402"
					( Origin gFrontEnd )
				)
				( attribute "TOLERANCE" "10%"
					( Origin gFrontEnd )
				)
				( attribute "VALUE" "0.22UF"
					( Origin gFrontEnd )
				)
				( attribute "VER" "1"
					( Origin gFrontEnd )
				)
				( attribute "VOLTAGE" "16V"
					( Units "uVoltage" "V" 1.000000)
					( Origin gFrontEnd )
				)
				( attribute "XY" "(500,3350)"
					( Origin gFrontEnd )
				)
				( attribute "CHIPS_PART_NAME" "CAP"
					( Origin gPackager )
				)
				( attribute "CDS_PART_NAME" "CAP_0402-0.22UF,16V,10%,X7R,A3A"
					( Origin gPackager )
				)
				( objectStatus "C7G18" )
			)
			( gate "@baseboard_fab2_lib.baseboard_fab2(sch_1):page105_i37"
				( attribute "CDS_LIB" "mstr_discrete"
					( Origin gPackager )
				)
				( attribute "CDS_LOCATION" "C7G22"
					( Origin gPackager )
				)
				( attribute "CDS_SEC" "1"
					( Origin gPackager )
				)
				( attribute "LOCATION" "C7G22"
					( Origin gFrontEnd )
				)
				( attribute "MATERIAL" "X7R"
					( Origin gFrontEnd )
				)
				( attribute "PACK_TYPE" "0402"
					( Origin gFrontEnd )
				)
				( attribute "PART_NUMBER" "A36096-155"
					( Origin gFrontEnd )
				)
				( attribute "PHYS_PAGE" "105"
					( Origin gFrontEnd )
				)
				( attribute "ROOM" "OCP_STEERING"
					( Origin gFrontEnd )
				)
				( attribute "ROT" "2"
					( Origin gFrontEnd )
				)
				( attribute "SEC" "1"
					( Origin gFrontEnd )
				)
				( attribute "SEC_TYPE" "0402"
					( Origin gFrontEnd )
				)
				( attribute "TOLERANCE" "10%"
					( Origin gFrontEnd )
				)
				( attribute "VALUE" "0.22UF"
					( Origin gFrontEnd )
				)
				( attribute "VER" "1"
					( Origin gFrontEnd )
				)
				( attribute "VOLTAGE" "16V"
					( Units "uVoltage" "V" 1.000000)
					( Origin gFrontEnd )
				)
				( attribute "XY" "(925,3350)"
					( Origin gFrontEnd )
				)
				( attribute "CHIPS_PART_NAME" "CAP"
					( Origin gPackager )
				)
				( attribute "CDS_PART_NAME" "CAP_0402-0.22UF,16V,10%,X7R,A3A"
					( Origin gPackager )
				)
				( objectStatus "C7G22" )
			)
			( gate "@baseboard_fab2_lib.baseboard_fab2(sch_1):page105_i44"
				( attribute "CDS_LIB" "mstr_discrete"
					( Origin gPackager )
				)
				( attribute "CDS_LOCATION" "C7G17"
					( Origin gPackager )
				)
				( attribute "CDS_SEC" "1"
					( Origin gPackager )
				)
				( attribute "LOCATION" "C7G17"
					( Origin gFrontEnd )
				)
				( attribute "MATERIAL" "X7R"
					( Origin gFrontEnd )
				)
				( attribute "PACK_TYPE" "0402"
					( Origin gFrontEnd )
				)
				( attribute "PART_NUMBER" "A36096-155"
					( Origin gFrontEnd )
				)
				( attribute "PHYS_PAGE" "105"
					( Origin gFrontEnd )
				)
				( attribute "ROOM" "OCP_STEERING"
					( Origin gFrontEnd )
				)
				( attribute "ROT" "2"
					( Origin gFrontEnd )
				)
				( attribute "SEC" "1"
					( Origin gFrontEnd )
				)
				( attribute "SEC_TYPE" "0402"
					( Origin gFrontEnd )
				)
				( attribute "TOLERANCE" "10%"
					( Origin gFrontEnd )
				)
				( attribute "VALUE" "0.22UF"
					( Origin gFrontEnd )
				)
				( attribute "VER" "1"
					( Origin gFrontEnd )
				)
				( attribute "VOLTAGE" "16V"
					( Units "uVoltage" "V" 1.000000)
					( Origin gFrontEnd )
				)
				( attribute "XY" "(450,4350)"
					( Origin gFrontEnd )
				)
				( attribute "CHIPS_PART_NAME" "CAP"
					( Origin gPackager )
				)
				( attribute "CDS_PART_NAME" "CAP_0402-0.22UF,16V,10%,X7R,A3A"
					( Origin gPackager )
				)
				( objectStatus "C7G17" )
			)
			( gate "@baseboard_fab2_lib.baseboard_fab2(sch_1):page105_i45"
				( attribute "CDS_LIB" "mstr_discrete"
					( Origin gPackager )
				)
				( attribute "CDS_LOCATION" "C7G15"
					( Origin gPackager )
				)
				( attribute "CDS_SEC" "1"
					( Origin gPackager )
				)
				( attribute "LOCATION" "C7G15"
					( Origin gFrontEnd )
				)
				( attribute "MATERIAL" "X7R"
					( Origin gFrontEnd )
				)
				( attribute "PACK_TYPE" "0402"
					( Origin gFrontEnd )
				)
				( attribute "PART_NUMBER" "A36096-155"
					( Origin gFrontEnd )
				)
				( attribute "PHYS_PAGE" "105"
					( Origin gFrontEnd )
				)
				( attribute "ROOM" "OCP_STEERING"
					( Origin gFrontEnd )
				)
				( attribute "ROT" "2"
					( Origin gFrontEnd )
				)
				( attribute "SEC" "1"
					( Origin gFrontEnd )
				)
				( attribute "SEC_TYPE" "0402"
					( Origin gFrontEnd )
				)
				( attribute "TOLERANCE" "10%"
					( Origin gFrontEnd )
				)
				( attribute "VALUE" "0.22UF"
					( Origin gFrontEnd )
				)
				( attribute "VER" "1"
					( Origin gFrontEnd )
				)
				( attribute "VOLTAGE" "16V"
					( Units "uVoltage" "V" 1.000000)
					( Origin gFrontEnd )
				)
				( attribute "XY" "(250,4650)"
					( Origin gFrontEnd )
				)
				( attribute "CHIPS_PART_NAME" "CAP"
					( Origin gPackager )
				)
				( attribute "CDS_PART_NAME" "CAP_0402-0.22UF,16V,10%,X7R,A3A"
					( Origin gPackager )
				)
				( objectStatus "C7G15" )
			)
			( gate "@baseboard_fab2_lib.baseboard_fab2(sch_1):page105_i51"
				( attribute "CDS_LIB" "mstr_discrete"
					( Origin gPackager )
				)
				( attribute "CDS_LOCATION" "C7G21"
					( Origin gPackager )
				)
				( attribute "CDS_SEC" "1"
					( Origin gPackager )
				)
				( attribute "LOCATION" "C7G21"
					( Origin gFrontEnd )
				)
				( attribute "MATERIAL" "X7R"
					( Origin gFrontEnd )
				)
				( attribute "PACK_TYPE" "0402"
					( Origin gFrontEnd )
				)
				( attribute "PART_NUMBER" "A36096-155"
					( Origin gFrontEnd )
				)
				( attribute "PHYS_PAGE" "105"
					( Origin gFrontEnd )
				)
				( attribute "ROOM" "OCP_STEERING"
					( Origin gFrontEnd )
				)
				( attribute "ROT" "2"
					( Origin gFrontEnd )
				)
				( attribute "SEC" "1"
					( Origin gFrontEnd )
				)
				( attribute "SEC_TYPE" "0402"
					( Origin gFrontEnd )
				)
				( attribute "TOLERANCE" "10%"
					( Origin gFrontEnd )
				)
				( attribute "VALUE" "0.22UF"
					( Origin gFrontEnd )
				)
				( attribute "VER" "1"
					( Origin gFrontEnd )
				)
				( attribute "VOLTAGE" "16V"
					( Units "uVoltage" "V" 1.000000)
					( Origin gFrontEnd )
				)
				( attribute "XY" "(875,4350)"
					( Origin gFrontEnd )
				)
				( attribute "CHIPS_PART_NAME" "CAP"
					( Origin gPackager )
				)
				( attribute "CDS_PART_NAME" "CAP_0402-0.22UF,16V,10%,X7R,A3A"
					( Origin gPackager )
				)
				( objectStatus "C7G21" )
			)
			( gate "@baseboard_fab2_lib.baseboard_fab2(sch_1):page105_i52"
				( attribute "CDS_LIB" "mstr_discrete"
					( Origin gPackager )
				)
				( attribute "CDS_LOCATION" "C7G23"
					( Origin gPackager )
				)
				( attribute "CDS_SEC" "1"
					( Origin gPackager )
				)
				( attribute "LOCATION" "C7G23"
					( Origin gFrontEnd )
				)
				( attribute "MATERIAL" "X7R"
					( Origin gFrontEnd )
				)
				( attribute "PACK_TYPE" "0402"
					( Origin gFrontEnd )
				)
				( attribute "PART_NUMBER" "A36096-155"
					( Origin gFrontEnd )
				)
				( attribute "PHYS_PAGE" "105"
					( Origin gFrontEnd )
				)
				( attribute "ROOM" "OCP_STEERING"
					( Origin gFrontEnd )
				)
				( attribute "ROT" "2"
					( Origin gFrontEnd )
				)
				( attribute "SEC" "1"
					( Origin gFrontEnd )
				)
				( attribute "SEC_TYPE" "0402"
					( Origin gFrontEnd )
				)
				( attribute "TOLERANCE" "10%"
					( Origin gFrontEnd )
				)
				( attribute "VALUE" "0.22UF"
					( Origin gFrontEnd )
				)
				( attribute "VER" "1"
					( Origin gFrontEnd )
				)
				( attribute "VOLTAGE" "16V"
					( Units "uVoltage" "V" 1.000000)
					( Origin gFrontEnd )
				)
				( attribute "XY" "(1075,4650)"
					( Origin gFrontEnd )
				)
				( attribute "CHIPS_PART_NAME" "CAP"
					( Origin gPackager )
				)
				( attribute "CDS_PART_NAME" "CAP_0402-0.22UF,16V,10%,X7R,A3A"
					( Origin gPackager )
				)
				( objectStatus "C7G23" )
			)
			( gate "@baseboard_fab2_lib.baseboard_fab2(sch_1):page105_i55"
				( attribute "CDS_LIB" "mstr_discrete"
					( Origin gPackager )
				)
				( attribute "CDS_LOCATION" "C7G26"
					( Origin gPackager )
				)
				( attribute "CDS_SEC" "1"
					( Origin gPackager )
				)
				( attribute "LOCATION" "C7G26"
					( Origin gFrontEnd )
				)
				( attribute "MATERIAL" "X7R"
					( Origin gFrontEnd )
				)
				( attribute "PACK_TYPE" "0402"
					( Origin gFrontEnd )
				)
				( attribute "PART_NUMBER" "A36096-155"
					( Origin gFrontEnd )
				)
				( attribute "PHYS_PAGE" "105"
					( Origin gFrontEnd )
				)
				( attribute "ROOM" "OCP_STEERING"
					( Origin gFrontEnd )
				)
				( attribute "ROT" "2"
					( Origin gFrontEnd )
				)
				( attribute "SEC" "1"
					( Origin gFrontEnd )
				)
				( attribute "SEC_TYPE" "0402"
					( Origin gFrontEnd )
				)
				( attribute "TOLERANCE" "10%"
					( Origin gFrontEnd )
				)
				( attribute "VALUE" "0.22UF"
					( Origin gFrontEnd )
				)
				( attribute "VER" "1"
					( Origin gFrontEnd )
				)
				( attribute "VOLTAGE" "16V"
					( Units "uVoltage" "V" 1.000000)
					( Origin gFrontEnd )
				)
				( attribute "XY" "(1325,3350)"
					( Origin gFrontEnd )
				)
				( attribute "CHIPS_PART_NAME" "CAP"
					( Origin gPackager )
				)
				( attribute "CDS_PART_NAME" "CAP_0402-0.22UF,16V,10%,X7R,A3A"
					( Origin gPackager )
				)
				( objectStatus "C7G26" )
			)
			( gate "@baseboard_fab2_lib.baseboard_fab2(sch_1):page105_i56"
				( attribute "CDS_LIB" "mstr_discrete"
					( Origin gPackager )
				)
				( attribute "CDS_LOCATION" "C8G4"
					( Origin gPackager )
				)
				( attribute "CDS_SEC" "1"
					( Origin gPackager )
				)
				( attribute "LOCATION" "C8G4"
					( Origin gFrontEnd )
				)
				( attribute "MATERIAL" "X7R"
					( Origin gFrontEnd )
				)
				( attribute "PACK_TYPE" "0402"
					( Origin gFrontEnd )
				)
				( attribute "PART_NUMBER" "A36096-155"
					( Origin gFrontEnd )
				)
				( attribute "PHYS_PAGE" "105"
					( Origin gFrontEnd )
				)
				( attribute "ROOM" "OCP_STEERING"
					( Origin gFrontEnd )
				)
				( attribute "ROT" "2"
					( Origin gFrontEnd )
				)
				( attribute "SEC" "1"
					( Origin gFrontEnd )
				)
				( attribute "SEC_TYPE" "0402"
					( Origin gFrontEnd )
				)
				( attribute "TOLERANCE" "10%"
					( Origin gFrontEnd )
				)
				( attribute "VALUE" "0.22UF"
					( Origin gFrontEnd )
				)
				( attribute "VER" "1"
					( Origin gFrontEnd )
				)
				( attribute "VOLTAGE" "16V"
					( Units "uVoltage" "V" 1.000000)
					( Origin gFrontEnd )
				)
				( attribute "XY" "(1725,3350)"
					( Origin gFrontEnd )
				)
				( attribute "CHIPS_PART_NAME" "CAP"
					( Origin gPackager )
				)
				( attribute "CDS_PART_NAME" "CAP_0402-0.22UF,16V,10%,X7R,A3A"
					( Origin gPackager )
				)
				( objectStatus "C8G4" )
			)
			( gate "@baseboard_fab2_lib.baseboard_fab2(sch_1):page105_i58"
				( attribute "CDS_LIB" "mstr_discrete"
					( Origin gPackager )
				)
				( attribute "CDS_LOCATION" "C8G2"
					( Origin gPackager )
				)
				( attribute "CDS_SEC" "1"
					( Origin gPackager )
				)
				( attribute "LOCATION" "C8G2"
					( Origin gFrontEnd )
				)
				( attribute "MATERIAL" "X7R"
					( Origin gFrontEnd )
				)
				( attribute "PACK_TYPE" "0402"
					( Origin gFrontEnd )
				)
				( attribute "PART_NUMBER" "A36096-155"
					( Origin gFrontEnd )
				)
				( attribute "PHYS_PAGE" "105"
					( Origin gFrontEnd )
				)
				( attribute "ROOM" "OCP_STEERING"
					( Origin gFrontEnd )
				)
				( attribute "ROT" "2"
					( Origin gFrontEnd )
				)
				( attribute "SEC" "1"
					( Origin gFrontEnd )
				)
				( attribute "SEC_TYPE" "0402"
					( Origin gFrontEnd )
				)
				( attribute "TOLERANCE" "10%"
					( Origin gFrontEnd )
				)
				( attribute "VALUE" "0.22UF"
					( Origin gFrontEnd )
				)
				( attribute "VER" "1"
					( Origin gFrontEnd )
				)
				( attribute "VOLTAGE" "16V"
					( Units "uVoltage" "V" 1.000000)
					( Origin gFrontEnd )
				)
				( attribute "XY" "(1525,3650)"
					( Origin gFrontEnd )
				)
				( attribute "CHIPS_PART_NAME" "CAP"
					( Origin gPackager )
				)
				( attribute "CDS_PART_NAME" "CAP_0402-0.22UF,16V,10%,X7R,A3A"
					( Origin gPackager )
				)
				( objectStatus "C8G2" )
			)
			( gate "@baseboard_fab2_lib.baseboard_fab2(sch_1):page105_i61"
				( attribute "CDS_LIB" "mstr_discrete"
					( Origin gPackager )
				)
				( attribute "CDS_LOCATION" "C8G6"
					( Origin gPackager )
				)
				( attribute "CDS_SEC" "1"
					( Origin gPackager )
				)
				( attribute "LOCATION" "C8G6"
					( Origin gFrontEnd )
				)
				( attribute "MATERIAL" "X7R"
					( Origin gFrontEnd )
				)
				( attribute "PACK_TYPE" "0402"
					( Origin gFrontEnd )
				)
				( attribute "PART_NUMBER" "A36096-155"
					( Origin gFrontEnd )
				)
				( attribute "PHYS_PAGE" "105"
					( Origin gFrontEnd )
				)
				( attribute "ROOM" "OCP_STEERING"
					( Origin gFrontEnd )
				)
				( attribute "ROT" "2"
					( Origin gFrontEnd )
				)
				( attribute "SEC" "1"
					( Origin gFrontEnd )
				)
				( attribute "SEC_TYPE" "0402"
					( Origin gFrontEnd )
				)
				( attribute "TOLERANCE" "10%"
					( Origin gFrontEnd )
				)
				( attribute "VALUE" "0.22UF"
					( Origin gFrontEnd )
				)
				( attribute "VER" "1"
					( Origin gFrontEnd )
				)
				( attribute "VOLTAGE" "16V"
					( Units "uVoltage" "V" 1.000000)
					( Origin gFrontEnd )
				)
				( attribute "XY" "(1925,3650)"
					( Origin gFrontEnd )
				)
				( attribute "CHIPS_PART_NAME" "CAP"
					( Origin gPackager )
				)
				( attribute "CDS_PART_NAME" "CAP_0402-0.22UF,16V,10%,X7R,A3A"
					( Origin gPackager )
				)
				( objectStatus "C8G6" )
			)
			( gate "@baseboard_fab2_lib.baseboard_fab2(sch_1):page105_i62"
				( attribute "CDS_LIB" "mstr_discrete"
					( Origin gPackager )
				)
				( attribute "CDS_LOCATION" "C8G7"
					( Origin gPackager )
				)
				( attribute "CDS_SEC" "1"
					( Origin gPackager )
				)
				( attribute "LOCATION" "C8G7"
					( Origin gFrontEnd )
				)
				( attribute "MATERIAL" "X7R"
					( Origin gFrontEnd )
				)
				( attribute "PACK_TYPE" "0402"
					( Origin gFrontEnd )
				)
				( attribute "PART_NUMBER" "A36096-155"
					( Origin gFrontEnd )
				)
				( attribute "PHYS_PAGE" "105"
					( Origin gFrontEnd )
				)
				( attribute "ROOM" "OCP_STEERING"
					( Origin gFrontEnd )
				)
				( attribute "ROT" "2"
					( Origin gFrontEnd )
				)
				( attribute "SEC" "1"
					( Origin gFrontEnd )
				)
				( attribute "SEC_TYPE" "0402"
					( Origin gFrontEnd )
				)
				( attribute "TOLERANCE" "10%"
					( Origin gFrontEnd )
				)
				( attribute "VALUE" "0.22UF"
					( Origin gFrontEnd )
				)
				( attribute "VER" "1"
					( Origin gFrontEnd )
				)
				( attribute "VOLTAGE" "16V"
					( Units "uVoltage" "V" 1.000000)
					( Origin gFrontEnd )
				)
				( attribute "XY" "(2125,3350)"
					( Origin gFrontEnd )
				)
				( attribute "CHIPS_PART_NAME" "CAP"
					( Origin gPackager )
				)
				( attribute "CDS_PART_NAME" "CAP_0402-0.22UF,16V,10%,X7R,A3A"
					( Origin gPackager )
				)
				( objectStatus "C8G7" )
			)
			( gate "@baseboard_fab2_lib.baseboard_fab2(sch_1):page105_i69"
				( attribute "CDS_LIB" "mstr_discrete"
					( Origin gPackager )
				)
				( attribute "CDS_LOCATION" "C7G25"
					( Origin gPackager )
				)
				( attribute "CDS_SEC" "1"
					( Origin gPackager )
				)
				( attribute "LOCATION" "C7G25"
					( Origin gFrontEnd )
				)
				( attribute "MATERIAL" "X7R"
					( Origin gFrontEnd )
				)
				( attribute "PACK_TYPE" "0402"
					( Origin gFrontEnd )
				)
				( attribute "PART_NUMBER" "A36096-155"
					( Origin gFrontEnd )
				)
				( attribute "PHYS_PAGE" "105"
					( Origin gFrontEnd )
				)
				( attribute "ROOM" "OCP_STEERING"
					( Origin gFrontEnd )
				)
				( attribute "ROT" "2"
					( Origin gFrontEnd )
				)
				( attribute "SEC" "1"
					( Origin gFrontEnd )
				)
				( attribute "SEC_TYPE" "0402"
					( Origin gFrontEnd )
				)
				( attribute "TOLERANCE" "10%"
					( Origin gFrontEnd )
				)
				( attribute "VALUE" "0.22UF"
					( Origin gFrontEnd )
				)
				( attribute "VER" "1"
					( Origin gFrontEnd )
				)
				( attribute "VOLTAGE" "16V"
					( Units "uVoltage" "V" 1.000000)
					( Origin gFrontEnd )
				)
				( attribute "XY" "(1275,4350)"
					( Origin gFrontEnd )
				)
				( attribute "CHIPS_PART_NAME" "CAP"
					( Origin gPackager )
				)
				( attribute "CDS_PART_NAME" "CAP_0402-0.22UF,16V,10%,X7R,A3A"
					( Origin gPackager )
				)
				( objectStatus "C7G25" )
			)
			( gate "@baseboard_fab2_lib.baseboard_fab2(sch_1):page105_i70"
				( attribute "CDS_LIB" "mstr_discrete"
					( Origin gPackager )
				)
				( attribute "CDS_LOCATION" "C8G1"
					( Origin gPackager )
				)
				( attribute "CDS_SEC" "1"
					( Origin gPackager )
				)
				( attribute "LOCATION" "C8G1"
					( Origin gFrontEnd )
				)
				( attribute "MATERIAL" "X7R"
					( Origin gFrontEnd )
				)
				( attribute "PACK_TYPE" "0402"
					( Origin gFrontEnd )
				)
				( attribute "PART_NUMBER" "A36096-155"
					( Origin gFrontEnd )
				)
				( attribute "PHYS_PAGE" "105"
					( Origin gFrontEnd )
				)
				( attribute "ROOM" "OCP_STEERING"
					( Origin gFrontEnd )
				)
				( attribute "ROT" "2"
					( Origin gFrontEnd )
				)
				( attribute "SEC" "1"
					( Origin gFrontEnd )
				)
				( attribute "SEC_TYPE" "0402"
					( Origin gFrontEnd )
				)
				( attribute "TOLERANCE" "10%"
					( Origin gFrontEnd )
				)
				( attribute "VALUE" "0.22UF"
					( Origin gFrontEnd )
				)
				( attribute "VER" "1"
					( Origin gFrontEnd )
				)
				( attribute "VOLTAGE" "16V"
					( Units "uVoltage" "V" 1.000000)
					( Origin gFrontEnd )
				)
				( attribute "XY" "(1475,4650)"
					( Origin gFrontEnd )
				)
				( attribute "CHIPS_PART_NAME" "CAP"
					( Origin gPackager )
				)
				( attribute "CDS_PART_NAME" "CAP_0402-0.22UF,16V,10%,X7R,A3A"
					( Origin gPackager )
				)
				( objectStatus "C8G1" )
			)
			( gate "@baseboard_fab2_lib.baseboard_fab2(sch_1):page105_i71"
				( attribute "CDS_LIB" "mstr_discrete"
					( Origin gPackager )
				)
				( attribute "CDS_LOCATION" "C8G3"
					( Origin gPackager )
				)
				( attribute "CDS_SEC" "1"
					( Origin gPackager )
				)
				( attribute "LOCATION" "C8G3"
					( Origin gFrontEnd )
				)
				( attribute "MATERIAL" "X7R"
					( Origin gFrontEnd )
				)
				( attribute "PACK_TYPE" "0402"
					( Origin gFrontEnd )
				)
				( attribute "PART_NUMBER" "A36096-155"
					( Origin gFrontEnd )
				)
				( attribute "PHYS_PAGE" "105"
					( Origin gFrontEnd )
				)
				( attribute "ROOM" "OCP_STEERING"
					( Origin gFrontEnd )
				)
				( attribute "ROT" "2"
					( Origin gFrontEnd )
				)
				( attribute "SEC" "1"
					( Origin gFrontEnd )
				)
				( attribute "SEC_TYPE" "0402"
					( Origin gFrontEnd )
				)
				( attribute "TOLERANCE" "10%"
					( Origin gFrontEnd )
				)
				( attribute "VALUE" "0.22UF"
					( Origin gFrontEnd )
				)
				( attribute "VER" "1"
					( Origin gFrontEnd )
				)
				( attribute "VOLTAGE" "16V"
					( Units "uVoltage" "V" 1.000000)
					( Origin gFrontEnd )
				)
				( attribute "XY" "(1675,4350)"
					( Origin gFrontEnd )
				)
				( attribute "CHIPS_PART_NAME" "CAP"
					( Origin gPackager )
				)
				( attribute "CDS_PART_NAME" "CAP_0402-0.22UF,16V,10%,X7R,A3A"
					( Origin gPackager )
				)
				( objectStatus "C8G3" )
			)
			( gate "@baseboard_fab2_lib.baseboard_fab2(sch_1):page105_i75"
				( attribute "CDS_LIB" "mstr_discrete"
					( Origin gPackager )
				)
				( attribute "CDS_LOCATION" "C8G5"
					( Origin gPackager )
				)
				( attribute "CDS_SEC" "1"
					( Origin gPackager )
				)
				( attribute "LOCATION" "C8G5"
					( Origin gFrontEnd )
				)
				( attribute "MATERIAL" "X7R"
					( Origin gFrontEnd )
				)
				( attribute "PACK_TYPE" "0402"
					( Origin gFrontEnd )
				)
				( attribute "PART_NUMBER" "A36096-155"
					( Origin gFrontEnd )
				)
				( attribute "PHYS_PAGE" "105"
					( Origin gFrontEnd )
				)
				( attribute "ROOM" "OCP_STEERING"
					( Origin gFrontEnd )
				)
				( attribute "ROT" "2"
					( Origin gFrontEnd )
				)
				( attribute "SEC" "1"
					( Origin gFrontEnd )
				)
				( attribute "SEC_TYPE" "0402"
					( Origin gFrontEnd )
				)
				( attribute "TOLERANCE" "10%"
					( Origin gFrontEnd )
				)
				( attribute "VALUE" "0.22UF"
					( Origin gFrontEnd )
				)
				( attribute "VER" "1"
					( Origin gFrontEnd )
				)
				( attribute "VOLTAGE" "16V"
					( Units "uVoltage" "V" 1.000000)
					( Origin gFrontEnd )
				)
				( attribute "XY" "(1875,4650)"
					( Origin gFrontEnd )
				)
				( attribute "CHIPS_PART_NAME" "CAP"
					( Origin gPackager )
				)
				( attribute "CDS_PART_NAME" "CAP_0402-0.22UF,16V,10%,X7R,A3A"
					( Origin gPackager )
				)
				( objectStatus "C8G5" )
			)
			( gate "@baseboard_fab2_lib.baseboard_fab2(sch_1):page105_i76"
				( attribute "CDS_LIB" "mstr_discrete"
					( Origin gPackager )
				)
				( attribute "CDS_LOCATION" "C8G8"
					( Origin gPackager )
				)
				( attribute "CDS_SEC" "1"
					( Origin gPackager )
				)
				( attribute "LOCATION" "C8G8"
					( Origin gFrontEnd )
				)
				( attribute "MATERIAL" "X7R"
					( Origin gFrontEnd )
				)
				( attribute "PACK_TYPE" "0402"
					( Origin gFrontEnd )
				)
				( attribute "PART_NUMBER" "A36096-155"
					( Origin gFrontEnd )
				)
				( attribute "PHYS_PAGE" "105"
					( Origin gFrontEnd )
				)
				( attribute "ROOM" "OCP_STEERING"
					( Origin gFrontEnd )
				)
				( attribute "ROT" "2"
					( Origin gFrontEnd )
				)
				( attribute "SEC" "1"
					( Origin gFrontEnd )
				)
				( attribute "SEC_TYPE" "0402"
					( Origin gFrontEnd )
				)
				( attribute "TOLERANCE" "10%"
					( Origin gFrontEnd )
				)
				( attribute "VALUE" "0.22UF"
					( Origin gFrontEnd )
				)
				( attribute "VER" "1"
					( Origin gFrontEnd )
				)
				( attribute "VOLTAGE" "16V"
					( Units "uVoltage" "V" 1.000000)
					( Origin gFrontEnd )
				)
				( attribute "XY" "(2075,4350)"
					( Origin gFrontEnd )
				)
				( attribute "CHIPS_PART_NAME" "CAP"
					( Origin gPackager )
				)
				( attribute "CDS_PART_NAME" "CAP_0402-0.22UF,16V,10%,X7R,A3A"
					( Origin gPackager )
				)
				( objectStatus "C8G8" )
			)
			( gate "@baseboard_fab2_lib.baseboard_fab2(sch_1):page105_i93"
				( attribute "CDS_LIB" "mstr_discrete"
					( Origin gPackager )
				)
				( attribute "CDS_LOCATION" "C8G9"
					( Origin gPackager )
				)
				( attribute "CDS_SEC" "1"
					( Origin gPackager )
				)
				( attribute "LOCATION" "C8G9"
					( Origin gFrontEnd )
				)
				( attribute "MATERIAL" "X7R"
					( Origin gFrontEnd )
				)
				( attribute "PACK_TYPE" "0402"
					( Origin gFrontEnd )
				)
				( attribute "PART_NUMBER" "A36096-155"
					( Origin gFrontEnd )
				)
				( attribute "PHYS_PAGE" "105"
					( Origin gFrontEnd )
				)
				( attribute "ROOM" "OCP_STEERING"
					( Origin gFrontEnd )
				)
				( attribute "ROT" "2"
					( Origin gFrontEnd )
				)
				( attribute "SEC" "1"
					( Origin gFrontEnd )
				)
				( attribute "SEC_TYPE" "0402"
					( Origin gFrontEnd )
				)
				( attribute "TOLERANCE" "10%"
					( Origin gFrontEnd )
				)
				( attribute "VALUE" "0.22UF"
					( Origin gFrontEnd )
				)
				( attribute "VER" "1"
					( Origin gFrontEnd )
				)
				( attribute "VOLTAGE" "16V"
					( Units "uVoltage" "V" 1.000000)
					( Origin gFrontEnd )
				)
				( attribute "XY" "(2275,4650)"
					( Origin gFrontEnd )
				)
				( attribute "CHIPS_PART_NAME" "CAP"
					( Origin gPackager )
				)
				( attribute "CDS_PART_NAME" "CAP_0402-0.22UF,16V,10%,X7R,A3A"
					( Origin gPackager )
				)
				( objectStatus "C8G9" )
			)
			( gate "@baseboard_fab2_lib.baseboard_fab2(sch_1):page105_i96"
				( attribute "CDS_LIB" "mstr_discrete"
					( Origin gPackager )
				)
				( attribute "CDS_LOCATION" "C8G10"
					( Origin gPackager )
				)
				( attribute "CDS_SEC" "1"
					( Origin gPackager )
				)
				( attribute "LOCATION" "C8G10"
					( Origin gFrontEnd )
				)
				( attribute "MATERIAL" "X7R"
					( Origin gFrontEnd )
				)
				( attribute "PACK_TYPE" "0402"
					( Origin gFrontEnd )
				)
				( attribute "PART_NUMBER" "A36096-155"
					( Origin gFrontEnd )
				)
				( attribute "PHYS_PAGE" "105"
					( Origin gFrontEnd )
				)
				( attribute "ROOM" "OCP_STEERING"
					( Origin gFrontEnd )
				)
				( attribute "ROT" "2"
					( Origin gFrontEnd )
				)
				( attribute "SEC" "1"
					( Origin gFrontEnd )
				)
				( attribute "SEC_TYPE" "0402"
					( Origin gFrontEnd )
				)
				( attribute "TOLERANCE" "10%"
					( Origin gFrontEnd )
				)
				( attribute "VALUE" "0.22UF"
					( Origin gFrontEnd )
				)
				( attribute "VER" "1"
					( Origin gFrontEnd )
				)
				( attribute "VOLTAGE" "16V"
					( Units "uVoltage" "V" 1.000000)
					( Origin gFrontEnd )
				)
				( attribute "XY" "(2325,3650)"
					( Origin gFrontEnd )
				)
				( attribute "CHIPS_PART_NAME" "CAP"
					( Origin gPackager )
				)
				( attribute "CDS_PART_NAME" "CAP_0402-0.22UF,16V,10%,X7R,A3A"
					( Origin gPackager )
				)
				( objectStatus "C8G10" )
			)
			( gate "@baseboard_fab2_lib.baseboard_fab2(sch_1):page105_i153"
				( attribute "CDS_LIB" "mstr_discrete"
					( Origin gPackager )
				)
				( attribute "CDS_LOCATION" "C6B18"
					( Origin gPackager )
				)
				( attribute "CDS_SEC" "1"
					( Origin gPackager )
				)
				( attribute "LOCATION" "C6B18"
					( Origin gFrontEnd )
				)
				( attribute "MATERIAL" "X7R"
					( Origin gFrontEnd )
				)
				( attribute "PACK_TYPE" "0402"
					( Origin gFrontEnd )
				)
				( attribute "PART_NUMBER" "A36096-155"
					( Origin gFrontEnd )
				)
				( attribute "PHYS_PAGE" "105"
					( Origin gFrontEnd )
				)
				( attribute "ROOM" "OCP_STEERING"
					( Origin gFrontEnd )
				)
				( attribute "ROT" "2"
					( Origin gFrontEnd )
				)
				( attribute "SEC" "1"
					( Origin gFrontEnd )
				)
				( attribute "SEC_TYPE" "0402"
					( Origin gFrontEnd )
				)
				( attribute "TOLERANCE" "10%"
					( Origin gFrontEnd )
				)
				( attribute "VALUE" "0.22UF"
					( Origin gFrontEnd )
				)
				( attribute "VER" "1"
					( Origin gFrontEnd )
				)
				( attribute "VOLTAGE" "16V"
					( Units "uVoltage" "V" 1.000000)
					( Origin gFrontEnd )
				)
				( attribute "XY" "(-1500,975)"
					( Origin gFrontEnd )
				)
				( attribute "CHIPS_PART_NAME" "CAP"
					( Origin gPackager )
				)
				( attribute "CDS_PART_NAME" "CAP_0402-0.22UF,16V,10%,X7R,A3A"
					( Origin gPackager )
				)
				( attribute "GROUP" "PCIE_UPLINK"
					( Origin gFrontEnd )
				)
				( objectStatus "C6B18" )
			)
			( gate "@baseboard_fab2_lib.baseboard_fab2(sch_1):page105_i160"
				( attribute "CDS_LIB" "mstr_discrete"
					( Origin gPackager )
				)
				( attribute "CDS_LOCATION" "C6B19"
					( Origin gPackager )
				)
				( attribute "CDS_SEC" "1"
					( Origin gPackager )
				)
				( attribute "LOCATION" "C6B19"
					( Origin gFrontEnd )
				)
				( attribute "MATERIAL" "X7R"
					( Origin gFrontEnd )
				)
				( attribute "PACK_TYPE" "0402"
					( Origin gFrontEnd )
				)
				( attribute "PART_NUMBER" "A36096-155"
					( Origin gFrontEnd )
				)
				( attribute "PHYS_PAGE" "105"
					( Origin gFrontEnd )
				)
				( attribute "ROOM" "OCP_STEERING"
					( Origin gFrontEnd )
				)
				( attribute "ROT" "2"
					( Origin gFrontEnd )
				)
				( attribute "SEC" "1"
					( Origin gFrontEnd )
				)
				( attribute "SEC_TYPE" "0402"
					( Origin gFrontEnd )
				)
				( attribute "TOLERANCE" "10%"
					( Origin gFrontEnd )
				)
				( attribute "VALUE" "0.22UF"
					( Origin gFrontEnd )
				)
				( attribute "VER" "1"
					( Origin gFrontEnd )
				)
				( attribute "VOLTAGE" "16V"
					( Units "uVoltage" "V" 1.000000)
					( Origin gFrontEnd )
				)
				( attribute "XY" "(-1350,2275)"
					( Origin gFrontEnd )
				)
				( attribute "CHIPS_PART_NAME" "CAP"
					( Origin gPackager )
				)
				( attribute "CDS_PART_NAME" "CAP_0402-0.22UF,16V,10%,X7R,A3A"
					( Origin gPackager )
				)
				( attribute "GROUP" "PCIE_UPLINK"
					( Origin gFrontEnd )
				)
				( objectStatus "C6B19" )
			)
			( gate "@baseboard_fab2_lib.baseboard_fab2(sch_1):page105_i163"
				( attribute "CDS_LIB" "mstr_discrete"
					( Origin gPackager )
				)
				( attribute "CDS_LOCATION" "C6B15"
					( Origin gPackager )
				)
				( attribute "CDS_SEC" "1"
					( Origin gPackager )
				)
				( attribute "LOCATION" "C6B15"
					( Origin gFrontEnd )
				)
				( attribute "MATERIAL" "X7R"
					( Origin gFrontEnd )
				)
				( attribute "PACK_TYPE" "0402"
					( Origin gFrontEnd )
				)
				( attribute "PART_NUMBER" "A36096-155"
					( Origin gFrontEnd )
				)
				( attribute "PHYS_PAGE" "105"
					( Origin gFrontEnd )
				)
				( attribute "ROOM" "OCP_STEERING"
					( Origin gFrontEnd )
				)
				( attribute "ROT" "2"
					( Origin gFrontEnd )
				)
				( attribute "SEC" "1"
					( Origin gFrontEnd )
				)
				( attribute "SEC_TYPE" "0402"
					( Origin gFrontEnd )
				)
				( attribute "TOLERANCE" "10%"
					( Origin gFrontEnd )
				)
				( attribute "VALUE" "0.22UF"
					( Origin gFrontEnd )
				)
				( attribute "VER" "1"
					( Origin gFrontEnd )
				)
				( attribute "VOLTAGE" "16V"
					( Units "uVoltage" "V" 1.000000)
					( Origin gFrontEnd )
				)
				( attribute "XY" "(-1750,2275)"
					( Origin gFrontEnd )
				)
				( attribute "CHIPS_PART_NAME" "CAP"
					( Origin gPackager )
				)
				( attribute "CDS_PART_NAME" "CAP_0402-0.22UF,16V,10%,X7R,A3A"
					( Origin gPackager )
				)
				( attribute "GROUP" "PCIE_UPLINK"
					( Origin gFrontEnd )
				)
				( objectStatus "C6B15" )
			)
			( gate "@baseboard_fab2_lib.baseboard_fab2(sch_1):page105_i166"
				( attribute "CDS_LIB" "mstr_discrete"
					( Origin gPackager )
				)
				( attribute "CDS_LOCATION" "C6B11"
					( Origin gPackager )
				)
				( attribute "CDS_SEC" "1"
					( Origin gPackager )
				)
				( attribute "LOCATION" "C6B11"
					( Origin gFrontEnd )
				)
				( attribute "MATERIAL" "X7R"
					( Origin gFrontEnd )
				)
				( attribute "PACK_TYPE" "0402"
					( Origin gFrontEnd )
				)
				( attribute "PART_NUMBER" "A36096-155"
					( Origin gFrontEnd )
				)
				( attribute "PHYS_PAGE" "105"
					( Origin gFrontEnd )
				)
				( attribute "ROOM" "OCP_STEERING"
					( Origin gFrontEnd )
				)
				( attribute "ROT" "2"
					( Origin gFrontEnd )
				)
				( attribute "SEC" "1"
					( Origin gFrontEnd )
				)
				( attribute "SEC_TYPE" "0402"
					( Origin gFrontEnd )
				)
				( attribute "TOLERANCE" "10%"
					( Origin gFrontEnd )
				)
				( attribute "VALUE" "0.22UF"
					( Origin gFrontEnd )
				)
				( attribute "VER" "1"
					( Origin gFrontEnd )
				)
				( attribute "VOLTAGE" "16V"
					( Units "uVoltage" "V" 1.000000)
					( Origin gFrontEnd )
				)
				( attribute "XY" "(-2150,2275)"
					( Origin gFrontEnd )
				)
				( attribute "CHIPS_PART_NAME" "CAP"
					( Origin gPackager )
				)
				( attribute "CDS_PART_NAME" "CAP_0402-0.22UF,16V,10%,X7R,A3A"
					( Origin gPackager )
				)
				( attribute "GROUP" "PCIE_UPLINK"
					( Origin gFrontEnd )
				)
				( objectStatus "C6B11" )
			)
			( gate "@baseboard_fab2_lib.baseboard_fab2(sch_1):page105_i169"
				( attribute "CDS_LIB" "mstr_discrete"
					( Origin gPackager )
				)
				( attribute "CDS_LOCATION" "C6B6"
					( Origin gPackager )
				)
				( attribute "CDS_SEC" "1"
					( Origin gPackager )
				)
				( attribute "LOCATION" "C6B6"
					( Origin gFrontEnd )
				)
				( attribute "MATERIAL" "X7R"
					( Origin gFrontEnd )
				)
				( attribute "PACK_TYPE" "0402"
					( Origin gFrontEnd )
				)
				( attribute "PART_NUMBER" "A36096-155"
					( Origin gFrontEnd )
				)
				( attribute "PHYS_PAGE" "105"
					( Origin gFrontEnd )
				)
				( attribute "ROOM" "OCP_STEERING"
					( Origin gFrontEnd )
				)
				( attribute "ROT" "2"
					( Origin gFrontEnd )
				)
				( attribute "SEC" "1"
					( Origin gFrontEnd )
				)
				( attribute "SEC_TYPE" "0402"
					( Origin gFrontEnd )
				)
				( attribute "TOLERANCE" "10%"
					( Origin gFrontEnd )
				)
				( attribute "VALUE" "0.22UF"
					( Origin gFrontEnd )
				)
				( attribute "VER" "1"
					( Origin gFrontEnd )
				)
				( attribute "VOLTAGE" "16V"
					( Units "uVoltage" "V" 1.000000)
					( Origin gFrontEnd )
				)
				( attribute "XY" "(-2550,2275)"
					( Origin gFrontEnd )
				)
				( attribute "CHIPS_PART_NAME" "CAP"
					( Origin gPackager )
				)
				( attribute "CDS_PART_NAME" "CAP_0402-0.22UF,16V,10%,X7R,A3A"
					( Origin gPackager )
				)
				( attribute "GROUP" "PCIE_UPLINK"
					( Origin gFrontEnd )
				)
				( objectStatus "C6B6" )
			)
			( gate "@baseboard_fab2_lib.baseboard_fab2(sch_1):page105_i173"
				( attribute "CDS_LIB" "mstr_discrete"
					( Origin gPackager )
				)
				( attribute "CDS_LOCATION" "C6B20"
					( Origin gPackager )
				)
				( attribute "CDS_SEC" "1"
					( Origin gPackager )
				)
				( attribute "LOCATION" "C6B20"
					( Origin gFrontEnd )
				)
				( attribute "MATERIAL" "X7R"
					( Origin gFrontEnd )
				)
				( attribute "PACK_TYPE" "0402"
					( Origin gFrontEnd )
				)
				( attribute "PART_NUMBER" "A36096-155"
					( Origin gFrontEnd )
				)
				( attribute "PHYS_PAGE" "105"
					( Origin gFrontEnd )
				)
				( attribute "ROOM" "OCP_STEERING"
					( Origin gFrontEnd )
				)
				( attribute "ROT" "2"
					( Origin gFrontEnd )
				)
				( attribute "SEC" "1"
					( Origin gFrontEnd )
				)
				( attribute "SEC_TYPE" "0402"
					( Origin gFrontEnd )
				)
				( attribute "TOLERANCE" "10%"
					( Origin gFrontEnd )
				)
				( attribute "VALUE" "0.22UF"
					( Origin gFrontEnd )
				)
				( attribute "VER" "1"
					( Origin gFrontEnd )
				)
				( attribute "VOLTAGE" "16V"
					( Units "uVoltage" "V" 1.000000)
					( Origin gFrontEnd )
				)
				( attribute "XY" "(-1300,1275)"
					( Origin gFrontEnd )
				)
				( attribute "CHIPS_PART_NAME" "CAP"
					( Origin gPackager )
				)
				( attribute "CDS_PART_NAME" "CAP_0402-0.22UF,16V,10%,X7R,A3A"
					( Origin gPackager )
				)
				( attribute "GROUP" "PCIE_UPLINK"
					( Origin gFrontEnd )
				)
				( objectStatus "C6B20" )
			)
			( gate "@baseboard_fab2_lib.baseboard_fab2(sch_1):page105_i175"
				( attribute "CDS_LIB" "mstr_discrete"
					( Origin gPackager )
				)
				( attribute "CDS_LOCATION" "C6B17"
					( Origin gPackager )
				)
				( attribute "CDS_SEC" "1"
					( Origin gPackager )
				)
				( attribute "LOCATION" "C6B17"
					( Origin gFrontEnd )
				)
				( attribute "MATERIAL" "X7R"
					( Origin gFrontEnd )
				)
				( attribute "PACK_TYPE" "0402"
					( Origin gFrontEnd )
				)
				( attribute "PART_NUMBER" "A36096-155"
					( Origin gFrontEnd )
				)
				( attribute "PHYS_PAGE" "105"
					( Origin gFrontEnd )
				)
				( attribute "ROOM" "OCP_STEERING"
					( Origin gFrontEnd )
				)
				( attribute "ROT" "2"
					( Origin gFrontEnd )
				)
				( attribute "SEC" "1"
					( Origin gFrontEnd )
				)
				( attribute "SEC_TYPE" "0402"
					( Origin gFrontEnd )
				)
				( attribute "TOLERANCE" "10%"
					( Origin gFrontEnd )
				)
				( attribute "VALUE" "0.22UF"
					( Origin gFrontEnd )
				)
				( attribute "VER" "1"
					( Origin gFrontEnd )
				)
				( attribute "VOLTAGE" "16V"
					( Units "uVoltage" "V" 1.000000)
					( Origin gFrontEnd )
				)
				( attribute "XY" "(-1550,1975)"
					( Origin gFrontEnd )
				)
				( attribute "CHIPS_PART_NAME" "CAP"
					( Origin gPackager )
				)
				( attribute "CDS_PART_NAME" "CAP_0402-0.22UF,16V,10%,X7R,A3A"
					( Origin gPackager )
				)
				( attribute "GROUP" "PCIE_UPLINK"
					( Origin gFrontEnd )
				)
				( objectStatus "C6B17" )
			)
			( gate "@baseboard_fab2_lib.baseboard_fab2(sch_1):page105_i180"
				( attribute "CDS_LIB" "mstr_discrete"
					( Origin gPackager )
				)
				( attribute "CDS_LOCATION" "C6B16"
					( Origin gPackager )
				)
				( attribute "CDS_SEC" "1"
					( Origin gPackager )
				)
				( attribute "LOCATION" "C6B16"
					( Origin gFrontEnd )
				)
				( attribute "MATERIAL" "X7R"
					( Origin gFrontEnd )
				)
				( attribute "PACK_TYPE" "0402"
					( Origin gFrontEnd )
				)
				( attribute "PART_NUMBER" "A36096-155"
					( Origin gFrontEnd )
				)
				( attribute "PHYS_PAGE" "105"
					( Origin gFrontEnd )
				)
				( attribute "ROOM" "OCP_STEERING"
					( Origin gFrontEnd )
				)
				( attribute "ROT" "2"
					( Origin gFrontEnd )
				)
				( attribute "SEC" "1"
					( Origin gFrontEnd )
				)
				( attribute "SEC_TYPE" "0402"
					( Origin gFrontEnd )
				)
				( attribute "TOLERANCE" "10%"
					( Origin gFrontEnd )
				)
				( attribute "VALUE" "0.22UF"
					( Origin gFrontEnd )
				)
				( attribute "VER" "1"
					( Origin gFrontEnd )
				)
				( attribute "VOLTAGE" "16V"
					( Units "uVoltage" "V" 1.000000)
					( Origin gFrontEnd )
				)
				( attribute "XY" "(-1700,1275)"
					( Origin gFrontEnd )
				)
				( attribute "CHIPS_PART_NAME" "CAP"
					( Origin gPackager )
				)
				( attribute "CDS_PART_NAME" "CAP_0402-0.22UF,16V,10%,X7R,A3A"
					( Origin gPackager )
				)
				( attribute "GROUP" "PCIE_UPLINK"
					( Origin gFrontEnd )
				)
				( objectStatus "C6B16" )
			)
			( gate "@baseboard_fab2_lib.baseboard_fab2(sch_1):page105_i181"
				( attribute "CDS_LIB" "mstr_discrete"
					( Origin gPackager )
				)
				( attribute "CDS_LOCATION" "C6B14"
					( Origin gPackager )
				)
				( attribute "CDS_SEC" "1"
					( Origin gPackager )
				)
				( attribute "LOCATION" "C6B14"
					( Origin gFrontEnd )
				)
				( attribute "MATERIAL" "X7R"
					( Origin gFrontEnd )
				)
				( attribute "PACK_TYPE" "0402"
					( Origin gFrontEnd )
				)
				( attribute "PART_NUMBER" "A36096-155"
					( Origin gFrontEnd )
				)
				( attribute "PHYS_PAGE" "105"
					( Origin gFrontEnd )
				)
				( attribute "ROOM" "OCP_STEERING"
					( Origin gFrontEnd )
				)
				( attribute "ROT" "2"
					( Origin gFrontEnd )
				)
				( attribute "SEC" "1"
					( Origin gFrontEnd )
				)
				( attribute "SEC_TYPE" "0402"
					( Origin gFrontEnd )
				)
				( attribute "TOLERANCE" "10%"
					( Origin gFrontEnd )
				)
				( attribute "VALUE" "0.22UF"
					( Origin gFrontEnd )
				)
				( attribute "VER" "1"
					( Origin gFrontEnd )
				)
				( attribute "VOLTAGE" "16V"
					( Units "uVoltage" "V" 1.000000)
					( Origin gFrontEnd )
				)
				( attribute "XY" "(-1950,1975)"
					( Origin gFrontEnd )
				)
				( attribute "CHIPS_PART_NAME" "CAP"
					( Origin gPackager )
				)
				( attribute "CDS_PART_NAME" "CAP_0402-0.22UF,16V,10%,X7R,A3A"
					( Origin gPackager )
				)
				( attribute "GROUP" "PCIE_UPLINK"
					( Origin gFrontEnd )
				)
				( objectStatus "C6B14" )
			)
			( gate "@baseboard_fab2_lib.baseboard_fab2(sch_1):page105_i185"
				( attribute "CDS_LIB" "mstr_discrete"
					( Origin gPackager )
				)
				( attribute "CDS_LOCATION" "C6B9"
					( Origin gPackager )
				)
				( attribute "CDS_SEC" "1"
					( Origin gPackager )
				)
				( attribute "LOCATION" "C6B9"
					( Origin gFrontEnd )
				)
				( attribute "MATERIAL" "X7R"
					( Origin gFrontEnd )
				)
				( attribute "PACK_TYPE" "0402"
					( Origin gFrontEnd )
				)
				( attribute "PART_NUMBER" "A36096-155"
					( Origin gFrontEnd )
				)
				( attribute "PHYS_PAGE" "105"
					( Origin gFrontEnd )
				)
				( attribute "ROOM" "OCP_STEERING"
					( Origin gFrontEnd )
				)
				( attribute "ROT" "2"
					( Origin gFrontEnd )
				)
				( attribute "SEC" "1"
					( Origin gFrontEnd )
				)
				( attribute "SEC_TYPE" "0402"
					( Origin gFrontEnd )
				)
				( attribute "TOLERANCE" "10%"
					( Origin gFrontEnd )
				)
				( attribute "VALUE" "0.22UF"
					( Origin gFrontEnd )
				)
				( attribute "VER" "1"
					( Origin gFrontEnd )
				)
				( attribute "VOLTAGE" "16V"
					( Units "uVoltage" "V" 1.000000)
					( Origin gFrontEnd )
				)
				( attribute "XY" "(-2350,1975)"
					( Origin gFrontEnd )
				)
				( attribute "CHIPS_PART_NAME" "CAP"
					( Origin gPackager )
				)
				( attribute "CDS_PART_NAME" "CAP_0402-0.22UF,16V,10%,X7R,A3A"
					( Origin gPackager )
				)
				( attribute "GROUP" "PCIE_UPLINK"
					( Origin gFrontEnd )
				)
				( objectStatus "C6B9" )
			)
			( gate "@baseboard_fab2_lib.baseboard_fab2(sch_1):page105_i187"
				( attribute "CDS_LIB" "mstr_discrete"
					( Origin gPackager )
				)
				( attribute "CDS_LOCATION" "C6B12"
					( Origin gPackager )
				)
				( attribute "CDS_SEC" "1"
					( Origin gPackager )
				)
				( attribute "LOCATION" "C6B12"
					( Origin gFrontEnd )
				)
				( attribute "MATERIAL" "X7R"
					( Origin gFrontEnd )
				)
				( attribute "PACK_TYPE" "0402"
					( Origin gFrontEnd )
				)
				( attribute "PART_NUMBER" "A36096-155"
					( Origin gFrontEnd )
				)
				( attribute "PHYS_PAGE" "105"
					( Origin gFrontEnd )
				)
				( attribute "ROOM" "OCP_STEERING"
					( Origin gFrontEnd )
				)
				( attribute "ROT" "2"
					( Origin gFrontEnd )
				)
				( attribute "SEC" "1"
					( Origin gFrontEnd )
				)
				( attribute "SEC_TYPE" "0402"
					( Origin gFrontEnd )
				)
				( attribute "TOLERANCE" "10%"
					( Origin gFrontEnd )
				)
				( attribute "VALUE" "0.22UF"
					( Origin gFrontEnd )
				)
				( attribute "VER" "1"
					( Origin gFrontEnd )
				)
				( attribute "VOLTAGE" "16V"
					( Units "uVoltage" "V" 1.000000)
					( Origin gFrontEnd )
				)
				( attribute "XY" "(-2100,1275)"
					( Origin gFrontEnd )
				)
				( attribute "CHIPS_PART_NAME" "CAP"
					( Origin gPackager )
				)
				( attribute "CDS_PART_NAME" "CAP_0402-0.22UF,16V,10%,X7R,A3A"
					( Origin gPackager )
				)
				( attribute "GROUP" "PCIE_UPLINK"
					( Origin gFrontEnd )
				)
				( objectStatus "C6B12" )
			)
			( gate "@baseboard_fab2_lib.baseboard_fab2(sch_1):page105_i189"
				( attribute "CDS_LIB" "mstr_discrete"
					( Origin gPackager )
				)
				( attribute "CDS_LOCATION" "C6B13"
					( Origin gPackager )
				)
				( attribute "CDS_SEC" "1"
					( Origin gPackager )
				)
				( attribute "LOCATION" "C6B13"
					( Origin gFrontEnd )
				)
				( attribute "MATERIAL" "X7R"
					( Origin gFrontEnd )
				)
				( attribute "PACK_TYPE" "0402"
					( Origin gFrontEnd )
				)
				( attribute "PART_NUMBER" "A36096-155"
					( Origin gFrontEnd )
				)
				( attribute "PHYS_PAGE" "105"
					( Origin gFrontEnd )
				)
				( attribute "ROOM" "OCP_STEERING"
					( Origin gFrontEnd )
				)
				( attribute "ROT" "2"
					( Origin gFrontEnd )
				)
				( attribute "SEC" "1"
					( Origin gFrontEnd )
				)
				( attribute "SEC_TYPE" "0402"
					( Origin gFrontEnd )
				)
				( attribute "TOLERANCE" "10%"
					( Origin gFrontEnd )
				)
				( attribute "VALUE" "0.22UF"
					( Origin gFrontEnd )
				)
				( attribute "VER" "1"
					( Origin gFrontEnd )
				)
				( attribute "VOLTAGE" "16V"
					( Units "uVoltage" "V" 1.000000)
					( Origin gFrontEnd )
				)
				( attribute "XY" "(-1900,975)"
					( Origin gFrontEnd )
				)
				( attribute "CHIPS_PART_NAME" "CAP"
					( Origin gPackager )
				)
				( attribute "CDS_PART_NAME" "CAP_0402-0.22UF,16V,10%,X7R,A3A"
					( Origin gPackager )
				)
				( attribute "GROUP" "PCIE_UPLINK"
					( Origin gFrontEnd )
				)
				( objectStatus "C6B13" )
			)
			( gate "@baseboard_fab2_lib.baseboard_fab2(sch_1):page105_i193"
				( attribute "CDS_LIB" "mstr_discrete"
					( Origin gPackager )
				)
				( attribute "CDS_LOCATION" "C6B10"
					( Origin gPackager )
				)
				( attribute "CDS_SEC" "1"
					( Origin gPackager )
				)
				( attribute "LOCATION" "C6B10"
					( Origin gFrontEnd )
				)
				( attribute "MATERIAL" "X7R"
					( Origin gFrontEnd )
				)
				( attribute "PACK_TYPE" "0402"
					( Origin gFrontEnd )
				)
				( attribute "PART_NUMBER" "A36096-155"
					( Origin gFrontEnd )
				)
				( attribute "PHYS_PAGE" "105"
					( Origin gFrontEnd )
				)
				( attribute "ROOM" "OCP_STEERING"
					( Origin gFrontEnd )
				)
				( attribute "ROT" "2"
					( Origin gFrontEnd )
				)
				( attribute "SEC" "1"
					( Origin gFrontEnd )
				)
				( attribute "SEC_TYPE" "0402"
					( Origin gFrontEnd )
				)
				( attribute "TOLERANCE" "10%"
					( Origin gFrontEnd )
				)
				( attribute "VALUE" "0.22UF"
					( Origin gFrontEnd )
				)
				( attribute "VER" "1"
					( Origin gFrontEnd )
				)
				( attribute "VOLTAGE" "16V"
					( Units "uVoltage" "V" 1.000000)
					( Origin gFrontEnd )
				)
				( attribute "XY" "(-2300,975)"
					( Origin gFrontEnd )
				)
				( attribute "CHIPS_PART_NAME" "CAP"
					( Origin gPackager )
				)
				( attribute "CDS_PART_NAME" "CAP_0402-0.22UF,16V,10%,X7R,A3A"
					( Origin gPackager )
				)
				( attribute "GROUP" "PCIE_UPLINK"
					( Origin gFrontEnd )
				)
				( objectStatus "C6B10" )
			)
			( gate "@baseboard_fab2_lib.baseboard_fab2(sch_1):page105_i196"
				( attribute "CDS_LIB" "mstr_discrete"
					( Origin gPackager )
				)
				( attribute "CDS_LOCATION" "C6B4"
					( Origin gPackager )
				)
				( attribute "CDS_SEC" "1"
					( Origin gPackager )
				)
				( attribute "LOCATION" "C6B4"
					( Origin gFrontEnd )
				)
				( attribute "MATERIAL" "X7R"
					( Origin gFrontEnd )
				)
				( attribute "PACK_TYPE" "0402"
					( Origin gFrontEnd )
				)
				( attribute "PART_NUMBER" "A36096-155"
					( Origin gFrontEnd )
				)
				( attribute "PHYS_PAGE" "105"
					( Origin gFrontEnd )
				)
				( attribute "ROOM" "OCP_STEERING"
					( Origin gFrontEnd )
				)
				( attribute "ROT" "2"
					( Origin gFrontEnd )
				)
				( attribute "SEC" "1"
					( Origin gFrontEnd )
				)
				( attribute "SEC_TYPE" "0402"
					( Origin gFrontEnd )
				)
				( attribute "TOLERANCE" "10%"
					( Origin gFrontEnd )
				)
				( attribute "VALUE" "0.22UF"
					( Origin gFrontEnd )
				)
				( attribute "VER" "1"
					( Origin gFrontEnd )
				)
				( attribute "VOLTAGE" "16V"
					( Units "uVoltage" "V" 1.000000)
					( Origin gFrontEnd )
				)
				( attribute "XY" "(-2750,1975)"
					( Origin gFrontEnd )
				)
				( attribute "CHIPS_PART_NAME" "CAP"
					( Origin gPackager )
				)
				( attribute "CDS_PART_NAME" "CAP_0402-0.22UF,16V,10%,X7R,A3A"
					( Origin gPackager )
				)
				( attribute "GROUP" "PCIE_UPLINK"
					( Origin gFrontEnd )
				)
				( objectStatus "C6B4" )
			)
			( gate "@baseboard_fab2_lib.baseboard_fab2(sch_1):page105_i198"
				( attribute "CDS_LIB" "mstr_discrete"
					( Origin gPackager )
				)
				( attribute "CDS_LOCATION" "C6B8"
					( Origin gPackager )
				)
				( attribute "CDS_SEC" "1"
					( Origin gPackager )
				)
				( attribute "LOCATION" "C6B8"
					( Origin gFrontEnd )
				)
				( attribute "MATERIAL" "X7R"
					( Origin gFrontEnd )
				)
				( attribute "PACK_TYPE" "0402"
					( Origin gFrontEnd )
				)
				( attribute "PART_NUMBER" "A36096-155"
					( Origin gFrontEnd )
				)
				( attribute "PHYS_PAGE" "105"
					( Origin gFrontEnd )
				)
				( attribute "ROOM" "OCP_STEERING"
					( Origin gFrontEnd )
				)
				( attribute "ROT" "2"
					( Origin gFrontEnd )
				)
				( attribute "SEC" "1"
					( Origin gFrontEnd )
				)
				( attribute "SEC_TYPE" "0402"
					( Origin gFrontEnd )
				)
				( attribute "TOLERANCE" "10%"
					( Origin gFrontEnd )
				)
				( attribute "VALUE" "0.22UF"
					( Origin gFrontEnd )
				)
				( attribute "VER" "1"
					( Origin gFrontEnd )
				)
				( attribute "VOLTAGE" "16V"
					( Units "uVoltage" "V" 1.000000)
					( Origin gFrontEnd )
				)
				( attribute "XY" "(-2500,1275)"
					( Origin gFrontEnd )
				)
				( attribute "CHIPS_PART_NAME" "CAP"
					( Origin gPackager )
				)
				( attribute "CDS_PART_NAME" "CAP_0402-0.22UF,16V,10%,X7R,A3A"
					( Origin gPackager )
				)
				( attribute "GROUP" "PCIE_UPLINK"
					( Origin gFrontEnd )
				)
				( objectStatus "C6B8" )
			)
			( gate "@baseboard_fab2_lib.baseboard_fab2(sch_1):page105_i201"
				( attribute "CDS_LIB" "mstr_discrete"
					( Origin gPackager )
				)
				( attribute "CDS_LOCATION" "C6B5"
					( Origin gPackager )
				)
				( attribute "CDS_SEC" "1"
					( Origin gPackager )
				)
				( attribute "LOCATION" "C6B5"
					( Origin gFrontEnd )
				)
				( attribute "MATERIAL" "X7R"
					( Origin gFrontEnd )
				)
				( attribute "PACK_TYPE" "0402"
					( Origin gFrontEnd )
				)
				( attribute "PART_NUMBER" "A36096-155"
					( Origin gFrontEnd )
				)
				( attribute "PHYS_PAGE" "105"
					( Origin gFrontEnd )
				)
				( attribute "ROOM" "OCP_STEERING"
					( Origin gFrontEnd )
				)
				( attribute "ROT" "2"
					( Origin gFrontEnd )
				)
				( attribute "SEC" "1"
					( Origin gFrontEnd )
				)
				( attribute "SEC_TYPE" "0402"
					( Origin gFrontEnd )
				)
				( attribute "TOLERANCE" "10%"
					( Origin gFrontEnd )
				)
				( attribute "VALUE" "0.22UF"
					( Origin gFrontEnd )
				)
				( attribute "VER" "1"
					( Origin gFrontEnd )
				)
				( attribute "VOLTAGE" "16V"
					( Units "uVoltage" "V" 1.000000)
					( Origin gFrontEnd )
				)
				( attribute "XY" "(-2700,975)"
					( Origin gFrontEnd )
				)
				( attribute "CHIPS_PART_NAME" "CAP"
					( Origin gPackager )
				)
				( attribute "CDS_PART_NAME" "CAP_0402-0.22UF,16V,10%,X7R,A3A"
					( Origin gPackager )
				)
				( attribute "GROUP" "PCIE_UPLINK"
					( Origin gFrontEnd )
				)
				( objectStatus "C6B5" )
			)
			( gate "@baseboard_fab2_lib.baseboard_fab2(sch_1):page105_i205"
				( attribute "CDS_LIB" "mstr_discrete"
					( Origin gPackager )
				)
				( attribute "CDS_LOCATION" "C3M25"
					( Origin gPackager )
				)
				( attribute "CDS_SEC" "1"
					( Origin gPackager )
				)
				( attribute "LOCATION" "C3M25"
					( Origin gFrontEnd )
				)
				( attribute "MATERIAL" "X7R"
					( Origin gFrontEnd )
				)
				( attribute "PACK_TYPE" "0402"
					( Origin gFrontEnd )
				)
				( attribute "PART_NUMBER" "A36096-155"
					( Origin gFrontEnd )
				)
				( attribute "PHYS_PAGE" "105"
					( Origin gFrontEnd )
				)
				( attribute "ROOM" "OCP_STEERING"
					( Origin gFrontEnd )
				)
				( attribute "ROT" "2"
					( Origin gFrontEnd )
				)
				( attribute "SEC" "1"
					( Origin gPackager )
				)
				( attribute "TOLERANCE" "10%"
					( Origin gFrontEnd )
				)
				( attribute "VALUE" "0.22UF"
					( Origin gFrontEnd )
				)
				( attribute "VER" "1"
					( Origin gFrontEnd )
				)
				( attribute "VOLTAGE" "16V"
					( Units "uVoltage" "V" 1.000000)
					( Origin gFrontEnd )
				)
				( attribute "XY" "(1800,2025)"
					( Origin gFrontEnd )
				)
				( attribute "CHIPS_PART_NAME" "CAP"
					( Origin gPackager )
				)
				( attribute "CDS_PART_NAME" "CAP_0402-0.22UF,16V,10%,X7R,A3A"
					( Origin gPackager )
				)
				( attribute "GROUP" "PCIE_UPLINK"
					( Origin gFrontEnd )
				)
				( objectStatus "C3M25" )
			)
			( gate "@baseboard_fab2_lib.baseboard_fab2(sch_1):page105_i206"
				( attribute "CDS_LIB" "mstr_discrete"
					( Origin gPackager )
				)
				( attribute "CDS_LOCATION" "C3M34"
					( Origin gPackager )
				)
				( attribute "CDS_SEC" "1"
					( Origin gPackager )
				)
				( attribute "LOCATION" "C3M34"
					( Origin gFrontEnd )
				)
				( attribute "MATERIAL" "X7R"
					( Origin gFrontEnd )
				)
				( attribute "PACK_TYPE" "0402"
					( Origin gFrontEnd )
				)
				( attribute "PART_NUMBER" "A36096-155"
					( Origin gFrontEnd )
				)
				( attribute "PHYS_PAGE" "105"
					( Origin gFrontEnd )
				)
				( attribute "ROOM" "OCP_STEERING"
					( Origin gFrontEnd )
				)
				( attribute "ROT" "2"
					( Origin gFrontEnd )
				)
				( attribute "SEC" "1"
					( Origin gPackager )
				)
				( attribute "TOLERANCE" "10%"
					( Origin gFrontEnd )
				)
				( attribute "VALUE" "0.22UF"
					( Origin gFrontEnd )
				)
				( attribute "VER" "1"
					( Origin gFrontEnd )
				)
				( attribute "VOLTAGE" "16V"
					( Units "uVoltage" "V" 1.000000)
					( Origin gFrontEnd )
				)
				( attribute "XY" "(2400,2325)"
					( Origin gFrontEnd )
				)
				( attribute "CHIPS_PART_NAME" "CAP"
					( Origin gPackager )
				)
				( attribute "CDS_PART_NAME" "CAP_0402-0.22UF,16V,10%,X7R,A3A"
					( Origin gPackager )
				)
				( attribute "GROUP" "PCIE_UPLINK"
					( Origin gFrontEnd )
				)
				( objectStatus "C3M34" )
			)
			( gate "@baseboard_fab2_lib.baseboard_fab2(sch_1):page105_i212"
				( attribute "CDS_LIB" "mstr_discrete"
					( Origin gPackager )
				)
				( attribute "CDS_LOCATION" "C3M28"
					( Origin gPackager )
				)
				( attribute "CDS_SEC" "1"
					( Origin gPackager )
				)
				( attribute "LOCATION" "C3M28"
					( Origin gFrontEnd )
				)
				( attribute "MATERIAL" "X7R"
					( Origin gFrontEnd )
				)
				( attribute "PACK_TYPE" "0402"
					( Origin gFrontEnd )
				)
				( attribute "PART_NUMBER" "A36096-155"
					( Origin gFrontEnd )
				)
				( attribute "PHYS_PAGE" "105"
					( Origin gFrontEnd )
				)
				( attribute "ROOM" "OCP_STEERING"
					( Origin gFrontEnd )
				)
				( attribute "ROT" "2"
					( Origin gFrontEnd )
				)
				( attribute "SEC" "1"
					( Origin gPackager )
				)
				( attribute "TOLERANCE" "10%"
					( Origin gFrontEnd )
				)
				( attribute "VALUE" "0.22UF"
					( Origin gFrontEnd )
				)
				( attribute "VER" "1"
					( Origin gFrontEnd )
				)
				( attribute "VOLTAGE" "16V"
					( Units "uVoltage" "V" 1.000000)
					( Origin gFrontEnd )
				)
				( attribute "XY" "(2000,2325)"
					( Origin gFrontEnd )
				)
				( attribute "CHIPS_PART_NAME" "CAP"
					( Origin gPackager )
				)
				( attribute "CDS_PART_NAME" "CAP_0402-0.22UF,16V,10%,X7R,A3A"
					( Origin gPackager )
				)
				( attribute "GROUP" "PCIE_UPLINK"
					( Origin gFrontEnd )
				)
				( objectStatus "C3M28" )
			)
			( gate "@baseboard_fab2_lib.baseboard_fab2(sch_1):page105_i217"
				( attribute "CDS_LIB" "mstr_discrete"
					( Origin gPackager )
				)
				( attribute "CDS_LOCATION" "C3M33"
					( Origin gPackager )
				)
				( attribute "CDS_SEC" "1"
					( Origin gPackager )
				)
				( attribute "LOCATION" "C3M33"
					( Origin gFrontEnd )
				)
				( attribute "MATERIAL" "X7R"
					( Origin gFrontEnd )
				)
				( attribute "PACK_TYPE" "0402"
					( Origin gFrontEnd )
				)
				( attribute "PART_NUMBER" "A36096-155"
					( Origin gFrontEnd )
				)
				( attribute "PHYS_PAGE" "105"
					( Origin gFrontEnd )
				)
				( attribute "ROOM" "OCP_STEERING"
					( Origin gFrontEnd )
				)
				( attribute "ROT" "2"
					( Origin gFrontEnd )
				)
				( attribute "SEC" "1"
					( Origin gPackager )
				)
				( attribute "TOLERANCE" "10%"
					( Origin gFrontEnd )
				)
				( attribute "VALUE" "0.22UF"
					( Origin gFrontEnd )
				)
				( attribute "VER" "1"
					( Origin gFrontEnd )
				)
				( attribute "VOLTAGE" "16V"
					( Units "uVoltage" "V" 1.000000)
					( Origin gFrontEnd )
				)
				( attribute "XY" "(2450,1325)"
					( Origin gFrontEnd )
				)
				( attribute "CHIPS_PART_NAME" "CAP"
					( Origin gPackager )
				)
				( attribute "CDS_PART_NAME" "CAP_0402-0.22UF,16V,10%,X7R,A3A"
					( Origin gPackager )
				)
				( attribute "GROUP" "PCIE_UPLINK"
					( Origin gFrontEnd )
				)
				( objectStatus "C3M33" )
			)
			( gate "@baseboard_fab2_lib.baseboard_fab2(sch_1):page105_i218"
				( attribute "CDS_LIB" "mstr_discrete"
					( Origin gPackager )
				)
				( attribute "CDS_LOCATION" "C3M36"
					( Origin gPackager )
				)
				( attribute "CDS_SEC" "1"
					( Origin gPackager )
				)
				( attribute "LOCATION" "C3M36"
					( Origin gFrontEnd )
				)
				( attribute "MATERIAL" "X7R"
					( Origin gFrontEnd )
				)
				( attribute "PACK_TYPE" "0402"
					( Origin gFrontEnd )
				)
				( attribute "PART_NUMBER" "A36096-155"
					( Origin gFrontEnd )
				)
				( attribute "PHYS_PAGE" "105"
					( Origin gFrontEnd )
				)
				( attribute "ROOM" "OCP_STEERING"
					( Origin gFrontEnd )
				)
				( attribute "ROT" "2"
					( Origin gFrontEnd )
				)
				( attribute "SEC" "1"
					( Origin gPackager )
				)
				( attribute "TOLERANCE" "10%"
					( Origin gFrontEnd )
				)
				( attribute "VALUE" "0.22UF"
					( Origin gFrontEnd )
				)
				( attribute "VER" "1"
					( Origin gFrontEnd )
				)
				( attribute "VOLTAGE" "16V"
					( Units "uVoltage" "V" 1.000000)
					( Origin gFrontEnd )
				)
				( attribute "XY" "(2200,2025)"
					( Origin gFrontEnd )
				)
				( attribute "CHIPS_PART_NAME" "CAP"
					( Origin gPackager )
				)
				( attribute "CDS_PART_NAME" "CAP_0402-0.22UF,16V,10%,X7R,A3A"
					( Origin gPackager )
				)
				( attribute "GROUP" "PCIE_UPLINK"
					( Origin gFrontEnd )
				)
				( objectStatus "C3M36" )
			)
			( gate "@baseboard_fab2_lib.baseboard_fab2(sch_1):page105_i223"
				( attribute "CDS_LIB" "mstr_discrete"
					( Origin gPackager )
				)
				( attribute "CDS_LOCATION" "C3M32"
					( Origin gPackager )
				)
				( attribute "CDS_SEC" "1"
					( Origin gPackager )
				)
				( attribute "LOCATION" "C3M32"
					( Origin gFrontEnd )
				)
				( attribute "MATERIAL" "X7R"
					( Origin gFrontEnd )
				)
				( attribute "PACK_TYPE" "0402"
					( Origin gFrontEnd )
				)
				( attribute "PART_NUMBER" "A36096-155"
					( Origin gFrontEnd )
				)
				( attribute "PHYS_PAGE" "105"
					( Origin gFrontEnd )
				)
				( attribute "ROOM" "OCP_STEERING"
					( Origin gFrontEnd )
				)
				( attribute "ROT" "2"
					( Origin gFrontEnd )
				)
				( attribute "SEC" "1"
					( Origin gPackager )
				)
				( attribute "TOLERANCE" "10%"
					( Origin gFrontEnd )
				)
				( attribute "VALUE" "0.22UF"
					( Origin gFrontEnd )
				)
				( attribute "VER" "1"
					( Origin gFrontEnd )
				)
				( attribute "VOLTAGE" "16V"
					( Units "uVoltage" "V" 1.000000)
					( Origin gFrontEnd )
				)
				( attribute "XY" "(2050,1325)"
					( Origin gFrontEnd )
				)
				( attribute "CHIPS_PART_NAME" "CAP"
					( Origin gPackager )
				)
				( attribute "CDS_PART_NAME" "CAP_0402-0.22UF,16V,10%,X7R,A3A"
					( Origin gPackager )
				)
				( attribute "GROUP" "PCIE_UPLINK"
					( Origin gFrontEnd )
				)
				( objectStatus "C3M32" )
			)
			( gate "@baseboard_fab2_lib.baseboard_fab2(sch_1):page105_i225"
				( attribute "CDS_LIB" "mstr_discrete"
					( Origin gPackager )
				)
				( attribute "CDS_LOCATION" "C3M35"
					( Origin gPackager )
				)
				( attribute "CDS_SEC" "1"
					( Origin gPackager )
				)
				( attribute "LOCATION" "C3M35"
					( Origin gFrontEnd )
				)
				( attribute "MATERIAL" "X7R"
					( Origin gFrontEnd )
				)
				( attribute "PACK_TYPE" "0402"
					( Origin gFrontEnd )
				)
				( attribute "PART_NUMBER" "A36096-155"
					( Origin gFrontEnd )
				)
				( attribute "PHYS_PAGE" "105"
					( Origin gFrontEnd )
				)
				( attribute "ROOM" "OCP_STEERING"
					( Origin gFrontEnd )
				)
				( attribute "ROT" "2"
					( Origin gFrontEnd )
				)
				( attribute "SEC" "1"
					( Origin gPackager )
				)
				( attribute "TOLERANCE" "10%"
					( Origin gFrontEnd )
				)
				( attribute "VALUE" "0.22UF"
					( Origin gFrontEnd )
				)
				( attribute "VER" "1"
					( Origin gFrontEnd )
				)
				( attribute "VOLTAGE" "16V"
					( Units "uVoltage" "V" 1.000000)
					( Origin gFrontEnd )
				)
				( attribute "XY" "(2250,1025)"
					( Origin gFrontEnd )
				)
				( attribute "CHIPS_PART_NAME" "CAP"
					( Origin gPackager )
				)
				( attribute "CDS_PART_NAME" "CAP_0402-0.22UF,16V,10%,X7R,A3A"
					( Origin gPackager )
				)
				( attribute "GROUP" "PCIE_UPLINK"
					( Origin gFrontEnd )
				)
				( objectStatus "C3M35" )
			)
			( gate "@baseboard_fab2_lib.baseboard_fab2(sch_1):page105_i229"
				( attribute "CDS_LIB" "mstr_discrete"
					( Origin gPackager )
				)
				( attribute "CDS_LOCATION" "C3M26"
					( Origin gPackager )
				)
				( attribute "CDS_SEC" "1"
					( Origin gPackager )
				)
				( attribute "LOCATION" "C3M26"
					( Origin gFrontEnd )
				)
				( attribute "MATERIAL" "X7R"
					( Origin gFrontEnd )
				)
				( attribute "PACK_TYPE" "0402"
					( Origin gFrontEnd )
				)
				( attribute "PART_NUMBER" "A36096-155"
					( Origin gFrontEnd )
				)
				( attribute "PHYS_PAGE" "105"
					( Origin gFrontEnd )
				)
				( attribute "ROOM" "OCP_STEERING"
					( Origin gFrontEnd )
				)
				( attribute "ROT" "2"
					( Origin gFrontEnd )
				)
				( attribute "SEC" "1"
					( Origin gPackager )
				)
				( attribute "TOLERANCE" "10%"
					( Origin gFrontEnd )
				)
				( attribute "VALUE" "0.22UF"
					( Origin gFrontEnd )
				)
				( attribute "VER" "1"
					( Origin gFrontEnd )
				)
				( attribute "VOLTAGE" "16V"
					( Units "uVoltage" "V" 1.000000)
					( Origin gFrontEnd )
				)
				( attribute "XY" "(1850,1025)"
					( Origin gFrontEnd )
				)
				( attribute "CHIPS_PART_NAME" "CAP"
					( Origin gPackager )
				)
				( attribute "CDS_PART_NAME" "CAP_0402-0.22UF,16V,10%,X7R,A3A"
					( Origin gPackager )
				)
				( attribute "GROUP" "PCIE_UPLINK"
					( Origin gFrontEnd )
				)
				( objectStatus "C3M26" )
			)
			( gate "@baseboard_fab2_lib.baseboard_fab2(sch_1):page105_i232"
				( attribute "CDS_LIB" "mstr_discrete"
					( Origin gPackager )
				)
				( attribute "CDS_LOCATION" "C3M3"
					( Origin gPackager )
				)
				( attribute "CDS_SEC" "1"
					( Origin gPackager )
				)
				( attribute "LOCATION" "C3M3"
					( Origin gFrontEnd )
				)
				( attribute "MATERIAL" "X7R"
					( Origin gFrontEnd )
				)
				( attribute "PACK_TYPE" "0402"
					( Origin gFrontEnd )
				)
				( attribute "PART_NUMBER" "A36096-155"
					( Origin gFrontEnd )
				)
				( attribute "PHYS_PAGE" "105"
					( Origin gFrontEnd )
				)
				( attribute "ROOM" "OCP_STEERING"
					( Origin gFrontEnd )
				)
				( attribute "ROT" "2"
					( Origin gFrontEnd )
				)
				( attribute "SEC" "1"
					( Origin gPackager )
				)
				( attribute "TOLERANCE" "10%"
					( Origin gFrontEnd )
				)
				( attribute "VALUE" "0.22UF"
					( Origin gFrontEnd )
				)
				( attribute "VER" "1"
					( Origin gFrontEnd )
				)
				( attribute "VOLTAGE" "16V"
					( Units "uVoltage" "V" 1.000000)
					( Origin gFrontEnd )
				)
				( attribute "XY" "(1600,2325)"
					( Origin gFrontEnd )
				)
				( attribute "CHIPS_PART_NAME" "CAP"
					( Origin gPackager )
				)
				( attribute "CDS_PART_NAME" "CAP_0402-0.22UF,16V,10%,X7R,A3A"
					( Origin gPackager )
				)
				( attribute "GROUP" "PCIE_UPLINK"
					( Origin gFrontEnd )
				)
				( objectStatus "C3M3" )
			)
			( gate "@baseboard_fab2_lib.baseboard_fab2(sch_1):page105_i234"
				( attribute "CDS_LIB" "mstr_discrete"
					( Origin gPackager )
				)
				( attribute "CDS_LOCATION" "C3M11"
					( Origin gPackager )
				)
				( attribute "CDS_SEC" "1"
					( Origin gPackager )
				)
				( attribute "LOCATION" "C3M11"
					( Origin gFrontEnd )
				)
				( attribute "MATERIAL" "X7R"
					( Origin gFrontEnd )
				)
				( attribute "PACK_TYPE" "0402"
					( Origin gFrontEnd )
				)
				( attribute "PART_NUMBER" "A36096-155"
					( Origin gFrontEnd )
				)
				( attribute "PHYS_PAGE" "105"
					( Origin gFrontEnd )
				)
				( attribute "ROOM" "OCP_STEERING"
					( Origin gFrontEnd )
				)
				( attribute "ROT" "2"
					( Origin gFrontEnd )
				)
				( attribute "SEC" "1"
					( Origin gPackager )
				)
				( attribute "TOLERANCE" "10%"
					( Origin gFrontEnd )
				)
				( attribute "VALUE" "0.22UF"
					( Origin gFrontEnd )
				)
				( attribute "VER" "1"
					( Origin gFrontEnd )
				)
				( attribute "VOLTAGE" "16V"
					( Units "uVoltage" "V" 1.000000)
					( Origin gFrontEnd )
				)
				( attribute "XY" "(1200,2325)"
					( Origin gFrontEnd )
				)
				( attribute "CHIPS_PART_NAME" "CAP"
					( Origin gPackager )
				)
				( attribute "CDS_PART_NAME" "CAP_0402-0.22UF,16V,10%,X7R,A3A"
					( Origin gPackager )
				)
				( attribute "GROUP" "PCIE_UPLINK"
					( Origin gFrontEnd )
				)
				( objectStatus "C3M11" )
			)
			( gate "@baseboard_fab2_lib.baseboard_fab2(sch_1):page105_i239"
				( attribute "CDS_LIB" "mstr_discrete"
					( Origin gPackager )
				)
				( attribute "CDS_LOCATION" "C3M13"
					( Origin gPackager )
				)
				( attribute "CDS_SEC" "1"
					( Origin gPackager )
				)
				( attribute "LOCATION" "C3M13"
					( Origin gFrontEnd )
				)
				( attribute "MATERIAL" "X7R"
					( Origin gFrontEnd )
				)
				( attribute "PACK_TYPE" "0402"
					( Origin gFrontEnd )
				)
				( attribute "PART_NUMBER" "A36096-155"
					( Origin gFrontEnd )
				)
				( attribute "PHYS_PAGE" "105"
					( Origin gFrontEnd )
				)
				( attribute "ROOM" "OCP_STEERING"
					( Origin gFrontEnd )
				)
				( attribute "ROT" "2"
					( Origin gFrontEnd )
				)
				( attribute "SEC" "1"
					( Origin gPackager )
				)
				( attribute "TOLERANCE" "10%"
					( Origin gFrontEnd )
				)
				( attribute "VALUE" "0.22UF"
					( Origin gFrontEnd )
				)
				( attribute "VER" "1"
					( Origin gFrontEnd )
				)
				( attribute "VOLTAGE" "16V"
					( Units "uVoltage" "V" 1.000000)
					( Origin gFrontEnd )
				)
				( attribute "XY" "(1400,2025)"
					( Origin gFrontEnd )
				)
				( attribute "CHIPS_PART_NAME" "CAP"
					( Origin gPackager )
				)
				( attribute "CDS_PART_NAME" "CAP_0402-0.22UF,16V,10%,X7R,A3A"
					( Origin gPackager )
				)
				( attribute "GROUP" "PCIE_UPLINK"
					( Origin gFrontEnd )
				)
				( objectStatus "C3M13" )
			)
			( gate "@baseboard_fab2_lib.baseboard_fab2(sch_1):page105_i244"
				( attribute "CDS_LIB" "mstr_discrete"
					( Origin gPackager )
				)
				( attribute "CDS_LOCATION" "C3M4"
					( Origin gPackager )
				)
				( attribute "CDS_SEC" "1"
					( Origin gPackager )
				)
				( attribute "LOCATION" "C3M4"
					( Origin gFrontEnd )
				)
				( attribute "MATERIAL" "X7R"
					( Origin gFrontEnd )
				)
				( attribute "PACK_TYPE" "0402"
					( Origin gFrontEnd )
				)
				( attribute "PART_NUMBER" "A36096-155"
					( Origin gFrontEnd )
				)
				( attribute "PHYS_PAGE" "105"
					( Origin gFrontEnd )
				)
				( attribute "ROOM" "OCP_STEERING"
					( Origin gFrontEnd )
				)
				( attribute "ROT" "2"
					( Origin gFrontEnd )
				)
				( attribute "SEC" "1"
					( Origin gPackager )
				)
				( attribute "TOLERANCE" "10%"
					( Origin gFrontEnd )
				)
				( attribute "VALUE" "0.22UF"
					( Origin gFrontEnd )
				)
				( attribute "VER" "1"
					( Origin gFrontEnd )
				)
				( attribute "VOLTAGE" "16V"
					( Units "uVoltage" "V" 1.000000)
					( Origin gFrontEnd )
				)
				( attribute "XY" "(1650,1325)"
					( Origin gFrontEnd )
				)
				( attribute "CHIPS_PART_NAME" "CAP"
					( Origin gPackager )
				)
				( attribute "CDS_PART_NAME" "CAP_0402-0.22UF,16V,10%,X7R,A3A"
					( Origin gPackager )
				)
				( attribute "GROUP" "PCIE_UPLINK"
					( Origin gFrontEnd )
				)
				( objectStatus "C3M4" )
			)
			( gate "@baseboard_fab2_lib.baseboard_fab2(sch_1):page105_i246"
				( attribute "CDS_LIB" "mstr_discrete"
					( Origin gPackager )
				)
				( attribute "CDS_LOCATION" "C3M12"
					( Origin gPackager )
				)
				( attribute "CDS_SEC" "1"
					( Origin gPackager )
				)
				( attribute "LOCATION" "C3M12"
					( Origin gFrontEnd )
				)
				( attribute "MATERIAL" "X7R"
					( Origin gFrontEnd )
				)
				( attribute "PACK_TYPE" "0402"
					( Origin gFrontEnd )
				)
				( attribute "PART_NUMBER" "A36096-155"
					( Origin gFrontEnd )
				)
				( attribute "PHYS_PAGE" "105"
					( Origin gFrontEnd )
				)
				( attribute "ROOM" "OCP_STEERING"
					( Origin gFrontEnd )
				)
				( attribute "ROT" "2"
					( Origin gFrontEnd )
				)
				( attribute "SEC" "1"
					( Origin gPackager )
				)
				( attribute "TOLERANCE" "10%"
					( Origin gFrontEnd )
				)
				( attribute "VALUE" "0.22UF"
					( Origin gFrontEnd )
				)
				( attribute "VER" "1"
					( Origin gFrontEnd )
				)
				( attribute "VOLTAGE" "16V"
					( Units "uVoltage" "V" 1.000000)
					( Origin gFrontEnd )
				)
				( attribute "XY" "(1250,1325)"
					( Origin gFrontEnd )
				)
				( attribute "CHIPS_PART_NAME" "CAP"
					( Origin gPackager )
				)
				( attribute "CDS_PART_NAME" "CAP_0402-0.22UF,16V,10%,X7R,A3A"
					( Origin gPackager )
				)
				( attribute "GROUP" "PCIE_UPLINK"
					( Origin gFrontEnd )
				)
				( objectStatus "C3M12" )
			)
			( gate "@baseboard_fab2_lib.baseboard_fab2(sch_1):page105_i247"
				( attribute "CDS_LIB" "mstr_discrete"
					( Origin gPackager )
				)
				( attribute "CDS_LOCATION" "C3M2"
					( Origin gPackager )
				)
				( attribute "CDS_SEC" "1"
					( Origin gPackager )
				)
				( attribute "LOCATION" "C3M2"
					( Origin gFrontEnd )
				)
				( attribute "MATERIAL" "X7R"
					( Origin gFrontEnd )
				)
				( attribute "PACK_TYPE" "0402"
					( Origin gFrontEnd )
				)
				( attribute "PART_NUMBER" "A36096-155"
					( Origin gFrontEnd )
				)
				( attribute "PHYS_PAGE" "105"
					( Origin gFrontEnd )
				)
				( attribute "ROOM" "OCP_STEERING"
					( Origin gFrontEnd )
				)
				( attribute "ROT" "2"
					( Origin gFrontEnd )
				)
				( attribute "SEC" "1"
					( Origin gPackager )
				)
				( attribute "TOLERANCE" "10%"
					( Origin gFrontEnd )
				)
				( attribute "VALUE" "0.22UF"
					( Origin gFrontEnd )
				)
				( attribute "VER" "1"
					( Origin gFrontEnd )
				)
				( attribute "VOLTAGE" "16V"
					( Units "uVoltage" "V" 1.000000)
					( Origin gFrontEnd )
				)
				( attribute "XY" "(1000,2025)"
					( Origin gFrontEnd )
				)
				( attribute "CHIPS_PART_NAME" "CAP"
					( Origin gPackager )
				)
				( attribute "CDS_PART_NAME" "CAP_0402-0.22UF,16V,10%,X7R,A3A"
					( Origin gPackager )
				)
				( attribute "GROUP" "PCIE_UPLINK"
					( Origin gFrontEnd )
				)
				( objectStatus "C3M2" )
			)
			( gate "@baseboard_fab2_lib.baseboard_fab2(sch_1):page105_i253"
				( attribute "CDS_LIB" "mstr_discrete"
					( Origin gPackager )
				)
				( attribute "CDS_LOCATION" "C3M14"
					( Origin gPackager )
				)
				( attribute "CDS_SEC" "1"
					( Origin gPackager )
				)
				( attribute "LOCATION" "C3M14"
					( Origin gFrontEnd )
				)
				( attribute "MATERIAL" "X7R"
					( Origin gFrontEnd )
				)
				( attribute "PACK_TYPE" "0402"
					( Origin gFrontEnd )
				)
				( attribute "PART_NUMBER" "A36096-155"
					( Origin gFrontEnd )
				)
				( attribute "PHYS_PAGE" "105"
					( Origin gFrontEnd )
				)
				( attribute "ROOM" "OCP_STEERING"
					( Origin gFrontEnd )
				)
				( attribute "ROT" "2"
					( Origin gFrontEnd )
				)
				( attribute "SEC" "1"
					( Origin gPackager )
				)
				( attribute "TOLERANCE" "10%"
					( Origin gFrontEnd )
				)
				( attribute "VALUE" "0.22UF"
					( Origin gFrontEnd )
				)
				( attribute "VER" "1"
					( Origin gFrontEnd )
				)
				( attribute "VOLTAGE" "16V"
					( Units "uVoltage" "V" 1.000000)
					( Origin gFrontEnd )
				)
				( attribute "XY" "(1450,1025)"
					( Origin gFrontEnd )
				)
				( attribute "CHIPS_PART_NAME" "CAP"
					( Origin gPackager )
				)
				( attribute "CDS_PART_NAME" "CAP_0402-0.22UF,16V,10%,X7R,A3A"
					( Origin gPackager )
				)
				( attribute "GROUP" "PCIE_UPLINK"
					( Origin gFrontEnd )
				)
				( objectStatus "C3M14" )
			)
			( gate "@baseboard_fab2_lib.baseboard_fab2(sch_1):page105_i255"
				( attribute "CDS_LIB" "mstr_discrete"
					( Origin gPackager )
				)
				( attribute "CDS_LOCATION" "C3M1"
					( Origin gPackager )
				)
				( attribute "CDS_SEC" "1"
					( Origin gPackager )
				)
				( attribute "LOCATION" "C3M1"
					( Origin gFrontEnd )
				)
				( attribute "MATERIAL" "X7R"
					( Origin gFrontEnd )
				)
				( attribute "PACK_TYPE" "0402"
					( Origin gFrontEnd )
				)
				( attribute "PART_NUMBER" "A36096-155"
					( Origin gFrontEnd )
				)
				( attribute "PHYS_PAGE" "105"
					( Origin gFrontEnd )
				)
				( attribute "ROOM" "OCP_STEERING"
					( Origin gFrontEnd )
				)
				( attribute "ROT" "2"
					( Origin gFrontEnd )
				)
				( attribute "SEC" "1"
					( Origin gPackager )
				)
				( attribute "TOLERANCE" "10%"
					( Origin gFrontEnd )
				)
				( attribute "VALUE" "0.22UF"
					( Origin gFrontEnd )
				)
				( attribute "VER" "1"
					( Origin gFrontEnd )
				)
				( attribute "VOLTAGE" "16V"
					( Units "uVoltage" "V" 1.000000)
					( Origin gFrontEnd )
				)
				( attribute "XY" "(1050,1025)"
					( Origin gFrontEnd )
				)
				( attribute "CHIPS_PART_NAME" "CAP"
					( Origin gPackager )
				)
				( attribute "CDS_PART_NAME" "CAP_0402-0.22UF,16V,10%,X7R,A3A"
					( Origin gPackager )
				)
				( attribute "GROUP" "PCIE_UPLINK"
					( Origin gFrontEnd )
				)
				( objectStatus "C3M1" )
			)
			( gate "@baseboard_fab2_lib.baseboard_fab2(sch_1):page106_i10"
				( attribute "BOM_COST" "IO_SLOT"
					( Origin gFrontEnd )
				)
				( attribute "CDS_LIB" "mstr_discrete"
					( Origin gPackager )
				)
				( attribute "CDS_LOCATION" "C1R2"
					( Origin gPackager )
				)
				( attribute "CDS_SEC" "1"
					( Origin gPackager )
				)
				( attribute "LOCATION" "C1R2"
					( Origin gFrontEnd )
				)
				( attribute "MATERIAL" "X7R"
					( Origin gFrontEnd )
				)
				( attribute "PACK_TYPE" "0402"
					( Origin gFrontEnd )
				)
				( attribute "PART_NUMBER" "A36096-155"
					( Origin gFrontEnd )
				)
				( attribute "PHYS_PAGE" "106"
					( Origin gFrontEnd )
				)
				( attribute "ROOM" "PCIE_STEERING"
					( Origin gFrontEnd )
				)
				( attribute "ROT" "2"
					( Origin gFrontEnd )
				)
				( attribute "SEC" "1"
					( Origin gPackager )
				)
				( attribute "TOLERANCE" "10%"
					( Origin gFrontEnd )
				)
				( attribute "VALUE" "0.22UF"
					( Origin gFrontEnd )
				)
				( attribute "VER" "1"
					( Origin gFrontEnd )
				)
				( attribute "VOLTAGE" "16V"
					( Units "uVoltage" "V" 1.000000)
					( Origin gFrontEnd )
				)
				( attribute "XY" "(-4100,2650)"
					( Origin gFrontEnd )
				)
				( attribute "CHIPS_PART_NAME" "CAP"
					( Origin gPackager )
				)
				( attribute "CDS_PART_NAME" "CAP_0402-0.22UF,16V,10%,X7R,A3A"
					( Origin gPackager )
				)
				( objectStatus "C1R2" )
			)
			( gate "@baseboard_fab2_lib.baseboard_fab2(sch_1):page106_i26"
				( attribute "BOM_COST" "IO_SLOT"
					( Origin gFrontEnd )
				)
				( attribute "CDS_LIB" "mstr_discrete"
					( Origin gPackager )
				)
				( attribute "CDS_LOCATION" "C1R4"
					( Origin gPackager )
				)
				( attribute "CDS_SEC" "1"
					( Origin gPackager )
				)
				( attribute "LOCATION" "C1R4"
					( Origin gFrontEnd )
				)
				( attribute "MATERIAL" "X7R"
					( Origin gFrontEnd )
				)
				( attribute "PACK_TYPE" "0402"
					( Origin gFrontEnd )
				)
				( attribute "PART_NUMBER" "A36096-155"
					( Origin gFrontEnd )
				)
				( attribute "PHYS_PAGE" "106"
					( Origin gFrontEnd )
				)
				( attribute "ROOM" "PCIE_STEERING"
					( Origin gFrontEnd )
				)
				( attribute "ROT" "2"
					( Origin gFrontEnd )
				)
				( attribute "SEC" "1"
					( Origin gPackager )
				)
				( attribute "TOLERANCE" "10%"
					( Origin gFrontEnd )
				)
				( attribute "VALUE" "0.22UF"
					( Origin gFrontEnd )
				)
				( attribute "VER" "1"
					( Origin gFrontEnd )
				)
				( attribute "VOLTAGE" "16V"
					( Units "uVoltage" "V" 1.000000)
					( Origin gFrontEnd )
				)
				( attribute "XY" "(-4300,2350)"
					( Origin gFrontEnd )
				)
				( attribute "CHIPS_PART_NAME" "CAP"
					( Origin gPackager )
				)
				( attribute "CDS_PART_NAME" "CAP_0402-0.22UF,16V,10%,X7R,A3A"
					( Origin gPackager )
				)
				( objectStatus "C1R4" )
			)
			( gate "@baseboard_fab2_lib.baseboard_fab2(sch_1):page106_i29"
				( attribute "BOM_COST" "IO_SLOT"
					( Origin gFrontEnd )
				)
				( attribute "CDS_LIB" "mstr_discrete"
					( Origin gPackager )
				)
				( attribute "CDS_LOCATION" "C1R1"
					( Origin gPackager )
				)
				( attribute "CDS_SEC" "1"
					( Origin gPackager )
				)
				( attribute "LOCATION" "C1R1"
					( Origin gFrontEnd )
				)
				( attribute "MATERIAL" "X7R"
					( Origin gFrontEnd )
				)
				( attribute "PACK_TYPE" "0402"
					( Origin gFrontEnd )
				)
				( attribute "PART_NUMBER" "A36096-155"
					( Origin gFrontEnd )
				)
				( attribute "PHYS_PAGE" "106"
					( Origin gFrontEnd )
				)
				( attribute "ROOM" "PCIE_STEERING"
					( Origin gFrontEnd )
				)
				( attribute "ROT" "2"
					( Origin gFrontEnd )
				)
				( attribute "SEC" "1"
					( Origin gPackager )
				)
				( attribute "TOLERANCE" "10%"
					( Origin gFrontEnd )
				)
				( attribute "VALUE" "0.22UF"
					( Origin gFrontEnd )
				)
				( attribute "VER" "1"
					( Origin gFrontEnd )
				)
				( attribute "VOLTAGE" "16V"
					( Units "uVoltage" "V" 1.000000)
					( Origin gFrontEnd )
				)
				( attribute "XY" "(-4075,1650)"
					( Origin gFrontEnd )
				)
				( attribute "CHIPS_PART_NAME" "CAP"
					( Origin gPackager )
				)
				( attribute "CDS_PART_NAME" "CAP_0402-0.22UF,16V,10%,X7R,A3A"
					( Origin gPackager )
				)
				( objectStatus "C1R1" )
			)
			( gate "@baseboard_fab2_lib.baseboard_fab2(sch_1):page106_i37"
				( attribute "BOM_COST" "IO_SLOT"
					( Origin gFrontEnd )
				)
				( attribute "CDS_LIB" "mstr_discrete"
					( Origin gPackager )
				)
				( attribute "CDS_LOCATION" "C1R3"
					( Origin gPackager )
				)
				( attribute "CDS_SEC" "1"
					( Origin gPackager )
				)
				( attribute "LOCATION" "C1R3"
					( Origin gFrontEnd )
				)
				( attribute "MATERIAL" "X7R"
					( Origin gFrontEnd )
				)
				( attribute "PACK_TYPE" "0402"
					( Origin gFrontEnd )
				)
				( attribute "PART_NUMBER" "A36096-155"
					( Origin gFrontEnd )
				)
				( attribute "PHYS_PAGE" "106"
					( Origin gFrontEnd )
				)
				( attribute "ROOM" "PCIE_STEERING"
					( Origin gFrontEnd )
				)
				( attribute "ROT" "2"
					( Origin gFrontEnd )
				)
				( attribute "SEC" "1"
					( Origin gPackager )
				)
				( attribute "TOLERANCE" "10%"
					( Origin gFrontEnd )
				)
				( attribute "VALUE" "0.22UF"
					( Origin gFrontEnd )
				)
				( attribute "VER" "1"
					( Origin gFrontEnd )
				)
				( attribute "VOLTAGE" "16V"
					( Units "uVoltage" "V" 1.000000)
					( Origin gFrontEnd )
				)
				( attribute "XY" "(-4275,1350)"
					( Origin gFrontEnd )
				)
				( attribute "CHIPS_PART_NAME" "CAP"
					( Origin gPackager )
				)
				( attribute "CDS_PART_NAME" "CAP_0402-0.22UF,16V,10%,X7R,A3A"
					( Origin gPackager )
				)
				( objectStatus "C1R3" )
			)
			( gate "@baseboard_fab2_lib.baseboard_fab2(sch_1):page106_i40"
				( attribute "CDS_LIB" "mstr_discrete"
					( Origin gPackager )
				)
				( attribute "CDS_LOCATION" "C1R6"
					( Origin gPackager )
				)
				( attribute "CDS_SEC" "1"
					( Origin gPackager )
				)
				( attribute "LOCATION" "C1R6"
					( Origin gFrontEnd )
				)
				( attribute "MATERIAL" "X7R"
					( Origin gFrontEnd )
				)
				( attribute "PACK_TYPE" "0402"
					( Origin gFrontEnd )
				)
				( attribute "PART_NUMBER" "A36096-155"
					( Origin gFrontEnd )
				)
				( attribute "PHYS_PAGE" "106"
					( Origin gFrontEnd )
				)
				( attribute "ROOM" "PCIE_STEERING"
					( Origin gFrontEnd )
				)
				( attribute "ROT" "2"
					( Origin gFrontEnd )
				)
				( attribute "SEC" "1"
					( Origin gPackager )
				)
				( attribute "TOLERANCE" "10%"
					( Origin gFrontEnd )
				)
				( attribute "VALUE" "0.22UF"
					( Origin gFrontEnd )
				)
				( attribute "VER" "1"
					( Origin gFrontEnd )
				)
				( attribute "VOLTAGE" "16V"
					( Units "uVoltage" "V" 1.000000)
					( Origin gFrontEnd )
				)
				( attribute "XY" "(-4500,2650)"
					( Origin gFrontEnd )
				)
				( attribute "CHIPS_PART_NAME" "CAP"
					( Origin gPackager )
				)
				( attribute "CDS_PART_NAME" "CAP_0402-0.22UF,16V,10%,X7R,A3A"
					( Origin gPackager )
				)
				( objectStatus "C1R6" )
			)
			( gate "@baseboard_fab2_lib.baseboard_fab2(sch_1):page106_i55"
				( attribute "CDS_LIB" "mstr_discrete"
					( Origin gPackager )
				)
				( attribute "CDS_LOCATION" "C1R8"
					( Origin gPackager )
				)
				( attribute "CDS_SEC" "1"
					( Origin gPackager )
				)
				( attribute "LOCATION" "C1R8"
					( Origin gFrontEnd )
				)
				( attribute "MATERIAL" "X7R"
					( Origin gFrontEnd )
				)
				( attribute "PACK_TYPE" "0402"
					( Origin gFrontEnd )
				)
				( attribute "PART_NUMBER" "A36096-155"
					( Origin gFrontEnd )
				)
				( attribute "PHYS_PAGE" "106"
					( Origin gFrontEnd )
				)
				( attribute "ROOM" "PCIE_STEERING"
					( Origin gFrontEnd )
				)
				( attribute "ROT" "2"
					( Origin gFrontEnd )
				)
				( attribute "SEC" "1"
					( Origin gPackager )
				)
				( attribute "TOLERANCE" "10%"
					( Origin gFrontEnd )
				)
				( attribute "VALUE" "0.22UF"
					( Origin gFrontEnd )
				)
				( attribute "VER" "1"
					( Origin gFrontEnd )
				)
				( attribute "VOLTAGE" "16V"
					( Units "uVoltage" "V" 1.000000)
					( Origin gFrontEnd )
				)
				( attribute "XY" "(-4700,2350)"
					( Origin gFrontEnd )
				)
				( attribute "CHIPS_PART_NAME" "CAP"
					( Origin gPackager )
				)
				( attribute "CDS_PART_NAME" "CAP_0402-0.22UF,16V,10%,X7R,A3A"
					( Origin gPackager )
				)
				( objectStatus "C1R8" )
			)
			( gate "@baseboard_fab2_lib.baseboard_fab2(sch_1):page106_i59"
				( attribute "BOM_COST" "IO_SLOT"
					( Origin gFrontEnd )
				)
				( attribute "CDS_LIB" "mstr_discrete"
					( Origin gPackager )
				)
				( attribute "CDS_LOCATION" "C1R5"
					( Origin gPackager )
				)
				( attribute "CDS_SEC" "1"
					( Origin gPackager )
				)
				( attribute "LOCATION" "C1R5"
					( Origin gFrontEnd )
				)
				( attribute "MATERIAL" "X7R"
					( Origin gFrontEnd )
				)
				( attribute "PACK_TYPE" "0402"
					( Origin gFrontEnd )
				)
				( attribute "PART_NUMBER" "A36096-155"
					( Origin gFrontEnd )
				)
				( attribute "PHYS_PAGE" "106"
					( Origin gFrontEnd )
				)
				( attribute "ROOM" "PCIE_STEERING"
					( Origin gFrontEnd )
				)
				( attribute "ROT" "2"
					( Origin gFrontEnd )
				)
				( attribute "SEC" "1"
					( Origin gPackager )
				)
				( attribute "TOLERANCE" "10%"
					( Origin gFrontEnd )
				)
				( attribute "VALUE" "0.22UF"
					( Origin gFrontEnd )
				)
				( attribute "VER" "1"
					( Origin gFrontEnd )
				)
				( attribute "VOLTAGE" "16V"
					( Units "uVoltage" "V" 1.000000)
					( Origin gFrontEnd )
				)
				( attribute "XY" "(-4475,1650)"
					( Origin gFrontEnd )
				)
				( attribute "CHIPS_PART_NAME" "CAP"
					( Origin gPackager )
				)
				( attribute "CDS_PART_NAME" "CAP_0402-0.22UF,16V,10%,X7R,A3A"
					( Origin gPackager )
				)
				( objectStatus "C1R5" )
			)
			( gate "@baseboard_fab2_lib.baseboard_fab2(sch_1):page106_i70"
				( attribute "BOM_COST" "IO_SLOT"
					( Origin gFrontEnd )
				)
				( attribute "CDS_LIB" "mstr_discrete"
					( Origin gPackager )
				)
				( attribute "CDS_LOCATION" "C1R7"
					( Origin gPackager )
				)
				( attribute "CDS_SEC" "1"
					( Origin gPackager )
				)
				( attribute "LOCATION" "C1R7"
					( Origin gFrontEnd )
				)
				( attribute "MATERIAL" "X7R"
					( Origin gFrontEnd )
				)
				( attribute "PACK_TYPE" "0402"
					( Origin gFrontEnd )
				)
				( attribute "PART_NUMBER" "A36096-155"
					( Origin gFrontEnd )
				)
				( attribute "PHYS_PAGE" "106"
					( Origin gFrontEnd )
				)
				( attribute "ROOM" "PCIE_STEERING"
					( Origin gFrontEnd )
				)
				( attribute "ROT" "2"
					( Origin gFrontEnd )
				)
				( attribute "SEC" "1"
					( Origin gPackager )
				)
				( attribute "TOLERANCE" "10%"
					( Origin gFrontEnd )
				)
				( attribute "VALUE" "0.22UF"
					( Origin gFrontEnd )
				)
				( attribute "VER" "1"
					( Origin gFrontEnd )
				)
				( attribute "VOLTAGE" "16V"
					( Units "uVoltage" "V" 1.000000)
					( Origin gFrontEnd )
				)
				( attribute "XY" "(-4675,1350)"
					( Origin gFrontEnd )
				)
				( attribute "CHIPS_PART_NAME" "CAP"
					( Origin gPackager )
				)
				( attribute "CDS_PART_NAME" "CAP_0402-0.22UF,16V,10%,X7R,A3A"
					( Origin gPackager )
				)
				( objectStatus "C1R7" )
			)
			( gate "@baseboard_fab2_lib.baseboard_fab2(sch_1):page106_i76"
				( attribute "BOM_COST" "IO_SLOT"
					( Origin gFrontEnd )
				)
				( attribute "CDS_LIB" "mstr_discrete"
					( Origin gPackager )
				)
				( attribute "CDS_LOCATION" "C2M14"
					( Origin gPackager )
				)
				( attribute "CDS_SEC" "1"
					( Origin gPackager )
				)
				( attribute "LOCATION" "C2M14"
					( Origin gFrontEnd )
				)
				( attribute "MATERIAL" "X7R"
					( Origin gFrontEnd )
				)
				( attribute "PACK_TYPE" "0402"
					( Origin gFrontEnd )
				)
				( attribute "PART_NUMBER" "A36096-155"
					( Origin gFrontEnd )
				)
				( attribute "PHYS_PAGE" "106"
					( Origin gFrontEnd )
				)
				( attribute "ROOM" "PCIE_STEERING"
					( Origin gFrontEnd )
				)
				( attribute "ROT" "2"
					( Origin gFrontEnd )
				)
				( attribute "SEC" "1"
					( Origin gPackager )
				)
				( attribute "TOLERANCE" "10%"
					( Origin gFrontEnd )
				)
				( attribute "VALUE" "0.22UF"
					( Origin gFrontEnd )
				)
				( attribute "VER" "1"
					( Origin gFrontEnd )
				)
				( attribute "VOLTAGE" "16V"
					( Units "uVoltage" "V" 1.000000)
					( Origin gFrontEnd )
				)
				( attribute "XY" "(-5700,2650)"
					( Origin gFrontEnd )
				)
				( attribute "CHIPS_PART_NAME" "CAP"
					( Origin gPackager )
				)
				( attribute "CDS_PART_NAME" "CAP_0402-0.22UF,16V,10%,X7R,A3A"
					( Origin gPackager )
				)
				( objectStatus "C2M14" )
			)
			( gate "@baseboard_fab2_lib.baseboard_fab2(sch_1):page106_i78"
				( attribute "BOM_COST" "IO_SLOT"
					( Origin gFrontEnd )
				)
				( attribute "CDS_LIB" "mstr_discrete"
					( Origin gPackager )
				)
				( attribute "CDS_LOCATION" "C1M18"
					( Origin gPackager )
				)
				( attribute "CDS_SEC" "1"
					( Origin gPackager )
				)
				( attribute "LOCATION" "C1M18"
					( Origin gFrontEnd )
				)
				( attribute "MATERIAL" "X7R"
					( Origin gFrontEnd )
				)
				( attribute "PACK_TYPE" "0402"
					( Origin gFrontEnd )
				)
				( attribute "PART_NUMBER" "A36096-155"
					( Origin gFrontEnd )
				)
				( attribute "PHYS_PAGE" "106"
					( Origin gFrontEnd )
				)
				( attribute "ROOM" "PCIE_STEERING"
					( Origin gFrontEnd )
				)
				( attribute "ROT" "2"
					( Origin gFrontEnd )
				)
				( attribute "SEC" "1"
					( Origin gPackager )
				)
				( attribute "TOLERANCE" "10%"
					( Origin gFrontEnd )
				)
				( attribute "VALUE" "0.22UF"
					( Origin gFrontEnd )
				)
				( attribute "VER" "1"
					( Origin gFrontEnd )
				)
				( attribute "VOLTAGE" "16V"
					( Units "uVoltage" "V" 1.000000)
					( Origin gFrontEnd )
				)
				( attribute "XY" "(-5900,2350)"
					( Origin gFrontEnd )
				)
				( attribute "CHIPS_PART_NAME" "CAP"
					( Origin gPackager )
				)
				( attribute "CDS_PART_NAME" "CAP_0402-0.22UF,16V,10%,X7R,A3A"
					( Origin gPackager )
				)
				( objectStatus "C1M18" )
			)
			( gate "@baseboard_fab2_lib.baseboard_fab2(sch_1):page106_i82"
				( attribute "BOM_COST" "IO_SLOT"
					( Origin gFrontEnd )
				)
				( attribute "CDS_LIB" "mstr_discrete"
					( Origin gPackager )
				)
				( attribute "CDS_LOCATION" "C1M16"
					( Origin gPackager )
				)
				( attribute "CDS_SEC" "1"
					( Origin gPackager )
				)
				( attribute "LOCATION" "C1M16"
					( Origin gFrontEnd )
				)
				( attribute "MATERIAL" "X7R"
					( Origin gFrontEnd )
				)
				( attribute "PACK_TYPE" "0402"
					( Origin gFrontEnd )
				)
				( attribute "PART_NUMBER" "A36096-155"
					( Origin gFrontEnd )
				)
				( attribute "PHYS_PAGE" "106"
					( Origin gFrontEnd )
				)
				( attribute "ROOM" "PCIE_STEERING"
					( Origin gFrontEnd )
				)
				( attribute "ROT" "2"
					( Origin gFrontEnd )
				)
				( attribute "SEC" "1"
					( Origin gPackager )
				)
				( attribute "TOLERANCE" "10%"
					( Origin gFrontEnd )
				)
				( attribute "VALUE" "0.22UF"
					( Origin gFrontEnd )
				)
				( attribute "VER" "1"
					( Origin gFrontEnd )
				)
				( attribute "VOLTAGE" "16V"
					( Units "uVoltage" "V" 1.000000)
					( Origin gFrontEnd )
				)
				( attribute "XY" "(-6100,2650)"
					( Origin gFrontEnd )
				)
				( attribute "CHIPS_PART_NAME" "CAP"
					( Origin gPackager )
				)
				( attribute "CDS_PART_NAME" "CAP_0402-0.22UF,16V,10%,X7R,A3A"
					( Origin gPackager )
				)
				( objectStatus "C1M16" )
			)
			( gate "@baseboard_fab2_lib.baseboard_fab2(sch_1):page106_i85"
				( attribute "BOM_COST" "IO_SLOT"
					( Origin gFrontEnd )
				)
				( attribute "CDS_LIB" "mstr_discrete"
					( Origin gPackager )
				)
				( attribute "CDS_LOCATION" "C1M14"
					( Origin gPackager )
				)
				( attribute "CDS_SEC" "1"
					( Origin gPackager )
				)
				( attribute "LOCATION" "C1M14"
					( Origin gFrontEnd )
				)
				( attribute "MATERIAL" "X7R"
					( Origin gFrontEnd )
				)
				( attribute "PACK_TYPE" "0402"
					( Origin gFrontEnd )
				)
				( attribute "PART_NUMBER" "A36096-155"
					( Origin gFrontEnd )
				)
				( attribute "PHYS_PAGE" "106"
					( Origin gFrontEnd )
				)
				( attribute "ROOM" "PCIE_STEERING"
					( Origin gFrontEnd )
				)
				( attribute "ROT" "2"
					( Origin gFrontEnd )
				)
				( attribute "SEC" "1"
					( Origin gPackager )
				)
				( attribute "TOLERANCE" "10%"
					( Origin gFrontEnd )
				)
				( attribute "VALUE" "0.22UF"
					( Origin gFrontEnd )
				)
				( attribute "VER" "1"
					( Origin gFrontEnd )
				)
				( attribute "VOLTAGE" "16V"
					( Units "uVoltage" "V" 1.000000)
					( Origin gFrontEnd )
				)
				( attribute "XY" "(-6300,2350)"
					( Origin gFrontEnd )
				)
				( attribute "CHIPS_PART_NAME" "CAP"
					( Origin gPackager )
				)
				( attribute "CDS_PART_NAME" "CAP_0402-0.22UF,16V,10%,X7R,A3A"
					( Origin gPackager )
				)
				( objectStatus "C1M14" )
			)
			( gate "@baseboard_fab2_lib.baseboard_fab2(sch_1):page106_i86"
				( attribute "BOM_COST" "IO_SLOT"
					( Origin gFrontEnd )
				)
				( attribute "CDS_LIB" "mstr_discrete"
					( Origin gPackager )
				)
				( attribute "CDS_LOCATION" "C2M15"
					( Origin gPackager )
				)
				( attribute "CDS_SEC" "1"
					( Origin gPackager )
				)
				( attribute "LOCATION" "C2M15"
					( Origin gFrontEnd )
				)
				( attribute "MATERIAL" "X7R"
					( Origin gFrontEnd )
				)
				( attribute "PACK_TYPE" "0402"
					( Origin gFrontEnd )
				)
				( attribute "PART_NUMBER" "A36096-155"
					( Origin gFrontEnd )
				)
				( attribute "PHYS_PAGE" "106"
					( Origin gFrontEnd )
				)
				( attribute "ROOM" "PCIE_STEERING"
					( Origin gFrontEnd )
				)
				( attribute "ROT" "2"
					( Origin gFrontEnd )
				)
				( attribute "SEC" "1"
					( Origin gPackager )
				)
				( attribute "TOLERANCE" "10%"
					( Origin gFrontEnd )
				)
				( attribute "VALUE" "0.22UF"
					( Origin gFrontEnd )
				)
				( attribute "VER" "1"
					( Origin gFrontEnd )
				)
				( attribute "VOLTAGE" "16V"
					( Units "uVoltage" "V" 1.000000)
					( Origin gFrontEnd )
				)
				( attribute "XY" "(-5650,1650)"
					( Origin gFrontEnd )
				)
				( attribute "CHIPS_PART_NAME" "CAP"
					( Origin gPackager )
				)
				( attribute "CDS_PART_NAME" "CAP_0402-0.22UF,16V,10%,X7R,A3A"
					( Origin gPackager )
				)
				( objectStatus "C2M15" )
			)
			( gate "@baseboard_fab2_lib.baseboard_fab2(sch_1):page106_i90"
				( attribute "BOM_COST" "IO_SLOT"
					( Origin gFrontEnd )
				)
				( attribute "CDS_LIB" "mstr_discrete"
					( Origin gPackager )
				)
				( attribute "CDS_LOCATION" "C1M19"
					( Origin gPackager )
				)
				( attribute "CDS_SEC" "1"
					( Origin gPackager )
				)
				( attribute "LOCATION" "C1M19"
					( Origin gFrontEnd )
				)
				( attribute "MATERIAL" "X7R"
					( Origin gFrontEnd )
				)
				( attribute "PACK_TYPE" "0402"
					( Origin gFrontEnd )
				)
				( attribute "PART_NUMBER" "A36096-155"
					( Origin gFrontEnd )
				)
				( attribute "PHYS_PAGE" "106"
					( Origin gFrontEnd )
				)
				( attribute "ROOM" "PCIE_STEERING"
					( Origin gFrontEnd )
				)
				( attribute "ROT" "2"
					( Origin gFrontEnd )
				)
				( attribute "SEC" "1"
					( Origin gPackager )
				)
				( attribute "TOLERANCE" "10%"
					( Origin gFrontEnd )
				)
				( attribute "VALUE" "0.22UF"
					( Origin gFrontEnd )
				)
				( attribute "VER" "1"
					( Origin gFrontEnd )
				)
				( attribute "VOLTAGE" "16V"
					( Units "uVoltage" "V" 1.000000)
					( Origin gFrontEnd )
				)
				( attribute "XY" "(-5850,1350)"
					( Origin gFrontEnd )
				)
				( attribute "CHIPS_PART_NAME" "CAP"
					( Origin gPackager )
				)
				( attribute "CDS_PART_NAME" "CAP_0402-0.22UF,16V,10%,X7R,A3A"
					( Origin gPackager )
				)
				( objectStatus "C1M19" )
			)
			( gate "@baseboard_fab2_lib.baseboard_fab2(sch_1):page106_i92"
				( attribute "BOM_COST" "IO_SLOT"
					( Origin gFrontEnd )
				)
				( attribute "CDS_LIB" "mstr_discrete"
					( Origin gPackager )
				)
				( attribute "CDS_LOCATION" "C1M17"
					( Origin gPackager )
				)
				( attribute "CDS_SEC" "1"
					( Origin gPackager )
				)
				( attribute "LOCATION" "C1M17"
					( Origin gFrontEnd )
				)
				( attribute "MATERIAL" "X7R"
					( Origin gFrontEnd )
				)
				( attribute "PACK_TYPE" "0402"
					( Origin gFrontEnd )
				)
				( attribute "PART_NUMBER" "A36096-155"
					( Origin gFrontEnd )
				)
				( attribute "PHYS_PAGE" "106"
					( Origin gFrontEnd )
				)
				( attribute "ROOM" "PCIE_STEERING"
					( Origin gFrontEnd )
				)
				( attribute "ROT" "2"
					( Origin gFrontEnd )
				)
				( attribute "SEC" "1"
					( Origin gPackager )
				)
				( attribute "TOLERANCE" "10%"
					( Origin gFrontEnd )
				)
				( attribute "VALUE" "0.22UF"
					( Origin gFrontEnd )
				)
				( attribute "VER" "1"
					( Origin gFrontEnd )
				)
				( attribute "VOLTAGE" "16V"
					( Units "uVoltage" "V" 1.000000)
					( Origin gFrontEnd )
				)
				( attribute "XY" "(-6050,1650)"
					( Origin gFrontEnd )
				)
				( attribute "CHIPS_PART_NAME" "CAP"
					( Origin gPackager )
				)
				( attribute "CDS_PART_NAME" "CAP_0402-0.22UF,16V,10%,X7R,A3A"
					( Origin gPackager )
				)
				( objectStatus "C1M17" )
			)
			( gate "@baseboard_fab2_lib.baseboard_fab2(sch_1):page106_i95"
				( attribute "BOM_COST" "IO_SLOT"
					( Origin gFrontEnd )
				)
				( attribute "CDS_LIB" "mstr_discrete"
					( Origin gPackager )
				)
				( attribute "CDS_LOCATION" "C1M15"
					( Origin gPackager )
				)
				( attribute "CDS_SEC" "1"
					( Origin gPackager )
				)
				( attribute "LOCATION" "C1M15"
					( Origin gFrontEnd )
				)
				( attribute "MATERIAL" "X7R"
					( Origin gFrontEnd )
				)
				( attribute "PACK_TYPE" "0402"
					( Origin gFrontEnd )
				)
				( attribute "PART_NUMBER" "A36096-155"
					( Origin gFrontEnd )
				)
				( attribute "PHYS_PAGE" "106"
					( Origin gFrontEnd )
				)
				( attribute "ROOM" "PCIE_STEERING"
					( Origin gFrontEnd )
				)
				( attribute "ROT" "2"
					( Origin gFrontEnd )
				)
				( attribute "SEC" "1"
					( Origin gPackager )
				)
				( attribute "TOLERANCE" "10%"
					( Origin gFrontEnd )
				)
				( attribute "VALUE" "0.22UF"
					( Origin gFrontEnd )
				)
				( attribute "VER" "1"
					( Origin gFrontEnd )
				)
				( attribute "VOLTAGE" "16V"
					( Units "uVoltage" "V" 1.000000)
					( Origin gFrontEnd )
				)
				( attribute "XY" "(-6250,1350)"
					( Origin gFrontEnd )
				)
				( attribute "CHIPS_PART_NAME" "CAP"
					( Origin gPackager )
				)
				( attribute "CDS_PART_NAME" "CAP_0402-0.22UF,16V,10%,X7R,A3A"
					( Origin gPackager )
				)
				( objectStatus "C1M15" )
			)
			( gate "@baseboard_fab2_lib.baseboard_fab2(sch_1):page106_i100"
				( attribute "BOM_COST" "IO_SLOT"
					( Origin gFrontEnd )
				)
				( attribute "CDS_LIB" "mstr_discrete"
					( Origin gPackager )
				)
				( attribute "CDS_LOCATION" "C1M12"
					( Origin gPackager )
				)
				( attribute "CDS_SEC" "1"
					( Origin gPackager )
				)
				( attribute "LOCATION" "C1M12"
					( Origin gFrontEnd )
				)
				( attribute "MATERIAL" "X7R"
					( Origin gFrontEnd )
				)
				( attribute "PACK_TYPE" "0402"
					( Origin gFrontEnd )
				)
				( attribute "PART_NUMBER" "A36096-155"
					( Origin gFrontEnd )
				)
				( attribute "PHYS_PAGE" "106"
					( Origin gFrontEnd )
				)
				( attribute "ROOM" "PCIE_STEERING"
					( Origin gFrontEnd )
				)
				( attribute "ROT" "2"
					( Origin gFrontEnd )
				)
				( attribute "SEC" "1"
					( Origin gPackager )
				)
				( attribute "TOLERANCE" "10%"
					( Origin gFrontEnd )
				)
				( attribute "VALUE" "0.22UF"
					( Origin gFrontEnd )
				)
				( attribute "VER" "1"
					( Origin gFrontEnd )
				)
				( attribute "VOLTAGE" "16V"
					( Units "uVoltage" "V" 1.000000)
					( Origin gFrontEnd )
				)
				( attribute "XY" "(-6500,2650)"
					( Origin gFrontEnd )
				)
				( attribute "CHIPS_PART_NAME" "CAP"
					( Origin gPackager )
				)
				( attribute "CDS_PART_NAME" "CAP_0402-0.22UF,16V,10%,X7R,A3A"
					( Origin gPackager )
				)
				( objectStatus "C1M12" )
			)
			( gate "@baseboard_fab2_lib.baseboard_fab2(sch_1):page106_i102"
				( attribute "BOM_COST" "IO_SLOT"
					( Origin gFrontEnd )
				)
				( attribute "CDS_LIB" "mstr_discrete"
					( Origin gPackager )
				)
				( attribute "CDS_LOCATION" "C1M10"
					( Origin gPackager )
				)
				( attribute "CDS_SEC" "1"
					( Origin gPackager )
				)
				( attribute "LOCATION" "C1M10"
					( Origin gFrontEnd )
				)
				( attribute "MATERIAL" "X7R"
					( Origin gFrontEnd )
				)
				( attribute "PACK_TYPE" "0402"
					( Origin gFrontEnd )
				)
				( attribute "PART_NUMBER" "A36096-155"
					( Origin gFrontEnd )
				)
				( attribute "PHYS_PAGE" "106"
					( Origin gFrontEnd )
				)
				( attribute "ROOM" "PCIE_STEERING"
					( Origin gFrontEnd )
				)
				( attribute "ROT" "2"
					( Origin gFrontEnd )
				)
				( attribute "SEC" "1"
					( Origin gPackager )
				)
				( attribute "TOLERANCE" "10%"
					( Origin gFrontEnd )
				)
				( attribute "VALUE" "0.22UF"
					( Origin gFrontEnd )
				)
				( attribute "VER" "1"
					( Origin gFrontEnd )
				)
				( attribute "VOLTAGE" "16V"
					( Units "uVoltage" "V" 1.000000)
					( Origin gFrontEnd )
				)
				( attribute "XY" "(-6700,2350)"
					( Origin gFrontEnd )
				)
				( attribute "CHIPS_PART_NAME" "CAP"
					( Origin gPackager )
				)
				( attribute "CDS_PART_NAME" "CAP_0402-0.22UF,16V,10%,X7R,A3A"
					( Origin gPackager )
				)
				( objectStatus "C1M10" )
			)
			( gate "@baseboard_fab2_lib.baseboard_fab2(sch_1):page106_i105"
				( attribute "CDS_LIB" "mstr_discrete"
					( Origin gPackager )
				)
				( attribute "CDS_LOCATION" "C1M8"
					( Origin gPackager )
				)
				( attribute "CDS_SEC" "1"
					( Origin gPackager )
				)
				( attribute "LOCATION" "C1M8"
					( Origin gFrontEnd )
				)
				( attribute "MATERIAL" "X7R"
					( Origin gFrontEnd )
				)
				( attribute "PACK_TYPE" "0402"
					( Origin gFrontEnd )
				)
				( attribute "PART_NUMBER" "A36096-155"
					( Origin gFrontEnd )
				)
				( attribute "PHYS_PAGE" "106"
					( Origin gFrontEnd )
				)
				( attribute "ROOM" "PCIE_STEERING"
					( Origin gFrontEnd )
				)
				( attribute "ROT" "2"
					( Origin gFrontEnd )
				)
				( attribute "SEC" "1"
					( Origin gPackager )
				)
				( attribute "TOLERANCE" "10%"
					( Origin gFrontEnd )
				)
				( attribute "VALUE" "0.22UF"
					( Origin gFrontEnd )
				)
				( attribute "VER" "1"
					( Origin gFrontEnd )
				)
				( attribute "VOLTAGE" "16V"
					( Units "uVoltage" "V" 1.000000)
					( Origin gFrontEnd )
				)
				( attribute "XY" "(-6900,2650)"
					( Origin gFrontEnd )
				)
				( attribute "CHIPS_PART_NAME" "CAP"
					( Origin gPackager )
				)
				( attribute "CDS_PART_NAME" "CAP_0402-0.22UF,16V,10%,X7R,A3A"
					( Origin gPackager )
				)
				( objectStatus "C1M8" )
			)
			( gate "@baseboard_fab2_lib.baseboard_fab2(sch_1):page106_i109"
				( attribute "CDS_LIB" "mstr_discrete"
					( Origin gPackager )
				)
				( attribute "CDS_LOCATION" "C1M6"
					( Origin gPackager )
				)
				( attribute "CDS_SEC" "1"
					( Origin gPackager )
				)
				( attribute "LOCATION" "C1M6"
					( Origin gFrontEnd )
				)
				( attribute "MATERIAL" "X7R"
					( Origin gFrontEnd )
				)
				( attribute "PACK_TYPE" "0402"
					( Origin gFrontEnd )
				)
				( attribute "PART_NUMBER" "A36096-155"
					( Origin gFrontEnd )
				)
				( attribute "PHYS_PAGE" "106"
					( Origin gFrontEnd )
				)
				( attribute "ROOM" "PCIE_STEERING"
					( Origin gFrontEnd )
				)
				( attribute "ROT" "2"
					( Origin gFrontEnd )
				)
				( attribute "SEC" "1"
					( Origin gPackager )
				)
				( attribute "TOLERANCE" "10%"
					( Origin gFrontEnd )
				)
				( attribute "VALUE" "0.22UF"
					( Origin gFrontEnd )
				)
				( attribute "VER" "1"
					( Origin gFrontEnd )
				)
				( attribute "VOLTAGE" "16V"
					( Units "uVoltage" "V" 1.000000)
					( Origin gFrontEnd )
				)
				( attribute "XY" "(-7100,2350)"
					( Origin gFrontEnd )
				)
				( attribute "CHIPS_PART_NAME" "CAP"
					( Origin gPackager )
				)
				( attribute "CDS_PART_NAME" "CAP_0402-0.22UF,16V,10%,X7R,A3A"
					( Origin gPackager )
				)
				( objectStatus "C1M6" )
			)
			( gate "@baseboard_fab2_lib.baseboard_fab2(sch_1):page106_i111"
				( attribute "BOM_COST" "IO_SLOT"
					( Origin gFrontEnd )
				)
				( attribute "CDS_LIB" "mstr_discrete"
					( Origin gPackager )
				)
				( attribute "CDS_LOCATION" "C1M13"
					( Origin gPackager )
				)
				( attribute "CDS_SEC" "1"
					( Origin gPackager )
				)
				( attribute "LOCATION" "C1M13"
					( Origin gFrontEnd )
				)
				( attribute "MATERIAL" "X7R"
					( Origin gFrontEnd )
				)
				( attribute "PACK_TYPE" "0402"
					( Origin gFrontEnd )
				)
				( attribute "PART_NUMBER" "A36096-155"
					( Origin gFrontEnd )
				)
				( attribute "PHYS_PAGE" "106"
					( Origin gFrontEnd )
				)
				( attribute "ROOM" "PCIE_STEERING"
					( Origin gFrontEnd )
				)
				( attribute "ROT" "2"
					( Origin gFrontEnd )
				)
				( attribute "SEC" "1"
					( Origin gPackager )
				)
				( attribute "TOLERANCE" "10%"
					( Origin gFrontEnd )
				)
				( attribute "VALUE" "0.22UF"
					( Origin gFrontEnd )
				)
				( attribute "VER" "1"
					( Origin gFrontEnd )
				)
				( attribute "VOLTAGE" "16V"
					( Units "uVoltage" "V" 1.000000)
					( Origin gFrontEnd )
				)
				( attribute "XY" "(-6450,1650)"
					( Origin gFrontEnd )
				)
				( attribute "CHIPS_PART_NAME" "CAP"
					( Origin gPackager )
				)
				( attribute "CDS_PART_NAME" "CAP_0402-0.22UF,16V,10%,X7R,A3A"
					( Origin gPackager )
				)
				( objectStatus "C1M13" )
			)
			( gate "@baseboard_fab2_lib.baseboard_fab2(sch_1):page106_i114"
				( attribute "CDS_LIB" "mstr_discrete"
					( Origin gPackager )
				)
				( attribute "CDS_LOCATION" "C1M9"
					( Origin gPackager )
				)
				( attribute "CDS_SEC" "1"
					( Origin gPackager )
				)
				( attribute "LOCATION" "C1M9"
					( Origin gFrontEnd )
				)
				( attribute "MATERIAL" "X7R"
					( Origin gFrontEnd )
				)
				( attribute "PACK_TYPE" "0402"
					( Origin gFrontEnd )
				)
				( attribute "PART_NUMBER" "A36096-155"
					( Origin gFrontEnd )
				)
				( attribute "PHYS_PAGE" "106"
					( Origin gFrontEnd )
				)
				( attribute "ROOM" "PCIE_STEERING"
					( Origin gFrontEnd )
				)
				( attribute "ROT" "2"
					( Origin gFrontEnd )
				)
				( attribute "SEC" "1"
					( Origin gPackager )
				)
				( attribute "TOLERANCE" "10%"
					( Origin gFrontEnd )
				)
				( attribute "VALUE" "0.22UF"
					( Origin gFrontEnd )
				)
				( attribute "VER" "1"
					( Origin gFrontEnd )
				)
				( attribute "VOLTAGE" "16V"
					( Units "uVoltage" "V" 1.000000)
					( Origin gFrontEnd )
				)
				( attribute "XY" "(-6850,1650)"
					( Origin gFrontEnd )
				)
				( attribute "CHIPS_PART_NAME" "CAP"
					( Origin gPackager )
				)
				( attribute "CDS_PART_NAME" "CAP_0402-0.22UF,16V,10%,X7R,A3A"
					( Origin gPackager )
				)
				( objectStatus "C1M9" )
			)
			( gate "@baseboard_fab2_lib.baseboard_fab2(sch_1):page106_i117"
				( attribute "BOM_COST" "IO_SLOT"
					( Origin gFrontEnd )
				)
				( attribute "CDS_LIB" "mstr_discrete"
					( Origin gPackager )
				)
				( attribute "CDS_LOCATION" "C1M11"
					( Origin gPackager )
				)
				( attribute "CDS_SEC" "1"
					( Origin gPackager )
				)
				( attribute "LOCATION" "C1M11"
					( Origin gFrontEnd )
				)
				( attribute "MATERIAL" "X7R"
					( Origin gFrontEnd )
				)
				( attribute "PACK_TYPE" "0402"
					( Origin gFrontEnd )
				)
				( attribute "PART_NUMBER" "A36096-155"
					( Origin gFrontEnd )
				)
				( attribute "PHYS_PAGE" "106"
					( Origin gFrontEnd )
				)
				( attribute "ROOM" "PCIE_STEERING"
					( Origin gFrontEnd )
				)
				( attribute "ROT" "2"
					( Origin gFrontEnd )
				)
				( attribute "SEC" "1"
					( Origin gPackager )
				)
				( attribute "TOLERANCE" "10%"
					( Origin gFrontEnd )
				)
				( attribute "VALUE" "0.22UF"
					( Origin gFrontEnd )
				)
				( attribute "VER" "1"
					( Origin gFrontEnd )
				)
				( attribute "VOLTAGE" "16V"
					( Units "uVoltage" "V" 1.000000)
					( Origin gFrontEnd )
				)
				( attribute "XY" "(-6650,1350)"
					( Origin gFrontEnd )
				)
				( attribute "CHIPS_PART_NAME" "CAP"
					( Origin gPackager )
				)
				( attribute "CDS_PART_NAME" "CAP_0402-0.22UF,16V,10%,X7R,A3A"
					( Origin gPackager )
				)
				( objectStatus "C1M11" )
			)
			( gate "@baseboard_fab2_lib.baseboard_fab2(sch_1):page106_i122"
				( attribute "CDS_LIB" "mstr_discrete"
					( Origin gPackager )
				)
				( attribute "CDS_LOCATION" "C1M7"
					( Origin gPackager )
				)
				( attribute "CDS_SEC" "1"
					( Origin gPackager )
				)
				( attribute "LOCATION" "C1M7"
					( Origin gFrontEnd )
				)
				( attribute "MATERIAL" "X7R"
					( Origin gFrontEnd )
				)
				( attribute "PACK_TYPE" "0402"
					( Origin gFrontEnd )
				)
				( attribute "PART_NUMBER" "A36096-155"
					( Origin gFrontEnd )
				)
				( attribute "PHYS_PAGE" "106"
					( Origin gFrontEnd )
				)
				( attribute "ROOM" "PCIE_STEERING"
					( Origin gFrontEnd )
				)
				( attribute "ROT" "2"
					( Origin gFrontEnd )
				)
				( attribute "SEC" "1"
					( Origin gPackager )
				)
				( attribute "TOLERANCE" "10%"
					( Origin gFrontEnd )
				)
				( attribute "VALUE" "0.22UF"
					( Origin gFrontEnd )
				)
				( attribute "VER" "1"
					( Origin gFrontEnd )
				)
				( attribute "VOLTAGE" "16V"
					( Units "uVoltage" "V" 1.000000)
					( Origin gFrontEnd )
				)
				( attribute "XY" "(-7050,1350)"
					( Origin gFrontEnd )
				)
				( attribute "CHIPS_PART_NAME" "CAP"
					( Origin gPackager )
				)
				( attribute "CDS_PART_NAME" "CAP_0402-0.22UF,16V,10%,X7R,A3A"
					( Origin gPackager )
				)
				( objectStatus "C1M7" )
			)
			( gate "@baseboard_fab2_lib.baseboard_fab2(sch_1):page106_i123"
				( attribute "BOM_COST" "IO_SLOT"
					( Origin gFrontEnd )
				)
				( attribute "CDS_LIB" "mstr_discrete"
					( Origin gPackager )
				)
				( attribute "CDS_LOCATION" "C2R7"
					( Origin gPackager )
				)
				( attribute "CDS_SEC" "1"
					( Origin gPackager )
				)
				( attribute "LOCATION" "C2R7"
					( Origin gFrontEnd )
				)
				( attribute "MATERIAL" "X7R"
					( Origin gFrontEnd )
				)
				( attribute "PACK_TYPE" "0402"
					( Origin gFrontEnd )
				)
				( attribute "PART_NUMBER" "A36096-155"
					( Origin gFrontEnd )
				)
				( attribute "PHYS_PAGE" "106"
					( Origin gFrontEnd )
				)
				( attribute "ROOM" "PCIE_STEERING"
					( Origin gFrontEnd )
				)
				( attribute "ROT" "2"
					( Origin gFrontEnd )
				)
				( attribute "SEC" "1"
					( Origin gPackager )
				)
				( attribute "TOLERANCE" "10%"
					( Origin gFrontEnd )
				)
				( attribute "VALUE" "0.22UF"
					( Origin gFrontEnd )
				)
				( attribute "VER" "1"
					( Origin gFrontEnd )
				)
				( attribute "VOLTAGE" "16V"
					( Units "uVoltage" "V" 1.000000)
					( Origin gFrontEnd )
				)
				( attribute "XY" "(-5275,1650)"
					( Origin gFrontEnd )
				)
				( attribute "CHIPS_PART_NAME" "CAP"
					( Origin gPackager )
				)
				( attribute "CDS_PART_NAME" "CAP_0402-0.22UF,16V,10%,X7R,A3A"
					( Origin gPackager )
				)
				( objectStatus "C2R7" )
			)
			( gate "@baseboard_fab2_lib.baseboard_fab2(sch_1):page106_i128"
				( attribute "BOM_COST" "IO_SLOT"
					( Origin gFrontEnd )
				)
				( attribute "CDS_LIB" "mstr_discrete"
					( Origin gPackager )
				)
				( attribute "CDS_LOCATION" "C1R10"
					( Origin gPackager )
				)
				( attribute "CDS_SEC" "1"
					( Origin gPackager )
				)
				( attribute "LOCATION" "C1R10"
					( Origin gFrontEnd )
				)
				( attribute "MATERIAL" "X7R"
					( Origin gFrontEnd )
				)
				( attribute "PACK_TYPE" "0402"
					( Origin gFrontEnd )
				)
				( attribute "PART_NUMBER" "A36096-155"
					( Origin gFrontEnd )
				)
				( attribute "PHYS_PAGE" "106"
					( Origin gFrontEnd )
				)
				( attribute "ROOM" "PCIE_STEERING"
					( Origin gFrontEnd )
				)
				( attribute "ROT" "2"
					( Origin gFrontEnd )
				)
				( attribute "SEC" "1"
					( Origin gPackager )
				)
				( attribute "TOLERANCE" "10%"
					( Origin gFrontEnd )
				)
				( attribute "VALUE" "0.22UF"
					( Origin gFrontEnd )
				)
				( attribute "VER" "1"
					( Origin gFrontEnd )
				)
				( attribute "VOLTAGE" "16V"
					( Units "uVoltage" "V" 1.000000)
					( Origin gFrontEnd )
				)
				( attribute "XY" "(-4900,2650)"
					( Origin gFrontEnd )
				)
				( attribute "CHIPS_PART_NAME" "CAP"
					( Origin gPackager )
				)
				( attribute "CDS_PART_NAME" "CAP_0402-0.22UF,16V,10%,X7R,A3A"
					( Origin gPackager )
				)
				( objectStatus "C1R10" )
			)
			( gate "@baseboard_fab2_lib.baseboard_fab2(sch_1):page106_i130"
				( attribute "BOM_COST" "IO_SLOT"
					( Origin gFrontEnd )
				)
				( attribute "CDS_LIB" "mstr_discrete"
					( Origin gPackager )
				)
				( attribute "CDS_LOCATION" "C2R14"
					( Origin gPackager )
				)
				( attribute "CDS_SEC" "1"
					( Origin gPackager )
				)
				( attribute "LOCATION" "C2R14"
					( Origin gFrontEnd )
				)
				( attribute "MATERIAL" "X7R"
					( Origin gFrontEnd )
				)
				( attribute "PACK_TYPE" "0402"
					( Origin gFrontEnd )
				)
				( attribute "PART_NUMBER" "A36096-155"
					( Origin gFrontEnd )
				)
				( attribute "PHYS_PAGE" "106"
					( Origin gFrontEnd )
				)
				( attribute "ROOM" "PCIE_STEERING"
					( Origin gFrontEnd )
				)
				( attribute "ROT" "2"
					( Origin gFrontEnd )
				)
				( attribute "SEC" "1"
					( Origin gPackager )
				)
				( attribute "TOLERANCE" "10%"
					( Origin gFrontEnd )
				)
				( attribute "VALUE" "0.22UF"
					( Origin gFrontEnd )
				)
				( attribute "VER" "1"
					( Origin gFrontEnd )
				)
				( attribute "VOLTAGE" "16V"
					( Units "uVoltage" "V" 1.000000)
					( Origin gFrontEnd )
				)
				( attribute "XY" "(-5100,2350)"
					( Origin gFrontEnd )
				)
				( attribute "CHIPS_PART_NAME" "CAP"
					( Origin gPackager )
				)
				( attribute "CDS_PART_NAME" "CAP_0402-0.22UF,16V,10%,X7R,A3A"
					( Origin gPackager )
				)
				( objectStatus "C2R14" )
			)
			( gate "@baseboard_fab2_lib.baseboard_fab2(sch_1):page106_i134"
				( attribute "BOM_COST" "IO_SLOT"
					( Origin gFrontEnd )
				)
				( attribute "CDS_LIB" "mstr_discrete"
					( Origin gPackager )
				)
				( attribute "CDS_LOCATION" "C1R9"
					( Origin gPackager )
				)
				( attribute "CDS_SEC" "1"
					( Origin gPackager )
				)
				( attribute "LOCATION" "C1R9"
					( Origin gFrontEnd )
				)
				( attribute "MATERIAL" "X7R"
					( Origin gFrontEnd )
				)
				( attribute "PACK_TYPE" "0402"
					( Origin gFrontEnd )
				)
				( attribute "PART_NUMBER" "A36096-155"
					( Origin gFrontEnd )
				)
				( attribute "PHYS_PAGE" "106"
					( Origin gFrontEnd )
				)
				( attribute "ROOM" "PCIE_STEERING"
					( Origin gFrontEnd )
				)
				( attribute "ROT" "2"
					( Origin gFrontEnd )
				)
				( attribute "SEC" "1"
					( Origin gPackager )
				)
				( attribute "TOLERANCE" "10%"
					( Origin gFrontEnd )
				)
				( attribute "VALUE" "0.22UF"
					( Origin gFrontEnd )
				)
				( attribute "VER" "1"
					( Origin gFrontEnd )
				)
				( attribute "VOLTAGE" "16V"
					( Units "uVoltage" "V" 1.000000)
					( Origin gFrontEnd )
				)
				( attribute "XY" "(-4875,1650)"
					( Origin gFrontEnd )
				)
				( attribute "CHIPS_PART_NAME" "CAP"
					( Origin gPackager )
				)
				( attribute "CDS_PART_NAME" "CAP_0402-0.22UF,16V,10%,X7R,A3A"
					( Origin gPackager )
				)
				( objectStatus "C1R9" )
			)
			( gate "@baseboard_fab2_lib.baseboard_fab2(sch_1):page106_i137"
				( attribute "BOM_COST" "IO_SLOT"
					( Origin gFrontEnd )
				)
				( attribute "CDS_LIB" "mstr_discrete"
					( Origin gPackager )
				)
				( attribute "CDS_LOCATION" "C2R13"
					( Origin gPackager )
				)
				( attribute "CDS_SEC" "1"
					( Origin gPackager )
				)
				( attribute "LOCATION" "C2R13"
					( Origin gFrontEnd )
				)
				( attribute "MATERIAL" "X7R"
					( Origin gFrontEnd )
				)
				( attribute "PACK_TYPE" "0402"
					( Origin gFrontEnd )
				)
				( attribute "PART_NUMBER" "A36096-155"
					( Origin gFrontEnd )
				)
				( attribute "PHYS_PAGE" "106"
					( Origin gFrontEnd )
				)
				( attribute "ROOM" "PCIE_STEERING"
					( Origin gFrontEnd )
				)
				( attribute "ROT" "2"
					( Origin gFrontEnd )
				)
				( attribute "SEC" "1"
					( Origin gPackager )
				)
				( attribute "TOLERANCE" "10%"
					( Origin gFrontEnd )
				)
				( attribute "VALUE" "0.22UF"
					( Origin gFrontEnd )
				)
				( attribute "VER" "1"
					( Origin gFrontEnd )
				)
				( attribute "VOLTAGE" "16V"
					( Units "uVoltage" "V" 1.000000)
					( Origin gFrontEnd )
				)
				( attribute "XY" "(-5075,1350)"
					( Origin gFrontEnd )
				)
				( attribute "CHIPS_PART_NAME" "CAP"
					( Origin gPackager )
				)
				( attribute "CDS_PART_NAME" "CAP_0402-0.22UF,16V,10%,X7R,A3A"
					( Origin gPackager )
				)
				( objectStatus "C2R13" )
			)
			( gate "@baseboard_fab2_lib.baseboard_fab2(sch_1):page106_i141"
				( attribute "BOM_COST" "IO_SLOT"
					( Origin gFrontEnd )
				)
				( attribute "CDS_LIB" "mstr_discrete"
					( Origin gPackager )
				)
				( attribute "CDS_LOCATION" "C2R8"
					( Origin gPackager )
				)
				( attribute "CDS_SEC" "1"
					( Origin gPackager )
				)
				( attribute "LOCATION" "C2R8"
					( Origin gFrontEnd )
				)
				( attribute "MATERIAL" "X7R"
					( Origin gFrontEnd )
				)
				( attribute "PACK_TYPE" "0402"
					( Origin gFrontEnd )
				)
				( attribute "PART_NUMBER" "A36096-155"
					( Origin gFrontEnd )
				)
				( attribute "PHYS_PAGE" "106"
					( Origin gFrontEnd )
				)
				( attribute "ROOM" "PCIE_STEERING"
					( Origin gFrontEnd )
				)
				( attribute "ROT" "2"
					( Origin gFrontEnd )
				)
				( attribute "SEC" "1"
					( Origin gPackager )
				)
				( attribute "TOLERANCE" "10%"
					( Origin gFrontEnd )
				)
				( attribute "VALUE" "0.22UF"
					( Origin gFrontEnd )
				)
				( attribute "VER" "1"
					( Origin gFrontEnd )
				)
				( attribute "VOLTAGE" "16V"
					( Units "uVoltage" "V" 1.000000)
					( Origin gFrontEnd )
				)
				( attribute "XY" "(-5300,2650)"
					( Origin gFrontEnd )
				)
				( attribute "CHIPS_PART_NAME" "CAP"
					( Origin gPackager )
				)
				( attribute "CDS_PART_NAME" "CAP_0402-0.22UF,16V,10%,X7R,A3A"
					( Origin gPackager )
				)
				( objectStatus "C2R8" )
			)
			( gate "@baseboard_fab2_lib.baseboard_fab2(sch_1):page106_i142"
				( attribute "BOM_COST" "IO_SLOT"
					( Origin gFrontEnd )
				)
				( attribute "CDS_LIB" "mstr_discrete"
					( Origin gPackager )
				)
				( attribute "CDS_LOCATION" "C2R10"
					( Origin gPackager )
				)
				( attribute "CDS_SEC" "1"
					( Origin gPackager )
				)
				( attribute "LOCATION" "C2R10"
					( Origin gFrontEnd )
				)
				( attribute "MATERIAL" "X7R"
					( Origin gFrontEnd )
				)
				( attribute "PACK_TYPE" "0402"
					( Origin gFrontEnd )
				)
				( attribute "PART_NUMBER" "A36096-155"
					( Origin gFrontEnd )
				)
				( attribute "PHYS_PAGE" "106"
					( Origin gFrontEnd )
				)
				( attribute "ROOM" "PCIE_STEERING"
					( Origin gFrontEnd )
				)
				( attribute "ROT" "2"
					( Origin gFrontEnd )
				)
				( attribute "SEC" "1"
					( Origin gPackager )
				)
				( attribute "TOLERANCE" "10%"
					( Origin gFrontEnd )
				)
				( attribute "VALUE" "0.22UF"
					( Origin gFrontEnd )
				)
				( attribute "VER" "1"
					( Origin gFrontEnd )
				)
				( attribute "VOLTAGE" "16V"
					( Units "uVoltage" "V" 1.000000)
					( Origin gFrontEnd )
				)
				( attribute "XY" "(-5500,2350)"
					( Origin gFrontEnd )
				)
				( attribute "CHIPS_PART_NAME" "CAP"
					( Origin gPackager )
				)
				( attribute "CDS_PART_NAME" "CAP_0402-0.22UF,16V,10%,X7R,A3A"
					( Origin gPackager )
				)
				( objectStatus "C2R10" )
			)
			( gate "@baseboard_fab2_lib.baseboard_fab2(sch_1):page106_i147"
				( attribute "BOM_COST" "IO_SLOT"
					( Origin gFrontEnd )
				)
				( attribute "CDS_LIB" "mstr_discrete"
					( Origin gPackager )
				)
				( attribute "CDS_LOCATION" "C2R9"
					( Origin gPackager )
				)
				( attribute "CDS_SEC" "1"
					( Origin gPackager )
				)
				( attribute "LOCATION" "C2R9"
					( Origin gFrontEnd )
				)
				( attribute "MATERIAL" "X7R"
					( Origin gFrontEnd )
				)
				( attribute "PACK_TYPE" "0402"
					( Origin gFrontEnd )
				)
				( attribute "PART_NUMBER" "A36096-155"
					( Origin gFrontEnd )
				)
				( attribute "PHYS_PAGE" "106"
					( Origin gFrontEnd )
				)
				( attribute "ROOM" "PCIE_STEERING"
					( Origin gFrontEnd )
				)
				( attribute "ROT" "2"
					( Origin gFrontEnd )
				)
				( attribute "SEC" "1"
					( Origin gPackager )
				)
				( attribute "TOLERANCE" "10%"
					( Origin gFrontEnd )
				)
				( attribute "VALUE" "0.22UF"
					( Origin gFrontEnd )
				)
				( attribute "VER" "1"
					( Origin gFrontEnd )
				)
				( attribute "VOLTAGE" "16V"
					( Units "uVoltage" "V" 1.000000)
					( Origin gFrontEnd )
				)
				( attribute "XY" "(-5475,1350)"
					( Origin gFrontEnd )
				)
				( attribute "CHIPS_PART_NAME" "CAP"
					( Origin gPackager )
				)
				( attribute "CDS_PART_NAME" "CAP_0402-0.22UF,16V,10%,X7R,A3A"
					( Origin gPackager )
				)
				( objectStatus "C2R9" )
			)
			( gate "@baseboard_fab2_lib.baseboard_fab2(sch_1):page107_i207"
				( attribute "CDS_LIB" "mstr_discrete"
					( Origin gPackager )
				)
				( attribute "CDS_LOCATION" "C3P13"
					( Origin gPackager )
				)
				( attribute "CDS_SEC" "1"
					( Origin gPackager )
				)
				( attribute "LOCATION" "C3P13"
					( Origin gFrontEnd )
				)
				( attribute "MATERIAL" "X7R"
					( Origin gFrontEnd )
				)
				( attribute "PACK_TYPE" "0402"
					( Origin gFrontEnd )
				)
				( attribute "PART_NUMBER" "A36096-155"
					( Origin gFrontEnd )
				)
				( attribute "PHYS_PAGE" "107"
					( Origin gFrontEnd )
				)
				( attribute "ROT" "2"
					( Origin gFrontEnd )
				)
				( attribute "SEC" "1"
					( Origin gPackager )
				)
				( attribute "TOLERANCE" "10%"
					( Origin gFrontEnd )
				)
				( attribute "VALUE" "0.22UF"
					( Origin gFrontEnd )
				)
				( attribute "VER" "1"
					( Origin gFrontEnd )
				)
				( attribute "VOLTAGE" "16V"
					( Units "uVoltage" "V" 1.000000)
					( Origin gFrontEnd )
				)
				( attribute "XY" "(-5525,1875)"
					( Origin gFrontEnd )
				)
				( attribute "CHIPS_PART_NAME" "CAP"
					( Origin gPackager )
				)
				( attribute "CDS_PART_NAME" "CAP_0402-0.22UF,16V,10%,X7R,A3A"
					( Origin gPackager )
				)
				( attribute "GROUP" "PCIE_UPLINK"
					( Origin gFrontEnd )
				)
				( objectStatus "C3P13" )
			)
			( gate "@baseboard_fab2_lib.baseboard_fab2(sch_1):page107_i208"
				( attribute "CDS_LIB" "mstr_discrete"
					( Origin gPackager )
				)
				( attribute "CDS_LOCATION" "C3P17"
					( Origin gPackager )
				)
				( attribute "CDS_SEC" "1"
					( Origin gPackager )
				)
				( attribute "LOCATION" "C3P17"
					( Origin gFrontEnd )
				)
				( attribute "MATERIAL" "X7R"
					( Origin gFrontEnd )
				)
				( attribute "PACK_TYPE" "0402"
					( Origin gFrontEnd )
				)
				( attribute "PART_NUMBER" "A36096-155"
					( Origin gFrontEnd )
				)
				( attribute "PHYS_PAGE" "107"
					( Origin gFrontEnd )
				)
				( attribute "ROT" "2"
					( Origin gFrontEnd )
				)
				( attribute "SEC" "1"
					( Origin gPackager )
				)
				( attribute "TOLERANCE" "10%"
					( Origin gFrontEnd )
				)
				( attribute "VALUE" "0.22UF"
					( Origin gFrontEnd )
				)
				( attribute "VER" "1"
					( Origin gFrontEnd )
				)
				( attribute "VOLTAGE" "16V"
					( Units "uVoltage" "V" 1.000000)
					( Origin gFrontEnd )
				)
				( attribute "XY" "(-5725,1575)"
					( Origin gFrontEnd )
				)
				( attribute "CHIPS_PART_NAME" "CAP"
					( Origin gPackager )
				)
				( attribute "CDS_PART_NAME" "CAP_0402-0.22UF,16V,10%,X7R,A3A"
					( Origin gPackager )
				)
				( attribute "GROUP" "PCIE_UPLINK"
					( Origin gFrontEnd )
				)
				( objectStatus "C3P17" )
			)
			( gate "@baseboard_fab2_lib.baseboard_fab2(sch_1):page107_i212"
				( attribute "CDS_LIB" "mstr_discrete"
					( Origin gPackager )
				)
				( attribute "CDS_LOCATION" "C3P11"
					( Origin gPackager )
				)
				( attribute "CDS_SEC" "1"
					( Origin gPackager )
				)
				( attribute "LOCATION" "C3P11"
					( Origin gFrontEnd )
				)
				( attribute "MATERIAL" "X7R"
					( Origin gFrontEnd )
				)
				( attribute "PACK_TYPE" "0402"
					( Origin gFrontEnd )
				)
				( attribute "PART_NUMBER" "A36096-155"
					( Origin gFrontEnd )
				)
				( attribute "PHYS_PAGE" "107"
					( Origin gFrontEnd )
				)
				( attribute "ROT" "2"
					( Origin gFrontEnd )
				)
				( attribute "SEC" "1"
					( Origin gPackager )
				)
				( attribute "TOLERANCE" "10%"
					( Origin gFrontEnd )
				)
				( attribute "VALUE" "0.22UF"
					( Origin gFrontEnd )
				)
				( attribute "VER" "1"
					( Origin gFrontEnd )
				)
				( attribute "VOLTAGE" "16V"
					( Units "uVoltage" "V" 1.000000)
					( Origin gFrontEnd )
				)
				( attribute "XY" "(-5475,875)"
					( Origin gFrontEnd )
				)
				( attribute "CHIPS_PART_NAME" "CAP"
					( Origin gPackager )
				)
				( attribute "CDS_PART_NAME" "CAP_0402-0.22UF,16V,10%,X7R,A3A"
					( Origin gPackager )
				)
				( attribute "GROUP" "PCIE_UPLINK"
					( Origin gFrontEnd )
				)
				( objectStatus "C3P11" )
			)
			( gate "@baseboard_fab2_lib.baseboard_fab2(sch_1):page107_i215"
				( attribute "CDS_LIB" "mstr_discrete"
					( Origin gPackager )
				)
				( attribute "CDS_LOCATION" "C3P20"
					( Origin gPackager )
				)
				( attribute "CDS_SEC" "1"
					( Origin gPackager )
				)
				( attribute "LOCATION" "C3P20"
					( Origin gFrontEnd )
				)
				( attribute "MATERIAL" "X7R"
					( Origin gFrontEnd )
				)
				( attribute "PACK_TYPE" "0402"
					( Origin gFrontEnd )
				)
				( attribute "PART_NUMBER" "A36096-155"
					( Origin gFrontEnd )
				)
				( attribute "PHYS_PAGE" "107"
					( Origin gFrontEnd )
				)
				( attribute "ROT" "2"
					( Origin gFrontEnd )
				)
				( attribute "SEC" "1"
					( Origin gPackager )
				)
				( attribute "TOLERANCE" "10%"
					( Origin gFrontEnd )
				)
				( attribute "VALUE" "0.22UF"
					( Origin gFrontEnd )
				)
				( attribute "VER" "1"
					( Origin gFrontEnd )
				)
				( attribute "VOLTAGE" "16V"
					( Units "uVoltage" "V" 1.000000)
					( Origin gFrontEnd )
				)
				( attribute "XY" "(-5925,1900)"
					( Origin gFrontEnd )
				)
				( attribute "CHIPS_PART_NAME" "CAP"
					( Origin gPackager )
				)
				( attribute "CDS_PART_NAME" "CAP_0402-0.22UF,16V,10%,X7R,A3A"
					( Origin gPackager )
				)
				( attribute "GROUP" "PCIE_UPLINK"
					( Origin gFrontEnd )
				)
				( objectStatus "C3P20" )
			)
			( gate "@baseboard_fab2_lib.baseboard_fab2(sch_1):page107_i216"
				( attribute "CDS_LIB" "mstr_discrete"
					( Origin gPackager )
				)
				( attribute "CDS_LOCATION" "C3P25"
					( Origin gPackager )
				)
				( attribute "CDS_SEC" "1"
					( Origin gPackager )
				)
				( attribute "LOCATION" "C3P25"
					( Origin gFrontEnd )
				)
				( attribute "MATERIAL" "X7R"
					( Origin gFrontEnd )
				)
				( attribute "PACK_TYPE" "0402"
					( Origin gFrontEnd )
				)
				( attribute "PART_NUMBER" "A36096-155"
					( Origin gFrontEnd )
				)
				( attribute "PHYS_PAGE" "107"
					( Origin gFrontEnd )
				)
				( attribute "ROT" "2"
					( Origin gFrontEnd )
				)
				( attribute "SEC" "1"
					( Origin gPackager )
				)
				( attribute "TOLERANCE" "10%"
					( Origin gFrontEnd )
				)
				( attribute "VALUE" "0.22UF"
					( Origin gFrontEnd )
				)
				( attribute "VER" "1"
					( Origin gFrontEnd )
				)
				( attribute "VOLTAGE" "16V"
					( Units "uVoltage" "V" 1.000000)
					( Origin gFrontEnd )
				)
				( attribute "XY" "(-6125,1575)"
					( Origin gFrontEnd )
				)
				( attribute "CHIPS_PART_NAME" "CAP"
					( Origin gPackager )
				)
				( attribute "CDS_PART_NAME" "CAP_0402-0.22UF,16V,10%,X7R,A3A"
					( Origin gPackager )
				)
				( attribute "GROUP" "PCIE_UPLINK"
					( Origin gFrontEnd )
				)
				( objectStatus "C3P25" )
			)
			( gate "@baseboard_fab2_lib.baseboard_fab2(sch_1):page107_i219"
				( attribute "CDS_LIB" "mstr_discrete"
					( Origin gPackager )
				)
				( attribute "CDS_LOCATION" "C3P18"
					( Origin gPackager )
				)
				( attribute "CDS_SEC" "1"
					( Origin gPackager )
				)
				( attribute "LOCATION" "C3P18"
					( Origin gFrontEnd )
				)
				( attribute "MATERIAL" "X7R"
					( Origin gFrontEnd )
				)
				( attribute "PACK_TYPE" "0402"
					( Origin gFrontEnd )
				)
				( attribute "PART_NUMBER" "A36096-155"
					( Origin gFrontEnd )
				)
				( attribute "PHYS_PAGE" "107"
					( Origin gFrontEnd )
				)
				( attribute "ROT" "2"
					( Origin gFrontEnd )
				)
				( attribute "SEC" "1"
					( Origin gPackager )
				)
				( attribute "TOLERANCE" "10%"
					( Origin gFrontEnd )
				)
				( attribute "VALUE" "0.22UF"
					( Origin gFrontEnd )
				)
				( attribute "VER" "1"
					( Origin gFrontEnd )
				)
				( attribute "VOLTAGE" "16V"
					( Units "uVoltage" "V" 1.000000)
					( Origin gFrontEnd )
				)
				( attribute "XY" "(-5875,875)"
					( Origin gFrontEnd )
				)
				( attribute "CHIPS_PART_NAME" "CAP"
					( Origin gPackager )
				)
				( attribute "CDS_PART_NAME" "CAP_0402-0.22UF,16V,10%,X7R,A3A"
					( Origin gPackager )
				)
				( attribute "GROUP" "PCIE_UPLINK"
					( Origin gFrontEnd )
				)
				( objectStatus "C3P18" )
			)
			( gate "@baseboard_fab2_lib.baseboard_fab2(sch_1):page107_i223"
				( attribute "CDS_LIB" "mstr_discrete"
					( Origin gPackager )
				)
				( attribute "CDS_LOCATION" "C3P27"
					( Origin gPackager )
				)
				( attribute "CDS_SEC" "1"
					( Origin gPackager )
				)
				( attribute "LOCATION" "C3P27"
					( Origin gFrontEnd )
				)
				( attribute "MATERIAL" "X7R"
					( Origin gFrontEnd )
				)
				( attribute "PACK_TYPE" "0402"
					( Origin gFrontEnd )
				)
				( attribute "PART_NUMBER" "A36096-155"
					( Origin gFrontEnd )
				)
				( attribute "PHYS_PAGE" "107"
					( Origin gFrontEnd )
				)
				( attribute "ROT" "2"
					( Origin gFrontEnd )
				)
				( attribute "SEC" "1"
					( Origin gPackager )
				)
				( attribute "TOLERANCE" "10%"
					( Origin gFrontEnd )
				)
				( attribute "VALUE" "0.22UF"
					( Origin gFrontEnd )
				)
				( attribute "VER" "1"
					( Origin gFrontEnd )
				)
				( attribute "VOLTAGE" "16V"
					( Units "uVoltage" "V" 1.000000)
					( Origin gFrontEnd )
				)
				( attribute "XY" "(-6275,875)"
					( Origin gFrontEnd )
				)
				( attribute "CHIPS_PART_NAME" "CAP"
					( Origin gPackager )
				)
				( attribute "CDS_PART_NAME" "CAP_0402-0.22UF,16V,10%,X7R,A3A"
					( Origin gPackager )
				)
				( attribute "GROUP" "PCIE_UPLINK"
					( Origin gFrontEnd )
				)
				( objectStatus "C3P27" )
			)
			( gate "@baseboard_fab2_lib.baseboard_fab2(sch_1):page107_i226"
				( attribute "CDS_LIB" "mstr_discrete"
					( Origin gPackager )
				)
				( attribute "CDS_LOCATION" "C3P15"
					( Origin gPackager )
				)
				( attribute "CDS_SEC" "1"
					( Origin gPackager )
				)
				( attribute "LOCATION" "C3P15"
					( Origin gFrontEnd )
				)
				( attribute "MATERIAL" "X7R"
					( Origin gFrontEnd )
				)
				( attribute "PACK_TYPE" "0402"
					( Origin gFrontEnd )
				)
				( attribute "PART_NUMBER" "A36096-155"
					( Origin gFrontEnd )
				)
				( attribute "PHYS_PAGE" "107"
					( Origin gFrontEnd )
				)
				( attribute "ROT" "2"
					( Origin gFrontEnd )
				)
				( attribute "SEC" "1"
					( Origin gPackager )
				)
				( attribute "TOLERANCE" "10%"
					( Origin gFrontEnd )
				)
				( attribute "VALUE" "0.22UF"
					( Origin gFrontEnd )
				)
				( attribute "VER" "1"
					( Origin gFrontEnd )
				)
				( attribute "VOLTAGE" "16V"
					( Units "uVoltage" "V" 1.000000)
					( Origin gFrontEnd )
				)
				( attribute "XY" "(-5675,575)"
					( Origin gFrontEnd )
				)
				( attribute "CHIPS_PART_NAME" "CAP"
					( Origin gPackager )
				)
				( attribute "CDS_PART_NAME" "CAP_0402-0.22UF,16V,10%,X7R,A3A"
					( Origin gPackager )
				)
				( attribute "GROUP" "PCIE_UPLINK"
					( Origin gFrontEnd )
				)
				( objectStatus "C3P15" )
			)
			( gate "@baseboard_fab2_lib.baseboard_fab2(sch_1):page107_i229"
				( attribute "CDS_LIB" "mstr_discrete"
					( Origin gPackager )
				)
				( attribute "CDS_LOCATION" "C3P23"
					( Origin gPackager )
				)
				( attribute "CDS_SEC" "1"
					( Origin gPackager )
				)
				( attribute "LOCATION" "C3P23"
					( Origin gFrontEnd )
				)
				( attribute "MATERIAL" "X7R"
					( Origin gFrontEnd )
				)
				( attribute "PACK_TYPE" "0402"
					( Origin gFrontEnd )
				)
				( attribute "PART_NUMBER" "A36096-155"
					( Origin gFrontEnd )
				)
				( attribute "PHYS_PAGE" "107"
					( Origin gFrontEnd )
				)
				( attribute "ROT" "2"
					( Origin gFrontEnd )
				)
				( attribute "SEC" "1"
					( Origin gPackager )
				)
				( attribute "TOLERANCE" "10%"
					( Origin gFrontEnd )
				)
				( attribute "VALUE" "0.22UF"
					( Origin gFrontEnd )
				)
				( attribute "VER" "1"
					( Origin gFrontEnd )
				)
				( attribute "VOLTAGE" "16V"
					( Units "uVoltage" "V" 1.000000)
					( Origin gFrontEnd )
				)
				( attribute "XY" "(-6075,575)"
					( Origin gFrontEnd )
				)
				( attribute "CHIPS_PART_NAME" "CAP"
					( Origin gPackager )
				)
				( attribute "CDS_PART_NAME" "CAP_0402-0.22UF,16V,10%,X7R,A3A"
					( Origin gPackager )
				)
				( attribute "GROUP" "PCIE_UPLINK"
					( Origin gFrontEnd )
				)
				( objectStatus "C3P23" )
			)
			( gate "@baseboard_fab2_lib.baseboard_fab2(sch_1):page107_i232"
				( attribute "CDS_LIB" "mstr_discrete"
					( Origin gPackager )
				)
				( attribute "CDS_LOCATION" "C3P28"
					( Origin gPackager )
				)
				( attribute "CDS_SEC" "1"
					( Origin gPackager )
				)
				( attribute "LOCATION" "C3P28"
					( Origin gFrontEnd )
				)
				( attribute "MATERIAL" "X7R"
					( Origin gFrontEnd )
				)
				( attribute "PACK_TYPE" "0402"
					( Origin gFrontEnd )
				)
				( attribute "PART_NUMBER" "A36096-155"
					( Origin gFrontEnd )
				)
				( attribute "PHYS_PAGE" "107"
					( Origin gFrontEnd )
				)
				( attribute "ROT" "2"
					( Origin gFrontEnd )
				)
				( attribute "SEC" "1"
					( Origin gPackager )
				)
				( attribute "TOLERANCE" "10%"
					( Origin gFrontEnd )
				)
				( attribute "VALUE" "0.22UF"
					( Origin gFrontEnd )
				)
				( attribute "VER" "1"
					( Origin gFrontEnd )
				)
				( attribute "VOLTAGE" "16V"
					( Units "uVoltage" "V" 1.000000)
					( Origin gFrontEnd )
				)
				( attribute "XY" "(-6325,1875)"
					( Origin gFrontEnd )
				)
				( attribute "CHIPS_PART_NAME" "CAP"
					( Origin gPackager )
				)
				( attribute "CDS_PART_NAME" "CAP_0402-0.22UF,16V,10%,X7R,A3A"
					( Origin gPackager )
				)
				( attribute "GROUP" "PCIE_UPLINK"
					( Origin gFrontEnd )
				)
				( objectStatus "C3P28" )
			)
			( gate "@baseboard_fab2_lib.baseboard_fab2(sch_1):page107_i234"
				( attribute "CDS_LIB" "mstr_discrete"
					( Origin gPackager )
				)
				( attribute "CDS_LOCATION" "C3P32"
					( Origin gPackager )
				)
				( attribute "CDS_SEC" "1"
					( Origin gPackager )
				)
				( attribute "LOCATION" "C3P32"
					( Origin gFrontEnd )
				)
				( attribute "MATERIAL" "X7R"
					( Origin gFrontEnd )
				)
				( attribute "PACK_TYPE" "0402"
					( Origin gFrontEnd )
				)
				( attribute "PART_NUMBER" "A36096-155"
					( Origin gFrontEnd )
				)
				( attribute "PHYS_PAGE" "107"
					( Origin gFrontEnd )
				)
				( attribute "ROT" "2"
					( Origin gFrontEnd )
				)
				( attribute "SEC" "1"
					( Origin gPackager )
				)
				( attribute "TOLERANCE" "10%"
					( Origin gFrontEnd )
				)
				( attribute "VALUE" "0.22UF"
					( Origin gFrontEnd )
				)
				( attribute "VER" "1"
					( Origin gFrontEnd )
				)
				( attribute "VOLTAGE" "16V"
					( Units "uVoltage" "V" 1.000000)
					( Origin gFrontEnd )
				)
				( attribute "XY" "(-6525,1575)"
					( Origin gFrontEnd )
				)
				( attribute "CHIPS_PART_NAME" "CAP"
					( Origin gPackager )
				)
				( attribute "CDS_PART_NAME" "CAP_0402-0.22UF,16V,10%,X7R,A3A"
					( Origin gPackager )
				)
				( attribute "GROUP" "PCIE_UPLINK"
					( Origin gFrontEnd )
				)
				( objectStatus "C3P32" )
			)
			( gate "@baseboard_fab2_lib.baseboard_fab2(sch_1):page107_i235"
				( attribute "CDS_LIB" "mstr_discrete"
					( Origin gPackager )
				)
				( attribute "CDS_LOCATION" "C3P37"
					( Origin gPackager )
				)
				( attribute "CDS_SEC" "1"
					( Origin gPackager )
				)
				( attribute "LOCATION" "C3P37"
					( Origin gFrontEnd )
				)
				( attribute "MATERIAL" "X7R"
					( Origin gFrontEnd )
				)
				( attribute "PACK_TYPE" "0402"
					( Origin gFrontEnd )
				)
				( attribute "PART_NUMBER" "A36096-155"
					( Origin gFrontEnd )
				)
				( attribute "PHYS_PAGE" "107"
					( Origin gFrontEnd )
				)
				( attribute "ROT" "2"
					( Origin gFrontEnd )
				)
				( attribute "SEC" "1"
					( Origin gPackager )
				)
				( attribute "TOLERANCE" "10%"
					( Origin gFrontEnd )
				)
				( attribute "VALUE" "0.22UF"
					( Origin gFrontEnd )
				)
				( attribute "VER" "1"
					( Origin gFrontEnd )
				)
				( attribute "VOLTAGE" "16V"
					( Units "uVoltage" "V" 1.000000)
					( Origin gFrontEnd )
				)
				( attribute "XY" "(-6725,1875)"
					( Origin gFrontEnd )
				)
				( attribute "CHIPS_PART_NAME" "CAP"
					( Origin gPackager )
				)
				( attribute "CDS_PART_NAME" "CAP_0402-0.22UF,16V,10%,X7R,A3A"
					( Origin gPackager )
				)
				( attribute "GROUP" "PCIE_UPLINK"
					( Origin gFrontEnd )
				)
				( objectStatus "C3P37" )
			)
			( gate "@baseboard_fab2_lib.baseboard_fab2(sch_1):page107_i240"
				( attribute "CDS_LIB" "mstr_discrete"
					( Origin gPackager )
				)
				( attribute "CDS_LOCATION" "C3P35"
					( Origin gPackager )
				)
				( attribute "CDS_SEC" "1"
					( Origin gPackager )
				)
				( attribute "LOCATION" "C3P35"
					( Origin gFrontEnd )
				)
				( attribute "MATERIAL" "X7R"
					( Origin gFrontEnd )
				)
				( attribute "PACK_TYPE" "0402"
					( Origin gFrontEnd )
				)
				( attribute "PART_NUMBER" "A36096-155"
					( Origin gFrontEnd )
				)
				( attribute "PHYS_PAGE" "107"
					( Origin gFrontEnd )
				)
				( attribute "ROT" "2"
					( Origin gFrontEnd )
				)
				( attribute "SEC" "1"
					( Origin gPackager )
				)
				( attribute "TOLERANCE" "10%"
					( Origin gFrontEnd )
				)
				( attribute "VALUE" "0.22UF"
					( Origin gFrontEnd )
				)
				( attribute "VER" "1"
					( Origin gFrontEnd )
				)
				( attribute "VOLTAGE" "16V"
					( Units "uVoltage" "V" 1.000000)
					( Origin gFrontEnd )
				)
				( attribute "XY" "(-6675,875)"
					( Origin gFrontEnd )
				)
				( attribute "CHIPS_PART_NAME" "CAP"
					( Origin gPackager )
				)
				( attribute "CDS_PART_NAME" "CAP_0402-0.22UF,16V,10%,X7R,A3A"
					( Origin gPackager )
				)
				( attribute "GROUP" "PCIE_UPLINK"
					( Origin gFrontEnd )
				)
				( objectStatus "C3P35" )
			)
			( gate "@baseboard_fab2_lib.baseboard_fab2(sch_1):page107_i241"
				( attribute "CDS_LIB" "mstr_discrete"
					( Origin gPackager )
				)
				( attribute "CDS_LOCATION" "C3P40"
					( Origin gPackager )
				)
				( attribute "CDS_SEC" "1"
					( Origin gPackager )
				)
				( attribute "LOCATION" "C3P40"
					( Origin gFrontEnd )
				)
				( attribute "MATERIAL" "X7R"
					( Origin gFrontEnd )
				)
				( attribute "PACK_TYPE" "0402"
					( Origin gFrontEnd )
				)
				( attribute "PART_NUMBER" "A36096-155"
					( Origin gFrontEnd )
				)
				( attribute "PHYS_PAGE" "107"
					( Origin gFrontEnd )
				)
				( attribute "ROT" "2"
					( Origin gFrontEnd )
				)
				( attribute "SEC" "1"
					( Origin gPackager )
				)
				( attribute "TOLERANCE" "10%"
					( Origin gFrontEnd )
				)
				( attribute "VALUE" "0.22UF"
					( Origin gFrontEnd )
				)
				( attribute "VER" "1"
					( Origin gFrontEnd )
				)
				( attribute "VOLTAGE" "16V"
					( Units "uVoltage" "V" 1.000000)
					( Origin gFrontEnd )
				)
				( attribute "XY" "(-6925,1575)"
					( Origin gFrontEnd )
				)
				( attribute "CHIPS_PART_NAME" "CAP"
					( Origin gPackager )
				)
				( attribute "CDS_PART_NAME" "CAP_0402-0.22UF,16V,10%,X7R,A3A"
					( Origin gPackager )
				)
				( attribute "GROUP" "PCIE_UPLINK"
					( Origin gFrontEnd )
				)
				( objectStatus "C3P40" )
			)
			( gate "@baseboard_fab2_lib.baseboard_fab2(sch_1):page107_i245"
				( attribute "CDS_LIB" "mstr_discrete"
					( Origin gPackager )
				)
				( attribute "CDS_LOCATION" "C3P30"
					( Origin gPackager )
				)
				( attribute "CDS_SEC" "1"
					( Origin gPackager )
				)
				( attribute "LOCATION" "C3P30"
					( Origin gFrontEnd )
				)
				( attribute "MATERIAL" "X7R"
					( Origin gFrontEnd )
				)
				( attribute "PACK_TYPE" "0402"
					( Origin gFrontEnd )
				)
				( attribute "PART_NUMBER" "A36096-155"
					( Origin gFrontEnd )
				)
				( attribute "PHYS_PAGE" "107"
					( Origin gFrontEnd )
				)
				( attribute "ROT" "2"
					( Origin gFrontEnd )
				)
				( attribute "SEC" "1"
					( Origin gPackager )
				)
				( attribute "TOLERANCE" "10%"
					( Origin gFrontEnd )
				)
				( attribute "VALUE" "0.22UF"
					( Origin gFrontEnd )
				)
				( attribute "VER" "1"
					( Origin gFrontEnd )
				)
				( attribute "VOLTAGE" "16V"
					( Units "uVoltage" "V" 1.000000)
					( Origin gFrontEnd )
				)
				( attribute "XY" "(-6475,575)"
					( Origin gFrontEnd )
				)
				( attribute "CHIPS_PART_NAME" "CAP"
					( Origin gPackager )
				)
				( attribute "CDS_PART_NAME" "CAP_0402-0.22UF,16V,10%,X7R,A3A"
					( Origin gPackager )
				)
				( attribute "GROUP" "PCIE_UPLINK"
					( Origin gFrontEnd )
				)
				( objectStatus "C3P30" )
			)
			( gate "@baseboard_fab2_lib.baseboard_fab2(sch_1):page107_i248"
				( attribute "CDS_LIB" "mstr_discrete"
					( Origin gPackager )
				)
				( attribute "CDS_LOCATION" "C3P39"
					( Origin gPackager )
				)
				( attribute "CDS_SEC" "1"
					( Origin gPackager )
				)
				( attribute "LOCATION" "C3P39"
					( Origin gFrontEnd )
				)
				( attribute "MATERIAL" "X7R"
					( Origin gFrontEnd )
				)
				( attribute "PACK_TYPE" "0402"
					( Origin gFrontEnd )
				)
				( attribute "PART_NUMBER" "A36096-155"
					( Origin gFrontEnd )
				)
				( attribute "PHYS_PAGE" "107"
					( Origin gFrontEnd )
				)
				( attribute "ROT" "2"
					( Origin gFrontEnd )
				)
				( attribute "SEC" "1"
					( Origin gPackager )
				)
				( attribute "TOLERANCE" "10%"
					( Origin gFrontEnd )
				)
				( attribute "VALUE" "0.22UF"
					( Origin gFrontEnd )
				)
				( attribute "VER" "1"
					( Origin gFrontEnd )
				)
				( attribute "VOLTAGE" "16V"
					( Units "uVoltage" "V" 1.000000)
					( Origin gFrontEnd )
				)
				( attribute "XY" "(-6875,575)"
					( Origin gFrontEnd )
				)
				( attribute "CHIPS_PART_NAME" "CAP"
					( Origin gPackager )
				)
				( attribute "CDS_PART_NAME" "CAP_0402-0.22UF,16V,10%,X7R,A3A"
					( Origin gPackager )
				)
				( attribute "GROUP" "PCIE_UPLINK"
					( Origin gFrontEnd )
				)
				( objectStatus "C3P39" )
			)
			( gate "@baseboard_fab2_lib.baseboard_fab2(sch_1):page107_i257"
				( attribute "CDS_LIB" "mstr_discrete"
					( Origin gPackager )
				)
				( attribute "CDS_LOCATION" "C2U4"
					( Origin gPackager )
				)
				( attribute "CDS_SEC" "1"
					( Origin gPackager )
				)
				( attribute "LOCATION" "C2U4"
					( Origin gFrontEnd )
				)
				( attribute "MATERIAL" "X7R"
					( Origin gFrontEnd )
				)
				( attribute "PACK_TYPE" "0402"
					( Origin gFrontEnd )
				)
				( attribute "PART_NUMBER" "A36096-155"
					( Origin gFrontEnd )
				)
				( attribute "PHYS_PAGE" "107"
					( Origin gFrontEnd )
				)
				( attribute "ROT" "2"
					( Origin gFrontEnd )
				)
				( attribute "SEC" "1"
					( Origin gFrontEnd )
				)
				( attribute "SEC_TYPE" "0402"
					( Origin gFrontEnd )
				)
				( attribute "TOLERANCE" "10%"
					( Origin gFrontEnd )
				)
				( attribute "VALUE" "0.22UF"
					( Origin gFrontEnd )
				)
				( attribute "VER" "1"
					( Origin gFrontEnd )
				)
				( attribute "VOLTAGE" "16V"
					( Units "uVoltage" "V" 1.000000)
					( Origin gFrontEnd )
				)
				( attribute "XY" "(-1950,1875)"
					( Origin gFrontEnd )
				)
				( attribute "CHIPS_PART_NAME" "CAP"
					( Origin gPackager )
				)
				( attribute "CDS_PART_NAME" "CAP_0402-0.22UF,16V,10%,X7R,A3A"
					( Origin gPackager )
				)
				( attribute "GROUP" "PCIE_UPLINK"
					( Origin gFrontEnd )
				)
				( objectStatus "C2U4" )
			)
			( gate "@baseboard_fab2_lib.baseboard_fab2(sch_1):page107_i260"
				( attribute "CDS_LIB" "mstr_discrete"
					( Origin gPackager )
				)
				( attribute "CDS_LOCATION" "C2U6"
					( Origin gPackager )
				)
				( attribute "CDS_SEC" "1"
					( Origin gPackager )
				)
				( attribute "LOCATION" "C2U6"
					( Origin gFrontEnd )
				)
				( attribute "MATERIAL" "X7R"
					( Origin gFrontEnd )
				)
				( attribute "PACK_TYPE" "0402"
					( Origin gFrontEnd )
				)
				( attribute "PART_NUMBER" "A36096-155"
					( Origin gFrontEnd )
				)
				( attribute "PHYS_PAGE" "107"
					( Origin gFrontEnd )
				)
				( attribute "ROT" "2"
					( Origin gFrontEnd )
				)
				( attribute "SEC" "1"
					( Origin gFrontEnd )
				)
				( attribute "SEC_TYPE" "0402"
					( Origin gFrontEnd )
				)
				( attribute "TOLERANCE" "10%"
					( Origin gFrontEnd )
				)
				( attribute "VALUE" "0.22UF"
					( Origin gFrontEnd )
				)
				( attribute "VER" "1"
					( Origin gFrontEnd )
				)
				( attribute "VOLTAGE" "16V"
					( Units "uVoltage" "V" 1.000000)
					( Origin gFrontEnd )
				)
				( attribute "XY" "(-2150,1525)"
					( Origin gFrontEnd )
				)
				( attribute "CHIPS_PART_NAME" "CAP"
					( Origin gPackager )
				)
				( attribute "CDS_PART_NAME" "CAP_0402-0.22UF,16V,10%,X7R,A3A"
					( Origin gPackager )
				)
				( attribute "GROUP" "PCIE_UPLINK"
					( Origin gFrontEnd )
				)
				( objectStatus "C2U6" )
			)
			( gate "@baseboard_fab2_lib.baseboard_fab2(sch_1):page107_i264"
				( attribute "CDS_LIB" "mstr_discrete"
					( Origin gPackager )
				)
				( attribute "CDS_LOCATION" "C2U8"
					( Origin gPackager )
				)
				( attribute "CDS_SEC" "1"
					( Origin gPackager )
				)
				( attribute "LOCATION" "C2U8"
					( Origin gFrontEnd )
				)
				( attribute "MATERIAL" "X7R"
					( Origin gFrontEnd )
				)
				( attribute "PACK_TYPE" "0402"
					( Origin gFrontEnd )
				)
				( attribute "PART_NUMBER" "A36096-155"
					( Origin gFrontEnd )
				)
				( attribute "PHYS_PAGE" "107"
					( Origin gFrontEnd )
				)
				( attribute "ROT" "2"
					( Origin gFrontEnd )
				)
				( attribute "SEC" "1"
					( Origin gFrontEnd )
				)
				( attribute "SEC_TYPE" "0402"
					( Origin gFrontEnd )
				)
				( attribute "TOLERANCE" "10%"
					( Origin gFrontEnd )
				)
				( attribute "VALUE" "0.22UF"
					( Origin gFrontEnd )
				)
				( attribute "VER" "1"
					( Origin gFrontEnd )
				)
				( attribute "VOLTAGE" "16V"
					( Units "uVoltage" "V" 1.000000)
					( Origin gFrontEnd )
				)
				( attribute "XY" "(-2350,1875)"
					( Origin gFrontEnd )
				)
				( attribute "CHIPS_PART_NAME" "CAP"
					( Origin gPackager )
				)
				( attribute "CDS_PART_NAME" "CAP_0402-0.22UF,16V,10%,X7R,A3A"
					( Origin gPackager )
				)
				( attribute "GROUP" "PCIE_UPLINK"
					( Origin gFrontEnd )
				)
				( objectStatus "C2U8" )
			)
			( gate "@baseboard_fab2_lib.baseboard_fab2(sch_1):page107_i265"
				( attribute "CDS_LIB" "mstr_discrete"
					( Origin gPackager )
				)
				( attribute "CDS_LOCATION" "C2U12"
					( Origin gPackager )
				)
				( attribute "CDS_SEC" "1"
					( Origin gPackager )
				)
				( attribute "LOCATION" "C2U12"
					( Origin gFrontEnd )
				)
				( attribute "MATERIAL" "X7R"
					( Origin gFrontEnd )
				)
				( attribute "PACK_TYPE" "0402"
					( Origin gFrontEnd )
				)
				( attribute "PART_NUMBER" "A36096-155"
					( Origin gFrontEnd )
				)
				( attribute "PHYS_PAGE" "107"
					( Origin gFrontEnd )
				)
				( attribute "ROT" "2"
					( Origin gFrontEnd )
				)
				( attribute "SEC" "1"
					( Origin gFrontEnd )
				)
				( attribute "SEC_TYPE" "0402"
					( Origin gFrontEnd )
				)
				( attribute "TOLERANCE" "10%"
					( Origin gFrontEnd )
				)
				( attribute "VALUE" "0.22UF"
					( Origin gFrontEnd )
				)
				( attribute "VER" "1"
					( Origin gFrontEnd )
				)
				( attribute "VOLTAGE" "16V"
					( Units "uVoltage" "V" 1.000000)
					( Origin gFrontEnd )
				)
				( attribute "XY" "(-2750,1875)"
					( Origin gFrontEnd )
				)
				( attribute "CHIPS_PART_NAME" "CAP"
					( Origin gPackager )
				)
				( attribute "CDS_PART_NAME" "CAP_0402-0.22UF,16V,10%,X7R,A3A"
					( Origin gPackager )
				)
				( attribute "GROUP" "PCIE_UPLINK"
					( Origin gFrontEnd )
				)
				( objectStatus "C2U12" )
			)
			( gate "@baseboard_fab2_lib.baseboard_fab2(sch_1):page107_i267"
				( attribute "CDS_LIB" "mstr_discrete"
					( Origin gPackager )
				)
				( attribute "CDS_LOCATION" "C2U10"
					( Origin gPackager )
				)
				( attribute "CDS_SEC" "1"
					( Origin gPackager )
				)
				( attribute "LOCATION" "C2U10"
					( Origin gFrontEnd )
				)
				( attribute "MATERIAL" "X7R"
					( Origin gFrontEnd )
				)
				( attribute "PACK_TYPE" "0402"
					( Origin gFrontEnd )
				)
				( attribute "PART_NUMBER" "A36096-155"
					( Origin gFrontEnd )
				)
				( attribute "PHYS_PAGE" "107"
					( Origin gFrontEnd )
				)
				( attribute "ROT" "2"
					( Origin gFrontEnd )
				)
				( attribute "SEC" "1"
					( Origin gFrontEnd )
				)
				( attribute "SEC_TYPE" "0402"
					( Origin gFrontEnd )
				)
				( attribute "TOLERANCE" "10%"
					( Origin gFrontEnd )
				)
				( attribute "VALUE" "0.22UF"
					( Origin gFrontEnd )
				)
				( attribute "VER" "1"
					( Origin gFrontEnd )
				)
				( attribute "VOLTAGE" "16V"
					( Units "uVoltage" "V" 1.000000)
					( Origin gFrontEnd )
				)
				( attribute "XY" "(-2550,1525)"
					( Origin gFrontEnd )
				)
				( attribute "CHIPS_PART_NAME" "CAP"
					( Origin gPackager )
				)
				( attribute "CDS_PART_NAME" "CAP_0402-0.22UF,16V,10%,X7R,A3A"
					( Origin gPackager )
				)
				( attribute "GROUP" "PCIE_UPLINK"
					( Origin gFrontEnd )
				)
				( objectStatus "C2U10" )
			)
			( gate "@baseboard_fab2_lib.baseboard_fab2(sch_1):page107_i272"
				( attribute "CDS_LIB" "mstr_discrete"
					( Origin gPackager )
				)
				( attribute "CDS_LOCATION" "C2U3"
					( Origin gPackager )
				)
				( attribute "CDS_SEC" "1"
					( Origin gPackager )
				)
				( attribute "LOCATION" "C2U3"
					( Origin gFrontEnd )
				)
				( attribute "MATERIAL" "X7R"
					( Origin gFrontEnd )
				)
				( attribute "PACK_TYPE" "0402"
					( Origin gFrontEnd )
				)
				( attribute "PART_NUMBER" "A36096-155"
					( Origin gFrontEnd )
				)
				( attribute "PHYS_PAGE" "107"
					( Origin gFrontEnd )
				)
				( attribute "ROT" "2"
					( Origin gFrontEnd )
				)
				( attribute "SEC" "1"
					( Origin gFrontEnd )
				)
				( attribute "SEC_TYPE" "0402"
					( Origin gFrontEnd )
				)
				( attribute "TOLERANCE" "10%"
					( Origin gFrontEnd )
				)
				( attribute "VALUE" "0.22UF"
					( Origin gFrontEnd )
				)
				( attribute "VER" "1"
					( Origin gFrontEnd )
				)
				( attribute "VOLTAGE" "16V"
					( Units "uVoltage" "V" 1.000000)
					( Origin gFrontEnd )
				)
				( attribute "XY" "(-1900,875)"
					( Origin gFrontEnd )
				)
				( attribute "CHIPS_PART_NAME" "CAP"
					( Origin gPackager )
				)
				( attribute "CDS_PART_NAME" "CAP_0402-0.22UF,16V,10%,X7R,A3A"
					( Origin gPackager )
				)
				( attribute "GROUP" "PCIE_UPLINK"
					( Origin gFrontEnd )
				)
				( objectStatus "C2U3" )
			)
			( gate "@baseboard_fab2_lib.baseboard_fab2(sch_1):page107_i274"
				( attribute "CDS_LIB" "mstr_discrete"
					( Origin gPackager )
				)
				( attribute "CDS_LOCATION" "C2U5"
					( Origin gPackager )
				)
				( attribute "CDS_SEC" "1"
					( Origin gPackager )
				)
				( attribute "LOCATION" "C2U5"
					( Origin gFrontEnd )
				)
				( attribute "MATERIAL" "X7R"
					( Origin gFrontEnd )
				)
				( attribute "PACK_TYPE" "0402"
					( Origin gFrontEnd )
				)
				( attribute "PART_NUMBER" "A36096-155"
					( Origin gFrontEnd )
				)
				( attribute "PHYS_PAGE" "107"
					( Origin gFrontEnd )
				)
				( attribute "ROT" "2"
					( Origin gFrontEnd )
				)
				( attribute "SEC" "1"
					( Origin gFrontEnd )
				)
				( attribute "SEC_TYPE" "0402"
					( Origin gFrontEnd )
				)
				( attribute "TOLERANCE" "10%"
					( Origin gFrontEnd )
				)
				( attribute "VALUE" "0.22UF"
					( Origin gFrontEnd )
				)
				( attribute "VER" "1"
					( Origin gFrontEnd )
				)
				( attribute "VOLTAGE" "16V"
					( Units "uVoltage" "V" 1.000000)
					( Origin gFrontEnd )
				)
				( attribute "XY" "(-2100,525)"
					( Origin gFrontEnd )
				)
				( attribute "CHIPS_PART_NAME" "CAP"
					( Origin gPackager )
				)
				( attribute "CDS_PART_NAME" "CAP_0402-0.22UF,16V,10%,X7R,A3A"
					( Origin gPackager )
				)
				( attribute "GROUP" "PCIE_UPLINK"
					( Origin gFrontEnd )
				)
				( objectStatus "C2U5" )
			)
			( gate "@baseboard_fab2_lib.baseboard_fab2(sch_1):page107_i277"
				( attribute "CDS_LIB" "mstr_discrete"
					( Origin gPackager )
				)
				( attribute "CDS_LOCATION" "C2U7"
					( Origin gPackager )
				)
				( attribute "CDS_SEC" "1"
					( Origin gPackager )
				)
				( attribute "LOCATION" "C2U7"
					( Origin gFrontEnd )
				)
				( attribute "MATERIAL" "X7R"
					( Origin gFrontEnd )
				)
				( attribute "PACK_TYPE" "0402"
					( Origin gFrontEnd )
				)
				( attribute "PART_NUMBER" "A36096-155"
					( Origin gFrontEnd )
				)
				( attribute "PHYS_PAGE" "107"
					( Origin gFrontEnd )
				)
				( attribute "ROT" "2"
					( Origin gFrontEnd )
				)
				( attribute "SEC" "1"
					( Origin gFrontEnd )
				)
				( attribute "SEC_TYPE" "0402"
					( Origin gFrontEnd )
				)
				( attribute "TOLERANCE" "10%"
					( Origin gFrontEnd )
				)
				( attribute "VALUE" "0.22UF"
					( Origin gFrontEnd )
				)
				( attribute "VER" "1"
					( Origin gFrontEnd )
				)
				( attribute "VOLTAGE" "16V"
					( Units "uVoltage" "V" 1.000000)
					( Origin gFrontEnd )
				)
				( attribute "XY" "(-2300,875)"
					( Origin gFrontEnd )
				)
				( attribute "CHIPS_PART_NAME" "CAP"
					( Origin gPackager )
				)
				( attribute "CDS_PART_NAME" "CAP_0402-0.22UF,16V,10%,X7R,A3A"
					( Origin gPackager )
				)
				( attribute "GROUP" "PCIE_UPLINK"
					( Origin gFrontEnd )
				)
				( objectStatus "C2U7" )
			)
			( gate "@baseboard_fab2_lib.baseboard_fab2(sch_1):page107_i278"
				( attribute "CDS_LIB" "mstr_discrete"
					( Origin gPackager )
				)
				( attribute "CDS_LOCATION" "C2U11"
					( Origin gPackager )
				)
				( attribute "CDS_SEC" "1"
					( Origin gPackager )
				)
				( attribute "LOCATION" "C2U11"
					( Origin gFrontEnd )
				)
				( attribute "MATERIAL" "X7R"
					( Origin gFrontEnd )
				)
				( attribute "PACK_TYPE" "0402"
					( Origin gFrontEnd )
				)
				( attribute "PART_NUMBER" "A36096-155"
					( Origin gFrontEnd )
				)
				( attribute "PHYS_PAGE" "107"
					( Origin gFrontEnd )
				)
				( attribute "ROT" "2"
					( Origin gFrontEnd )
				)
				( attribute "SEC" "1"
					( Origin gFrontEnd )
				)
				( attribute "SEC_TYPE" "0402"
					( Origin gFrontEnd )
				)
				( attribute "TOLERANCE" "10%"
					( Origin gFrontEnd )
				)
				( attribute "VALUE" "0.22UF"
					( Origin gFrontEnd )
				)
				( attribute "VER" "1"
					( Origin gFrontEnd )
				)
				( attribute "VOLTAGE" "16V"
					( Units "uVoltage" "V" 1.000000)
					( Origin gFrontEnd )
				)
				( attribute "XY" "(-2700,875)"
					( Origin gFrontEnd )
				)
				( attribute "CHIPS_PART_NAME" "CAP"
					( Origin gPackager )
				)
				( attribute "CDS_PART_NAME" "CAP_0402-0.22UF,16V,10%,X7R,A3A"
					( Origin gPackager )
				)
				( attribute "GROUP" "PCIE_UPLINK"
					( Origin gFrontEnd )
				)
				( objectStatus "C2U11" )
			)
			( gate "@baseboard_fab2_lib.baseboard_fab2(sch_1):page107_i279"
				( attribute "CDS_LIB" "mstr_discrete"
					( Origin gPackager )
				)
				( attribute "CDS_LOCATION" "C2U9"
					( Origin gPackager )
				)
				( attribute "CDS_SEC" "1"
					( Origin gPackager )
				)
				( attribute "LOCATION" "C2U9"
					( Origin gFrontEnd )
				)
				( attribute "MATERIAL" "X7R"
					( Origin gFrontEnd )
				)
				( attribute "PACK_TYPE" "0402"
					( Origin gFrontEnd )
				)
				( attribute "PART_NUMBER" "A36096-155"
					( Origin gFrontEnd )
				)
				( attribute "PHYS_PAGE" "107"
					( Origin gFrontEnd )
				)
				( attribute "ROT" "2"
					( Origin gFrontEnd )
				)
				( attribute "SEC" "1"
					( Origin gFrontEnd )
				)
				( attribute "SEC_TYPE" "0402"
					( Origin gFrontEnd )
				)
				( attribute "TOLERANCE" "10%"
					( Origin gFrontEnd )
				)
				( attribute "VALUE" "0.22UF"
					( Origin gFrontEnd )
				)
				( attribute "VER" "1"
					( Origin gFrontEnd )
				)
				( attribute "VOLTAGE" "16V"
					( Units "uVoltage" "V" 1.000000)
					( Origin gFrontEnd )
				)
				( attribute "XY" "(-2500,525)"
					( Origin gFrontEnd )
				)
				( attribute "CHIPS_PART_NAME" "CAP"
					( Origin gPackager )
				)
				( attribute "CDS_PART_NAME" "CAP_0402-0.22UF,16V,10%,X7R,A3A"
					( Origin gPackager )
				)
				( attribute "GROUP" "PCIE_UPLINK"
					( Origin gFrontEnd )
				)
				( objectStatus "C2U9" )
			)
			( gate "@baseboard_fab2_lib.baseboard_fab2(sch_1):page107_i286"
				( attribute "CDS_LIB" "mstr_discrete"
					( Origin gPackager )
				)
				( attribute "CDS_LOCATION" "C2U16"
					( Origin gPackager )
				)
				( attribute "CDS_SEC" "1"
					( Origin gPackager )
				)
				( attribute "LOCATION" "C2U16"
					( Origin gFrontEnd )
				)
				( attribute "MATERIAL" "X7R"
					( Origin gFrontEnd )
				)
				( attribute "PACK_TYPE" "0402"
					( Origin gFrontEnd )
				)
				( attribute "PART_NUMBER" "A36096-155"
					( Origin gFrontEnd )
				)
				( attribute "PHYS_PAGE" "107"
					( Origin gFrontEnd )
				)
				( attribute "ROT" "2"
					( Origin gFrontEnd )
				)
				( attribute "SEC" "1"
					( Origin gFrontEnd )
				)
				( attribute "SEC_TYPE" "0402"
					( Origin gFrontEnd )
				)
				( attribute "TOLERANCE" "10%"
					( Origin gFrontEnd )
				)
				( attribute "VALUE" "0.22UF"
					( Origin gFrontEnd )
				)
				( attribute "VER" "1"
					( Origin gFrontEnd )
				)
				( attribute "VOLTAGE" "16V"
					( Units "uVoltage" "V" 1.000000)
					( Origin gFrontEnd )
				)
				( attribute "XY" "(-3150,1875)"
					( Origin gFrontEnd )
				)
				( attribute "CHIPS_PART_NAME" "CAP"
					( Origin gPackager )
				)
				( attribute "CDS_PART_NAME" "CAP_0402-0.22UF,16V,10%,X7R,A3A"
					( Origin gPackager )
				)
				( attribute "GROUP" "PCIE_UPLINK"
					( Origin gFrontEnd )
				)
				( objectStatus "C2U16" )
			)
			( gate "@baseboard_fab2_lib.baseboard_fab2(sch_1):page107_i287"
				( attribute "CDS_LIB" "mstr_discrete"
					( Origin gPackager )
				)
				( attribute "CDS_LOCATION" "C2U14"
					( Origin gPackager )
				)
				( attribute "CDS_SEC" "1"
					( Origin gPackager )
				)
				( attribute "LOCATION" "C2U14"
					( Origin gFrontEnd )
				)
				( attribute "MATERIAL" "X7R"
					( Origin gFrontEnd )
				)
				( attribute "PACK_TYPE" "0402"
					( Origin gFrontEnd )
				)
				( attribute "PART_NUMBER" "A36096-155"
					( Origin gFrontEnd )
				)
				( attribute "PHYS_PAGE" "107"
					( Origin gFrontEnd )
				)
				( attribute "ROT" "2"
					( Origin gFrontEnd )
				)
				( attribute "SEC" "1"
					( Origin gFrontEnd )
				)
				( attribute "SEC_TYPE" "0402"
					( Origin gFrontEnd )
				)
				( attribute "TOLERANCE" "10%"
					( Origin gFrontEnd )
				)
				( attribute "VALUE" "0.22UF"
					( Origin gFrontEnd )
				)
				( attribute "VER" "1"
					( Origin gFrontEnd )
				)
				( attribute "VOLTAGE" "16V"
					( Units "uVoltage" "V" 1.000000)
					( Origin gFrontEnd )
				)
				( attribute "XY" "(-2950,1525)"
					( Origin gFrontEnd )
				)
				( attribute "CHIPS_PART_NAME" "CAP"
					( Origin gPackager )
				)
				( attribute "CDS_PART_NAME" "CAP_0402-0.22UF,16V,10%,X7R,A3A"
					( Origin gPackager )
				)
				( attribute "GROUP" "PCIE_UPLINK"
					( Origin gFrontEnd )
				)
				( objectStatus "C2U14" )
			)
			( gate "@baseboard_fab2_lib.baseboard_fab2(sch_1):page107_i294"
				( attribute "CDS_LIB" "mstr_discrete"
					( Origin gPackager )
				)
				( attribute "CDS_LOCATION" "C2U18"
					( Origin gPackager )
				)
				( attribute "CDS_SEC" "1"
					( Origin gPackager )
				)
				( attribute "LOCATION" "C2U18"
					( Origin gFrontEnd )
				)
				( attribute "MATERIAL" "X7R"
					( Origin gFrontEnd )
				)
				( attribute "PACK_TYPE" "0402"
					( Origin gFrontEnd )
				)
				( attribute "PART_NUMBER" "A36096-155"
					( Origin gFrontEnd )
				)
				( attribute "PHYS_PAGE" "107"
					( Origin gFrontEnd )
				)
				( attribute "ROT" "2"
					( Origin gFrontEnd )
				)
				( attribute "SEC" "1"
					( Origin gFrontEnd )
				)
				( attribute "SEC_TYPE" "0402"
					( Origin gFrontEnd )
				)
				( attribute "TOLERANCE" "10%"
					( Origin gFrontEnd )
				)
				( attribute "VALUE" "0.22UF"
					( Origin gFrontEnd )
				)
				( attribute "VER" "1"
					( Origin gFrontEnd )
				)
				( attribute "VOLTAGE" "16V"
					( Units "uVoltage" "V" 1.000000)
					( Origin gFrontEnd )
				)
				( attribute "XY" "(-3350,1525)"
					( Origin gFrontEnd )
				)
				( attribute "CHIPS_PART_NAME" "CAP"
					( Origin gPackager )
				)
				( attribute "CDS_PART_NAME" "CAP_0402-0.22UF,16V,10%,X7R,A3A"
					( Origin gPackager )
				)
				( attribute "GROUP" "PCIE_UPLINK"
					( Origin gFrontEnd )
				)
				( objectStatus "C2U18" )
			)
			( gate "@baseboard_fab2_lib.baseboard_fab2(sch_1):page107_i296"
				( attribute "CDS_LIB" "mstr_discrete"
					( Origin gPackager )
				)
				( attribute "CDS_LOCATION" "C2U15"
					( Origin gPackager )
				)
				( attribute "CDS_SEC" "1"
					( Origin gPackager )
				)
				( attribute "LOCATION" "C2U15"
					( Origin gFrontEnd )
				)
				( attribute "MATERIAL" "X7R"
					( Origin gFrontEnd )
				)
				( attribute "PACK_TYPE" "0402"
					( Origin gFrontEnd )
				)
				( attribute "PART_NUMBER" "A36096-155"
					( Origin gFrontEnd )
				)
				( attribute "PHYS_PAGE" "107"
					( Origin gFrontEnd )
				)
				( attribute "ROT" "2"
					( Origin gFrontEnd )
				)
				( attribute "SEC" "1"
					( Origin gFrontEnd )
				)
				( attribute "SEC_TYPE" "0402"
					( Origin gFrontEnd )
				)
				( attribute "TOLERANCE" "10%"
					( Origin gFrontEnd )
				)
				( attribute "VALUE" "0.22UF"
					( Origin gFrontEnd )
				)
				( attribute "VER" "1"
					( Origin gFrontEnd )
				)
				( attribute "VOLTAGE" "16V"
					( Units "uVoltage" "V" 1.000000)
					( Origin gFrontEnd )
				)
				( attribute "XY" "(-3100,875)"
					( Origin gFrontEnd )
				)
				( attribute "CHIPS_PART_NAME" "CAP"
					( Origin gPackager )
				)
				( attribute "CDS_PART_NAME" "CAP_0402-0.22UF,16V,10%,X7R,A3A"
					( Origin gPackager )
				)
				( attribute "GROUP" "PCIE_UPLINK"
					( Origin gFrontEnd )
				)
				( objectStatus "C2U15" )
			)
			( gate "@baseboard_fab2_lib.baseboard_fab2(sch_1):page107_i297"
				( attribute "CDS_LIB" "mstr_discrete"
					( Origin gPackager )
				)
				( attribute "CDS_LOCATION" "C2U13"
					( Origin gPackager )
				)
				( attribute "CDS_SEC" "1"
					( Origin gPackager )
				)
				( attribute "LOCATION" "C2U13"
					( Origin gFrontEnd )
				)
				( attribute "MATERIAL" "X7R"
					( Origin gFrontEnd )
				)
				( attribute "PACK_TYPE" "0402"
					( Origin gFrontEnd )
				)
				( attribute "PART_NUMBER" "A36096-155"
					( Origin gFrontEnd )
				)
				( attribute "PHYS_PAGE" "107"
					( Origin gFrontEnd )
				)
				( attribute "ROT" "2"
					( Origin gFrontEnd )
				)
				( attribute "SEC" "1"
					( Origin gFrontEnd )
				)
				( attribute "SEC_TYPE" "0402"
					( Origin gFrontEnd )
				)
				( attribute "TOLERANCE" "10%"
					( Origin gFrontEnd )
				)
				( attribute "VALUE" "0.22UF"
					( Origin gFrontEnd )
				)
				( attribute "VER" "1"
					( Origin gFrontEnd )
				)
				( attribute "VOLTAGE" "16V"
					( Units "uVoltage" "V" 1.000000)
					( Origin gFrontEnd )
				)
				( attribute "XY" "(-2900,525)"
					( Origin gFrontEnd )
				)
				( attribute "CHIPS_PART_NAME" "CAP"
					( Origin gPackager )
				)
				( attribute "CDS_PART_NAME" "CAP_0402-0.22UF,16V,10%,X7R,A3A"
					( Origin gPackager )
				)
				( attribute "GROUP" "PCIE_UPLINK"
					( Origin gFrontEnd )
				)
				( objectStatus "C2U13" )
			)
			( gate "@baseboard_fab2_lib.baseboard_fab2(sch_1):page107_i300"
				( attribute "CDS_LIB" "mstr_discrete"
					( Origin gPackager )
				)
				( attribute "CDS_LOCATION" "C2U17"
					( Origin gPackager )
				)
				( attribute "CDS_SEC" "1"
					( Origin gPackager )
				)
				( attribute "LOCATION" "C2U17"
					( Origin gFrontEnd )
				)
				( attribute "MATERIAL" "X7R"
					( Origin gFrontEnd )
				)
				( attribute "PACK_TYPE" "0402"
					( Origin gFrontEnd )
				)
				( attribute "PART_NUMBER" "A36096-155"
					( Origin gFrontEnd )
				)
				( attribute "PHYS_PAGE" "107"
					( Origin gFrontEnd )
				)
				( attribute "ROT" "2"
					( Origin gFrontEnd )
				)
				( attribute "SEC" "1"
					( Origin gFrontEnd )
				)
				( attribute "SEC_TYPE" "0402"
					( Origin gFrontEnd )
				)
				( attribute "TOLERANCE" "10%"
					( Origin gFrontEnd )
				)
				( attribute "VALUE" "0.22UF"
					( Origin gFrontEnd )
				)
				( attribute "VER" "1"
					( Origin gFrontEnd )
				)
				( attribute "VOLTAGE" "16V"
					( Units "uVoltage" "V" 1.000000)
					( Origin gFrontEnd )
				)
				( attribute "XY" "(-3300,525)"
					( Origin gFrontEnd )
				)
				( attribute "CHIPS_PART_NAME" "CAP"
					( Origin gPackager )
				)
				( attribute "CDS_PART_NAME" "CAP_0402-0.22UF,16V,10%,X7R,A3A"
					( Origin gPackager )
				)
				( attribute "GROUP" "PCIE_UPLINK"
					( Origin gFrontEnd )
				)
				( objectStatus "C2U17" )
			)
			( gate "@baseboard_fab2_lib.baseboard_fab2(sch_1):page107_i489"
				( attribute "CDS_LIB" "mstr_discrete"
					( Origin gPackager )
				)
				( attribute "LOCATION" "C3P34"
					( Origin gFrontEnd )
				)
				( attribute "MATERIAL" "X7R"
					( Origin gFrontEnd )
				)
				( attribute "PACK_TYPE" "0402"
					( Origin gFrontEnd )
				)
				( attribute "PART_NUMBER" "A36096-155"
					( Origin gFrontEnd )
				)
				( attribute "PHYS_PAGE" "107"
					( Origin gFrontEnd )
				)
				( attribute "ROT" "0"
					( Origin gFrontEnd )
				)
				( attribute "TOLERANCE" "10%"
					( Origin gFrontEnd )
				)
				( attribute "VALUE" "0.22UF"
					( Origin gFrontEnd )
				)
				( attribute "VER" "1"
					( Origin gFrontEnd )
				)
				( attribute "VOLTAGE" "16V"
					( Units "uVoltage" "V" 1.000000)
					( Origin gFrontEnd )
				)
				( attribute "XY" "(-5450,2975)"
					( Origin gFrontEnd )
				)
				( attribute "CHIPS_PART_NAME" "CAP"
					( Origin gPackager )
				)
				( attribute "CDS_PART_NAME" "CAP_0402-0.22UF,16V,10%,X7R,A3A"
					( Origin gPackager )
				)
				( attribute "CDS_LOCATION" "C3P34"
					( Origin gPackager )
				)
				( attribute "CDS_SEC" "1"
					( Origin gPackager )
				)
				( attribute "SEC" "1"
					( Origin gPackager )
				)
				( attribute "GROUP" "PCIE_RISER"
					( Origin gFrontEnd )
				)
				( objectStatus "C3P34" )
			)
			( gate "@baseboard_fab2_lib.baseboard_fab2(sch_1):page107_i497"
				( attribute "CDS_LIB" "mstr_discrete"
					( Origin gPackager )
				)
				( attribute "LOCATION" "R2U27"
					( Origin gFrontEnd )
				)
				( attribute "MATERIAL" "CHIP"
					( Origin gFrontEnd )
				)
				( attribute "PACK_TYPE" "0402"
					( Origin gFrontEnd )
				)
				( attribute "PART_NUMBER" "G21497-005"
					( Origin gFrontEnd )
				)
				( attribute "PHYS_PAGE" "107"
					( Origin gFrontEnd )
				)
				( attribute "ROT" "1"
					( Origin gFrontEnd )
				)
				( attribute "TOLERANCE" "5%"
					( Origin gFrontEnd )
				)
				( attribute "VALUE" "0.0"
					( Origin gFrontEnd )
				)
				( attribute "VER" "1"
					( Origin gFrontEnd )
				)
				( attribute "WATTAGE" "1/16W"
					( Origin gFrontEnd )
				)
				( attribute "XY" "(-2025,4125)"
					( Origin gFrontEnd )
				)
				( attribute "CHIPS_PART_NAME" "RES"
					( Origin gPackager )
				)
				( attribute "CDS_PART_NAME" "RES_0402-0.0,5%,1/16W,CHIP,G21A"
					( Origin gPackager )
				)
				( attribute "CDS_LOCATION" "R2U27"
					( Origin gPackager )
				)
				( attribute "CDS_SEC" "1"
					( Origin gPackager )
				)
				( attribute "SEC" "1"
					( Origin gPackager )
				)
				( attribute "GROUP" "PCIE_RISER"
					( Origin gFrontEnd )
				)
				( objectStatus "R2U27" )
			)
			( gate "@baseboard_fab2_lib.baseboard_fab2(sch_1):page107_i488"
				( attribute "CDS_LIB" "mstr_discrete"
					( Origin gPackager )
				)
				( attribute "LOCATION" "C3P31"
					( Origin gFrontEnd )
				)
				( attribute "MATERIAL" "X7R"
					( Origin gFrontEnd )
				)
				( attribute "PACK_TYPE" "0402"
					( Origin gFrontEnd )
				)
				( attribute "PART_NUMBER" "A36096-155"
					( Origin gFrontEnd )
				)
				( attribute "PHYS_PAGE" "107"
					( Origin gFrontEnd )
				)
				( attribute "ROT" "0"
					( Origin gFrontEnd )
				)
				( attribute "TOLERANCE" "10%"
					( Origin gFrontEnd )
				)
				( attribute "VALUE" "0.22UF"
					( Origin gFrontEnd )
				)
				( attribute "VER" "1"
					( Origin gFrontEnd )
				)
				( attribute "VOLTAGE" "16V"
					( Units "uVoltage" "V" 1.000000)
					( Origin gFrontEnd )
				)
				( attribute "XY" "(-5250,2675)"
					( Origin gFrontEnd )
				)
				( attribute "CHIPS_PART_NAME" "CAP"
					( Origin gPackager )
				)
				( attribute "CDS_PART_NAME" "CAP_0402-0.22UF,16V,10%,X7R,A3A"
					( Origin gPackager )
				)
				( attribute "CDS_LOCATION" "C3P31"
					( Origin gPackager )
				)
				( attribute "CDS_SEC" "1"
					( Origin gPackager )
				)
				( attribute "SEC" "1"
					( Origin gPackager )
				)
				( attribute "GROUP" "PCIE_RISER"
					( Origin gFrontEnd )
				)
				( objectStatus "C3P31" )
			)
			( gate "@baseboard_fab2_lib.baseboard_fab2(sch_1):page107_i487"
				( attribute "CDS_LIB" "mstr_discrete"
					( Origin gPackager )
				)
				( attribute "LOCATION" "C3P26"
					( Origin gFrontEnd )
				)
				( attribute "MATERIAL" "X7R"
					( Origin gFrontEnd )
				)
				( attribute "PACK_TYPE" "0402"
					( Origin gFrontEnd )
				)
				( attribute "PART_NUMBER" "A36096-155"
					( Origin gFrontEnd )
				)
				( attribute "PHYS_PAGE" "107"
					( Origin gFrontEnd )
				)
				( attribute "ROT" "0"
					( Origin gFrontEnd )
				)
				( attribute "TOLERANCE" "10%"
					( Origin gFrontEnd )
				)
				( attribute "VALUE" "0.22UF"
					( Origin gFrontEnd )
				)
				( attribute "VER" "1"
					( Origin gFrontEnd )
				)
				( attribute "VOLTAGE" "16V"
					( Units "uVoltage" "V" 1.000000)
					( Origin gFrontEnd )
				)
				( attribute "XY" "(-5050,2975)"
					( Origin gFrontEnd )
				)
				( attribute "CHIPS_PART_NAME" "CAP"
					( Origin gPackager )
				)
				( attribute "CDS_PART_NAME" "CAP_0402-0.22UF,16V,10%,X7R,A3A"
					( Origin gPackager )
				)
				( attribute "CDS_LOCATION" "C3P26"
					( Origin gPackager )
				)
				( attribute "CDS_SEC" "1"
					( Origin gPackager )
				)
				( attribute "SEC" "1"
					( Origin gPackager )
				)
				( attribute "GROUP" "PCIE_RISER"
					( Origin gFrontEnd )
				)
				( objectStatus "C3P26" )
			)
			( gate "@baseboard_fab2_lib.baseboard_fab2(sch_1):page107_i486"
				( attribute "CDS_LIB" "mstr_discrete"
					( Origin gPackager )
				)
				( attribute "LOCATION" "C3P38"
					( Origin gFrontEnd )
				)
				( attribute "MATERIAL" "X7R"
					( Origin gFrontEnd )
				)
				( attribute "PACK_TYPE" "0402"
					( Origin gFrontEnd )
				)
				( attribute "PART_NUMBER" "A36096-155"
					( Origin gFrontEnd )
				)
				( attribute "PHYS_PAGE" "107"
					( Origin gFrontEnd )
				)
				( attribute "ROT" "0"
					( Origin gFrontEnd )
				)
				( attribute "TOLERANCE" "10%"
					( Origin gFrontEnd )
				)
				( attribute "VALUE" "0.22UF"
					( Origin gFrontEnd )
				)
				( attribute "VER" "1"
					( Origin gFrontEnd )
				)
				( attribute "VOLTAGE" "16V"
					( Units "uVoltage" "V" 1.000000)
					( Origin gFrontEnd )
				)
				( attribute "XY" "(-5650,2675)"
					( Origin gFrontEnd )
				)
				( attribute "CHIPS_PART_NAME" "CAP"
					( Origin gPackager )
				)
				( attribute "CDS_PART_NAME" "CAP_0402-0.22UF,16V,10%,X7R,A3A"
					( Origin gPackager )
				)
				( attribute "CDS_LOCATION" "C3P38"
					( Origin gPackager )
				)
				( attribute "CDS_SEC" "1"
					( Origin gPackager )
				)
				( attribute "SEC" "1"
					( Origin gPackager )
				)
				( attribute "GROUP" "PCIE_RISER"
					( Origin gFrontEnd )
				)
				( objectStatus "C3P38" )
			)
			( gate "@baseboard_fab2_lib.baseboard_fab2(sch_1):page107_i496"
				( attribute "CDS_LIB" "mstr_discrete"
					( Origin gPackager )
				)
				( attribute "LOCATION" "R2U25"
					( Origin gFrontEnd )
				)
				( attribute "MATERIAL" "CHIP"
					( Origin gFrontEnd )
				)
				( attribute "PACK_TYPE" "0402"
					( Origin gFrontEnd )
				)
				( attribute "PART_NUMBER" "G21497-005"
					( Origin gFrontEnd )
				)
				( attribute "PHYS_PAGE" "107"
					( Origin gFrontEnd )
				)
				( attribute "ROT" "1"
					( Origin gFrontEnd )
				)
				( attribute "TOLERANCE" "5%"
					( Origin gFrontEnd )
				)
				( attribute "VALUE" "0.0"
					( Origin gFrontEnd )
				)
				( attribute "VER" "1"
					( Origin gFrontEnd )
				)
				( attribute "WATTAGE" "1/16W"
					( Origin gFrontEnd )
				)
				( attribute "XY" "(-1825,3825)"
					( Origin gFrontEnd )
				)
				( attribute "CHIPS_PART_NAME" "RES"
					( Origin gPackager )
				)
				( attribute "CDS_PART_NAME" "RES_0402-0.0,5%,1/16W,CHIP,G21A"
					( Origin gPackager )
				)
				( attribute "CDS_LOCATION" "R2U25"
					( Origin gPackager )
				)
				( attribute "CDS_SEC" "1"
					( Origin gPackager )
				)
				( attribute "SEC" "1"
					( Origin gPackager )
				)
				( attribute "GROUP" "PCIE_RISER"
					( Origin gFrontEnd )
				)
				( objectStatus "R2U25" )
			)
			( gate "@baseboard_fab2_lib.baseboard_fab2(sch_1):page107_i495"
				( attribute "CDS_LIB" "mstr_discrete"
					( Origin gPackager )
				)
				( attribute "LOCATION" "R2U23"
					( Origin gFrontEnd )
				)
				( attribute "MATERIAL" "CHIP"
					( Origin gFrontEnd )
				)
				( attribute "PACK_TYPE" "0402"
					( Origin gFrontEnd )
				)
				( attribute "PART_NUMBER" "G21497-005"
					( Origin gFrontEnd )
				)
				( attribute "PHYS_PAGE" "107"
					( Origin gFrontEnd )
				)
				( attribute "ROT" "1"
					( Origin gFrontEnd )
				)
				( attribute "TOLERANCE" "5%"
					( Origin gFrontEnd )
				)
				( attribute "VALUE" "0.0"
					( Origin gFrontEnd )
				)
				( attribute "VER" "1"
					( Origin gFrontEnd )
				)
				( attribute "WATTAGE" "1/16W"
					( Origin gFrontEnd )
				)
				( attribute "XY" "(-1625,4125)"
					( Origin gFrontEnd )
				)
				( attribute "CHIPS_PART_NAME" "RES"
					( Origin gPackager )
				)
				( attribute "CDS_PART_NAME" "RES_0402-0.0,5%,1/16W,CHIP,G21A"
					( Origin gPackager )
				)
				( attribute "CDS_LOCATION" "R2U23"
					( Origin gPackager )
				)
				( attribute "CDS_SEC" "1"
					( Origin gPackager )
				)
				( attribute "SEC" "1"
					( Origin gPackager )
				)
				( attribute "GROUP" "PCIE_RISER"
					( Origin gFrontEnd )
				)
				( objectStatus "R2U23" )
			)
			( gate "@baseboard_fab2_lib.baseboard_fab2(sch_1):page107_i494"
				( attribute "CDS_LIB" "mstr_discrete"
					( Origin gPackager )
				)
				( attribute "LOCATION" "R2U29"
					( Origin gFrontEnd )
				)
				( attribute "MATERIAL" "CHIP"
					( Origin gFrontEnd )
				)
				( attribute "PACK_TYPE" "0402"
					( Origin gFrontEnd )
				)
				( attribute "PART_NUMBER" "G21497-005"
					( Origin gFrontEnd )
				)
				( attribute "PHYS_PAGE" "107"
					( Origin gFrontEnd )
				)
				( attribute "ROT" "1"
					( Origin gFrontEnd )
				)
				( attribute "TOLERANCE" "5%"
					( Origin gFrontEnd )
				)
				( attribute "VALUE" "0.0"
					( Origin gFrontEnd )
				)
				( attribute "VER" "1"
					( Origin gFrontEnd )
				)
				( attribute "WATTAGE" "1/16W"
					( Origin gFrontEnd )
				)
				( attribute "XY" "(-2225,3825)"
					( Origin gFrontEnd )
				)
				( attribute "CHIPS_PART_NAME" "RES"
					( Origin gPackager )
				)
				( attribute "CDS_PART_NAME" "RES_0402-0.0,5%,1/16W,CHIP,G21A"
					( Origin gPackager )
				)
				( attribute "CDS_LOCATION" "R2U29"
					( Origin gPackager )
				)
				( attribute "CDS_SEC" "1"
					( Origin gPackager )
				)
				( attribute "SEC" "1"
					( Origin gPackager )
				)
				( attribute "GROUP" "PCIE_RISER"
					( Origin gFrontEnd )
				)
				( objectStatus "R2U29" )
			)
			( gate "@baseboard_fab2_lib.baseboard_fab2(sch_1):page107_i485"
				( attribute "CDS_LIB" "mstr_discrete"
					( Origin gPackager )
				)
				( attribute "LOCATION" "C3P19"
					( Origin gFrontEnd )
				)
				( attribute "MATERIAL" "X7R"
					( Origin gFrontEnd )
				)
				( attribute "PACK_TYPE" "0402"
					( Origin gFrontEnd )
				)
				( attribute "PART_NUMBER" "A36096-155"
					( Origin gFrontEnd )
				)
				( attribute "PHYS_PAGE" "107"
					( Origin gFrontEnd )
				)
				( attribute "ROT" "0"
					( Origin gFrontEnd )
				)
				( attribute "TOLERANCE" "10%"
					( Origin gFrontEnd )
				)
				( attribute "VALUE" "0.22UF"
					( Origin gFrontEnd )
				)
				( attribute "VER" "1"
					( Origin gFrontEnd )
				)
				( attribute "VOLTAGE" "16V"
					( Units "uVoltage" "V" 1.000000)
					( Origin gFrontEnd )
				)
				( attribute "XY" "(-4650,2975)"
					( Origin gFrontEnd )
				)
				( attribute "CHIPS_PART_NAME" "CAP"
					( Origin gPackager )
				)
				( attribute "CDS_PART_NAME" "CAP_0402-0.22UF,16V,10%,X7R,A3A"
					( Origin gPackager )
				)
				( attribute "CDS_LOCATION" "C3P19"
					( Origin gPackager )
				)
				( attribute "CDS_SEC" "1"
					( Origin gPackager )
				)
				( attribute "SEC" "1"
					( Origin gPackager )
				)
				( attribute "GROUP" "PCIE_RISER"
					( Origin gFrontEnd )
				)
				( objectStatus "C3P19" )
			)
			( gate "@baseboard_fab2_lib.baseboard_fab2(sch_1):page107_i484"
				( attribute "CDS_LIB" "mstr_discrete"
					( Origin gPackager )
				)
				( attribute "LOCATION" "C3P22"
					( Origin gFrontEnd )
				)
				( attribute "MATERIAL" "X7R"
					( Origin gFrontEnd )
				)
				( attribute "PACK_TYPE" "0402"
					( Origin gFrontEnd )
				)
				( attribute "PART_NUMBER" "A36096-155"
					( Origin gFrontEnd )
				)
				( attribute "PHYS_PAGE" "107"
					( Origin gFrontEnd )
				)
				( attribute "ROT" "0"
					( Origin gFrontEnd )
				)
				( attribute "TOLERANCE" "10%"
					( Origin gFrontEnd )
				)
				( attribute "VALUE" "0.22UF"
					( Origin gFrontEnd )
				)
				( attribute "VER" "1"
					( Origin gFrontEnd )
				)
				( attribute "VOLTAGE" "16V"
					( Units "uVoltage" "V" 1.000000)
					( Origin gFrontEnd )
				)
				( attribute "XY" "(-4850,2675)"
					( Origin gFrontEnd )
				)
				( attribute "CHIPS_PART_NAME" "CAP"
					( Origin gPackager )
				)
				( attribute "CDS_PART_NAME" "CAP_0402-0.22UF,16V,10%,X7R,A3A"
					( Origin gPackager )
				)
				( attribute "CDS_LOCATION" "C3P22"
					( Origin gPackager )
				)
				( attribute "CDS_SEC" "1"
					( Origin gPackager )
				)
				( attribute "SEC" "1"
					( Origin gPackager )
				)
				( attribute "GROUP" "PCIE_RISER"
					( Origin gFrontEnd )
				)
				( objectStatus "C3P22" )
			)
			( gate "@baseboard_fab2_lib.baseboard_fab2(sch_1):page107_i483"
				( attribute "CDS_LIB" "mstr_discrete"
					( Origin gPackager )
				)
				( attribute "LOCATION" "C3P14"
					( Origin gFrontEnd )
				)
				( attribute "MATERIAL" "X7R"
					( Origin gFrontEnd )
				)
				( attribute "PACK_TYPE" "0402"
					( Origin gFrontEnd )
				)
				( attribute "PART_NUMBER" "A36096-155"
					( Origin gFrontEnd )
				)
				( attribute "PHYS_PAGE" "107"
					( Origin gFrontEnd )
				)
				( attribute "ROT" "0"
					( Origin gFrontEnd )
				)
				( attribute "TOLERANCE" "10%"
					( Origin gFrontEnd )
				)
				( attribute "VALUE" "0.22UF"
					( Origin gFrontEnd )
				)
				( attribute "VER" "1"
					( Origin gFrontEnd )
				)
				( attribute "VOLTAGE" "16V"
					( Units "uVoltage" "V" 1.000000)
					( Origin gFrontEnd )
				)
				( attribute "XY" "(-4450,2675)"
					( Origin gFrontEnd )
				)
				( attribute "CHIPS_PART_NAME" "CAP"
					( Origin gPackager )
				)
				( attribute "CDS_PART_NAME" "CAP_0402-0.22UF,16V,10%,X7R,A3A"
					( Origin gPackager )
				)
				( attribute "CDS_LOCATION" "C3P14"
					( Origin gPackager )
				)
				( attribute "CDS_SEC" "1"
					( Origin gPackager )
				)
				( attribute "SEC" "1"
					( Origin gPackager )
				)
				( attribute "GROUP" "PCIE_RISER"
					( Origin gFrontEnd )
				)
				( objectStatus "C3P14" )
			)
			( gate "@baseboard_fab2_lib.baseboard_fab2(sch_1):page107_i493"
				( attribute "CDS_LIB" "mstr_discrete"
					( Origin gPackager )
				)
				( attribute "LOCATION" "R2U19"
					( Origin gFrontEnd )
				)
				( attribute "MATERIAL" "CHIP"
					( Origin gFrontEnd )
				)
				( attribute "PACK_TYPE" "0402"
					( Origin gFrontEnd )
				)
				( attribute "PART_NUMBER" "G21497-005"
					( Origin gFrontEnd )
				)
				( attribute "PHYS_PAGE" "107"
					( Origin gFrontEnd )
				)
				( attribute "ROT" "1"
					( Origin gFrontEnd )
				)
				( attribute "TOLERANCE" "5%"
					( Origin gFrontEnd )
				)
				( attribute "VALUE" "0.0"
					( Origin gFrontEnd )
				)
				( attribute "VER" "1"
					( Origin gFrontEnd )
				)
				( attribute "WATTAGE" "1/16W"
					( Origin gFrontEnd )
				)
				( attribute "XY" "(-1225,4125)"
					( Origin gFrontEnd )
				)
				( attribute "CHIPS_PART_NAME" "RES"
					( Origin gPackager )
				)
				( attribute "CDS_PART_NAME" "RES_0402-0.0,5%,1/16W,CHIP,G21A"
					( Origin gPackager )
				)
				( attribute "CDS_LOCATION" "R2U19"
					( Origin gPackager )
				)
				( attribute "CDS_SEC" "1"
					( Origin gPackager )
				)
				( attribute "SEC" "1"
					( Origin gPackager )
				)
				( attribute "GROUP" "PCIE_RISER"
					( Origin gFrontEnd )
				)
				( objectStatus "R2U19" )
			)
			( gate "@baseboard_fab2_lib.baseboard_fab2(sch_1):page107_i492"
				( attribute "CDS_LIB" "mstr_discrete"
					( Origin gPackager )
				)
				( attribute "LOCATION" "R2U17"
					( Origin gFrontEnd )
				)
				( attribute "MATERIAL" "CHIP"
					( Origin gFrontEnd )
				)
				( attribute "PACK_TYPE" "0402"
					( Origin gFrontEnd )
				)
				( attribute "PART_NUMBER" "G21497-005"
					( Origin gFrontEnd )
				)
				( attribute "PHYS_PAGE" "107"
					( Origin gFrontEnd )
				)
				( attribute "ROT" "1"
					( Origin gFrontEnd )
				)
				( attribute "TOLERANCE" "5%"
					( Origin gFrontEnd )
				)
				( attribute "VALUE" "0.0"
					( Origin gFrontEnd )
				)
				( attribute "VER" "1"
					( Origin gFrontEnd )
				)
				( attribute "WATTAGE" "1/16W"
					( Origin gFrontEnd )
				)
				( attribute "XY" "(-1025,3825)"
					( Origin gFrontEnd )
				)
				( attribute "CHIPS_PART_NAME" "RES"
					( Origin gPackager )
				)
				( attribute "CDS_PART_NAME" "RES_0402-0.0,5%,1/16W,CHIP,G21A"
					( Origin gPackager )
				)
				( attribute "CDS_LOCATION" "R2U17"
					( Origin gPackager )
				)
				( attribute "CDS_SEC" "1"
					( Origin gPackager )
				)
				( attribute "SEC" "1"
					( Origin gPackager )
				)
				( attribute "GROUP" "PCIE_RISER"
					( Origin gFrontEnd )
				)
				( objectStatus "R2U17" )
			)
			( gate "@baseboard_fab2_lib.baseboard_fab2(sch_1):page107_i482"
				( attribute "CDS_LIB" "mstr_discrete"
					( Origin gPackager )
				)
				( attribute "LOCATION" "C3P10"
					( Origin gFrontEnd )
				)
				( attribute "MATERIAL" "X7R"
					( Origin gFrontEnd )
				)
				( attribute "PACK_TYPE" "0402"
					( Origin gFrontEnd )
				)
				( attribute "PART_NUMBER" "A36096-155"
					( Origin gFrontEnd )
				)
				( attribute "PHYS_PAGE" "107"
					( Origin gFrontEnd )
				)
				( attribute "ROT" "0"
					( Origin gFrontEnd )
				)
				( attribute "TOLERANCE" "10%"
					( Origin gFrontEnd )
				)
				( attribute "VALUE" "0.22UF"
					( Origin gFrontEnd )
				)
				( attribute "VER" "1"
					( Origin gFrontEnd )
				)
				( attribute "VOLTAGE" "16V"
					( Units "uVoltage" "V" 1.000000)
					( Origin gFrontEnd )
				)
				( attribute "XY" "(-4250,2975)"
					( Origin gFrontEnd )
				)
				( attribute "CHIPS_PART_NAME" "CAP"
					( Origin gPackager )
				)
				( attribute "CDS_PART_NAME" "CAP_0402-0.22UF,16V,10%,X7R,A3A"
					( Origin gPackager )
				)
				( attribute "CDS_LOCATION" "C3P10"
					( Origin gPackager )
				)
				( attribute "CDS_SEC" "1"
					( Origin gPackager )
				)
				( attribute "SEC" "1"
					( Origin gPackager )
				)
				( attribute "GROUP" "PCIE_RISER"
					( Origin gFrontEnd )
				)
				( objectStatus "C3P10" )
			)
			( gate "@baseboard_fab2_lib.baseboard_fab2(sch_1):page107_i491"
				( attribute "CDS_LIB" "mstr_discrete"
					( Origin gPackager )
				)
				( attribute "LOCATION" "R2U21"
					( Origin gFrontEnd )
				)
				( attribute "MATERIAL" "CHIP"
					( Origin gFrontEnd )
				)
				( attribute "PACK_TYPE" "0402"
					( Origin gFrontEnd )
				)
				( attribute "PART_NUMBER" "G21497-005"
					( Origin gFrontEnd )
				)
				( attribute "PHYS_PAGE" "107"
					( Origin gFrontEnd )
				)
				( attribute "ROT" "1"
					( Origin gFrontEnd )
				)
				( attribute "TOLERANCE" "5%"
					( Origin gFrontEnd )
				)
				( attribute "VALUE" "0.0"
					( Origin gFrontEnd )
				)
				( attribute "VER" "1"
					( Origin gFrontEnd )
				)
				( attribute "WATTAGE" "1/16W"
					( Origin gFrontEnd )
				)
				( attribute "XY" "(-1425,3825)"
					( Origin gFrontEnd )
				)
				( attribute "CHIPS_PART_NAME" "RES"
					( Origin gPackager )
				)
				( attribute "CDS_PART_NAME" "RES_0402-0.0,5%,1/16W,CHIP,G21A"
					( Origin gPackager )
				)
				( attribute "CDS_LOCATION" "R2U21"
					( Origin gPackager )
				)
				( attribute "CDS_SEC" "1"
					( Origin gPackager )
				)
				( attribute "SEC" "1"
					( Origin gPackager )
				)
				( attribute "GROUP" "PCIE_RISER"
					( Origin gFrontEnd )
				)
				( objectStatus "R2U21" )
			)
			( gate "@baseboard_fab2_lib.baseboard_fab2(sch_1):page107_i490"
				( attribute "CDS_LIB" "mstr_discrete"
					( Origin gPackager )
				)
				( attribute "LOCATION" "R2U15"
					( Origin gFrontEnd )
				)
				( attribute "MATERIAL" "CHIP"
					( Origin gFrontEnd )
				)
				( attribute "PACK_TYPE" "0402"
					( Origin gFrontEnd )
				)
				( attribute "PART_NUMBER" "G21497-005"
					( Origin gFrontEnd )
				)
				( attribute "PHYS_PAGE" "107"
					( Origin gFrontEnd )
				)
				( attribute "ROT" "1"
					( Origin gFrontEnd )
				)
				( attribute "TOLERANCE" "5%"
					( Origin gFrontEnd )
				)
				( attribute "VALUE" "0.0"
					( Origin gFrontEnd )
				)
				( attribute "VER" "1"
					( Origin gFrontEnd )
				)
				( attribute "WATTAGE" "1/16W"
					( Origin gFrontEnd )
				)
				( attribute "XY" "(-825,4125)"
					( Origin gFrontEnd )
				)
				( attribute "CHIPS_PART_NAME" "RES"
					( Origin gPackager )
				)
				( attribute "CDS_PART_NAME" "RES_0402-0.0,5%,1/16W,CHIP,G21A"
					( Origin gPackager )
				)
				( attribute "CDS_LOCATION" "R2U15"
					( Origin gPackager )
				)
				( attribute "CDS_SEC" "1"
					( Origin gPackager )
				)
				( attribute "SEC" "1"
					( Origin gPackager )
				)
				( attribute "GROUP" "PCIE_RISER"
					( Origin gFrontEnd )
				)
				( objectStatus "R2U15" )
			)
			( gate "@baseboard_fab2_lib.baseboard_fab2(sch_1):page211_i96"
				( attribute "CDS_LIB" "mstr_discrete"
					( Origin gPackager )
				)
				( attribute "LOCATION" "RF13"
					( Origin gFrontEnd )
				)
				( attribute "MATERIAL" "CHIP"
					( Origin gFrontEnd )
				)
				( attribute "PACK_TYPE" "0402"
					( Origin gFrontEnd )
				)
				( attribute "PART_NUMBER" "G85996-004"
					( Origin gFrontEnd )
				)
				( attribute "PHYS_PAGE" "211"
					( Origin gFrontEnd )
				)
				( attribute "ROOM" "SB"
					( Origin gFrontEnd )
				)
				( attribute "ROT" "0"
					( Origin gFrontEnd )
				)
				( attribute "TOLERANCE" "0.1%"
					( Origin gFrontEnd )
				)
				( attribute "VALUE" "1.0K"
					( Origin gFrontEnd )
				)
				( attribute "VER" "1"
					( Origin gFrontEnd )
				)
				( attribute "WATTAGE" "1/16W"
					( Origin gFrontEnd )
				)
				( attribute "XY" "(-1975,3750)"
					( Origin gFrontEnd )
				)
				( attribute "CHIPS_PART_NAME" "RES"
					( Origin gPackager )
				)
				( attribute "CDS_PART_NAME" "RES_0402-1.0K,0.1%,1/16W,CHIP,A"
					( Origin gPackager )
				)
				( attribute "CDS_LOCATION" "RF13"
					( Origin gPackager )
				)
				( attribute "SEC" "1"
					( Origin gFrontEnd )
				)
				( attribute "SEC_TYPE" "0402"
					( Origin gFrontEnd )
				)
				( attribute "CDS_SEC" "1"
					( Origin gPackager )
				)
				( attribute "GROUP" "POWER_FAIR"
					( Origin gFrontEnd )
				)
				( objectStatus "RF13" )
			)
			( gate "@baseboard_fab2_lib.baseboard_fab2(sch_1):page221_i2"
				( attribute "BOM_COST" "MEM_VRD_VTT_ABC"
					( Origin gFrontEnd )
				)
				( attribute "CDS_LIB" "mstr_discrete"
					( Origin gPackager )
				)
				( attribute "CDS_LOCATION" "C4G23"
					( Origin gPackager )
				)
				( attribute "CDS_SEC" "1"
					( Origin gPackager )
				)
				( attribute "LOCATION" "C4G23"
					( Origin gFrontEnd )
				)
				( attribute "MATERIAL" "EMPTY"
					( Origin gFrontEnd )
				)
				( attribute "PACK_TYPE" "0402LF"
					( Origin gFrontEnd )
				)
				( attribute "PART_NUMBER" "A36096-046"
					( Origin gFrontEnd )
				)
				( attribute "PHYS_PAGE" "221"
					( Origin gFrontEnd )
				)
				( attribute "ROOM" "VTT_ABC_PWR_VR"
					( Origin gFrontEnd )
				)
				( attribute "ROT" "2"
					( Origin gFrontEnd )
				)
				( attribute "SEC" "1"
					( Origin gFrontEnd )
				)
				( attribute "SEC_TYPE" "0402LF"
					( Origin gFrontEnd )
				)
				( attribute "TOLERANCE" "10%"
					( Origin gFrontEnd )
				)
				( attribute "VALUE" "1000PF"
					( Origin gFrontEnd )
				)
				( attribute "VER" "1"
					( Origin gFrontEnd )
				)
				( attribute "VOLTAGE" "50V"
					( Units "uVoltage" "V" 1.000000)
					( Origin gFrontEnd )
				)
				( attribute "XY" "(-650,-475)"
					( Origin gFrontEnd )
				)
				( attribute "CHIPS_PART_NAME" "CAP"
					( Origin gPackager )
				)
				( attribute "CDS_PART_NAME" "CAP_0402LF-1000PF,50V,10%,EMPTA"
					( Origin gPackager )
				)
				( objectStatus "C4G23" )
			)
			( gate "@baseboard_fab2_lib.baseboard_fab2(sch_1):page108_i1"
				( attribute "CDS_LIB" "dev_discrete"
					( Origin gPackager )
				)
				( attribute "CDS_LOCATION" "C2U20"
					( Origin gPackager )
				)
				( attribute "CDS_SEC" "1"
					( Origin gPackager )
				)
				( attribute "LOCATION" "C2U20"
					( Origin gFrontEnd )
				)
				( attribute "MATERIAL" "X7R"
					( Origin gFrontEnd )
				)
				( attribute "PACK_TYPE" "0402V"
					( Origin gFrontEnd )
				)
				( attribute "PART_NUMBER" "A36096-030"
					( Origin gFrontEnd )
				)
				( attribute "PHYS_PAGE" "108"
					( Origin gFrontEnd )
				)
				( attribute "ROOM" "IO_SLOT"
					( Origin gFrontEnd )
				)
				( attribute "ROT" "0"
					( Origin gFrontEnd )
				)
				( attribute "SEC" "1"
					( Origin gFrontEnd )
				)
				( attribute "SEC_TYPE" "0402V"
					( Origin gFrontEnd )
				)
				( attribute "TOLERANCE" "10%"
					( Origin gFrontEnd )
				)
				( attribute "VALUE" "0.1UF"
					( Origin gFrontEnd )
				)
				( attribute "VER" "1"
					( Origin gFrontEnd )
				)
				( attribute "VOLTAGE" "16V"
					( Units "uVoltage" "V" 1.000000)
					( Origin gFrontEnd )
				)
				( attribute "XY" "(-3275,675)"
					( Origin gFrontEnd )
				)
				( attribute "CHIPS_PART_NAME" "CAP_A"
					( Origin gPackager )
				)
				( attribute "CDS_PART_NAME" "CAP_A_0402V-0.1UF,16V,10%,X7R,A"
					( Origin gPackager )
				)
				( objectStatus "C2U20" )
			)
			( gate "@baseboard_fab2_lib.baseboard_fab2(sch_1):page108_i2"
				( attribute "CDS_LIB" "dev_discrete"
					( Origin gPackager )
				)
				( attribute "CDS_LOCATION" "C2U24"
					( Origin gPackager )
				)
				( attribute "CDS_SEC" "1"
					( Origin gPackager )
				)
				( attribute "LOCATION" "C2U24"
					( Origin gFrontEnd )
				)
				( attribute "MATERIAL" "X7R"
					( Origin gFrontEnd )
				)
				( attribute "PACK_TYPE" "0402V"
					( Origin gFrontEnd )
				)
				( attribute "PART_NUMBER" "A36096-030"
					( Origin gFrontEnd )
				)
				( attribute "PHYS_PAGE" "108"
					( Origin gFrontEnd )
				)
				( attribute "ROOM" "IO_SLOT"
					( Origin gFrontEnd )
				)
				( attribute "ROT" "0"
					( Origin gFrontEnd )
				)
				( attribute "SEC" "1"
					( Origin gFrontEnd )
				)
				( attribute "SEC_TYPE" "0402V"
					( Origin gFrontEnd )
				)
				( attribute "TOLERANCE" "10%"
					( Origin gFrontEnd )
				)
				( attribute "VALUE" "0.1UF"
					( Origin gFrontEnd )
				)
				( attribute "VER" "1"
					( Origin gFrontEnd )
				)
				( attribute "VOLTAGE" "16V"
					( Units "uVoltage" "V" 1.000000)
					( Origin gFrontEnd )
				)
				( attribute "XY" "(-2875,650)"
					( Origin gFrontEnd )
				)
				( attribute "CHIPS_PART_NAME" "CAP_A"
					( Origin gPackager )
				)
				( attribute "CDS_PART_NAME" "CAP_A_0402V-0.1UF,16V,10%,X7R,A"
					( Origin gPackager )
				)
				( objectStatus "C2U24" )
			)
			( gate "@baseboard_fab2_lib.baseboard_fab2(sch_1):page108_i5"
				( attribute "CDS_LIB" "dev_discrete"
					( Origin gPackager )
				)
				( attribute "CDS_LOCATION" "C2U21"
					( Origin gPackager )
				)
				( attribute "CDS_SEC" "1"
					( Origin gPackager )
				)
				( attribute "LOCATION" "C2U21"
					( Origin gFrontEnd )
				)
				( attribute "MATERIAL" "X7R"
					( Origin gFrontEnd )
				)
				( attribute "PACK_TYPE" "0402V"
					( Origin gFrontEnd )
				)
				( attribute "PART_NUMBER" "A36096-030"
					( Origin gFrontEnd )
				)
				( attribute "PHYS_PAGE" "108"
					( Origin gFrontEnd )
				)
				( attribute "ROOM" "IO_SLOT"
					( Origin gFrontEnd )
				)
				( attribute "ROT" "0"
					( Origin gFrontEnd )
				)
				( attribute "SEC" "1"
					( Origin gFrontEnd )
				)
				( attribute "SEC_TYPE" "0402V"
					( Origin gFrontEnd )
				)
				( attribute "TOLERANCE" "10%"
					( Origin gFrontEnd )
				)
				( attribute "VALUE" "0.1UF"
					( Origin gFrontEnd )
				)
				( attribute "VER" "1"
					( Origin gFrontEnd )
				)
				( attribute "VOLTAGE" "16V"
					( Units "uVoltage" "V" 1.000000)
					( Origin gFrontEnd )
				)
				( attribute "XY" "(-3275,1400)"
					( Origin gFrontEnd )
				)
				( attribute "CHIPS_PART_NAME" "CAP_A"
					( Origin gPackager )
				)
				( attribute "CDS_PART_NAME" "CAP_A_0402V-0.1UF,16V,10%,X7R,A"
					( Origin gPackager )
				)
				( objectStatus "C2U21" )
			)
			( gate "@baseboard_fab2_lib.baseboard_fab2(sch_1):page108_i7"
				( attribute "CDS_LIB" "dev_discrete"
					( Origin gPackager )
				)
				( attribute "CDS_LOCATION" "C2U25"
					( Origin gPackager )
				)
				( attribute "CDS_SEC" "1"
					( Origin gPackager )
				)
				( attribute "LOCATION" "C2U25"
					( Origin gFrontEnd )
				)
				( attribute "MATERIAL" "X7R"
					( Origin gFrontEnd )
				)
				( attribute "PACK_TYPE" "0402V"
					( Origin gFrontEnd )
				)
				( attribute "PART_NUMBER" "A36096-030"
					( Origin gFrontEnd )
				)
				( attribute "PHYS_PAGE" "108"
					( Origin gFrontEnd )
				)
				( attribute "ROOM" "IO_SLOT"
					( Origin gFrontEnd )
				)
				( attribute "ROT" "0"
					( Origin gFrontEnd )
				)
				( attribute "SEC" "1"
					( Origin gFrontEnd )
				)
				( attribute "SEC_TYPE" "0402V"
					( Origin gFrontEnd )
				)
				( attribute "TOLERANCE" "10%"
					( Origin gFrontEnd )
				)
				( attribute "VALUE" "0.1UF"
					( Origin gFrontEnd )
				)
				( attribute "VER" "1"
					( Origin gFrontEnd )
				)
				( attribute "VOLTAGE" "16V"
					( Units "uVoltage" "V" 1.000000)
					( Origin gFrontEnd )
				)
				( attribute "XY" "(-2875,1375)"
					( Origin gFrontEnd )
				)
				( attribute "CHIPS_PART_NAME" "CAP_A"
					( Origin gPackager )
				)
				( attribute "CDS_PART_NAME" "CAP_A_0402V-0.1UF,16V,10%,X7R,A"
					( Origin gPackager )
				)
				( objectStatus "C2U25" )
			)
			( gate "@baseboard_fab2_lib.baseboard_fab2(sch_1):page108_i173"
				( attribute "CDS_LIB" "mstr_discrete"
					( Origin gPackager )
				)
				( attribute "CDS_LOCATION" "R2U37"
					( Origin gPackager )
				)
				( attribute "CDS_SEC" "1"
					( Origin gPackager )
				)
				( attribute "LOCATION" "R2U37"
					( Origin gFrontEnd )
				)
				( attribute "MATERIAL" "CHIP"
					( Origin gFrontEnd )
				)
				( attribute "PACK_TYPE" "0402"
					( Origin gFrontEnd )
				)
				( attribute "PART_NUMBER" "G21497-005"
					( Origin gFrontEnd )
				)
				( attribute "PHYS_PAGE" "108"
					( Origin gFrontEnd )
				)
				( attribute "ROOM" "IO_SLOT"
					( Origin gFrontEnd )
				)
				( attribute "ROT" "0"
					( Origin gFrontEnd )
				)
				( attribute "SEC" "1"
					( Origin gFrontEnd )
				)
				( attribute "SEC_TYPE" "0402"
					( Origin gFrontEnd )
				)
				( attribute "TOLERANCE" "5%"
					( Origin gFrontEnd )
				)
				( attribute "VALUE" "0.0"
					( Origin gFrontEnd )
				)
				( attribute "VER" "1"
					( Origin gFrontEnd )
				)
				( attribute "WATTAGE" "1/16W"
					( Origin gFrontEnd )
				)
				( attribute "XY" "(-1100,3625)"
					( Origin gFrontEnd )
				)
				( attribute "CHIPS_PART_NAME" "RES"
					( Origin gPackager )
				)
				( attribute "CDS_PART_NAME" "RES_0402-0.0,5%,1/16W,CHIP,G21A"
					( Origin gPackager )
				)
				( objectStatus "R2U37" )
			)
			( gate "@baseboard_fab2_lib.baseboard_fab2(sch_1):page108_i258"
				( attribute "CDS_LIB" "mstr_sconn"
					( Origin gPackager )
				)
				( attribute "CDS_LMAN_SYM_OUTLINE" "-250,1350,250,-1350"
					( Origin gPackager )
				)
				( attribute "CDS_LOCATION" "J8G1"
					( Origin gPackager )
				)
				( attribute "LOCATION" "J8G1"
					( Origin gFrontEnd )
				)
				( attribute "MATERIAL" "CONN"
					( Origin gFrontEnd )
				)
				( attribute "PACK_TYPE" "SM"
					( Origin gFrontEnd )
				)
				( attribute "PART_NUMBER" "H68296-001"
					( Origin gFrontEnd )
				)
				( attribute "PHYS_PAGE" "108"
					( Origin gFrontEnd )
				)
				( attribute "ROOM" "IO_SLOT"
					( Origin gFrontEnd )
				)
				( attribute "ROT" "0"
					( Origin gFrontEnd )
				)
				( attribute "SEC" "1"
					( Origin gFrontEnd )
				)
				( attribute "SEC_TYPE" "SM"
					( Origin gFrontEnd )
				)
				( attribute "VER" "1"
					( Origin gFrontEnd )
				)
				( attribute "XY" "(500,3075)"
					( Origin gFrontEnd )
				)
				( attribute "CHIPS_PART_NAME" "SCONN200_H68296001"
					( Origin gPackager )
				)
				( attribute "CDS_PART_NAME" "SCONN200_H68296001_SM-CONN,H68A"
					( Origin gPackager )
				)
				( attribute "CDS_SEC" "1"
					( Origin gPackager )
				)
				( objectStatus "J8G1" )
			)
			( gate "@baseboard_fab2_lib.baseboard_fab2(sch_1):page108_i315"
				( attribute "CDS_LIB" "dev_discrete"
					( Origin gPackager )
				)
				( attribute "CDS_LOCATION" "C2U23"
					( Origin gPackager )
				)
				( attribute "CDS_SEC" "1"
					( Origin gPackager )
				)
				( attribute "LOCATION" "C2U23"
					( Origin gFrontEnd )
				)
				( attribute "MATERIAL" "X7R"
					( Origin gFrontEnd )
				)
				( attribute "PACK_TYPE" "0402V"
					( Origin gFrontEnd )
				)
				( attribute "PART_NUMBER" "A36096-030"
					( Origin gFrontEnd )
				)
				( attribute "PHYS_PAGE" "108"
					( Origin gFrontEnd )
				)
				( attribute "ROOM" "IO_SLOT"
					( Origin gFrontEnd )
				)
				( attribute "ROT" "0"
					( Origin gFrontEnd )
				)
				( attribute "SEC" "1"
					( Origin gFrontEnd )
				)
				( attribute "SEC_TYPE" "0402V"
					( Origin gFrontEnd )
				)
				( attribute "TOLERANCE" "10%"
					( Origin gFrontEnd )
				)
				( attribute "VALUE" "0.1UF"
					( Origin gFrontEnd )
				)
				( attribute "VER" "1"
					( Origin gFrontEnd )
				)
				( attribute "VOLTAGE" "16V"
					( Units "uVoltage" "V" 1.000000)
					( Origin gFrontEnd )
				)
				( attribute "XY" "(-1950,1350)"
					( Origin gFrontEnd )
				)
				( attribute "CHIPS_PART_NAME" "CAP_A"
					( Origin gPackager )
				)
				( attribute "CDS_PART_NAME" "CAP_A_0402V-0.1UF,16V,10%,X7R,A"
					( Origin gPackager )
				)
				( objectStatus "C2U23" )
			)
			( gate "@baseboard_fab2_lib.baseboard_fab2(sch_1):page108_i318"
				( attribute "CDS_LIB" "dev_discrete"
					( Origin gPackager )
				)
				( attribute "CDS_LOCATION" "C2U22"
					( Origin gPackager )
				)
				( attribute "CDS_SEC" "1"
					( Origin gPackager )
				)
				( attribute "LOCATION" "C2U22"
					( Origin gFrontEnd )
				)
				( attribute "MATERIAL" "X7R"
					( Origin gFrontEnd )
				)
				( attribute "PACK_TYPE" "0402V"
					( Origin gFrontEnd )
				)
				( attribute "PART_NUMBER" "A36096-030"
					( Origin gFrontEnd )
				)
				( attribute "PHYS_PAGE" "108"
					( Origin gFrontEnd )
				)
				( attribute "ROOM" "IO_SLOT"
					( Origin gFrontEnd )
				)
				( attribute "ROT" "0"
					( Origin gFrontEnd )
				)
				( attribute "SEC" "1"
					( Origin gFrontEnd )
				)
				( attribute "SEC_TYPE" "0402V"
					( Origin gFrontEnd )
				)
				( attribute "TOLERANCE" "10%"
					( Origin gFrontEnd )
				)
				( attribute "VALUE" "0.1UF"
					( Origin gFrontEnd )
				)
				( attribute "VER" "1"
					( Origin gFrontEnd )
				)
				( attribute "VOLTAGE" "16V"
					( Units "uVoltage" "V" 1.000000)
					( Origin gFrontEnd )
				)
				( attribute "XY" "(-2350,1375)"
					( Origin gFrontEnd )
				)
				( attribute "CHIPS_PART_NAME" "CAP_A"
					( Origin gPackager )
				)
				( attribute "CDS_PART_NAME" "CAP_A_0402V-0.1UF,16V,10%,X7R,A"
					( Origin gPackager )
				)
				( objectStatus "C2U22" )
			)
			( gate "@baseboard_fab2_lib.baseboard_fab2(sch_1):page108_i330"
				( attribute "BOM_COST" "SM_CONTROLLER"
					( Origin gFrontEnd )
				)
				( attribute "CDS_LIB" "mstr_discrete"
					( Origin gPackager )
				)
				( attribute "CDS_LOCATION" "R2U31"
					( Origin gPackager )
				)
				( attribute "CDS_SEC" "1"
					( Origin gPackager )
				)
				( attribute "LOCATION" "R2U31"
					( Origin gFrontEnd )
				)
				( attribute "MATERIAL" "CHIP"
					( Origin gFrontEnd )
				)
				( attribute "PACK_TYPE" "0402"
					( Origin gFrontEnd )
				)
				( attribute "PART_NUMBER" "G21796-173"
					( Origin gFrontEnd )
				)
				( attribute "PHYS_PAGE" "108"
					( Origin gFrontEnd )
				)
				( attribute "ROOM" "SMBUS"
					( Origin gFrontEnd )
				)
				( attribute "ROT" "0"
					( Origin gFrontEnd )
				)
				( attribute "SEC" "1"
					( Origin gPackager )
				)
				( attribute "SKU" "B"
					( Origin gFrontEnd )
				)
				( attribute "TOLERANCE" "1%"
					( Origin gFrontEnd )
				)
				( attribute "VALUE" "20.0"
					( Origin gFrontEnd )
				)
				( attribute "VER" "1"
					( Origin gFrontEnd )
				)
				( attribute "WATTAGE" "1/16W"
					( Origin gFrontEnd )
				)
				( attribute "XY" "(-2275,4500)"
					( Origin gFrontEnd )
				)
				( attribute "CHIPS_PART_NAME" "RES"
					( Origin gPackager )
				)
				( attribute "CDS_PART_NAME" "RES_0402-20.0,1%,1/16W,CHIP,G2A"
					( Origin gPackager )
				)
				( objectStatus "R2U31" )
			)
			( gate "@baseboard_fab2_lib.baseboard_fab2(sch_1):page108_i339"
				( attribute "BOM_COST" "SM_CONTROLLER"
					( Origin gFrontEnd )
				)
				( attribute "CDS_LIB" "mstr_discrete"
					( Origin gPackager )
				)
				( attribute "CDS_LOCATION" "R2U32"
					( Origin gPackager )
				)
				( attribute "CDS_SEC" "1"
					( Origin gPackager )
				)
				( attribute "LOCATION" "R2U32"
					( Origin gFrontEnd )
				)
				( attribute "MATERIAL" "CHIP"
					( Origin gFrontEnd )
				)
				( attribute "PACK_TYPE" "0402"
					( Origin gFrontEnd )
				)
				( attribute "PART_NUMBER" "G21796-173"
					( Origin gFrontEnd )
				)
				( attribute "PHYS_PAGE" "108"
					( Origin gFrontEnd )
				)
				( attribute "ROOM" "SMBUS"
					( Origin gFrontEnd )
				)
				( attribute "ROT" "0"
					( Origin gFrontEnd )
				)
				( attribute "SEC" "1"
					( Origin gPackager )
				)
				( attribute "SKU" "B"
					( Origin gFrontEnd )
				)
				( attribute "TOLERANCE" "1%"
					( Origin gFrontEnd )
				)
				( attribute "VALUE" "20.0"
					( Origin gFrontEnd )
				)
				( attribute "VER" "1"
					( Origin gFrontEnd )
				)
				( attribute "WATTAGE" "1/16W"
					( Origin gFrontEnd )
				)
				( attribute "XY" "(-2275,4250)"
					( Origin gFrontEnd )
				)
				( attribute "CHIPS_PART_NAME" "RES"
					( Origin gPackager )
				)
				( attribute "CDS_PART_NAME" "RES_0402-20.0,1%,1/16W,CHIP,G2A"
					( Origin gPackager )
				)
				( objectStatus "R2U32" )
			)
			( gate "@baseboard_fab2_lib.baseboard_fab2(sch_1):page108_i341"
				( attribute "CDS_LIB" "mstr_discrete"
					( Origin gPackager )
				)
				( attribute "CDS_LOCATION" "R7E22"
					( Origin gPackager )
				)
				( attribute "CDS_SEC" "1"
					( Origin gPackager )
				)
				( attribute "LOCATION" "R7E22"
					( Origin gFrontEnd )
				)
				( attribute "MATERIAL" "CHIP"
					( Origin gFrontEnd )
				)
				( attribute "PACK_TYPE" "0402"
					( Origin gFrontEnd )
				)
				( attribute "PART_NUMBER" "G21497-005"
					( Origin gFrontEnd )
				)
				( attribute "PHYS_PAGE" "108"
					( Origin gFrontEnd )
				)
				( attribute "ROOM" "IO_SLOT"
					( Origin gFrontEnd )
				)
				( attribute "ROT" "0"
					( Origin gFrontEnd )
				)
				( attribute "SEC" "1"
					( Origin gFrontEnd )
				)
				( attribute "SEC_TYPE" "0402"
					( Origin gFrontEnd )
				)
				( attribute "TOLERANCE" "5%"
					( Origin gFrontEnd )
				)
				( attribute "VALUE" "0.0"
					( Origin gFrontEnd )
				)
				( attribute "VER" "1"
					( Origin gFrontEnd )
				)
				( attribute "WATTAGE" "1/16W"
					( Origin gFrontEnd )
				)
				( attribute "XY" "(2600,3775)"
					( Origin gFrontEnd )
				)
				( attribute "CHIPS_PART_NAME" "RES"
					( Origin gPackager )
				)
				( attribute "CDS_PART_NAME" "RES_0402-0.0,5%,1/16W,CHIP,G21A"
					( Origin gPackager )
				)
				( objectStatus "R7E22" )
			)
			( gate "@baseboard_fab2_lib.baseboard_fab2(sch_1):page108_i343"
				( attribute "CDS_LIB" "mstr_discrete"
					( Origin gPackager )
				)
				( attribute "CDS_LOCATION" "R7E21"
					( Origin gPackager )
				)
				( attribute "CDS_SEC" "1"
					( Origin gPackager )
				)
				( attribute "LOCATION" "R7E21"
					( Origin gFrontEnd )
				)
				( attribute "MATERIAL" "CHIP"
					( Origin gFrontEnd )
				)
				( attribute "PACK_TYPE" "0402"
					( Origin gFrontEnd )
				)
				( attribute "PART_NUMBER" "G21796-072"
					( Origin gFrontEnd )
				)
				( attribute "PHYS_PAGE" "108"
					( Origin gFrontEnd )
				)
				( attribute "ROOM" "IO_SLOT"
					( Origin gFrontEnd )
				)
				( attribute "ROT" "0"
					( Origin gFrontEnd )
				)
				( attribute "SEC" "1"
					( Origin gFrontEnd )
				)
				( attribute "SEC_TYPE" "0402"
					( Origin gFrontEnd )
				)
				( attribute "TOLERANCE" "1%"
					( Origin gFrontEnd )
				)
				( attribute "VALUE" "4.75K"
					( Origin gFrontEnd )
				)
				( attribute "VER" "2"
					( Origin gFrontEnd )
				)
				( attribute "WATTAGE" "1/16W"
					( Origin gFrontEnd )
				)
				( attribute "XY" "(2350,4200)"
					( Origin gFrontEnd )
				)
				( attribute "CHIPS_PART_NAME" "RES"
					( Origin gPackager )
				)
				( attribute "CDS_PART_NAME" "RES_0402-4.75K,1%,1/16W,CHIP,GA"
					( Origin gPackager )
				)
				( objectStatus "R7E21" )
			)
			( gate "@baseboard_fab2_lib.baseboard_fab2(sch_1):page111_i6"
				( attribute "BOM_COST" "DEBUG"
					( Origin gFrontEnd )
				)
				( attribute "CDS_LIB" "mstr_discrete"
					( Origin gPackager )
				)
				( attribute "CDS_LOCATION" "R1L13"
					( Origin gPackager )
				)
				( attribute "CDS_SEC" "1"
					( Origin gPackager )
				)
				( attribute "LOCATION" "R1L13"
					( Origin gFrontEnd )
				)
				( attribute "MATERIAL" "CHIP"
					( Origin gFrontEnd )
				)
				( attribute "PACK_TYPE" "0402"
					( Origin gFrontEnd )
				)
				( attribute "PART_NUMBER" "G21796-026"
					( Origin gFrontEnd )
				)
				( attribute "PHYS_PAGE" "111"
					( Origin gFrontEnd )
				)
				( attribute "ROOM" "DEBUG"
					( Origin gFrontEnd )
				)
				( attribute "ROT" "0"
					( Origin gFrontEnd )
				)
				( attribute "SEC" "1"
					( Origin gFrontEnd )
				)
				( attribute "SEC_TYPE" "0402"
					( Origin gFrontEnd )
				)
				( attribute "TOLERANCE" "1%"
					( Origin gFrontEnd )
				)
				( attribute "VALUE" "1.00K"
					( Origin gFrontEnd )
				)
				( attribute "VER" "1"
					( Origin gFrontEnd )
				)
				( attribute "WATTAGE" "1/16W"
					( Origin gFrontEnd )
				)
				( attribute "XY" "(2725,2150)"
					( Origin gFrontEnd )
				)
				( attribute "CHIPS_PART_NAME" "RES"
					( Origin gPackager )
				)
				( attribute "CDS_PART_NAME" "RES_0402-1.00K,1%,1/16W,CHIP,GA"
					( Origin gPackager )
				)
				( objectStatus "R1L13" )
			)
			( gate "@baseboard_fab2_lib.baseboard_fab2(sch_1):page111_i10"
				( attribute "BOM_COST" "DEBUG"
					( Origin gFrontEnd )
				)
				( attribute "CDS_LIB" "dev_discrete"
					( Origin gPackager )
				)
				( attribute "CDS_LOCATION" "C9A2"
					( Origin gPackager )
				)
				( attribute "CDS_SEC" "1"
					( Origin gPackager )
				)
				( attribute "LOCATION" "C9A2"
					( Origin gFrontEnd )
				)
				( attribute "MATERIAL" "X7R"
					( Origin gFrontEnd )
				)
				( attribute "PACK_TYPE" "0402V"
					( Origin gFrontEnd )
				)
				( attribute "PART_NUMBER" "A36096-030"
					( Origin gFrontEnd )
				)
				( attribute "PHYS_PAGE" "111"
					( Origin gFrontEnd )
				)
				( attribute "ROOM" "DEBUG"
					( Origin gFrontEnd )
				)
				( attribute "ROT" "1"
					( Origin gFrontEnd )
				)
				( attribute "SEC" "1"
					( Origin gFrontEnd )
				)
				( attribute "SEC_TYPE" "0402V"
					( Origin gFrontEnd )
				)
				( attribute "TOLERANCE" "10%"
					( Origin gFrontEnd )
				)
				( attribute "VALUE" "0.1UF"
					( Origin gFrontEnd )
				)
				( attribute "VER" "1"
					( Origin gFrontEnd )
				)
				( attribute "VOLTAGE" "16V"
					( Units "uVoltage" "V" 1.000000)
					( Origin gFrontEnd )
				)
				( attribute "XY" "(2750,1900)"
					( Origin gFrontEnd )
				)
				( attribute "CHIPS_PART_NAME" "CAP_A"
					( Origin gPackager )
				)
				( attribute "CDS_PART_NAME" "CAP_A_0402V-0.1UF,16V,10%,X7R,A"
					( Origin gPackager )
				)
				( objectStatus "C9A2" )
			)
			( gate "@baseboard_fab2_lib.baseboard_fab2(sch_1):page111_i11"
				( attribute "BOM_COST" "DEBUG"
					( Origin gFrontEnd )
				)
				( attribute "CDS_LIB" "mstr_discrete"
					( Origin gPackager )
				)
				( attribute "CDS_LOCATION" "R9A14"
					( Origin gPackager )
				)
				( attribute "CDS_SEC" "1"
					( Origin gPackager )
				)
				( attribute "LOCATION" "R9A14"
					( Origin gFrontEnd )
				)
				( attribute "MATERIAL" "CHIP"
					( Origin gFrontEnd )
				)
				( attribute "PACK_TYPE" "0402"
					( Origin gFrontEnd )
				)
				( attribute "PART_NUMBER" "G21796-026"
					( Origin gFrontEnd )
				)
				( attribute "PHYS_PAGE" "111"
					( Origin gFrontEnd )
				)
				( attribute "ROOM" "DEBUG"
					( Origin gFrontEnd )
				)
				( attribute "ROT" "0"
					( Origin gFrontEnd )
				)
				( attribute "SEC" "1"
					( Origin gFrontEnd )
				)
				( attribute "SEC_TYPE" "0402"
					( Origin gFrontEnd )
				)
				( attribute "TOLERANCE" "1%"
					( Origin gFrontEnd )
				)
				( attribute "VALUE" "1.00K"
					( Origin gFrontEnd )
				)
				( attribute "VER" "1"
					( Origin gFrontEnd )
				)
				( attribute "WATTAGE" "1/16W"
					( Origin gFrontEnd )
				)
				( attribute "XY" "(2725,1700)"
					( Origin gFrontEnd )
				)
				( attribute "CHIPS_PART_NAME" "RES"
					( Origin gPackager )
				)
				( attribute "CDS_PART_NAME" "RES_0402-1.00K,1%,1/16W,CHIP,GA"
					( Origin gPackager )
				)
				( objectStatus "R9A14" )
			)
			( gate "@baseboard_fab2_lib.baseboard_fab2(sch_1):page111_i12"
				( attribute "BOM_COST" "DEBUG"
					( Origin gFrontEnd )
				)
				( attribute "CDS_LIB" "dev_discrete"
					( Origin gPackager )
				)
				( attribute "CDS_LOCATION" "C9A5"
					( Origin gPackager )
				)
				( attribute "CDS_SEC" "1"
					( Origin gPackager )
				)
				( attribute "LOCATION" "C9A5"
					( Origin gFrontEnd )
				)
				( attribute "MATERIAL" "X7R"
					( Origin gFrontEnd )
				)
				( attribute "PACK_TYPE" "0402V"
					( Origin gFrontEnd )
				)
				( attribute "PART_NUMBER" "A36096-030"
					( Origin gFrontEnd )
				)
				( attribute "PHYS_PAGE" "111"
					( Origin gFrontEnd )
				)
				( attribute "ROOM" "DEBUG"
					( Origin gFrontEnd )
				)
				( attribute "ROT" "1"
					( Origin gFrontEnd )
				)
				( attribute "SEC" "1"
					( Origin gFrontEnd )
				)
				( attribute "SEC_TYPE" "0402V"
					( Origin gFrontEnd )
				)
				( attribute "TOLERANCE" "10%"
					( Origin gFrontEnd )
				)
				( attribute "VALUE" "0.1UF"
					( Origin gFrontEnd )
				)
				( attribute "VER" "1"
					( Origin gFrontEnd )
				)
				( attribute "VOLTAGE" "16V"
					( Units "uVoltage" "V" 1.000000)
					( Origin gFrontEnd )
				)
				( attribute "XY" "(2800,1450)"
					( Origin gFrontEnd )
				)
				( attribute "CHIPS_PART_NAME" "CAP_A"
					( Origin gPackager )
				)
				( attribute "CDS_PART_NAME" "CAP_A_0402V-0.1UF,16V,10%,X7R,A"
					( Origin gPackager )
				)
				( objectStatus "C9A5" )
			)
			( gate "@baseboard_fab2_lib.baseboard_fab2(sch_1):page111_i13"
				( attribute "BOM_COST" "DEBUG"
					( Origin gFrontEnd )
				)
				( attribute "CDS_LIB" "mstr_discrete"
					( Origin gPackager )
				)
				( attribute "CDS_LOCATION" "R1L23"
					( Origin gPackager )
				)
				( attribute "CDS_SEC" "1"
					( Origin gPackager )
				)
				( attribute "LOCATION" "R1L23"
					( Origin gFrontEnd )
				)
				( attribute "MATERIAL" "CHIP"
					( Origin gFrontEnd )
				)
				( attribute "PACK_TYPE" "0402"
					( Origin gFrontEnd )
				)
				( attribute "PART_NUMBER" "G21796-026"
					( Origin gFrontEnd )
				)
				( attribute "PHYS_PAGE" "111"
					( Origin gFrontEnd )
				)
				( attribute "ROOM" "DEBUG"
					( Origin gFrontEnd )
				)
				( attribute "ROT" "0"
					( Origin gFrontEnd )
				)
				( attribute "SEC" "1"
					( Origin gFrontEnd )
				)
				( attribute "SEC_TYPE" "0402"
					( Origin gFrontEnd )
				)
				( attribute "TOLERANCE" "1%"
					( Origin gFrontEnd )
				)
				( attribute "VALUE" "1.00K"
					( Origin gFrontEnd )
				)
				( attribute "VER" "1"
					( Origin gFrontEnd )
				)
				( attribute "WATTAGE" "1/16W"
					( Origin gFrontEnd )
				)
				( attribute "XY" "(2725,1150)"
					( Origin gFrontEnd )
				)
				( attribute "CHIPS_PART_NAME" "RES"
					( Origin gPackager )
				)
				( attribute "CDS_PART_NAME" "RES_0402-1.00K,1%,1/16W,CHIP,GA"
					( Origin gPackager )
				)
				( objectStatus "R1L23" )
			)
			( gate "@baseboard_fab2_lib.baseboard_fab2(sch_1):page111_i14"
				( attribute "BOM_COST" "DEBUG"
					( Origin gFrontEnd )
				)
				( attribute "CDS_LIB" "dev_discrete"
					( Origin gPackager )
				)
				( attribute "CDS_LOCATION" "C1L8"
					( Origin gPackager )
				)
				( attribute "CDS_SEC" "1"
					( Origin gPackager )
				)
				( attribute "LOCATION" "C1L8"
					( Origin gFrontEnd )
				)
				( attribute "MATERIAL" "X7R"
					( Origin gFrontEnd )
				)
				( attribute "PACK_TYPE" "0402V"
					( Origin gFrontEnd )
				)
				( attribute "PART_NUMBER" "A36096-030"
					( Origin gFrontEnd )
				)
				( attribute "PHYS_PAGE" "111"
					( Origin gFrontEnd )
				)
				( attribute "ROOM" "DEBUG"
					( Origin gFrontEnd )
				)
				( attribute "ROT" "1"
					( Origin gFrontEnd )
				)
				( attribute "SEC" "1"
					( Origin gFrontEnd )
				)
				( attribute "SEC_TYPE" "0402V"
					( Origin gFrontEnd )
				)
				( attribute "TOLERANCE" "10%"
					( Origin gFrontEnd )
				)
				( attribute "VALUE" "0.1UF"
					( Origin gFrontEnd )
				)
				( attribute "VER" "1"
					( Origin gFrontEnd )
				)
				( attribute "VOLTAGE" "16V"
					( Units "uVoltage" "V" 1.000000)
					( Origin gFrontEnd )
				)
				( attribute "XY" "(2825,950)"
					( Origin gFrontEnd )
				)
				( attribute "CHIPS_PART_NAME" "CAP_A"
					( Origin gPackager )
				)
				( attribute "CDS_PART_NAME" "CAP_A_0402V-0.1UF,16V,10%,X7R,A"
					( Origin gPackager )
				)
				( objectStatus "C1L8" )
			)
			( gate "@baseboard_fab2_lib.baseboard_fab2(sch_1):page111_i25"
				( attribute "BOM_COST" "DEBUG"
					( Origin gFrontEnd )
				)
				( attribute "CDS_LIB" "dev_discrete"
					( Origin gPackager )
				)
				( attribute "CDS_LOCATION" "C9A6"
					( Origin gPackager )
				)
				( attribute "CDS_SEC" "1"
					( Origin gPackager )
				)
				( attribute "LOCATION" "C9A6"
					( Origin gFrontEnd )
				)
				( attribute "MATERIAL" "X6S"
					( Origin gFrontEnd )
				)
				( attribute "PACK_TYPE" "0402V"
					( Origin gFrontEnd )
				)
				( attribute "PART_NUMBER" "D97712-004"
					( Origin gFrontEnd )
				)
				( attribute "PHYS_PAGE" "111"
					( Origin gFrontEnd )
				)
				( attribute "ROOM" "DEBUG"
					( Origin gFrontEnd )
				)
				( attribute "ROT" "2"
					( Origin gFrontEnd )
				)
				( attribute "SEC" "1"
					( Origin gPackager )
				)
				( attribute "TOLERANCE" "10%"
					( Origin gFrontEnd )
				)
				( attribute "VALUE" "1.0UF"
					( Origin gFrontEnd )
				)
				( attribute "VER" "1"
					( Origin gFrontEnd )
				)
				( attribute "VOLTAGE" "6.3V"
					( Units "uVoltage" "V" 1.000000)
					( Origin gFrontEnd )
				)
				( attribute "XY" "(750,2925)"
					( Origin gFrontEnd )
				)
				( attribute "CHIPS_PART_NAME" "CAP_A"
					( Origin gPackager )
				)
				( attribute "CDS_PART_NAME" "CAP_A_0402V-1.0UF,6.3V,10%,X6SA"
					( Origin gPackager )
				)
				( objectStatus "C9A6" )
			)
			( gate "@baseboard_fab2_lib.baseboard_fab2(sch_1):page111_i26"
				( attribute "ALLOW_CONNECT" "TRUE"
					( Origin gFrontEnd )
				)
				( attribute "BOM_COST" "DEBUG"
					( Origin gFrontEnd )
				)
				( attribute "CDS_LIB" "mstr_sconn"
					( Origin gPackager )
				)
				( attribute "CDS_LOCATION" "J9A3"
					( Origin gPackager )
				)
				( attribute "CDS_SEC" "1"
					( Origin gPackager )
				)
				( attribute "LOCATION" "J9A3"
					( Origin gFrontEnd )
				)
				( attribute "MATERIAL" "CONN"
					( Origin gFrontEnd )
				)
				( attribute "PACK_TYPE" "SMLF"
					( Origin gFrontEnd )
				)
				( attribute "PART_NUMBER" "C21100-002"
					( Origin gFrontEnd )
				)
				( attribute "PHYS_PAGE" "111"
					( Origin gFrontEnd )
				)
				( attribute "ROOM" "DEBUG"
					( Origin gFrontEnd )
				)
				( attribute "ROT" "0"
					( Origin gFrontEnd )
				)
				( attribute "SEC" "1"
					( Origin gFrontEnd )
				)
				( attribute "SEC_TYPE" "SMLF"
					( Origin gFrontEnd )
				)
				( attribute "VER" "1"
					( Origin gFrontEnd )
				)
				( attribute "XY" "(350,3950)"
					( Origin gFrontEnd )
				)
				( attribute "CHIPS_PART_NAME" "SCONN60_C21100002"
					( Origin gPackager )
				)
				( attribute "CDS_PART_NAME" "SCONN60_C21100002_SMLF-CONN,C2A"
					( Origin gPackager )
				)
				( objectStatus "J9A3" )
			)
			( gate "@baseboard_fab2_lib.baseboard_fab2(sch_1):page111_i30"
				( attribute "BOM_COST" "DEBUG"
					( Origin gFrontEnd )
				)
				( attribute "CDS_LIB" "dev_discrete"
					( Origin gPackager )
				)
				( attribute "CDS_LOCATION" "C1L5"
					( Origin gPackager )
				)
				( attribute "CDS_SEC" "1"
					( Origin gPackager )
				)
				( attribute "LOCATION" "C1L5"
					( Origin gFrontEnd )
				)
				( attribute "MATERIAL" "X6S"
					( Origin gFrontEnd )
				)
				( attribute "PACK_TYPE" "0402V"
					( Origin gFrontEnd )
				)
				( attribute "PART_NUMBER" "D97712-004"
					( Origin gFrontEnd )
				)
				( attribute "PHYS_PAGE" "111"
					( Origin gFrontEnd )
				)
				( attribute "ROOM" "DEBUG"
					( Origin gFrontEnd )
				)
				( attribute "ROT" "0"
					( Origin gFrontEnd )
				)
				( attribute "SEC" "1"
					( Origin gPackager )
				)
				( attribute "TOLERANCE" "10%"
					( Origin gFrontEnd )
				)
				( attribute "VALUE" "1.0UF"
					( Origin gFrontEnd )
				)
				( attribute "VER" "1"
					( Origin gFrontEnd )
				)
				( attribute "VOLTAGE" "6.3V"
					( Units "uVoltage" "V" 1.000000)
					( Origin gFrontEnd )
				)
				( attribute "XY" "(0,2925)"
					( Origin gFrontEnd )
				)
				( attribute "CHIPS_PART_NAME" "CAP_A"
					( Origin gPackager )
				)
				( attribute "CDS_PART_NAME" "CAP_A_0402V-1.0UF,6.3V,10%,X6SA"
					( Origin gPackager )
				)
				( objectStatus "C1L5" )
			)
			( gate "@baseboard_fab2_lib.baseboard_fab2(sch_1):page111_i37"
				( attribute "BOM_COST" "DEBUG"
					( Origin gFrontEnd )
				)
				( attribute "CDS_LIB" "mstr_discrete"
					( Origin gPackager )
				)
				( attribute "CDS_LOCATION" "R2P2"
					( Origin gPackager )
				)
				( attribute "CDS_SEC" "1"
					( Origin gPackager )
				)
				( attribute "LOCATION" "R2P2"
					( Origin gFrontEnd )
				)
				( attribute "MATERIAL" "CHIP"
					( Origin gFrontEnd )
				)
				( attribute "PACK_TYPE" "0402"
					( Origin gFrontEnd )
				)
				( attribute "PART_NUMBER" "G21796-026"
					( Origin gFrontEnd )
				)
				( attribute "PHYS_PAGE" "111"
					( Origin gFrontEnd )
				)
				( attribute "ROOM" "DEBUG"
					( Origin gFrontEnd )
				)
				( attribute "ROT" "0"
					( Origin gFrontEnd )
				)
				( attribute "SEC" "1"
					( Origin gFrontEnd )
				)
				( attribute "SEC_TYPE" "0402"
					( Origin gFrontEnd )
				)
				( attribute "TOLERANCE" "1%"
					( Origin gFrontEnd )
				)
				( attribute "VALUE" "1.00K"
					( Origin gFrontEnd )
				)
				( attribute "VER" "1"
					( Origin gFrontEnd )
				)
				( attribute "WATTAGE" "1/16W"
					( Origin gFrontEnd )
				)
				( attribute "XY" "(-2100,4650)"
					( Origin gFrontEnd )
				)
				( attribute "CHIPS_PART_NAME" "RES"
					( Origin gPackager )
				)
				( attribute "CDS_PART_NAME" "RES_0402-1.00K,1%,1/16W,CHIP,GA"
					( Origin gPackager )
				)
				( objectStatus "R2P2" )
			)
			( gate "@baseboard_fab2_lib.baseboard_fab2(sch_1):page111_i55"
				( attribute "BOM_COST" "DEBUG"
					( Origin gFrontEnd )
				)
				( attribute "CDS_LIB" "mstr_discrete"
					( Origin gPackager )
				)
				( attribute "CDS_LOCATION" "R9A4"
					( Origin gPackager )
				)
				( attribute "CDS_SEC" "1"
					( Origin gPackager )
				)
				( attribute "LOCATION" "R9A4"
					( Origin gFrontEnd )
				)
				( attribute "MATERIAL" "CHIP"
					( Origin gFrontEnd )
				)
				( attribute "PACK_TYPE" "0402"
					( Origin gFrontEnd )
				)
				( attribute "PART_NUMBER" "G21796-077"
					( Origin gFrontEnd )
				)
				( attribute "PHYS_PAGE" "111"
					( Origin gFrontEnd )
				)
				( attribute "ROOM" "DEBUG"
					( Origin gFrontEnd )
				)
				( attribute "ROT" "0"
					( Origin gFrontEnd )
				)
				( attribute "SEC" "1"
					( Origin gFrontEnd )
				)
				( attribute "SEC_TYPE" "0402"
					( Origin gFrontEnd )
				)
				( attribute "TOLERANCE" "1%"
					( Origin gFrontEnd )
				)
				( attribute "VALUE" "475.0"
					( Origin gFrontEnd )
				)
				( attribute "VER" "1"
					( Origin gFrontEnd )
				)
				( attribute "WATTAGE" "1/16W"
					( Origin gFrontEnd )
				)
				( attribute "XY" "(-1400,1450)"
					( Origin gFrontEnd )
				)
				( attribute "CHIPS_PART_NAME" "RES"
					( Origin gPackager )
				)
				( attribute "CDS_PART_NAME" "RES_0402-475.0,1%,1/16W,CHIP,GA"
					( Origin gPackager )
				)
				( objectStatus "R9A4" )
			)
			( gate "@baseboard_fab2_lib.baseboard_fab2(sch_1):page111_i56"
				( attribute "BOM_COST" "DEBUG"
					( Origin gFrontEnd )
				)
				( attribute "CDS_LIB" "mstr_discrete"
					( Origin gPackager )
				)
				( attribute "CDS_LOCATION" "R1L17"
					( Origin gPackager )
				)
				( attribute "CDS_SEC" "1"
					( Origin gPackager )
				)
				( attribute "LOCATION" "R1L17"
					( Origin gFrontEnd )
				)
				( attribute "MATERIAL" "CHIP"
					( Origin gFrontEnd )
				)
				( attribute "PACK_TYPE" "0402"
					( Origin gFrontEnd )
				)
				( attribute "PART_NUMBER" "G21796-009"
					( Origin gFrontEnd )
				)
				( attribute "PHYS_PAGE" "111"
					( Origin gFrontEnd )
				)
				( attribute "ROOM" "DEBUG"
					( Origin gFrontEnd )
				)
				( attribute "ROT" "0"
					( Origin gFrontEnd )
				)
				( attribute "SEC" "1"
					( Origin gFrontEnd )
				)
				( attribute "SEC_TYPE" "0402"
					( Origin gFrontEnd )
				)
				( attribute "TOLERANCE" "1%"
					( Origin gFrontEnd )
				)
				( attribute "VALUE" "150.0"
					( Origin gFrontEnd )
				)
				( attribute "VER" "1"
					( Origin gFrontEnd )
				)
				( attribute "WATTAGE" "1/16W"
					( Origin gFrontEnd )
				)
				( attribute "XY" "(-1400,1100)"
					( Origin gFrontEnd )
				)
				( attribute "CHIPS_PART_NAME" "RES"
					( Origin gPackager )
				)
				( attribute "CDS_PART_NAME" "RES_0402-150.0,1%,1/16W,CHIP,GA"
					( Origin gPackager )
				)
				( objectStatus "R1L17" )
			)
			( gate "@baseboard_fab2_lib.baseboard_fab2(sch_1):page111_i57"
				( attribute "BOM_COST" "DEBUG"
					( Origin gFrontEnd )
				)
				( attribute "CDS_LIB" "mstr_discrete"
					( Origin gPackager )
				)
				( attribute "CDS_LOCATION" "R9A17"
					( Origin gPackager )
				)
				( attribute "CDS_SEC" "1"
					( Origin gPackager )
				)
				( attribute "LOCATION" "R9A17"
					( Origin gFrontEnd )
				)
				( attribute "MATERIAL" "CHIP"
					( Origin gFrontEnd )
				)
				( attribute "PACK_TYPE" "0402"
					( Origin gFrontEnd )
				)
				( attribute "PART_NUMBER" "G21796-026"
					( Origin gFrontEnd )
				)
				( attribute "PHYS_PAGE" "111"
					( Origin gFrontEnd )
				)
				( attribute "ROOM" "DEBUG"
					( Origin gFrontEnd )
				)
				( attribute "ROT" "0"
					( Origin gFrontEnd )
				)
				( attribute "SEC" "1"
					( Origin gFrontEnd )
				)
				( attribute "SEC_TYPE" "0402"
					( Origin gFrontEnd )
				)
				( attribute "TOLERANCE" "1%"
					( Origin gFrontEnd )
				)
				( attribute "VALUE" "1.00K"
					( Origin gFrontEnd )
				)
				( attribute "VER" "1"
					( Origin gFrontEnd )
				)
				( attribute "WATTAGE" "1/16W"
					( Origin gFrontEnd )
				)
				( attribute "XY" "(-1400,500)"
					( Origin gFrontEnd )
				)
				( attribute "CHIPS_PART_NAME" "RES"
					( Origin gPackager )
				)
				( attribute "CDS_PART_NAME" "RES_0402-1.00K,1%,1/16W,CHIP,GA"
					( Origin gPackager )
				)
				( objectStatus "R9A17" )
			)
			( gate "@baseboard_fab2_lib.baseboard_fab2(sch_1):page111_i59"
				( attribute "BOM_COST" "DEBUG"
					( Origin gFrontEnd )
				)
				( attribute "CDS_LIB" "dev_discrete"
					( Origin gPackager )
				)
				( attribute "CDS_LOCATION" "C9A4"
					( Origin gPackager )
				)
				( attribute "CDS_SEC" "1"
					( Origin gPackager )
				)
				( attribute "LOCATION" "C9A4"
					( Origin gFrontEnd )
				)
				( attribute "MATERIAL" "X7R"
					( Origin gFrontEnd )
				)
				( attribute "PACK_TYPE" "0402V"
					( Origin gFrontEnd )
				)
				( attribute "PART_NUMBER" "A36096-030"
					( Origin gFrontEnd )
				)
				( attribute "PHYS_PAGE" "111"
					( Origin gFrontEnd )
				)
				( attribute "ROOM" "DEBUG"
					( Origin gFrontEnd )
				)
				( attribute "ROT" "1"
					( Origin gFrontEnd )
				)
				( attribute "SEC" "1"
					( Origin gFrontEnd )
				)
				( attribute "SEC_TYPE" "0402V"
					( Origin gFrontEnd )
				)
				( attribute "TOLERANCE" "10%"
					( Origin gFrontEnd )
				)
				( attribute "VALUE" "0.1UF"
					( Origin gFrontEnd )
				)
				( attribute "VER" "1"
					( Origin gFrontEnd )
				)
				( attribute "VOLTAGE" "16V"
					( Units "uVoltage" "V" 1.000000)
					( Origin gFrontEnd )
				)
				( attribute "XY" "(-1400,875)"
					( Origin gFrontEnd )
				)
				( attribute "CHIPS_PART_NAME" "CAP_A"
					( Origin gPackager )
				)
				( attribute "CDS_PART_NAME" "CAP_A_0402V-0.1UF,16V,10%,X7R,A"
					( Origin gPackager )
				)
				( objectStatus "C9A4" )
			)
			( gate "@baseboard_fab2_lib.baseboard_fab2(sch_1):page111_i60"
				( attribute "BOM_COST" "DEBUG"
					( Origin gFrontEnd )
				)
				( attribute "CDS_LIB" "mstr_discrete"
					( Origin gPackager )
				)
				( attribute "CDS_LOCATION" "R9A15"
					( Origin gPackager )
				)
				( attribute "CDS_SEC" "1"
					( Origin gPackager )
				)
				( attribute "LOCATION" "R9A15"
					( Origin gFrontEnd )
				)
				( attribute "MATERIAL" "CHIP"
					( Origin gFrontEnd )
				)
				( attribute "PACK_TYPE" "0402"
					( Origin gFrontEnd )
				)
				( attribute "PART_NUMBER" "G21796-026"
					( Origin gFrontEnd )
				)
				( attribute "PHYS_PAGE" "111"
					( Origin gFrontEnd )
				)
				( attribute "ROOM" "DEBUG"
					( Origin gFrontEnd )
				)
				( attribute "ROT" "0"
					( Origin gFrontEnd )
				)
				( attribute "SEC" "1"
					( Origin gFrontEnd )
				)
				( attribute "SEC_TYPE" "0402"
					( Origin gFrontEnd )
				)
				( attribute "TOLERANCE" "1%"
					( Origin gFrontEnd )
				)
				( attribute "VALUE" "1.00K"
					( Origin gFrontEnd )
				)
				( attribute "VER" "1"
					( Origin gFrontEnd )
				)
				( attribute "WATTAGE" "1/16W"
					( Origin gFrontEnd )
				)
				( attribute "XY" "(-2175,3700)"
					( Origin gFrontEnd )
				)
				( attribute "CHIPS_PART_NAME" "RES"
					( Origin gPackager )
				)
				( attribute "CDS_PART_NAME" "RES_0402-1.00K,1%,1/16W,CHIP,GA"
					( Origin gPackager )
				)
				( objectStatus "R9A15" )
			)
			( gate "@baseboard_fab2_lib.baseboard_fab2(sch_1):page111_i68"
				( attribute "CDS_LIB" "mstr_discrete"
					( Origin gPackager )
				)
				( attribute "CDS_LOCATION" "R1L29"
					( Origin gPackager )
				)
				( attribute "CDS_SEC" "1"
					( Origin gPackager )
				)
				( attribute "LOCATION" "R1L29"
					( Origin gFrontEnd )
				)
				( attribute "MATERIAL" "CHIP"
					( Origin gFrontEnd )
				)
				( attribute "PACK_TYPE" "0402"
					( Origin gFrontEnd )
				)
				( attribute "PART_NUMBER" "G21796-074"
					( Origin gFrontEnd )
				)
				( attribute "PHYS_PAGE" "111"
					( Origin gFrontEnd )
				)
				( attribute "ROOM" "M-SATA"
					( Origin gFrontEnd )
				)
				( attribute "ROT" "0"
					( Origin gFrontEnd )
				)
				( attribute "SEC" "1"
					( Origin gFrontEnd )
				)
				( attribute "SEC_TYPE" "0402"
					( Origin gFrontEnd )
				)
				( attribute "TOLERANCE" "1%"
					( Origin gFrontEnd )
				)
				( attribute "VALUE" "33.2"
					( Origin gFrontEnd )
				)
				( attribute "VER" "1"
					( Origin gFrontEnd )
				)
				( attribute "WATTAGE" "1/16W"
					( Origin gFrontEnd )
				)
				( attribute "XY" "(2950,2600)"
					( Origin gFrontEnd )
				)
				( attribute "CHIPS_PART_NAME" "RES"
					( Origin gPackager )
				)
				( attribute "CDS_PART_NAME" "RES_0402-33.2,1%,1/16W,CHIP,G2A"
					( Origin gPackager )
				)
				( objectStatus "R1L29" )
			)
			( gate "@baseboard_fab2_lib.baseboard_fab2(sch_1):page111_i74"
				( attribute "CDS_LIB" "mstr_discrete"
					( Origin gPackager )
				)
				( attribute "CDS_LOCATION" "R9A3"
					( Origin gPackager )
				)
				( attribute "CDS_SEC" "1"
					( Origin gPackager )
				)
				( attribute "LOCATION" "R9A3"
					( Origin gFrontEnd )
				)
				( attribute "MATERIAL" "CHIP"
					( Origin gFrontEnd )
				)
				( attribute "PACK_TYPE" "0402"
					( Origin gFrontEnd )
				)
				( attribute "PART_NUMBER" "G21497-005"
					( Origin gFrontEnd )
				)
				( attribute "PHYS_PAGE" "111"
					( Origin gFrontEnd )
				)
				( attribute "ROOM" "DEBUG"
					( Origin gFrontEnd )
				)
				( attribute "ROT" "0"
					( Origin gFrontEnd )
				)
				( attribute "SEC" "1"
					( Origin gFrontEnd )
				)
				( attribute "SEC_TYPE" "0402"
					( Origin gFrontEnd )
				)
				( attribute "TOLERANCE" "5%"
					( Origin gFrontEnd )
				)
				( attribute "VALUE" "0.0"
					( Origin gFrontEnd )
				)
				( attribute "VER" "1"
					( Origin gFrontEnd )
				)
				( attribute "WATTAGE" "1/16W"
					( Origin gFrontEnd )
				)
				( attribute "XY" "(-1900,3100)"
					( Origin gFrontEnd )
				)
				( attribute "CHIPS_PART_NAME" "RES"
					( Origin gPackager )
				)
				( attribute "CDS_PART_NAME" "RES_0402-0.0,5%,1/16W,CHIP,G21A"
					( Origin gPackager )
				)
				( objectStatus "R9A3" )
			)
			( gate "@baseboard_fab2_lib.baseboard_fab2(sch_1):page111_i83"
				( attribute "CDS_LIB" "mstr_discrete"
					( Origin gPackager )
				)
				( attribute "CDS_LOCATION" "R9A2"
					( Origin gPackager )
				)
				( attribute "CDS_SEC" "1"
					( Origin gPackager )
				)
				( attribute "LOCATION" "R9A2"
					( Origin gFrontEnd )
				)
				( attribute "MATERIAL" "EMPTY"
					( Origin gFrontEnd )
				)
				( attribute "PACK_TYPE" "0402"
					( Origin gFrontEnd )
				)
				( attribute "PART_NUMBER" "G21796-074"
					( Origin gFrontEnd )
				)
				( attribute "PHYS_PAGE" "111"
					( Origin gFrontEnd )
				)
				( attribute "ROOM" "DEBUG"
					( Origin gFrontEnd )
				)
				( attribute "ROT" "0"
					( Origin gFrontEnd )
				)
				( attribute "SEC" "1"
					( Origin gFrontEnd )
				)
				( attribute "SEC_TYPE" "0402"
					( Origin gFrontEnd )
				)
				( attribute "TOLERANCE" "1%"
					( Origin gFrontEnd )
				)
				( attribute "VALUE" "33.2"
					( Origin gFrontEnd )
				)
				( attribute "VER" "2"
					( Origin gFrontEnd )
				)
				( attribute "WATTAGE" "1/16W"
					( Origin gFrontEnd )
				)
				( attribute "XY" "(-2925,2675)"
					( Origin gFrontEnd )
				)
				( attribute "CHIPS_PART_NAME" "RES"
					( Origin gPackager )
				)
				( attribute "CDS_PART_NAME" "RES_0402-33.2,1%,1/16W,EMPTY,GA"
					( Origin gPackager )
				)
				( objectStatus "R9A2" )
			)
			( gate "@baseboard_fab2_lib.baseboard_fab2(sch_1):page111_i85"
				( attribute "BOM_COST" "M-SATA"
					( Origin gFrontEnd )
				)
				( attribute "CDS_LIB" "mstr_ttl"
					( Origin gPackager )
				)
				( attribute "CDS_LOCATION" "U1L4"
					( Origin gPackager )
				)
				( attribute "CDS_SEC" "1"
					( Origin gPackager )
				)
				( attribute "LOCATION" "U1L4"
					( Origin gFrontEnd )
				)
				( attribute "MATERIAL" "IC"
					( Origin gFrontEnd )
				)
				( attribute "PACK_TYPE" "SOP"
					( Origin gFrontEnd )
				)
				( attribute "PART_NUMBER" "C88419-001"
					( Origin gFrontEnd )
				)
				( attribute "PHYS_PAGE" "111"
					( Origin gFrontEnd )
				)
				( attribute "ROOM" "M-SATA"
					( Origin gFrontEnd )
				)
				( attribute "ROT" "0"
					( Origin gFrontEnd )
				)
				( attribute "SEC" "1"
					( Origin gFrontEnd )
				)
				( attribute "SEC_TYPE" "SOP"
					( Origin gFrontEnd )
				)
				( attribute "VALUE" "74LVC1G07"
					( Origin gFrontEnd )
				)
				( attribute "VER" "1"
					( Origin gFrontEnd )
				)
				( attribute "XY" "(1775,2600)"
					( Origin gFrontEnd )
				)
				( attribute "CHIPS_PART_NAME" "TTL1G07_A"
					( Origin gPackager )
				)
				( attribute "CDS_PART_NAME" "TTL1G07_A_SOP-74LVC1G07,IC,C88B"
					( Origin gPackager )
				)
				( objectStatus "U1L4" )
			)
			( gate "@baseboard_fab2_lib.baseboard_fab2(sch_1):page111_i87"
				( attribute "BOM_COST" "DEBUG"
					( Origin gFrontEnd )
				)
				( attribute "CDS_LIB" "dev_discrete"
					( Origin gPackager )
				)
				( attribute "CDS_LOCATION" "C1L11"
					( Origin gPackager )
				)
				( attribute "CDS_SEC" "1"
					( Origin gPackager )
				)
				( attribute "LOCATION" "C1L11"
					( Origin gFrontEnd )
				)
				( attribute "MATERIAL" "X7R"
					( Origin gFrontEnd )
				)
				( attribute "PACK_TYPE" "0402V"
					( Origin gFrontEnd )
				)
				( attribute "PART_NUMBER" "A36096-030"
					( Origin gFrontEnd )
				)
				( attribute "PHYS_PAGE" "111"
					( Origin gFrontEnd )
				)
				( attribute "ROOM" "DEBUG"
					( Origin gFrontEnd )
				)
				( attribute "ROT" "0"
					( Origin gFrontEnd )
				)
				( attribute "SEC" "1"
					( Origin gFrontEnd )
				)
				( attribute "SEC_TYPE" "0402V"
					( Origin gFrontEnd )
				)
				( attribute "TOLERANCE" "10%"
					( Origin gFrontEnd )
				)
				( attribute "VALUE" "0.1UF"
					( Origin gFrontEnd )
				)
				( attribute "VER" "1"
					( Origin gFrontEnd )
				)
				( attribute "VOLTAGE" "16V"
					( Units "uVoltage" "V" 1.000000)
					( Origin gFrontEnd )
				)
				( attribute "XY" "(3900,3625)"
					( Origin gFrontEnd )
				)
				( attribute "CHIPS_PART_NAME" "CAP_A"
					( Origin gPackager )
				)
				( attribute "CDS_PART_NAME" "CAP_A_0402V-0.1UF,16V,10%,X7R,A"
					( Origin gPackager )
				)
				( objectStatus "C1L11" )
			)
			( gate "@baseboard_fab2_lib.baseboard_fab2(sch_1):page111_i89"
				( attribute "BOM_COST" "DEBUG"
					( Origin gFrontEnd )
				)
				( attribute "CDS_LIB" "mstr_discrete"
					( Origin gPackager )
				)
				( attribute "CDS_LOCATION" "R8E2"
					( Origin gPackager )
				)
				( attribute "CDS_SEC" "1"
					( Origin gPackager )
				)
				( attribute "LOCATION" "R8E2"
					( Origin gFrontEnd )
				)
				( attribute "MATERIAL" "CHIP"
					( Origin gFrontEnd )
				)
				( attribute "PACK_TYPE" "0402"
					( Origin gFrontEnd )
				)
				( attribute "PART_NUMBER" "G21796-026"
					( Origin gFrontEnd )
				)
				( attribute "PHYS_PAGE" "111"
					( Origin gFrontEnd )
				)
				( attribute "ROOM" "DEBUG"
					( Origin gFrontEnd )
				)
				( attribute "ROT" "0"
					( Origin gFrontEnd )
				)
				( attribute "SEC" "1"
					( Origin gFrontEnd )
				)
				( attribute "SEC_TYPE" "0402"
					( Origin gFrontEnd )
				)
				( attribute "TOLERANCE" "1%"
					( Origin gFrontEnd )
				)
				( attribute "VALUE" "1.00K"
					( Origin gFrontEnd )
				)
				( attribute "VER" "1"
					( Origin gFrontEnd )
				)
				( attribute "WATTAGE" "1/16W"
					( Origin gFrontEnd )
				)
				( attribute "XY" "(2050,4550)"
					( Origin gFrontEnd )
				)
				( attribute "CHIPS_PART_NAME" "RES"
					( Origin gPackager )
				)
				( attribute "CDS_PART_NAME" "RES_0402-1.00K,1%,1/16W,CHIP,GA"
					( Origin gPackager )
				)
				( objectStatus "R8E2" )
			)
			( gate "@baseboard_fab2_lib.baseboard_fab2(sch_1):page111_i93"
				( attribute "CDS_LIB" "mstr_discrete"
					( Origin gPackager )
				)
				( attribute "CDS_LOCATION" "Q9A1"
					( Origin gPackager )
				)
				( attribute "CDS_SEC" "2"
					( Origin gPackager )
				)
				( attribute "LOCATION" "Q9A1"
					( Origin gFrontEnd )
				)
				( attribute "MATERIAL" "EMPTY"
					( Origin gFrontEnd )
				)
				( attribute "PACK_TYPE" "SSOPLF"
					( Origin gFrontEnd )
				)
				( attribute "PART_NUMBER" "C52264-001"
					( Origin gFrontEnd )
				)
				( attribute "PHYS_PAGE" "111"
					( Origin gFrontEnd )
				)
				( attribute "ROOM" "DEBUG"
					( Origin gFrontEnd )
				)
				( attribute "ROT" "0"
					( Origin gFrontEnd )
				)
				( attribute "SEC" "2"
					( Origin gFrontEnd )
				)
				( attribute "SEC_TYPE" "SSOPLF"
					( Origin gFrontEnd )
				)
				( attribute "VALUE" "MBT3904"
					( Origin gFrontEnd )
				)
				( attribute "VER" "2"
					( Origin gFrontEnd )
				)
				( attribute "XY" "(-2150,2325)"
					( Origin gFrontEnd )
				)
				( attribute "CHIPS_PART_NAME" "NPN_DUAL"
					( Origin gPackager )
				)
				( attribute "CDS_PART_NAME" "NPN_DUAL_SSOPLF-MBT3904,EMPTY,A"
					( Origin gPackager )
				)
				( objectStatus "Q9A1" )
			)
			( gate "@baseboard_fab2_lib.baseboard_fab2(sch_1):page111_i94"
				( attribute "CDS_LIB" "mstr_discrete"
					( Origin gPackager )
				)
				( attribute "CDS_LOCATION" "Q9A1"
					( Origin gPackager )
				)
				( attribute "CDS_SEC" "1"
					( Origin gPackager )
				)
				( attribute "LOCATION" "Q9A1"
					( Origin gFrontEnd )
				)
				( attribute "MATERIAL" "EMPTY"
					( Origin gFrontEnd )
				)
				( attribute "PACK_TYPE" "SSOPLF"
					( Origin gFrontEnd )
				)
				( attribute "PART_NUMBER" "C52264-001"
					( Origin gFrontEnd )
				)
				( attribute "PHYS_PAGE" "111"
					( Origin gFrontEnd )
				)
				( attribute "ROOM" "DEBUG"
					( Origin gFrontEnd )
				)
				( attribute "ROT" "0"
					( Origin gFrontEnd )
				)
				( attribute "SEC" "1"
					( Origin gFrontEnd )
				)
				( attribute "SEC_TYPE" "SSOPLF"
					( Origin gFrontEnd )
				)
				( attribute "VALUE" "MBT3904"
					( Origin gFrontEnd )
				)
				( attribute "VER" "1"
					( Origin gFrontEnd )
				)
				( attribute "XY" "(-1150,2275)"
					( Origin gFrontEnd )
				)
				( attribute "CHIPS_PART_NAME" "NPN_DUAL"
					( Origin gPackager )
				)
				( attribute "CDS_PART_NAME" "NPN_DUAL_SSOPLF-MBT3904,EMPTY,A"
					( Origin gPackager )
				)
				( objectStatus "Q9A1" )
			)
			( gate "@baseboard_fab2_lib.baseboard_fab2(sch_1):page111_i95"
				( attribute "CDS_LIB" "mstr_discrete"
					( Origin gPackager )
				)
				( attribute "CDS_LOCATION" "R9A1"
					( Origin gPackager )
				)
				( attribute "CDS_SEC" "1"
					( Origin gPackager )
				)
				( attribute "LOCATION" "R9A1"
					( Origin gFrontEnd )
				)
				( attribute "MATERIAL" "EMPTY"
					( Origin gFrontEnd )
				)
				( attribute "PACK_TYPE" "0402"
					( Origin gFrontEnd )
				)
				( attribute "PART_NUMBER" "G21796-026"
					( Origin gFrontEnd )
				)
				( attribute "PHYS_PAGE" "111"
					( Origin gFrontEnd )
				)
				( attribute "ROOM" "DEBUG"
					( Origin gFrontEnd )
				)
				( attribute "ROT" "2"
					( Origin gFrontEnd )
				)
				( attribute "SEC" "1"
					( Origin gFrontEnd )
				)
				( attribute "SEC_TYPE" "0402"
					( Origin gFrontEnd )
				)
				( attribute "TOLERANCE" "1%"
					( Origin gFrontEnd )
				)
				( attribute "VALUE" "1.00K"
					( Origin gFrontEnd )
				)
				( attribute "VER" "2"
					( Origin gFrontEnd )
				)
				( attribute "WATTAGE" "1/16W"
					( Origin gFrontEnd )
				)
				( attribute "XY" "(-1850,2700)"
					( Origin gFrontEnd )
				)
				( attribute "CHIPS_PART_NAME" "RES"
					( Origin gPackager )
				)
				( attribute "CDS_PART_NAME" "RES_0402-1.00K,1%,1/16W,EMPTY,A"
					( Origin gPackager )
				)
				( objectStatus "R9A1" )
			)
			( gate "@baseboard_fab2_lib.baseboard_fab2(sch_1):page112_i40"
				( attribute "BOM_COST" "DEBUG"
					( Origin gFrontEnd )
				)
				( attribute "CDS_LIB" "mstr_analog"
					( Origin gPackager )
				)
				( attribute "CDS_LOCATION" "U1M7"
					( Origin gPackager )
				)
				( attribute "CDS_SEC" "1"
					( Origin gPackager )
				)
				( attribute "LOCATION" "U1M7"
					( Origin gFrontEnd )
				)
				( attribute "MATERIAL" "IC"
					( Origin gFrontEnd )
				)
				( attribute "PACK_TYPE" "SMLF"
					( Origin gFrontEnd )
				)
				( attribute "PART_NUMBER" "C99406-001"
					( Origin gFrontEnd )
				)
				( attribute "PHYS_PAGE" "112"
					( Origin gFrontEnd )
				)
				( attribute "ROOM" "DEBUG"
					( Origin gFrontEnd )
				)
				( attribute "ROT" "2"
					( Origin gFrontEnd )
				)
				( attribute "SEC" "1"
					( Origin gPackager )
				)
				( attribute "VER" "1"
					( Origin gFrontEnd )
				)
				( attribute "XY" "(2600,4675)"
					( Origin gFrontEnd )
				)
				( attribute "CHIPS_PART_NAME" "NC7SB3157"
					( Origin gPackager )
				)
				( attribute "CDS_PART_NAME" "NC7SB3157_SMLF-IC,C99406-001"
					( Origin gPackager )
				)
				( objectStatus "U1M7" )
			)
			( gate "@baseboard_fab2_lib.baseboard_fab2(sch_1):page112_i42"
				( attribute "BOM_COST" "DEBUG"
					( Origin gFrontEnd )
				)
				( attribute "CDS_LIB" "dev_discrete"
					( Origin gPackager )
				)
				( attribute "CDS_LOCATION" "C1M36"
					( Origin gPackager )
				)
				( attribute "CDS_SEC" "1"
					( Origin gPackager )
				)
				( attribute "LOCATION" "C1M36"
					( Origin gFrontEnd )
				)
				( attribute "MATERIAL" "X7R"
					( Origin gFrontEnd )
				)
				( attribute "PACK_TYPE" "0402V"
					( Origin gFrontEnd )
				)
				( attribute "PART_NUMBER" "A36096-045"
					( Origin gFrontEnd )
				)
				( attribute "PHYS_PAGE" "112"
					( Origin gFrontEnd )
				)
				( attribute "ROOM" "DEBUG"
					( Origin gFrontEnd )
				)
				( attribute "ROT" "2"
					( Origin gFrontEnd )
				)
				( attribute "SEC" "1"
					( Origin gFrontEnd )
				)
				( attribute "SEC_TYPE" "0402V"
					( Origin gFrontEnd )
				)
				( attribute "TOLERANCE" "10%"
					( Origin gFrontEnd )
				)
				( attribute "VALUE" "0.01UF"
					( Origin gFrontEnd )
				)
				( attribute "VER" "1"
					( Origin gFrontEnd )
				)
				( attribute "VOLTAGE" "25V"
					( Units "uVoltage" "V" 1.000000)
					( Origin gFrontEnd )
				)
				( attribute "XY" "(3100,4025)"
					( Origin gFrontEnd )
				)
				( attribute "CHIPS_PART_NAME" "CAP_A"
					( Origin gPackager )
				)
				( attribute "CDS_PART_NAME" "CAP_A_0402V-0.01UF,25V,10%,X7RA"
					( Origin gPackager )
				)
				( objectStatus "C1M36" )
			)
			( gate "@baseboard_fab2_lib.baseboard_fab2(sch_1):page112_i47"
				( attribute "BOM_COST" "DEBUG"
					( Origin gFrontEnd )
				)
				( attribute "CDS_LIB" "dev_discrete"
					( Origin gPackager )
				)
				( attribute "CDS_LOCATION" "C1M37"
					( Origin gPackager )
				)
				( attribute "CDS_SEC" "1"
					( Origin gPackager )
				)
				( attribute "LOCATION" "C1M37"
					( Origin gFrontEnd )
				)
				( attribute "MATERIAL" "X6S"
					( Origin gFrontEnd )
				)
				( attribute "PACK_TYPE" "0402V"
					( Origin gFrontEnd )
				)
				( attribute "PART_NUMBER" "D97712-004"
					( Origin gFrontEnd )
				)
				( attribute "PHYS_PAGE" "112"
					( Origin gFrontEnd )
				)
				( attribute "ROOM" "DEBUG"
					( Origin gFrontEnd )
				)
				( attribute "ROT" "2"
					( Origin gFrontEnd )
				)
				( attribute "SEC" "1"
					( Origin gPackager )
				)
				( attribute "TOLERANCE" "10%"
					( Origin gFrontEnd )
				)
				( attribute "VALUE" "1.0UF"
					( Origin gFrontEnd )
				)
				( attribute "VER" "1"
					( Origin gFrontEnd )
				)
				( attribute "VOLTAGE" "6.3V"
					( Units "uVoltage" "V" 1.000000)
					( Origin gFrontEnd )
				)
				( attribute "XY" "(2700,4025)"
					( Origin gFrontEnd )
				)
				( attribute "CHIPS_PART_NAME" "CAP_A"
					( Origin gPackager )
				)
				( attribute "CDS_PART_NAME" "CAP_A_0402V-1.0UF,6.3V,10%,X6SA"
					( Origin gPackager )
				)
				( objectStatus "C1M37" )
			)
			( gate "@baseboard_fab2_lib.baseboard_fab2(sch_1):page112_i49"
				( attribute "CDS_LIB" "mstr_discrete"
					( Origin gPackager )
				)
				( attribute "CDS_LOCATION" "R6P46"
					( Origin gPackager )
				)
				( attribute "CDS_SEC" "1"
					( Origin gPackager )
				)
				( attribute "LOCATION" "R6P46"
					( Origin gFrontEnd )
				)
				( attribute "MATERIAL" "CHIP"
					( Origin gFrontEnd )
				)
				( attribute "PACK_TYPE" "0402"
					( Origin gFrontEnd )
				)
				( attribute "PART_NUMBER" "G21796-017"
					( Origin gFrontEnd )
				)
				( attribute "PHYS_PAGE" "112"
					( Origin gFrontEnd )
				)
				( attribute "ROOM" "DEBUG"
					( Origin gFrontEnd )
				)
				( attribute "ROT" "0"
					( Origin gFrontEnd )
				)
				( attribute "SEC" "1"
					( Origin gFrontEnd )
				)
				( attribute "SEC_TYPE" "0402"
					( Origin gFrontEnd )
				)
				( attribute "TOLERANCE" "1%"
					( Origin gFrontEnd )
				)
				( attribute "VALUE" "100.0"
					( Origin gFrontEnd )
				)
				( attribute "VER" "2"
					( Origin gFrontEnd )
				)
				( attribute "WATTAGE" "1/16W"
					( Origin gFrontEnd )
				)
				( attribute "XY" "(2675,2400)"
					( Origin gFrontEnd )
				)
				( attribute "CHIPS_PART_NAME" "RES"
					( Origin gPackager )
				)
				( attribute "CDS_PART_NAME" "RES_0402-100.0,1%,1/16W,CHIP,GA"
					( Origin gPackager )
				)
				( objectStatus "R6P46" )
			)
			( gate "@baseboard_fab2_lib.baseboard_fab2(sch_1):page112_i50"
				( attribute "CDS_LIB" "mstr_discrete"
					( Origin gPackager )
				)
				( attribute "CDS_LOCATION" "R7P30"
					( Origin gPackager )
				)
				( attribute "CDS_SEC" "1"
					( Origin gPackager )
				)
				( attribute "LOCATION" "R7P30"
					( Origin gFrontEnd )
				)
				( attribute "MATERIAL" "CHIP"
					( Origin gFrontEnd )
				)
				( attribute "PACK_TYPE" "0402"
					( Origin gFrontEnd )
				)
				( attribute "PART_NUMBER" "G21796-017"
					( Origin gFrontEnd )
				)
				( attribute "PHYS_PAGE" "112"
					( Origin gFrontEnd )
				)
				( attribute "ROOM" "DEBUG"
					( Origin gFrontEnd )
				)
				( attribute "ROT" "0"
					( Origin gFrontEnd )
				)
				( attribute "SEC" "1"
					( Origin gFrontEnd )
				)
				( attribute "SEC_TYPE" "0402"
					( Origin gFrontEnd )
				)
				( attribute "TOLERANCE" "1%"
					( Origin gFrontEnd )
				)
				( attribute "VALUE" "100.0"
					( Origin gFrontEnd )
				)
				( attribute "VER" "2"
					( Origin gFrontEnd )
				)
				( attribute "WATTAGE" "1/16W"
					( Origin gFrontEnd )
				)
				( attribute "XY" "(2325,2400)"
					( Origin gFrontEnd )
				)
				( attribute "CHIPS_PART_NAME" "RES"
					( Origin gPackager )
				)
				( attribute "CDS_PART_NAME" "RES_0402-100.0,1%,1/16W,CHIP,GA"
					( Origin gPackager )
				)
				( objectStatus "R7P30" )
			)
			( gate "@baseboard_fab2_lib.baseboard_fab2(sch_1):page112_i51"
				( attribute "CDS_LIB" "mstr_discrete"
					( Origin gPackager )
				)
				( attribute "CDS_LOCATION" "R1M3"
					( Origin gPackager )
				)
				( attribute "CDS_SEC" "1"
					( Origin gPackager )
				)
				( attribute "LOCATION" "R1M3"
					( Origin gFrontEnd )
				)
				( attribute "MATERIAL" "CHIP"
					( Origin gFrontEnd )
				)
				( attribute "PACK_TYPE" "0402"
					( Origin gFrontEnd )
				)
				( attribute "PART_NUMBER" "G21796-017"
					( Origin gFrontEnd )
				)
				( attribute "PHYS_PAGE" "112"
					( Origin gFrontEnd )
				)
				( attribute "ROOM" "DEBUG"
					( Origin gFrontEnd )
				)
				( attribute "ROT" "0"
					( Origin gFrontEnd )
				)
				( attribute "SEC" "1"
					( Origin gFrontEnd )
				)
				( attribute "SEC_TYPE" "0402"
					( Origin gFrontEnd )
				)
				( attribute "TOLERANCE" "1%"
					( Origin gFrontEnd )
				)
				( attribute "VALUE" "100.0"
					( Origin gFrontEnd )
				)
				( attribute "VER" "2"
					( Origin gFrontEnd )
				)
				( attribute "WATTAGE" "1/16W"
					( Origin gFrontEnd )
				)
				( attribute "XY" "(1950,2400)"
					( Origin gFrontEnd )
				)
				( attribute "CHIPS_PART_NAME" "RES"
					( Origin gPackager )
				)
				( attribute "CDS_PART_NAME" "RES_0402-100.0,1%,1/16W,CHIP,GA"
					( Origin gPackager )
				)
				( objectStatus "R1M3" )
			)
			( gate "@baseboard_fab2_lib.baseboard_fab2(sch_1):page112_i53"
				( attribute "CDS_LIB" "mstr_discrete"
					( Origin gPackager )
				)
				( attribute "CDS_LOCATION" "R4P15"
					( Origin gPackager )
				)
				( attribute "CDS_SEC" "1"
					( Origin gPackager )
				)
				( attribute "LOCATION" "R4P15"
					( Origin gFrontEnd )
				)
				( attribute "MATERIAL" "CHIP"
					( Origin gFrontEnd )
				)
				( attribute "PACK_TYPE" "0402"
					( Origin gFrontEnd )
				)
				( attribute "PART_NUMBER" "G21796-017"
					( Origin gFrontEnd )
				)
				( attribute "PHYS_PAGE" "112"
					( Origin gFrontEnd )
				)
				( attribute "ROOM" "DEBUG"
					( Origin gFrontEnd )
				)
				( attribute "ROT" "0"
					( Origin gFrontEnd )
				)
				( attribute "SEC" "1"
					( Origin gFrontEnd )
				)
				( attribute "SEC_TYPE" "0402"
					( Origin gFrontEnd )
				)
				( attribute "TOLERANCE" "1%"
					( Origin gFrontEnd )
				)
				( attribute "VALUE" "100.0"
					( Origin gFrontEnd )
				)
				( attribute "VER" "2"
					( Origin gFrontEnd )
				)
				( attribute "WATTAGE" "1/16W"
					( Origin gFrontEnd )
				)
				( attribute "XY" "(1175,3800)"
					( Origin gFrontEnd )
				)
				( attribute "CHIPS_PART_NAME" "RES"
					( Origin gPackager )
				)
				( attribute "CDS_PART_NAME" "RES_0402-100.0,1%,1/16W,CHIP,GA"
					( Origin gPackager )
				)
				( objectStatus "R4P15" )
			)
			( gate "@baseboard_fab2_lib.baseboard_fab2(sch_1):page112_i54"
				( attribute "CDS_LIB" "mstr_discrete"
					( Origin gPackager )
				)
				( attribute "CDS_LOCATION" "R1M4"
					( Origin gPackager )
				)
				( attribute "CDS_SEC" "1"
					( Origin gPackager )
				)
				( attribute "LOCATION" "R1M4"
					( Origin gFrontEnd )
				)
				( attribute "MATERIAL" "CHIP"
					( Origin gFrontEnd )
				)
				( attribute "PACK_TYPE" "0402"
					( Origin gFrontEnd )
				)
				( attribute "PART_NUMBER" "G21796-017"
					( Origin gFrontEnd )
				)
				( attribute "PHYS_PAGE" "112"
					( Origin gFrontEnd )
				)
				( attribute "ROOM" "DEBUG"
					( Origin gFrontEnd )
				)
				( attribute "ROT" "0"
					( Origin gFrontEnd )
				)
				( attribute "SEC" "1"
					( Origin gFrontEnd )
				)
				( attribute "SEC_TYPE" "0402"
					( Origin gFrontEnd )
				)
				( attribute "TOLERANCE" "1%"
					( Origin gFrontEnd )
				)
				( attribute "VALUE" "100.0"
					( Origin gFrontEnd )
				)
				( attribute "VER" "2"
					( Origin gFrontEnd )
				)
				( attribute "WATTAGE" "1/16W"
					( Origin gFrontEnd )
				)
				( attribute "XY" "(1600,2400)"
					( Origin gFrontEnd )
				)
				( attribute "CHIPS_PART_NAME" "RES"
					( Origin gPackager )
				)
				( attribute "CDS_PART_NAME" "RES_0402-100.0,1%,1/16W,CHIP,GA"
					( Origin gPackager )
				)
				( objectStatus "R1M4" )
			)
			( gate "@baseboard_fab2_lib.baseboard_fab2(sch_1):page112_i55"
				( attribute "CDS_LIB" "mstr_discrete"
					( Origin gPackager )
				)
				( attribute "CDS_LOCATION" "R6T7"
					( Origin gPackager )
				)
				( attribute "CDS_SEC" "1"
					( Origin gPackager )
				)
				( attribute "LOCATION" "R6T7"
					( Origin gFrontEnd )
				)
				( attribute "MATERIAL" "CHIP"
					( Origin gFrontEnd )
				)
				( attribute "PACK_TYPE" "0402"
					( Origin gFrontEnd )
				)
				( attribute "PART_NUMBER" "G21796-009"
					( Origin gFrontEnd )
				)
				( attribute "PHYS_PAGE" "112"
					( Origin gFrontEnd )
				)
				( attribute "ROOM" "DEBUG"
					( Origin gFrontEnd )
				)
				( attribute "ROT" "0"
					( Origin gFrontEnd )
				)
				( attribute "SEC" "1"
					( Origin gFrontEnd )
				)
				( attribute "SEC_TYPE" "0402"
					( Origin gFrontEnd )
				)
				( attribute "TOLERANCE" "1%"
					( Origin gFrontEnd )
				)
				( attribute "VALUE" "150.0"
					( Origin gFrontEnd )
				)
				( attribute "VER" "2"
					( Origin gFrontEnd )
				)
				( attribute "WATTAGE" "1/16W"
					( Origin gFrontEnd )
				)
				( attribute "XY" "(1225,2400)"
					( Origin gFrontEnd )
				)
				( attribute "CHIPS_PART_NAME" "RES"
					( Origin gPackager )
				)
				( attribute "CDS_PART_NAME" "RES_0402-150.0,1%,1/16W,CHIP,GA"
					( Origin gPackager )
				)
				( objectStatus "R6T7" )
			)
			( gate "@baseboard_fab2_lib.baseboard_fab2(sch_1):page112_i56"
				( attribute "CDS_LIB" "mstr_discrete"
					( Origin gPackager )
				)
				( attribute "CDS_LOCATION" "R6T6"
					( Origin gPackager )
				)
				( attribute "CDS_SEC" "1"
					( Origin gPackager )
				)
				( attribute "LOCATION" "R6T6"
					( Origin gFrontEnd )
				)
				( attribute "MATERIAL" "CHIP"
					( Origin gFrontEnd )
				)
				( attribute "PACK_TYPE" "0402"
					( Origin gFrontEnd )
				)
				( attribute "PART_NUMBER" "G21796-009"
					( Origin gFrontEnd )
				)
				( attribute "PHYS_PAGE" "112"
					( Origin gFrontEnd )
				)
				( attribute "ROOM" "DEBUG"
					( Origin gFrontEnd )
				)
				( attribute "ROT" "0"
					( Origin gFrontEnd )
				)
				( attribute "SEC" "1"
					( Origin gFrontEnd )
				)
				( attribute "SEC_TYPE" "0402"
					( Origin gFrontEnd )
				)
				( attribute "TOLERANCE" "1%"
					( Origin gFrontEnd )
				)
				( attribute "VALUE" "150.0"
					( Origin gFrontEnd )
				)
				( attribute "VER" "2"
					( Origin gFrontEnd )
				)
				( attribute "WATTAGE" "1/16W"
					( Origin gFrontEnd )
				)
				( attribute "XY" "(875,2400)"
					( Origin gFrontEnd )
				)
				( attribute "CHIPS_PART_NAME" "RES"
					( Origin gPackager )
				)
				( attribute "CDS_PART_NAME" "RES_0402-150.0,1%,1/16W,CHIP,GA"
					( Origin gPackager )
				)
				( objectStatus "R6T6" )
			)
			( gate "@baseboard_fab2_lib.baseboard_fab2(sch_1):page112_i57"
				( attribute "CDS_LIB" "mstr_discrete"
					( Origin gPackager )
				)
				( attribute "CDS_LOCATION" "R4P12"
					( Origin gPackager )
				)
				( attribute "CDS_SEC" "1"
					( Origin gPackager )
				)
				( attribute "LOCATION" "R4P12"
					( Origin gFrontEnd )
				)
				( attribute "MATERIAL" "CHIP"
					( Origin gFrontEnd )
				)
				( attribute "PACK_TYPE" "0402"
					( Origin gFrontEnd )
				)
				( attribute "PART_NUMBER" "G21796-017"
					( Origin gFrontEnd )
				)
				( attribute "PHYS_PAGE" "112"
					( Origin gFrontEnd )
				)
				( attribute "ROOM" "DEBUG"
					( Origin gFrontEnd )
				)
				( attribute "ROT" "0"
					( Origin gFrontEnd )
				)
				( attribute "SEC" "1"
					( Origin gFrontEnd )
				)
				( attribute "SEC_TYPE" "0402"
					( Origin gFrontEnd )
				)
				( attribute "TOLERANCE" "1%"
					( Origin gFrontEnd )
				)
				( attribute "VALUE" "100.0"
					( Origin gFrontEnd )
				)
				( attribute "VER" "2"
					( Origin gFrontEnd )
				)
				( attribute "WATTAGE" "1/16W"
					( Origin gFrontEnd )
				)
				( attribute "XY" "(875,3825)"
					( Origin gFrontEnd )
				)
				( attribute "CHIPS_PART_NAME" "RES"
					( Origin gPackager )
				)
				( attribute "CDS_PART_NAME" "RES_0402-100.0,1%,1/16W,CHIP,GA"
					( Origin gPackager )
				)
				( objectStatus "R4P12" )
			)
			( gate "@baseboard_fab2_lib.baseboard_fab2(sch_1):page112_i58"
				( attribute "CDS_LIB" "mstr_discrete"
					( Origin gPackager )
				)
				( attribute "CDS_LOCATION" "R4P23"
					( Origin gPackager )
				)
				( attribute "CDS_SEC" "1"
					( Origin gPackager )
				)
				( attribute "LOCATION" "R4P23"
					( Origin gFrontEnd )
				)
				( attribute "MATERIAL" "CHIP"
					( Origin gFrontEnd )
				)
				( attribute "PACK_TYPE" "0402"
					( Origin gFrontEnd )
				)
				( attribute "PART_NUMBER" "G21796-009"
					( Origin gFrontEnd )
				)
				( attribute "PHYS_PAGE" "112"
					( Origin gFrontEnd )
				)
				( attribute "ROOM" "DEBUG"
					( Origin gFrontEnd )
				)
				( attribute "ROT" "0"
					( Origin gFrontEnd )
				)
				( attribute "SEC" "1"
					( Origin gFrontEnd )
				)
				( attribute "SEC_TYPE" "0402"
					( Origin gFrontEnd )
				)
				( attribute "TOLERANCE" "1%"
					( Origin gFrontEnd )
				)
				( attribute "VALUE" "150.0"
					( Origin gFrontEnd )
				)
				( attribute "VER" "2"
					( Origin gFrontEnd )
				)
				( attribute "WATTAGE" "1/16W"
					( Origin gFrontEnd )
				)
				( attribute "XY" "(575,3800)"
					( Origin gFrontEnd )
				)
				( attribute "CHIPS_PART_NAME" "RES"
					( Origin gPackager )
				)
				( attribute "CDS_PART_NAME" "RES_0402-150.0,1%,1/16W,CHIP,GA"
					( Origin gPackager )
				)
				( objectStatus "R4P23" )
			)
			( gate "@baseboard_fab2_lib.baseboard_fab2(sch_1):page112_i59"
				( attribute "CDS_LIB" "mstr_discrete"
					( Origin gPackager )
				)
				( attribute "CDS_LOCATION" "R4P24"
					( Origin gPackager )
				)
				( attribute "CDS_SEC" "1"
					( Origin gPackager )
				)
				( attribute "LOCATION" "R4P24"
					( Origin gFrontEnd )
				)
				( attribute "MATERIAL" "CHIP"
					( Origin gFrontEnd )
				)
				( attribute "PACK_TYPE" "0402"
					( Origin gFrontEnd )
				)
				( attribute "PART_NUMBER" "G21796-009"
					( Origin gFrontEnd )
				)
				( attribute "PHYS_PAGE" "112"
					( Origin gFrontEnd )
				)
				( attribute "ROOM" "DEBUG"
					( Origin gFrontEnd )
				)
				( attribute "ROT" "0"
					( Origin gFrontEnd )
				)
				( attribute "SEC" "1"
					( Origin gFrontEnd )
				)
				( attribute "SEC_TYPE" "0402"
					( Origin gFrontEnd )
				)
				( attribute "TOLERANCE" "1%"
					( Origin gFrontEnd )
				)
				( attribute "VALUE" "150.0"
					( Origin gFrontEnd )
				)
				( attribute "VER" "2"
					( Origin gFrontEnd )
				)
				( attribute "WATTAGE" "1/16W"
					( Origin gFrontEnd )
				)
				( attribute "XY" "(275,3800)"
					( Origin gFrontEnd )
				)
				( attribute "CHIPS_PART_NAME" "RES"
					( Origin gPackager )
				)
				( attribute "CDS_PART_NAME" "RES_0402-150.0,1%,1/16W,CHIP,GA"
					( Origin gPackager )
				)
				( objectStatus "R4P24" )
			)
			( gate "@baseboard_fab2_lib.baseboard_fab2(sch_1):page112_i60"
				( attribute "CDS_LIB" "mstr_discrete"
					( Origin gPackager )
				)
				( attribute "CDS_LOCATION" "R1L15"
					( Origin gPackager )
				)
				( attribute "CDS_SEC" "1"
					( Origin gPackager )
				)
				( attribute "LOCATION" "R1L15"
					( Origin gFrontEnd )
				)
				( attribute "MATERIAL" "CHIP"
					( Origin gFrontEnd )
				)
				( attribute "PACK_TYPE" "0402"
					( Origin gFrontEnd )
				)
				( attribute "PART_NUMBER" "G21796-009"
					( Origin gFrontEnd )
				)
				( attribute "PHYS_PAGE" "112"
					( Origin gFrontEnd )
				)
				( attribute "ROOM" "DEBUG"
					( Origin gFrontEnd )
				)
				( attribute "ROT" "0"
					( Origin gFrontEnd )
				)
				( attribute "SEC" "1"
					( Origin gFrontEnd )
				)
				( attribute "SEC_TYPE" "0402"
					( Origin gFrontEnd )
				)
				( attribute "TOLERANCE" "1%"
					( Origin gFrontEnd )
				)
				( attribute "VALUE" "150.0"
					( Origin gFrontEnd )
				)
				( attribute "VER" "2"
					( Origin gFrontEnd )
				)
				( attribute "WATTAGE" "1/16W"
					( Origin gFrontEnd )
				)
				( attribute "XY" "(500,2400)"
					( Origin gFrontEnd )
				)
				( attribute "CHIPS_PART_NAME" "RES"
					( Origin gPackager )
				)
				( attribute "CDS_PART_NAME" "RES_0402-150.0,1%,1/16W,CHIP,GA"
					( Origin gPackager )
				)
				( objectStatus "R1L15" )
			)
			( gate "@baseboard_fab2_lib.baseboard_fab2(sch_1):page112_i61"
				( attribute "BOM_COST" "DEBUG"
					( Origin gFrontEnd )
				)
				( attribute "CDS_LIB" "mstr_discrete"
					( Origin gPackager )
				)
				( attribute "CDS_LOCATION" "R7P29"
					( Origin gPackager )
				)
				( attribute "CDS_SEC" "1"
					( Origin gPackager )
				)
				( attribute "LOCATION" "R7P29"
					( Origin gFrontEnd )
				)
				( attribute "MATERIAL" "CHIP"
					( Origin gFrontEnd )
				)
				( attribute "PACK_TYPE" "0402"
					( Origin gFrontEnd )
				)
				( attribute "PART_NUMBER" "G21796-208"
					( Origin gFrontEnd )
				)
				( attribute "PHYS_PAGE" "112"
					( Origin gFrontEnd )
				)
				( attribute "ROOM" "DEBUG"
					( Origin gFrontEnd )
				)
				( attribute "ROT" "0"
					( Origin gFrontEnd )
				)
				( attribute "SEC" "1"
					( Origin gPackager )
				)
				( attribute "TOLERANCE" "1.0%"
					( Origin gFrontEnd )
				)
				( attribute "VALUE" "51.1"
					( Origin gFrontEnd )
				)
				( attribute "VER" "2"
					( Origin gFrontEnd )
				)
				( attribute "WATTAGE" "1/16W"
					( Origin gFrontEnd )
				)
				( attribute "XY" "(875,1100)"
					( Origin gFrontEnd )
				)
				( attribute "CHIPS_PART_NAME" "RES"
					( Origin gPackager )
				)
				( attribute "CDS_PART_NAME" "RES_0402-51.1,1.0%,1/16W,CHIP,A"
					( Origin gPackager )
				)
				( objectStatus "R7P29" )
			)
			( gate "@baseboard_fab2_lib.baseboard_fab2(sch_1):page112_i62"
				( attribute "BOM_COST" "DEBUG"
					( Origin gFrontEnd )
				)
				( attribute "CDS_LIB" "mstr_discrete"
					( Origin gPackager )
				)
				( attribute "CDS_LOCATION" "R6T5"
					( Origin gPackager )
				)
				( attribute "CDS_SEC" "1"
					( Origin gPackager )
				)
				( attribute "LOCATION" "R6T5"
					( Origin gFrontEnd )
				)
				( attribute "MATERIAL" "CHIP"
					( Origin gFrontEnd )
				)
				( attribute "PACK_TYPE" "0402"
					( Origin gFrontEnd )
				)
				( attribute "PART_NUMBER" "G21796-026"
					( Origin gFrontEnd )
				)
				( attribute "PHYS_PAGE" "112"
					( Origin gFrontEnd )
				)
				( attribute "ROOM" "DEBUG"
					( Origin gFrontEnd )
				)
				( attribute "ROT" "0"
					( Origin gFrontEnd )
				)
				( attribute "SEC" "1"
					( Origin gFrontEnd )
				)
				( attribute "SEC_TYPE" "0402"
					( Origin gFrontEnd )
				)
				( attribute "TOLERANCE" "1%"
					( Origin gFrontEnd )
				)
				( attribute "VALUE" "1.00K"
					( Origin gFrontEnd )
				)
				( attribute "VER" "2"
					( Origin gFrontEnd )
				)
				( attribute "WATTAGE" "1/16W"
					( Origin gFrontEnd )
				)
				( attribute "XY" "(500,1100)"
					( Origin gFrontEnd )
				)
				( attribute "CHIPS_PART_NAME" "RES"
					( Origin gPackager )
				)
				( attribute "CDS_PART_NAME" "RES_0402-1.00K,1%,1/16W,CHIP,GA"
					( Origin gPackager )
				)
				( objectStatus "R6T5" )
			)
			( gate "@baseboard_fab2_lib.baseboard_fab2(sch_1):page112_i76"
				( attribute "CDS_LIB" "mstr_discrete"
					( Origin gPackager )
				)
				( attribute "CDS_LOCATION" "R1L39"
					( Origin gPackager )
				)
				( attribute "CDS_SEC" "1"
					( Origin gPackager )
				)
				( attribute "LOCATION" "R1L39"
					( Origin gFrontEnd )
				)
				( attribute "MATERIAL" "CHIP"
					( Origin gFrontEnd )
				)
				( attribute "PACK_TYPE" "0402"
					( Origin gFrontEnd )
				)
				( attribute "PART_NUMBER" "G21796-017"
					( Origin gFrontEnd )
				)
				( attribute "PHYS_PAGE" "112"
					( Origin gFrontEnd )
				)
				( attribute "ROOM" "DEBUG"
					( Origin gFrontEnd )
				)
				( attribute "ROT" "0"
					( Origin gFrontEnd )
				)
				( attribute "SEC" "1"
					( Origin gFrontEnd )
				)
				( attribute "SEC_TYPE" "0402"
					( Origin gFrontEnd )
				)
				( attribute "TOLERANCE" "1%"
					( Origin gFrontEnd )
				)
				( attribute "VALUE" "100.0"
					( Origin gFrontEnd )
				)
				( attribute "VER" "2"
					( Origin gFrontEnd )
				)
				( attribute "WATTAGE" "1/16W"
					( Origin gFrontEnd )
				)
				( attribute "XY" "(-1200,4425)"
					( Origin gFrontEnd )
				)
				( attribute "CHIPS_PART_NAME" "RES"
					( Origin gPackager )
				)
				( attribute "CDS_PART_NAME" "RES_0402-100.0,1%,1/16W,CHIP,GA"
					( Origin gPackager )
				)
				( objectStatus "R1L39" )
			)
			( gate "@baseboard_fab2_lib.baseboard_fab2(sch_1):page112_i77"
				( attribute "CDS_LIB" "mstr_discrete"
					( Origin gPackager )
				)
				( attribute "CDS_LOCATION" "R1L41"
					( Origin gPackager )
				)
				( attribute "CDS_SEC" "1"
					( Origin gPackager )
				)
				( attribute "LOCATION" "R1L41"
					( Origin gFrontEnd )
				)
				( attribute "MATERIAL" "CHIP"
					( Origin gFrontEnd )
				)
				( attribute "PACK_TYPE" "0402"
					( Origin gFrontEnd )
				)
				( attribute "PART_NUMBER" "G21796-017"
					( Origin gFrontEnd )
				)
				( attribute "PHYS_PAGE" "112"
					( Origin gFrontEnd )
				)
				( attribute "ROOM" "DEBUG"
					( Origin gFrontEnd )
				)
				( attribute "ROT" "0"
					( Origin gFrontEnd )
				)
				( attribute "SEC" "1"
					( Origin gFrontEnd )
				)
				( attribute "SEC_TYPE" "0402"
					( Origin gFrontEnd )
				)
				( attribute "TOLERANCE" "1%"
					( Origin gFrontEnd )
				)
				( attribute "VALUE" "100.0"
					( Origin gFrontEnd )
				)
				( attribute "VER" "2"
					( Origin gFrontEnd )
				)
				( attribute "WATTAGE" "1/16W"
					( Origin gFrontEnd )
				)
				( attribute "XY" "(-1575,4425)"
					( Origin gFrontEnd )
				)
				( attribute "CHIPS_PART_NAME" "RES"
					( Origin gPackager )
				)
				( attribute "CDS_PART_NAME" "RES_0402-100.0,1%,1/16W,CHIP,GA"
					( Origin gPackager )
				)
				( objectStatus "R1L41" )
			)
			( gate "@baseboard_fab2_lib.baseboard_fab2(sch_1):page112_i78"
				( attribute "CDS_LIB" "mstr_discrete"
					( Origin gPackager )
				)
				( attribute "CDS_LOCATION" "R9A11"
					( Origin gPackager )
				)
				( attribute "CDS_SEC" "1"
					( Origin gPackager )
				)
				( attribute "LOCATION" "R9A11"
					( Origin gFrontEnd )
				)
				( attribute "MATERIAL" "CHIP"
					( Origin gFrontEnd )
				)
				( attribute "PACK_TYPE" "0402"
					( Origin gFrontEnd )
				)
				( attribute "PART_NUMBER" "G21796-009"
					( Origin gFrontEnd )
				)
				( attribute "PHYS_PAGE" "112"
					( Origin gFrontEnd )
				)
				( attribute "ROOM" "DEBUG"
					( Origin gFrontEnd )
				)
				( attribute "ROT" "0"
					( Origin gFrontEnd )
				)
				( attribute "SEC" "1"
					( Origin gFrontEnd )
				)
				( attribute "SEC_TYPE" "0402"
					( Origin gFrontEnd )
				)
				( attribute "TOLERANCE" "1%"
					( Origin gFrontEnd )
				)
				( attribute "VALUE" "150.0"
					( Origin gFrontEnd )
				)
				( attribute "VER" "2"
					( Origin gFrontEnd )
				)
				( attribute "WATTAGE" "1/16W"
					( Origin gFrontEnd )
				)
				( attribute "XY" "(-1950,4425)"
					( Origin gFrontEnd )
				)
				( attribute "CHIPS_PART_NAME" "RES"
					( Origin gPackager )
				)
				( attribute "CDS_PART_NAME" "RES_0402-150.0,1%,1/16W,CHIP,GA"
					( Origin gPackager )
				)
				( objectStatus "R9A11" )
			)
			( gate "@baseboard_fab2_lib.baseboard_fab2(sch_1):page112_i79"
				( attribute "CDS_LIB" "mstr_discrete"
					( Origin gPackager )
				)
				( attribute "CDS_LOCATION" "R8A13"
					( Origin gPackager )
				)
				( attribute "CDS_SEC" "1"
					( Origin gPackager )
				)
				( attribute "LOCATION" "R8A13"
					( Origin gFrontEnd )
				)
				( attribute "MATERIAL" "CHIP"
					( Origin gFrontEnd )
				)
				( attribute "PACK_TYPE" "0402"
					( Origin gFrontEnd )
				)
				( attribute "PART_NUMBER" "G21796-009"
					( Origin gFrontEnd )
				)
				( attribute "PHYS_PAGE" "112"
					( Origin gFrontEnd )
				)
				( attribute "ROOM" "DEBUG"
					( Origin gFrontEnd )
				)
				( attribute "ROT" "0"
					( Origin gFrontEnd )
				)
				( attribute "SEC" "1"
					( Origin gFrontEnd )
				)
				( attribute "SEC_TYPE" "0402"
					( Origin gFrontEnd )
				)
				( attribute "TOLERANCE" "1%"
					( Origin gFrontEnd )
				)
				( attribute "VALUE" "150.0"
					( Origin gFrontEnd )
				)
				( attribute "VER" "2"
					( Origin gFrontEnd )
				)
				( attribute "WATTAGE" "1/16W"
					( Origin gFrontEnd )
				)
				( attribute "XY" "(-2325,4425)"
					( Origin gFrontEnd )
				)
				( attribute "CHIPS_PART_NAME" "RES"
					( Origin gPackager )
				)
				( attribute "CDS_PART_NAME" "RES_0402-150.0,1%,1/16W,CHIP,GA"
					( Origin gPackager )
				)
				( objectStatus "R8A13" )
			)
			( gate "@baseboard_fab2_lib.baseboard_fab2(sch_1):page112_i80"
				( attribute "CDS_LIB" "mstr_discrete"
					( Origin gPackager )
				)
				( attribute "CDS_LOCATION" "R8A14"
					( Origin gPackager )
				)
				( attribute "CDS_SEC" "1"
					( Origin gPackager )
				)
				( attribute "LOCATION" "R8A14"
					( Origin gFrontEnd )
				)
				( attribute "MATERIAL" "CHIP"
					( Origin gFrontEnd )
				)
				( attribute "PACK_TYPE" "0402"
					( Origin gFrontEnd )
				)
				( attribute "PART_NUMBER" "G21796-009"
					( Origin gFrontEnd )
				)
				( attribute "PHYS_PAGE" "112"
					( Origin gFrontEnd )
				)
				( attribute "ROOM" "DEBUG"
					( Origin gFrontEnd )
				)
				( attribute "ROT" "0"
					( Origin gFrontEnd )
				)
				( attribute "SEC" "1"
					( Origin gFrontEnd )
				)
				( attribute "SEC_TYPE" "0402"
					( Origin gFrontEnd )
				)
				( attribute "TOLERANCE" "1%"
					( Origin gFrontEnd )
				)
				( attribute "VALUE" "150.0"
					( Origin gFrontEnd )
				)
				( attribute "VER" "2"
					( Origin gFrontEnd )
				)
				( attribute "WATTAGE" "1/16W"
					( Origin gFrontEnd )
				)
				( attribute "XY" "(-2700,4425)"
					( Origin gFrontEnd )
				)
				( attribute "CHIPS_PART_NAME" "RES"
					( Origin gPackager )
				)
				( attribute "CDS_PART_NAME" "RES_0402-150.0,1%,1/16W,CHIP,GA"
					( Origin gPackager )
				)
				( objectStatus "R8A14" )
			)
			( gate "@baseboard_fab2_lib.baseboard_fab2(sch_1):page112_i85"
				( attribute "BOM_COST" "DEBUG"
					( Origin gFrontEnd )
				)
				( attribute "CDS_LIB" "mstr_discrete"
					( Origin gPackager )
				)
				( attribute "CDS_LOCATION" "R3M10"
					( Origin gPackager )
				)
				( attribute "CDS_SEC" "1"
					( Origin gPackager )
				)
				( attribute "LOCATION" "R3M10"
					( Origin gFrontEnd )
				)
				( attribute "MATERIAL" "CHIP"
					( Origin gFrontEnd )
				)
				( attribute "PACK_TYPE" "0402"
					( Origin gFrontEnd )
				)
				( attribute "PART_NUMBER" "G21796-026"
					( Origin gFrontEnd )
				)
				( attribute "PHYS_PAGE" "112"
					( Origin gFrontEnd )
				)
				( attribute "ROOM" "DEBUG"
					( Origin gFrontEnd )
				)
				( attribute "ROT" "0"
					( Origin gFrontEnd )
				)
				( attribute "SEC" "1"
					( Origin gFrontEnd )
				)
				( attribute "SEC_TYPE" "0402"
					( Origin gFrontEnd )
				)
				( attribute "TOLERANCE" "1%"
					( Origin gFrontEnd )
				)
				( attribute "VALUE" "1.00K"
					( Origin gFrontEnd )
				)
				( attribute "VER" "2"
					( Origin gFrontEnd )
				)
				( attribute "WATTAGE" "1/16W"
					( Origin gFrontEnd )
				)
				( attribute "XY" "(-1950,3600)"
					( Origin gFrontEnd )
				)
				( attribute "CHIPS_PART_NAME" "RES"
					( Origin gPackager )
				)
				( attribute "CDS_PART_NAME" "RES_0402-1.00K,1%,1/16W,CHIP,GA"
					( Origin gPackager )
				)
				( objectStatus "R3M10" )
			)
			( gate "@baseboard_fab2_lib.baseboard_fab2(sch_1):page112_i94"
				( attribute "BOM_COST" "DEBUG"
					( Origin gFrontEnd )
				)
				( attribute "CDS_LIB" "mstr_discrete"
					( Origin gPackager )
				)
				( attribute "CDS_LOCATION" "R8B2"
					( Origin gPackager )
				)
				( attribute "CDS_SEC" "1"
					( Origin gPackager )
				)
				( attribute "LOCATION" "R8B2"
					( Origin gFrontEnd )
				)
				( attribute "MATERIAL" "CHIP"
					( Origin gFrontEnd )
				)
				( attribute "PACK_TYPE" "0402"
					( Origin gFrontEnd )
				)
				( attribute "PART_NUMBER" "G21796-026"
					( Origin gFrontEnd )
				)
				( attribute "PHYS_PAGE" "112"
					( Origin gFrontEnd )
				)
				( attribute "ROOM" "DEBUG"
					( Origin gFrontEnd )
				)
				( attribute "ROT" "0"
					( Origin gFrontEnd )
				)
				( attribute "SEC" "1"
					( Origin gFrontEnd )
				)
				( attribute "SEC_TYPE" "0402"
					( Origin gFrontEnd )
				)
				( attribute "TOLERANCE" "1%"
					( Origin gFrontEnd )
				)
				( attribute "VALUE" "1.00K"
					( Origin gFrontEnd )
				)
				( attribute "VER" "2"
					( Origin gFrontEnd )
				)
				( attribute "WATTAGE" "1/16W"
					( Origin gFrontEnd )
				)
				( attribute "XY" "(-2325,3600)"
					( Origin gFrontEnd )
				)
				( attribute "CHIPS_PART_NAME" "RES"
					( Origin gPackager )
				)
				( attribute "CDS_PART_NAME" "RES_0402-1.00K,1%,1/16W,CHIP,GA"
					( Origin gPackager )
				)
				( objectStatus "R8B2" )
			)
			( gate "@baseboard_fab2_lib.baseboard_fab2(sch_1):page112_i95"
				( attribute "BOM_COST" "DEBUG"
					( Origin gFrontEnd )
				)
				( attribute "CDS_LIB" "mstr_discrete"
					( Origin gPackager )
				)
				( attribute "CDS_LOCATION" "R8B1"
					( Origin gPackager )
				)
				( attribute "CDS_SEC" "1"
					( Origin gPackager )
				)
				( attribute "LOCATION" "R8B1"
					( Origin gFrontEnd )
				)
				( attribute "MATERIAL" "CHIP"
					( Origin gFrontEnd )
				)
				( attribute "PACK_TYPE" "0402"
					( Origin gFrontEnd )
				)
				( attribute "PART_NUMBER" "G21796-208"
					( Origin gFrontEnd )
				)
				( attribute "PHYS_PAGE" "112"
					( Origin gFrontEnd )
				)
				( attribute "ROOM" "DEBUG"
					( Origin gFrontEnd )
				)
				( attribute "ROT" "0"
					( Origin gFrontEnd )
				)
				( attribute "SEC" "1"
					( Origin gPackager )
				)
				( attribute "TOLERANCE" "1.0%"
					( Origin gFrontEnd )
				)
				( attribute "VALUE" "51.1"
					( Origin gFrontEnd )
				)
				( attribute "VER" "2"
					( Origin gFrontEnd )
				)
				( attribute "WATTAGE" "1/16W"
					( Origin gFrontEnd )
				)
				( attribute "XY" "(-2700,3600)"
					( Origin gFrontEnd )
				)
				( attribute "CHIPS_PART_NAME" "RES"
					( Origin gPackager )
				)
				( attribute "CDS_PART_NAME" "RES_0402-51.1,1.0%,1/16W,CHIP,A"
					( Origin gPackager )
				)
				( objectStatus "R8B1" )
			)
			( gate "@baseboard_fab2_lib.baseboard_fab2(sch_1):page112_i108"
				( attribute "CDS_LIB" "mstr_ttl"
					( Origin gPackager )
				)
				( attribute "CDS_LOCATION" "U1L1"
					( Origin gPackager )
				)
				( attribute "HAS_FIXED_SIZE" "4"
					( Origin gFrontEnd )
				)
				( attribute "LOCATION" "U1L1"
					( Origin gFrontEnd )
				)
				( attribute "MATERIAL" "IC"
					( Origin gFrontEnd )
				)
				( attribute "PACK_TYPE" "QFNLF"
					( Origin gFrontEnd )
				)
				( attribute "PART_NUMBER" "D18317-001"
					( Origin gFrontEnd )
				)
				( attribute "PHYS_PAGE" "112"
					( Origin gFrontEnd )
				)
				( attribute "ROOM" "DEBUG"
					( Origin gFrontEnd )
				)
				( attribute "ROT" "0"
					( Origin gFrontEnd )
				)
				( attribute "SIZE" "4"
					( Origin gFrontEnd )
				)
				( attribute "VALUE" "74CBTLV3126"
					( Origin gFrontEnd )
				)
				( attribute "VER" "3"
					( Origin gFrontEnd )
				)
				( attribute "XY" "(-2200,2425)"
					( Origin gFrontEnd )
				)
				( attribute "CHIPS_PART_NAME" "TTL3126"
					( Origin gPackager )
				)
				( attribute "CDS_PART_NAME" "TTL3126_QFNLF-74CBTLV3126,IC,DB"
					( Origin gPackager )
				)
				( objectStatus "U1L1" )
			)
			( gate "@baseboard_fab2_lib.baseboard_fab2(sch_1):page112_i109"
				( attribute "CDS_LIB" "mstr_ttl"
					( Origin gPackager )
				)
				( attribute "CDS_LOCATION" "U1L5"
					( Origin gPackager )
				)
				( attribute "HAS_FIXED_SIZE" "4"
					( Origin gFrontEnd )
				)
				( attribute "LOCATION" "U1L5"
					( Origin gFrontEnd )
				)
				( attribute "MATERIAL" "IC"
					( Origin gFrontEnd )
				)
				( attribute "PACK_TYPE" "QFNLF"
					( Origin gFrontEnd )
				)
				( attribute "PART_NUMBER" "D18317-001"
					( Origin gFrontEnd )
				)
				( attribute "PHYS_PAGE" "112"
					( Origin gFrontEnd )
				)
				( attribute "ROOM" "DEBUG"
					( Origin gFrontEnd )
				)
				( attribute "ROT" "0"
					( Origin gFrontEnd )
				)
				( attribute "SIZE" "4"
					( Origin gFrontEnd )
				)
				( attribute "VALUE" "74CBTLV3126"
					( Origin gFrontEnd )
				)
				( attribute "VER" "3"
					( Origin gFrontEnd )
				)
				( attribute "XY" "(-2200,1200)"
					( Origin gFrontEnd )
				)
				( attribute "CHIPS_PART_NAME" "TTL3126"
					( Origin gPackager )
				)
				( attribute "CDS_PART_NAME" "TTL3126_QFNLF-74CBTLV3126,IC,DB"
					( Origin gPackager )
				)
				( objectStatus "U1L5" )
			)
			( gate "@baseboard_fab2_lib.baseboard_fab2(sch_1):page112_i120"
				( attribute "CDS_LIB" "mstr_discrete"
					( Origin gPackager )
				)
				( attribute "CDS_LOCATION" "R6T9"
					( Origin gPackager )
				)
				( attribute "CDS_SEC" "1"
					( Origin gPackager )
				)
				( attribute "LOCATION" "R6T9"
					( Origin gFrontEnd )
				)
				( attribute "MATERIAL" "CHIP"
					( Origin gFrontEnd )
				)
				( attribute "PACK_TYPE" "0402"
					( Origin gFrontEnd )
				)
				( attribute "PART_NUMBER" "G21796-017"
					( Origin gFrontEnd )
				)
				( attribute "PHYS_PAGE" "112"
					( Origin gFrontEnd )
				)
				( attribute "ROOM" "DEBUG"
					( Origin gFrontEnd )
				)
				( attribute "ROT" "0"
					( Origin gFrontEnd )
				)
				( attribute "SEC" "1"
					( Origin gFrontEnd )
				)
				( attribute "SEC_TYPE" "0402"
					( Origin gFrontEnd )
				)
				( attribute "TOLERANCE" "1%"
					( Origin gFrontEnd )
				)
				( attribute "VALUE" "100.0"
					( Origin gFrontEnd )
				)
				( attribute "VER" "2"
					( Origin gFrontEnd )
				)
				( attribute "WATTAGE" "1/16W"
					( Origin gFrontEnd )
				)
				( attribute "XY" "(3500,2400)"
					( Origin gFrontEnd )
				)
				( attribute "CHIPS_PART_NAME" "RES"
					( Origin gPackager )
				)
				( attribute "CDS_PART_NAME" "RES_0402-100.0,1%,1/16W,CHIP,GA"
					( Origin gPackager )
				)
				( objectStatus "R6T9" )
			)
			( gate "@baseboard_fab2_lib.baseboard_fab2(sch_1):page112_i121"
				( attribute "CDS_LIB" "mstr_discrete"
					( Origin gPackager )
				)
				( attribute "CDS_LOCATION" "R6T8"
					( Origin gPackager )
				)
				( attribute "CDS_SEC" "1"
					( Origin gPackager )
				)
				( attribute "LOCATION" "R6T8"
					( Origin gFrontEnd )
				)
				( attribute "MATERIAL" "CHIP"
					( Origin gFrontEnd )
				)
				( attribute "PACK_TYPE" "0402"
					( Origin gFrontEnd )
				)
				( attribute "PART_NUMBER" "G21796-017"
					( Origin gFrontEnd )
				)
				( attribute "PHYS_PAGE" "112"
					( Origin gFrontEnd )
				)
				( attribute "ROOM" "DEBUG"
					( Origin gFrontEnd )
				)
				( attribute "ROT" "0"
					( Origin gFrontEnd )
				)
				( attribute "SEC" "1"
					( Origin gFrontEnd )
				)
				( attribute "SEC_TYPE" "0402"
					( Origin gFrontEnd )
				)
				( attribute "TOLERANCE" "1%"
					( Origin gFrontEnd )
				)
				( attribute "VALUE" "100.0"
					( Origin gFrontEnd )
				)
				( attribute "VER" "2"
					( Origin gFrontEnd )
				)
				( attribute "WATTAGE" "1/16W"
					( Origin gFrontEnd )
				)
				( attribute "XY" "(3175,2400)"
					( Origin gFrontEnd )
				)
				( attribute "CHIPS_PART_NAME" "RES"
					( Origin gPackager )
				)
				( attribute "CDS_PART_NAME" "RES_0402-100.0,1%,1/16W,CHIP,GA"
					( Origin gPackager )
				)
				( objectStatus "R6T8" )
			)
			( gate "@baseboard_fab2_lib.baseboard_fab2(sch_1):page112_i127"
				( attribute "BOM_COST" "DEBUG"
					( Origin gFrontEnd )
				)
				( attribute "CDS_LIB" "mstr_ttl"
					( Origin gPackager )
				)
				( attribute "CDS_LOCATION" "U1M4"
					( Origin gPackager )
				)
				( attribute "CDS_SEC" "1"
					( Origin gPackager )
				)
				( attribute "LOCATION" "U1M4"
					( Origin gFrontEnd )
				)
				( attribute "MATERIAL" "IC"
					( Origin gFrontEnd )
				)
				( attribute "PACK_TYPE" "SMLF"
					( Origin gFrontEnd )
				)
				( attribute "PART_NUMBER" "C88177-001"
					( Origin gFrontEnd )
				)
				( attribute "PHYS_PAGE" "112"
					( Origin gFrontEnd )
				)
				( attribute "ROOM" "DEBUG"
					( Origin gFrontEnd )
				)
				( attribute "ROT" "0"
					( Origin gFrontEnd )
				)
				( attribute "SEC" "1"
					( Origin gFrontEnd )
				)
				( attribute "SEC_TYPE" "SMLF"
					( Origin gFrontEnd )
				)
				( attribute "VER" "1"
					( Origin gFrontEnd )
				)
				( attribute "XY" "(3075,3425)"
					( Origin gFrontEnd )
				)
				( attribute "CHIPS_PART_NAME" "74CBTLV1G125"
					( Origin gPackager )
				)
				( attribute "CDS_PART_NAME" "74CBTLV1G125_SMLF-IC,C88177-00A"
					( Origin gPackager )
				)
				( objectStatus "U1M4" )
			)
			( gate "@baseboard_fab2_lib.baseboard_fab2(sch_1):page112_i131"
				( attribute "BOM_COST" "DEBUG"
					( Origin gFrontEnd )
				)
				( attribute "CDS_LIB" "dev_discrete"
					( Origin gPackager )
				)
				( attribute "CDS_LOCATION" "C1M30"
					( Origin gPackager )
				)
				( attribute "CDS_SEC" "1"
					( Origin gPackager )
				)
				( attribute "LOCATION" "C1M30"
					( Origin gFrontEnd )
				)
				( attribute "MATERIAL" "X7R"
					( Origin gFrontEnd )
				)
				( attribute "PACK_TYPE" "0402V"
					( Origin gFrontEnd )
				)
				( attribute "PART_NUMBER" "A36096-045"
					( Origin gFrontEnd )
				)
				( attribute "PHYS_PAGE" "112"
					( Origin gFrontEnd )
				)
				( attribute "ROOM" "DEBUG"
					( Origin gFrontEnd )
				)
				( attribute "ROT" "2"
					( Origin gFrontEnd )
				)
				( attribute "SEC" "1"
					( Origin gFrontEnd )
				)
				( attribute "SEC_TYPE" "0402V"
					( Origin gFrontEnd )
				)
				( attribute "TOLERANCE" "10%"
					( Origin gFrontEnd )
				)
				( attribute "VALUE" "0.01UF"
					( Origin gFrontEnd )
				)
				( attribute "VER" "1"
					( Origin gFrontEnd )
				)
				( attribute "VOLTAGE" "25V"
					( Units "uVoltage" "V" 1.000000)
					( Origin gFrontEnd )
				)
				( attribute "XY" "(3550,3725)"
					( Origin gFrontEnd )
				)
				( attribute "CHIPS_PART_NAME" "CAP_A"
					( Origin gPackager )
				)
				( attribute "CDS_PART_NAME" "CAP_A_0402V-0.01UF,25V,10%,X7RA"
					( Origin gPackager )
				)
				( objectStatus "C1M30" )
			)
			( gate "@baseboard_fab2_lib.baseboard_fab2(sch_1):page112_i136"
				( attribute "CDS_LIB" "mstr_discrete"
					( Origin gPackager )
				)
				( attribute "CDS_LOCATION" "C1L1"
					( Origin gPackager )
				)
				( attribute "CDS_SEC" "1"
					( Origin gPackager )
				)
				( attribute "LOCATION" "C1L1"
					( Origin gFrontEnd )
				)
				( attribute "MATERIAL" "X6S"
					( Origin gFrontEnd )
				)
				( attribute "PACK_TYPE" "0402"
					( Origin gFrontEnd )
				)
				( attribute "PART_NUMBER" "D97712-011"
					( Origin gFrontEnd )
				)
				( attribute "PHYS_PAGE" "112"
					( Origin gFrontEnd )
				)
				( attribute "ROOM" "DEBUG"
					( Origin gFrontEnd )
				)
				( attribute "ROT" "0"
					( Origin gFrontEnd )
				)
				( attribute "SEC" "1"
					( Origin gFrontEnd )
				)
				( attribute "SEC_TYPE" "0402"
					( Origin gFrontEnd )
				)
				( attribute "TOLERANCE" "10%"
					( Origin gFrontEnd )
				)
				( attribute "VALUE" "1.0UF"
					( Origin gFrontEnd )
				)
				( attribute "VER" "1"
					( Origin gFrontEnd )
				)
				( attribute "VOLTAGE" "16V"
					( Units "uVoltage" "V" 1.000000)
					( Origin gFrontEnd )
				)
				( attribute "XY" "(-1125,1850)"
					( Origin gFrontEnd )
				)
				( attribute "CHIPS_PART_NAME" "CAP"
					( Origin gPackager )
				)
				( attribute "CDS_PART_NAME" "CAP_0402-1.0UF,16V,10%,X6S,D97A"
					( Origin gPackager )
				)
				( objectStatus "C1L1" )
			)
			( gate "@baseboard_fab2_lib.baseboard_fab2(sch_1):page112_i140"
				( attribute "CDS_LIB" "mstr_discrete"
					( Origin gPackager )
				)
				( attribute "CDS_LOCATION" "C1L19"
					( Origin gPackager )
				)
				( attribute "CDS_SEC" "1"
					( Origin gPackager )
				)
				( attribute "LOCATION" "C1L19"
					( Origin gFrontEnd )
				)
				( attribute "MATERIAL" "X6S"
					( Origin gFrontEnd )
				)
				( attribute "PACK_TYPE" "0402"
					( Origin gFrontEnd )
				)
				( attribute "PART_NUMBER" "D97712-011"
					( Origin gFrontEnd )
				)
				( attribute "PHYS_PAGE" "112"
					( Origin gFrontEnd )
				)
				( attribute "ROOM" "DEBUG"
					( Origin gFrontEnd )
				)
				( attribute "ROT" "0"
					( Origin gFrontEnd )
				)
				( attribute "SEC" "1"
					( Origin gFrontEnd )
				)
				( attribute "SEC_TYPE" "0402"
					( Origin gFrontEnd )
				)
				( attribute "TOLERANCE" "10%"
					( Origin gFrontEnd )
				)
				( attribute "VALUE" "1.0UF"
					( Origin gFrontEnd )
				)
				( attribute "VER" "1"
					( Origin gFrontEnd )
				)
				( attribute "VOLTAGE" "16V"
					( Units "uVoltage" "V" 1.000000)
					( Origin gFrontEnd )
				)
				( attribute "XY" "(-1350,625)"
					( Origin gFrontEnd )
				)
				( attribute "CHIPS_PART_NAME" "CAP"
					( Origin gPackager )
				)
				( attribute "CDS_PART_NAME" "CAP_0402-1.0UF,16V,10%,X6S,D97A"
					( Origin gPackager )
				)
				( objectStatus "C1L19" )
			)
			( gate "@baseboard_fab2_lib.baseboard_fab2(sch_1):page113_i107"
				( attribute "BOM_COST" "DEBUG"
					( Origin gFrontEnd )
				)
				( attribute "CDS_LIB" "mstr_analog"
					( Origin gPackager )
				)
				( attribute "CDS_LOCATION" "U1M2"
					( Origin gPackager )
				)
				( attribute "CDS_SEC" "1"
					( Origin gPackager )
				)
				( attribute "LOCATION" "U1M2"
					( Origin gFrontEnd )
				)
				( attribute "MATERIAL" "IC"
					( Origin gFrontEnd )
				)
				( attribute "PACK_TYPE" "SMLF"
					( Origin gFrontEnd )
				)
				( attribute "PART_NUMBER" "C99406-001"
					( Origin gFrontEnd )
				)
				( attribute "PHYS_PAGE" "113"
					( Origin gFrontEnd )
				)
				( attribute "ROOM" "DEBUG"
					( Origin gFrontEnd )
				)
				( attribute "ROT" "2"
					( Origin gFrontEnd )
				)
				( attribute "SEC" "1"
					( Origin gFrontEnd )
				)
				( attribute "SEC_TYPE" "SMLF"
					( Origin gFrontEnd )
				)
				( attribute "VER" "1"
					( Origin gFrontEnd )
				)
				( attribute "XY" "(-2075,3525)"
					( Origin gFrontEnd )
				)
				( attribute "CHIPS_PART_NAME" "NC7SB3157"
					( Origin gPackager )
				)
				( attribute "CDS_PART_NAME" "NC7SB3157_SMLF-IC,C99406-001"
					( Origin gPackager )
				)
				( attribute "GROUP" "MCP"
					( Origin gFrontEnd )
				)
				( objectStatus "U1M2" )
			)
			( gate "@baseboard_fab2_lib.baseboard_fab2(sch_1):page113_i116"
				( attribute "BOM_COST" "DEBUG"
					( Origin gFrontEnd )
				)
				( attribute "CDS_LIB" "dev_discrete"
					( Origin gPackager )
				)
				( attribute "CDS_LOCATION" "C1M31"
					( Origin gPackager )
				)
				( attribute "CDS_SEC" "1"
					( Origin gPackager )
				)
				( attribute "LOCATION" "C1M31"
					( Origin gFrontEnd )
				)
				( attribute "MATERIAL" "X7R"
					( Origin gFrontEnd )
				)
				( attribute "PACK_TYPE" "0402V"
					( Origin gFrontEnd )
				)
				( attribute "PART_NUMBER" "A36096-045"
					( Origin gFrontEnd )
				)
				( attribute "PHYS_PAGE" "113"
					( Origin gFrontEnd )
				)
				( attribute "ROOM" "DEBUG"
					( Origin gFrontEnd )
				)
				( attribute "ROT" "2"
					( Origin gFrontEnd )
				)
				( attribute "SEC" "1"
					( Origin gFrontEnd )
				)
				( attribute "SEC_TYPE" "0402V"
					( Origin gFrontEnd )
				)
				( attribute "TOLERANCE" "10%"
					( Origin gFrontEnd )
				)
				( attribute "VALUE" "0.01UF"
					( Origin gFrontEnd )
				)
				( attribute "VER" "1"
					( Origin gFrontEnd )
				)
				( attribute "VOLTAGE" "25V"
					( Units "uVoltage" "V" 1.000000)
					( Origin gFrontEnd )
				)
				( attribute "XY" "(-1550,3025)"
					( Origin gFrontEnd )
				)
				( attribute "CHIPS_PART_NAME" "CAP_A"
					( Origin gPackager )
				)
				( attribute "CDS_PART_NAME" "CAP_A_0402V-0.01UF,25V,10%,X7RA"
					( Origin gPackager )
				)
				( attribute "GROUP" "MCP"
					( Origin gFrontEnd )
				)
				( objectStatus "C1M31" )
			)
			( gate "@baseboard_fab2_lib.baseboard_fab2(sch_1):page113_i117"
				( attribute "BOM_COST" "DEBUG"
					( Origin gFrontEnd )
				)
				( attribute "CDS_LIB" "dev_discrete"
					( Origin gPackager )
				)
				( attribute "CDS_LOCATION" "C1M32"
					( Origin gPackager )
				)
				( attribute "CDS_SEC" "1"
					( Origin gPackager )
				)
				( attribute "LOCATION" "C1M32"
					( Origin gFrontEnd )
				)
				( attribute "MATERIAL" "X6S"
					( Origin gFrontEnd )
				)
				( attribute "PACK_TYPE" "0402V"
					( Origin gFrontEnd )
				)
				( attribute "PART_NUMBER" "D97712-004"
					( Origin gFrontEnd )
				)
				( attribute "PHYS_PAGE" "113"
					( Origin gFrontEnd )
				)
				( attribute "ROOM" "DEBUG"
					( Origin gFrontEnd )
				)
				( attribute "ROT" "2"
					( Origin gFrontEnd )
				)
				( attribute "SEC" "1"
					( Origin gFrontEnd )
				)
				( attribute "SEC_TYPE" "0402V"
					( Origin gFrontEnd )
				)
				( attribute "TOLERANCE" "10%"
					( Origin gFrontEnd )
				)
				( attribute "VALUE" "1.0UF"
					( Origin gFrontEnd )
				)
				( attribute "VER" "1"
					( Origin gFrontEnd )
				)
				( attribute "VOLTAGE" "6.3V"
					( Units "uVoltage" "V" 1.000000)
					( Origin gFrontEnd )
				)
				( attribute "XY" "(-1250,3025)"
					( Origin gFrontEnd )
				)
				( attribute "CHIPS_PART_NAME" "CAP_A"
					( Origin gPackager )
				)
				( attribute "CDS_PART_NAME" "CAP_A_0402V-1.0UF,6.3V,10%,X6SA"
					( Origin gPackager )
				)
				( attribute "GROUP" "MCP"
					( Origin gFrontEnd )
				)
				( objectStatus "C1M32" )
			)
			( gate "@baseboard_fab2_lib.baseboard_fab2(sch_1):page113_i119"
				( attribute "BOM_COST" "DEBUG"
					( Origin gFrontEnd )
				)
				( attribute "CDS_LIB" "dev_discrete"
					( Origin gPackager )
				)
				( attribute "CDS_LOCATION" "C1M28"
					( Origin gPackager )
				)
				( attribute "CDS_SEC" "1"
					( Origin gPackager )
				)
				( attribute "LOCATION" "C1M28"
					( Origin gFrontEnd )
				)
				( attribute "MATERIAL" "X7R"
					( Origin gFrontEnd )
				)
				( attribute "PACK_TYPE" "0402V"
					( Origin gFrontEnd )
				)
				( attribute "PART_NUMBER" "A36096-045"
					( Origin gFrontEnd )
				)
				( attribute "PHYS_PAGE" "113"
					( Origin gFrontEnd )
				)
				( attribute "ROOM" "DEBUG"
					( Origin gFrontEnd )
				)
				( attribute "ROT" "2"
					( Origin gFrontEnd )
				)
				( attribute "SEC" "1"
					( Origin gFrontEnd )
				)
				( attribute "SEC_TYPE" "0402V"
					( Origin gFrontEnd )
				)
				( attribute "TOLERANCE" "10%"
					( Origin gFrontEnd )
				)
				( attribute "VALUE" "0.01UF"
					( Origin gFrontEnd )
				)
				( attribute "VER" "1"
					( Origin gFrontEnd )
				)
				( attribute "VOLTAGE" "25V"
					( Units "uVoltage" "V" 1.000000)
					( Origin gFrontEnd )
				)
				( attribute "XY" "(-2250,1250)"
					( Origin gFrontEnd )
				)
				( attribute "CHIPS_PART_NAME" "CAP_A"
					( Origin gPackager )
				)
				( attribute "CDS_PART_NAME" "CAP_A_0402V-0.01UF,25V,10%,X7RA"
					( Origin gPackager )
				)
				( attribute "GROUP" "MCP"
					( Origin gFrontEnd )
				)
				( objectStatus "C1M28" )
			)
			( gate "@baseboard_fab2_lib.baseboard_fab2(sch_1):page113_i127"
				( attribute "BOM_COST" "DEBUG"
					( Origin gFrontEnd )
				)
				( attribute "CDS_LIB" "mstr_ttl"
					( Origin gPackager )
				)
				( attribute "CDS_LOCATION" "U1M6"
					( Origin gPackager )
				)
				( attribute "CDS_SEC" "1"
					( Origin gPackager )
				)
				( attribute "LOCATION" "U1M6"
					( Origin gFrontEnd )
				)
				( attribute "MATERIAL" "IC"
					( Origin gFrontEnd )
				)
				( attribute "PACK_TYPE" "SMLF"
					( Origin gFrontEnd )
				)
				( attribute "PART_NUMBER" "C88177-001"
					( Origin gFrontEnd )
				)
				( attribute "PHYS_PAGE" "113"
					( Origin gFrontEnd )
				)
				( attribute "ROOM" "DEBUG"
					( Origin gFrontEnd )
				)
				( attribute "ROT" "0"
					( Origin gFrontEnd )
				)
				( attribute "SEC" "1"
					( Origin gFrontEnd )
				)
				( attribute "SEC_TYPE" "SMLF"
					( Origin gFrontEnd )
				)
				( attribute "VER" "1"
					( Origin gFrontEnd )
				)
				( attribute "XY" "(-1500,850)"
					( Origin gFrontEnd )
				)
				( attribute "CHIPS_PART_NAME" "74CBTLV1G125"
					( Origin gPackager )
				)
				( attribute "CDS_PART_NAME" "74CBTLV1G125_SMLF-IC,C88177-00A"
					( Origin gPackager )
				)
				( attribute "GROUP" "MCP"
					( Origin gFrontEnd )
				)
				( objectStatus "U1M6" )
			)
			( gate "@baseboard_fab2_lib.baseboard_fab2(sch_1):page113_i147"
				( attribute "CDS_LIB" "dev_discrete"
					( Origin gPackager )
				)
				( attribute "CDS_LOCATION" "C1M29"
					( Origin gPackager )
				)
				( attribute "CDS_SEC" "1"
					( Origin gPackager )
				)
				( attribute "LOCATION" "C1M29"
					( Origin gFrontEnd )
				)
				( attribute "MATERIAL" "X7R"
					( Origin gFrontEnd )
				)
				( attribute "PACK_TYPE" "0402V"
					( Origin gFrontEnd )
				)
				( attribute "PART_NUMBER" "A36096-030"
					( Origin gFrontEnd )
				)
				( attribute "PHYS_PAGE" "113"
					( Origin gFrontEnd )
				)
				( attribute "ROOM" "DEBUG"
					( Origin gFrontEnd )
				)
				( attribute "ROT" "0"
					( Origin gFrontEnd )
				)
				( attribute "SEC" "1"
					( Origin gPackager )
				)
				( attribute "TOLERANCE" "10%"
					( Origin gFrontEnd )
				)
				( attribute "VALUE" "0.1UF"
					( Origin gFrontEnd )
				)
				( attribute "VER" "1"
					( Origin gFrontEnd )
				)
				( attribute "VOLTAGE" "16V"
					( Units "uVoltage" "V" 1.000000)
					( Origin gFrontEnd )
				)
				( attribute "XY" "(-975,4650)"
					( Origin gFrontEnd )
				)
				( attribute "CHIPS_PART_NAME" "CAP_A"
					( Origin gPackager )
				)
				( attribute "CDS_PART_NAME" "CAP_A_0402V-0.1UF,16V,10%,X7R,A"
					( Origin gPackager )
				)
				( attribute "GROUP" "MCP"
					( Origin gFrontEnd )
				)
				( objectStatus "C1M29" )
			)
			( gate "@baseboard_fab2_lib.baseboard_fab2(sch_1):page113_i168"
				( attribute "CDS_LIB" "mstr_discrete"
					( Origin gPackager )
				)
				( attribute "CDS_LOCATION" "R9B14"
					( Origin gPackager )
				)
				( attribute "CDS_SEC" "1"
					( Origin gPackager )
				)
				( attribute "LOCATION" "R9B14"
					( Origin gFrontEnd )
				)
				( attribute "MATERIAL" "CHIP"
					( Origin gFrontEnd )
				)
				( attribute "PACK_TYPE" "0402"
					( Origin gFrontEnd )
				)
				( attribute "PART_NUMBER" "G21796-026"
					( Origin gFrontEnd )
				)
				( attribute "PHYS_PAGE" "113"
					( Origin gFrontEnd )
				)
				( attribute "ROOM" "DEBUG"
					( Origin gFrontEnd )
				)
				( attribute "ROT" "0"
					( Origin gFrontEnd )
				)
				( attribute "SEC" "1"
					( Origin gFrontEnd )
				)
				( attribute "SEC_TYPE" "0402"
					( Origin gFrontEnd )
				)
				( attribute "TOLERANCE" "1%"
					( Origin gFrontEnd )
				)
				( attribute "VALUE" "1.00K"
					( Origin gFrontEnd )
				)
				( attribute "VER" "1"
					( Origin gFrontEnd )
				)
				( attribute "WATTAGE" "1/16W"
					( Origin gFrontEnd )
				)
				( attribute "XY" "(-2600,4150)"
					( Origin gFrontEnd )
				)
				( attribute "CHIPS_PART_NAME" "RES"
					( Origin gPackager )
				)
				( attribute "CDS_PART_NAME" "RES_0402-1.00K,1%,1/16W,CHIP,GA"
					( Origin gPackager )
				)
				( attribute "GROUP" "MCP"
					( Origin gFrontEnd )
				)
				( objectStatus "R9B14" )
			)
			( gate "@baseboard_fab2_lib.baseboard_fab2(sch_1):page113_i175"
				( attribute "CDS_LIB" "mstr_sconn"
					( Origin gPackager )
				)
				( attribute "CDS_LOCATION" "J9B4"
					( Origin gPackager )
				)
				( attribute "CDS_SEC" "1"
					( Origin gPackager )
				)
				( attribute "LOCATION" "J9B4"
					( Origin gFrontEnd )
				)
				( attribute "MATERIAL" "CONN"
					( Origin gFrontEnd )
				)
				( attribute "PACK_TYPE" "SMLF"
					( Origin gFrontEnd )
				)
				( attribute "PART_NUMBER" "C12536-004"
					( Origin gFrontEnd )
				)
				( attribute "PHYS_PAGE" "113"
					( Origin gFrontEnd )
				)
				( attribute "ROOM" "DEBUG"
					( Origin gFrontEnd )
				)
				( attribute "ROT" "0"
					( Origin gFrontEnd )
				)
				( attribute "SEC" "1"
					( Origin gFrontEnd )
				)
				( attribute "SEC_TYPE" "SMLF"
					( Origin gFrontEnd )
				)
				( attribute "VER" "1"
					( Origin gFrontEnd )
				)
				( attribute "XY" "(-1375,4375)"
					( Origin gFrontEnd )
				)
				( attribute "CHIPS_PART_NAME" "SCONN10_C12536004"
					( Origin gPackager )
				)
				( attribute "CDS_PART_NAME" "SCONN10_C12536004_SMLF-CONN,C1A"
					( Origin gPackager )
				)
				( attribute "GROUP" "MCP"
					( Origin gFrontEnd )
				)
				( objectStatus "J9B4" )
			)
			( gate "@baseboard_fab2_lib.baseboard_fab2(sch_1):page113_i179"
				( attribute "CDS_LIB" "mstr_discrete"
					( Origin gPackager )
				)
				( attribute "CDS_LOCATION" "R9B9"
					( Origin gPackager )
				)
				( attribute "CDS_SEC" "1"
					( Origin gPackager )
				)
				( attribute "LOCATION" "R9B9"
					( Origin gFrontEnd )
				)
				( attribute "MATERIAL" "CHIP"
					( Origin gFrontEnd )
				)
				( attribute "PACK_TYPE" "0402"
					( Origin gFrontEnd )
				)
				( attribute "PART_NUMBER" "G21796-026"
					( Origin gFrontEnd )
				)
				( attribute "PHYS_PAGE" "113"
					( Origin gFrontEnd )
				)
				( attribute "ROT" "2"
					( Origin gFrontEnd )
				)
				( attribute "SEC" "1"
					( Origin gFrontEnd )
				)
				( attribute "SEC_TYPE" "0402"
					( Origin gFrontEnd )
				)
				( attribute "TOLERANCE" "1%"
					( Origin gFrontEnd )
				)
				( attribute "VALUE" "1.00K"
					( Origin gFrontEnd )
				)
				( attribute "VER" "2"
					( Origin gFrontEnd )
				)
				( attribute "WATTAGE" "1/16W"
					( Origin gFrontEnd )
				)
				( attribute "XY" "(2600,4150)"
					( Origin gFrontEnd )
				)
				( attribute "CHIPS_PART_NAME" "RES"
					( Origin gPackager )
				)
				( attribute "CDS_PART_NAME" "RES_0402-1.00K,1%,1/16W,CHIP,GA"
					( Origin gPackager )
				)
				( attribute "GROUP" "MCP"
					( Origin gFrontEnd )
				)
				( objectStatus "R9B9" )
			)
			( gate "@baseboard_fab2_lib.baseboard_fab2(sch_1):page113_i180"
				( attribute "BOM_COST" "DEBUG"
					( Origin gFrontEnd )
				)
				( attribute "CDS_LIB" "mstr_discrete"
					( Origin gPackager )
				)
				( attribute "CDS_LOCATION" "R9B10"
					( Origin gPackager )
				)
				( attribute "CDS_SEC" "1"
					( Origin gPackager )
				)
				( attribute "LOCATION" "R9B10"
					( Origin gFrontEnd )
				)
				( attribute "MATERIAL" "CHIP"
					( Origin gFrontEnd )
				)
				( attribute "PACK_TYPE" "0402"
					( Origin gFrontEnd )
				)
				( attribute "PART_NUMBER" "G21796-047"
					( Origin gFrontEnd )
				)
				( attribute "PHYS_PAGE" "113"
					( Origin gFrontEnd )
				)
				( attribute "ROOM" "DEBUG"
					( Origin gFrontEnd )
				)
				( attribute "ROT" "0"
					( Origin gFrontEnd )
				)
				( attribute "SEC" "1"
					( Origin gFrontEnd )
				)
				( attribute "SEC_TYPE" "0402"
					( Origin gFrontEnd )
				)
				( attribute "TOLERANCE" "1%"
					( Origin gFrontEnd )
				)
				( attribute "VALUE" "49.9"
					( Origin gFrontEnd )
				)
				( attribute "VER" "1"
					( Origin gFrontEnd )
				)
				( attribute "WATTAGE" "1/16W"
					( Origin gFrontEnd )
				)
				( attribute "XY" "(2800,4400)"
					( Origin gFrontEnd )
				)
				( attribute "CHIPS_PART_NAME" "RES"
					( Origin gPackager )
				)
				( attribute "CDS_PART_NAME" "RES_0402-49.9,1%,1/16W,CHIP,G2A"
					( Origin gPackager )
				)
				( attribute "POP" "NOPOP"
					( Origin gFrontEnd )
				)
				( objectStatus "R9B10" )
			)
			( gate "@baseboard_fab2_lib.baseboard_fab2(sch_1):page113_i185"
				( attribute "BOM_COST" "DEBUG"
					( Origin gFrontEnd )
				)
				( attribute "CDS_LIB" "mstr_ttl"
					( Origin gPackager )
				)
				( attribute "CDS_LOCATION" "U9A5"
					( Origin gPackager )
				)
				( attribute "CDS_SEC" "1"
					( Origin gPackager )
				)
				( attribute "LOCATION" "U9A5"
					( Origin gFrontEnd )
				)
				( attribute "MATERIAL" "IC"
					( Origin gFrontEnd )
				)
				( attribute "PACK_TYPE" "SMLF"
					( Origin gFrontEnd )
				)
				( attribute "PART_NUMBER" "C88177-001"
					( Origin gFrontEnd )
				)
				( attribute "PHYS_PAGE" "113"
					( Origin gFrontEnd )
				)
				( attribute "ROOM" "DEBUG"
					( Origin gFrontEnd )
				)
				( attribute "ROT" "0"
					( Origin gFrontEnd )
				)
				( attribute "SEC" "1"
					( Origin gFrontEnd )
				)
				( attribute "SEC_TYPE" "SMLF"
					( Origin gFrontEnd )
				)
				( attribute "VER" "1"
					( Origin gFrontEnd )
				)
				( attribute "XY" "(3650,4400)"
					( Origin gFrontEnd )
				)
				( attribute "CHIPS_PART_NAME" "74CBTLV1G125"
					( Origin gPackager )
				)
				( attribute "CDS_PART_NAME" "74CBTLV1G125_SMLF-IC,C88177-00A"
					( Origin gPackager )
				)
				( attribute "POP" "NOPOP"
					( Origin gFrontEnd )
				)
				( objectStatus "U9A5" )
			)
			( gate "@baseboard_fab2_lib.baseboard_fab2(sch_1):page113_i190"
				( attribute "BOM_COST" "DEBUG"
					( Origin gFrontEnd )
				)
				( attribute "CDS_LIB" "mstr_ttl"
					( Origin gPackager )
				)
				( attribute "CDS_LOCATION" "U6M1"
					( Origin gPackager )
				)
				( attribute "CDS_SEC" "1"
					( Origin gPackager )
				)
				( attribute "LOCATION" "U6M1"
					( Origin gFrontEnd )
				)
				( attribute "MATERIAL" "IC"
					( Origin gFrontEnd )
				)
				( attribute "PACK_TYPE" "SMLF"
					( Origin gFrontEnd )
				)
				( attribute "PART_NUMBER" "C88177-001"
					( Origin gFrontEnd )
				)
				( attribute "PHYS_PAGE" "113"
					( Origin gFrontEnd )
				)
				( attribute "ROOM" "DEBUG"
					( Origin gFrontEnd )
				)
				( attribute "ROT" "0"
					( Origin gFrontEnd )
				)
				( attribute "SEC" "1"
					( Origin gFrontEnd )
				)
				( attribute "SEC_TYPE" "SMLF"
					( Origin gFrontEnd )
				)
				( attribute "VER" "1"
					( Origin gFrontEnd )
				)
				( attribute "XY" "(1600,2000)"
					( Origin gFrontEnd )
				)
				( attribute "CHIPS_PART_NAME" "74CBTLV1G125"
					( Origin gPackager )
				)
				( attribute "CDS_PART_NAME" "74CBTLV1G125_SMLF-IC,C88177-00A"
					( Origin gPackager )
				)
				( attribute "POP" "NOPOP"
					( Origin gFrontEnd )
				)
				( objectStatus "U6M1" )
			)
			( gate "@baseboard_fab2_lib.baseboard_fab2(sch_1):page113_i195"
				( attribute "CDS_LIB" "mstr_discrete"
					( Origin gPackager )
				)
				( attribute "CDS_LOCATION" "R1M22"
					( Origin gPackager )
				)
				( attribute "CDS_SEC" "1"
					( Origin gPackager )
				)
				( attribute "LOCATION" "R1M22"
					( Origin gFrontEnd )
				)
				( attribute "MATERIAL" "CHIP"
					( Origin gFrontEnd )
				)
				( attribute "PACK_TYPE" "0402"
					( Origin gFrontEnd )
				)
				( attribute "PART_NUMBER" "G21796-047"
					( Origin gFrontEnd )
				)
				( attribute "PHYS_PAGE" "113"
					( Origin gFrontEnd )
				)
				( attribute "ROOM" "DEBUG"
					( Origin gFrontEnd )
				)
				( attribute "ROT" "2"
					( Origin gFrontEnd )
				)
				( attribute "SEC" "1"
					( Origin gFrontEnd )
				)
				( attribute "SEC_TYPE" "0402"
					( Origin gFrontEnd )
				)
				( attribute "TOLERANCE" "1%"
					( Origin gFrontEnd )
				)
				( attribute "VALUE" "49.9"
					( Origin gFrontEnd )
				)
				( attribute "VER" "2"
					( Origin gFrontEnd )
				)
				( attribute "WATTAGE" "1/16W"
					( Origin gFrontEnd )
				)
				( attribute "XY" "(2450,2650)"
					( Origin gFrontEnd )
				)
				( attribute "CHIPS_PART_NAME" "RES"
					( Origin gPackager )
				)
				( attribute "CDS_PART_NAME" "RES_0402-49.9,1%,1/16W,CHIP,G2A"
					( Origin gPackager )
				)
				( attribute "POP" "NOPOP"
					( Origin gFrontEnd )
				)
				( objectStatus "R1M22" )
			)
			( gate "@baseboard_fab2_lib.baseboard_fab2(sch_1):page113_i196"
				( attribute "BOM_COST" "DEBUG"
					( Origin gFrontEnd )
				)
				( attribute "CDS_LIB" "mstr_ttl"
					( Origin gPackager )
				)
				( attribute "CDS_LOCATION" "U1M5"
					( Origin gPackager )
				)
				( attribute "CDS_SEC" "1"
					( Origin gPackager )
				)
				( attribute "LOCATION" "U1M5"
					( Origin gFrontEnd )
				)
				( attribute "MATERIAL" "IC"
					( Origin gFrontEnd )
				)
				( attribute "PACK_TYPE" "SMLF"
					( Origin gFrontEnd )
				)
				( attribute "PART_NUMBER" "C88177-001"
					( Origin gFrontEnd )
				)
				( attribute "PHYS_PAGE" "113"
					( Origin gFrontEnd )
				)
				( attribute "ROOM" "DEBUG"
					( Origin gFrontEnd )
				)
				( attribute "ROT" "0"
					( Origin gFrontEnd )
				)
				( attribute "SEC" "1"
					( Origin gFrontEnd )
				)
				( attribute "SEC_TYPE" "SMLF"
					( Origin gFrontEnd )
				)
				( attribute "VER" "1"
					( Origin gFrontEnd )
				)
				( attribute "XY" "(1600,2825)"
					( Origin gFrontEnd )
				)
				( attribute "CHIPS_PART_NAME" "74CBTLV1G125"
					( Origin gPackager )
				)
				( attribute "CDS_PART_NAME" "74CBTLV1G125_SMLF-IC,C88177-00A"
					( Origin gPackager )
				)
				( attribute "POP" "NOPOP"
					( Origin gFrontEnd )
				)
				( objectStatus "U1M5" )
			)
			( gate "@baseboard_fab2_lib.baseboard_fab2(sch_1):page113_i199"
				( attribute "BOM_COST" "DEBUG"
					( Origin gFrontEnd )
				)
				( attribute "CDS_LIB" "mstr_discrete"
					( Origin gPackager )
				)
				( attribute "CDS_LOCATION" "R1M23"
					( Origin gPackager )
				)
				( attribute "CDS_SEC" "1"
					( Origin gPackager )
				)
				( attribute "LOCATION" "R1M23"
					( Origin gFrontEnd )
				)
				( attribute "MATERIAL" "EMPTY"
					( Origin gFrontEnd )
				)
				( attribute "PACK_TYPE" "0402"
					( Origin gFrontEnd )
				)
				( attribute "PART_NUMBER" "G21796-026"
					( Origin gFrontEnd )
				)
				( attribute "PHYS_PAGE" "113"
					( Origin gFrontEnd )
				)
				( attribute "ROOM" "DEBUG"
					( Origin gFrontEnd )
				)
				( attribute "ROT" "0"
					( Origin gFrontEnd )
				)
				( attribute "SEC" "1"
					( Origin gFrontEnd )
				)
				( attribute "SEC_TYPE" "0402"
					( Origin gFrontEnd )
				)
				( attribute "TOLERANCE" "1%"
					( Origin gFrontEnd )
				)
				( attribute "VALUE" "1.00K"
					( Origin gFrontEnd )
				)
				( attribute "VER" "2"
					( Origin gFrontEnd )
				)
				( attribute "WATTAGE" "1/16W"
					( Origin gFrontEnd )
				)
				( attribute "XY" "(1400,4225)"
					( Origin gFrontEnd )
				)
				( attribute "CHIPS_PART_NAME" "RES"
					( Origin gPackager )
				)
				( attribute "CDS_PART_NAME" "RES_0402-1.00K,1%,1/16W,EMPTY,A"
					( Origin gPackager )
				)
				( objectStatus "R1M23" )
			)
			( gate "@baseboard_fab2_lib.baseboard_fab2(sch_1):page113_i202"
				( attribute "BOM_COST" "DEBUG"
					( Origin gFrontEnd )
				)
				( attribute "CDS_LIB" "mstr_discrete"
					( Origin gPackager )
				)
				( attribute "CDS_LOCATION" "R1M19"
					( Origin gPackager )
				)
				( attribute "CDS_SEC" "1"
					( Origin gPackager )
				)
				( attribute "LOCATION" "R1M19"
					( Origin gFrontEnd )
				)
				( attribute "MATERIAL" "CHIP"
					( Origin gFrontEnd )
				)
				( attribute "PACK_TYPE" "0402"
					( Origin gFrontEnd )
				)
				( attribute "PART_NUMBER" "G21796-026"
					( Origin gFrontEnd )
				)
				( attribute "PHYS_PAGE" "113"
					( Origin gFrontEnd )
				)
				( attribute "ROOM" "DEBUG"
					( Origin gFrontEnd )
				)
				( attribute "ROT" "0"
					( Origin gFrontEnd )
				)
				( attribute "SEC" "1"
					( Origin gFrontEnd )
				)
				( attribute "SEC_TYPE" "0402"
					( Origin gFrontEnd )
				)
				( attribute "TOLERANCE" "1%"
					( Origin gFrontEnd )
				)
				( attribute "VALUE" "1.00K"
					( Origin gFrontEnd )
				)
				( attribute "VER" "2"
					( Origin gFrontEnd )
				)
				( attribute "WATTAGE" "1/16W"
					( Origin gFrontEnd )
				)
				( attribute "XY" "(3175,1025)"
					( Origin gFrontEnd )
				)
				( attribute "CHIPS_PART_NAME" "RES"
					( Origin gPackager )
				)
				( attribute "CDS_PART_NAME" "RES_0402-1.00K,1%,1/16W,CHIP,GA"
					( Origin gPackager )
				)
				( attribute "GROUP" "MCP"
					( Origin gFrontEnd )
				)
				( objectStatus "R1M19" )
			)
			( gate "@baseboard_fab2_lib.baseboard_fab2(sch_1):page113_i203"
				( attribute "BOM_COST" "DEBUG"
					( Origin gFrontEnd )
				)
				( attribute "CDS_LIB" "mstr_discrete"
					( Origin gPackager )
				)
				( attribute "CDS_LOCATION" "R9B12"
					( Origin gPackager )
				)
				( attribute "CDS_SEC" "1"
					( Origin gPackager )
				)
				( attribute "LOCATION" "R9B12"
					( Origin gFrontEnd )
				)
				( attribute "MATERIAL" "CHIP"
					( Origin gFrontEnd )
				)
				( attribute "PACK_TYPE" "0402"
					( Origin gFrontEnd )
				)
				( attribute "PART_NUMBER" "G21796-026"
					( Origin gFrontEnd )
				)
				( attribute "PHYS_PAGE" "113"
					( Origin gFrontEnd )
				)
				( attribute "ROOM" "DEBUG"
					( Origin gFrontEnd )
				)
				( attribute "ROT" "0"
					( Origin gFrontEnd )
				)
				( attribute "SEC" "1"
					( Origin gFrontEnd )
				)
				( attribute "SEC_TYPE" "0402"
					( Origin gFrontEnd )
				)
				( attribute "TOLERANCE" "1%"
					( Origin gFrontEnd )
				)
				( attribute "VALUE" "1.00K"
					( Origin gFrontEnd )
				)
				( attribute "VER" "2"
					( Origin gFrontEnd )
				)
				( attribute "WATTAGE" "1/16W"
					( Origin gFrontEnd )
				)
				( attribute "XY" "(3425,1025)"
					( Origin gFrontEnd )
				)
				( attribute "CHIPS_PART_NAME" "RES"
					( Origin gPackager )
				)
				( attribute "CDS_PART_NAME" "RES_0402-1.00K,1%,1/16W,CHIP,GA"
					( Origin gPackager )
				)
				( attribute "GROUP" "MCP"
					( Origin gFrontEnd )
				)
				( objectStatus "R9B12" )
			)
			( gate "@baseboard_fab2_lib.baseboard_fab2(sch_1):page113_i204"
				( attribute "BOM_COST" "DEBUG"
					( Origin gFrontEnd )
				)
				( attribute "CDS_LIB" "mstr_discrete"
					( Origin gPackager )
				)
				( attribute "CDS_LOCATION" "R1M20"
					( Origin gPackager )
				)
				( attribute "CDS_SEC" "1"
					( Origin gPackager )
				)
				( attribute "LOCATION" "R1M20"
					( Origin gFrontEnd )
				)
				( attribute "MATERIAL" "CHIP"
					( Origin gFrontEnd )
				)
				( attribute "PACK_TYPE" "0402"
					( Origin gFrontEnd )
				)
				( attribute "PART_NUMBER" "G21796-026"
					( Origin gFrontEnd )
				)
				( attribute "PHYS_PAGE" "113"
					( Origin gFrontEnd )
				)
				( attribute "ROOM" "DEBUG"
					( Origin gFrontEnd )
				)
				( attribute "ROT" "0"
					( Origin gFrontEnd )
				)
				( attribute "SEC" "1"
					( Origin gFrontEnd )
				)
				( attribute "SEC_TYPE" "0402"
					( Origin gFrontEnd )
				)
				( attribute "TOLERANCE" "1%"
					( Origin gFrontEnd )
				)
				( attribute "VALUE" "1.00K"
					( Origin gFrontEnd )
				)
				( attribute "VER" "2"
					( Origin gFrontEnd )
				)
				( attribute "WATTAGE" "1/16W"
					( Origin gFrontEnd )
				)
				( attribute "XY" "(2925,1025)"
					( Origin gFrontEnd )
				)
				( attribute "CHIPS_PART_NAME" "RES"
					( Origin gPackager )
				)
				( attribute "CDS_PART_NAME" "RES_0402-1.00K,1%,1/16W,CHIP,GA"
					( Origin gPackager )
				)
				( attribute "POP" "NOPOP"
					( Origin gFrontEnd )
				)
				( objectStatus "R1M20" )
			)
			( gate "@baseboard_fab2_lib.baseboard_fab2(sch_1):page113_i205"
				( attribute "BOM_COST" "DEBUG"
					( Origin gFrontEnd )
				)
				( attribute "CDS_LIB" "mstr_discrete"
					( Origin gPackager )
				)
				( attribute "CDS_LOCATION" "R1M21"
					( Origin gPackager )
				)
				( attribute "CDS_SEC" "1"
					( Origin gPackager )
				)
				( attribute "LOCATION" "R1M21"
					( Origin gFrontEnd )
				)
				( attribute "MATERIAL" "CHIP"
					( Origin gFrontEnd )
				)
				( attribute "PACK_TYPE" "0402"
					( Origin gFrontEnd )
				)
				( attribute "PART_NUMBER" "G21796-026"
					( Origin gFrontEnd )
				)
				( attribute "PHYS_PAGE" "113"
					( Origin gFrontEnd )
				)
				( attribute "ROOM" "DEBUG"
					( Origin gFrontEnd )
				)
				( attribute "ROT" "0"
					( Origin gFrontEnd )
				)
				( attribute "SEC" "1"
					( Origin gFrontEnd )
				)
				( attribute "SEC_TYPE" "0402"
					( Origin gFrontEnd )
				)
				( attribute "TOLERANCE" "1%"
					( Origin gFrontEnd )
				)
				( attribute "VALUE" "1.00K"
					( Origin gFrontEnd )
				)
				( attribute "VER" "2"
					( Origin gFrontEnd )
				)
				( attribute "WATTAGE" "1/16W"
					( Origin gFrontEnd )
				)
				( attribute "XY" "(3675,1025)"
					( Origin gFrontEnd )
				)
				( attribute "CHIPS_PART_NAME" "RES"
					( Origin gPackager )
				)
				( attribute "CDS_PART_NAME" "RES_0402-1.00K,1%,1/16W,CHIP,GA"
					( Origin gPackager )
				)
				( attribute "GROUP" "MCP"
					( Origin gFrontEnd )
				)
				( objectStatus "R1M21" )
			)
			( gate "@baseboard_fab2_lib.baseboard_fab2(sch_1):page113_i206"
				( attribute "BOM_COST" "DEBUG"
					( Origin gFrontEnd )
				)
				( attribute "CDS_LIB" "mstr_ttl"
					( Origin gPackager )
				)
				( attribute "CDS_LOCATION" "U4R1"
					( Origin gPackager )
				)
				( attribute "CDS_SEC" "1"
					( Origin gPackager )
				)
				( attribute "LOCATION" "U4R1"
					( Origin gFrontEnd )
				)
				( attribute "MATERIAL" "IC"
					( Origin gFrontEnd )
				)
				( attribute "PACK_TYPE" "SMLF"
					( Origin gFrontEnd )
				)
				( attribute "PART_NUMBER" "C88177-001"
					( Origin gFrontEnd )
				)
				( attribute "PHYS_PAGE" "113"
					( Origin gFrontEnd )
				)
				( attribute "ROOM" "DEBUG"
					( Origin gFrontEnd )
				)
				( attribute "ROT" "0"
					( Origin gFrontEnd )
				)
				( attribute "SEC" "1"
					( Origin gFrontEnd )
				)
				( attribute "SEC_TYPE" "SMLF"
					( Origin gFrontEnd )
				)
				( attribute "VER" "1"
					( Origin gFrontEnd )
				)
				( attribute "XY" "(1625,3375)"
					( Origin gFrontEnd )
				)
				( attribute "CHIPS_PART_NAME" "74CBTLV1G125"
					( Origin gPackager )
				)
				( attribute "CDS_PART_NAME" "74CBTLV1G125_SMLF-IC,C88177-00A"
					( Origin gPackager )
				)
				( attribute "POP" "NOPOP"
					( Origin gFrontEnd )
				)
				( objectStatus "U4R1" )
			)
			( gate "@baseboard_fab2_lib.baseboard_fab2(sch_1):page113_i239"
				( attribute "CDS_LIB" "mstr_discrete"
					( Origin gPackager )
				)
				( attribute "CDS_LOCATION" "R9B11"
					( Origin gPackager )
				)
				( attribute "CDS_SEC" "1"
					( Origin gPackager )
				)
				( attribute "LOCATION" "R9B11"
					( Origin gFrontEnd )
				)
				( attribute "MATERIAL" "CHIP"
					( Origin gFrontEnd )
				)
				( attribute "PACK_TYPE" "0402"
					( Origin gFrontEnd )
				)
				( attribute "PART_NUMBER" "G21497-005"
					( Origin gFrontEnd )
				)
				( attribute "PHYS_PAGE" "113"
					( Origin gFrontEnd )
				)
				( attribute "ROT" "0"
					( Origin gFrontEnd )
				)
				( attribute "SEC" "1"
					( Origin gFrontEnd )
				)
				( attribute "SEC_TYPE" "0402"
					( Origin gFrontEnd )
				)
				( attribute "TOLERANCE" "5%"
					( Origin gFrontEnd )
				)
				( attribute "VALUE" "0.0"
					( Origin gFrontEnd )
				)
				( attribute "VER" "1"
					( Origin gFrontEnd )
				)
				( attribute "WATTAGE" "1/16W"
					( Origin gFrontEnd )
				)
				( attribute "XY" "(-2600,4625)"
					( Origin gFrontEnd )
				)
				( attribute "CHIPS_PART_NAME" "RES"
					( Origin gPackager )
				)
				( attribute "CDS_PART_NAME" "RES_0402-0.0,5%,1/16W,CHIP,G21A"
					( Origin gPackager )
				)
				( attribute "GROUP" "MCP"
					( Origin gFrontEnd )
				)
				( objectStatus "R9B11" )
			)
			( gate "@baseboard_fab2_lib.baseboard_fab2(sch_1):page113_i240"
				( attribute "CDS_LIB" "mstr_discrete"
					( Origin gPackager )
				)
				( attribute "CDS_LOCATION" "R9B13"
					( Origin gPackager )
				)
				( attribute "CDS_SEC" "1"
					( Origin gPackager )
				)
				( attribute "LOCATION" "R9B13"
					( Origin gFrontEnd )
				)
				( attribute "MATERIAL" "CHIP"
					( Origin gFrontEnd )
				)
				( attribute "PACK_TYPE" "0402"
					( Origin gFrontEnd )
				)
				( attribute "PART_NUMBER" "G21497-005"
					( Origin gFrontEnd )
				)
				( attribute "PHYS_PAGE" "113"
					( Origin gFrontEnd )
				)
				( attribute "ROT" "0"
					( Origin gFrontEnd )
				)
				( attribute "SEC" "1"
					( Origin gFrontEnd )
				)
				( attribute "SEC_TYPE" "0402"
					( Origin gFrontEnd )
				)
				( attribute "TOLERANCE" "5%"
					( Origin gFrontEnd )
				)
				( attribute "VALUE" "0.0"
					( Origin gFrontEnd )
				)
				( attribute "VER" "1"
					( Origin gFrontEnd )
				)
				( attribute "WATTAGE" "1/16W"
					( Origin gFrontEnd )
				)
				( attribute "XY" "(-2600,4375)"
					( Origin gFrontEnd )
				)
				( attribute "CHIPS_PART_NAME" "RES"
					( Origin gPackager )
				)
				( attribute "CDS_PART_NAME" "RES_0402-0.0,5%,1/16W,CHIP,G21A"
					( Origin gPackager )
				)
				( attribute "GROUP" "MCP"
					( Origin gFrontEnd )
				)
				( objectStatus "R9B13" )
			)
			( gate "@baseboard_fab2_lib.baseboard_fab2(sch_1):page113_i246"
				( attribute "CDS_LIB" "dev_discrete"
					( Origin gPackager )
				)
				( attribute "CDS_LOCATION" "C4R2"
					( Origin gPackager )
				)
				( attribute "CDS_SEC" "1"
					( Origin gPackager )
				)
				( attribute "LOCATION" "C4R2"
					( Origin gFrontEnd )
				)
				( attribute "MATERIAL" "X7R"
					( Origin gFrontEnd )
				)
				( attribute "PACK_TYPE" "0402V"
					( Origin gFrontEnd )
				)
				( attribute "PART_NUMBER" "A36096-030"
					( Origin gFrontEnd )
				)
				( attribute "PHYS_PAGE" "113"
					( Origin gFrontEnd )
				)
				( attribute "ROOM" "DEBUG"
					( Origin gFrontEnd )
				)
				( attribute "ROT" "2"
					( Origin gFrontEnd )
				)
				( attribute "SEC" "1"
					( Origin gFrontEnd )
				)
				( attribute "SEC_TYPE" "0402V"
					( Origin gFrontEnd )
				)
				( attribute "TOLERANCE" "10%"
					( Origin gFrontEnd )
				)
				( attribute "VALUE" "0.1UF"
					( Origin gFrontEnd )
				)
				( attribute "VER" "1"
					( Origin gFrontEnd )
				)
				( attribute "VOLTAGE" "16V"
					( Units "uVoltage" "V" 1.000000)
					( Origin gFrontEnd )
				)
				( attribute "XY" "(2125,3200)"
					( Origin gFrontEnd )
				)
				( attribute "CHIPS_PART_NAME" "CAP_A"
					( Origin gPackager )
				)
				( attribute "CDS_PART_NAME" "CAP_A_0402V-0.1UF,16V,10%,X7R,A"
					( Origin gPackager )
				)
				( attribute "POP" "NOPOP"
					( Origin gFrontEnd )
				)
				( objectStatus "C4R2" )
			)
			( gate "@baseboard_fab2_lib.baseboard_fab2(sch_1):page113_i248"
				( attribute "BOM_COST" "DEBUG"
					( Origin gFrontEnd )
				)
				( attribute "CDS_LIB" "dev_discrete"
					( Origin gPackager )
				)
				( attribute "CDS_LOCATION" "C1M33"
					( Origin gPackager )
				)
				( attribute "CDS_SEC" "1"
					( Origin gPackager )
				)
				( attribute "LOCATION" "C1M33"
					( Origin gFrontEnd )
				)
				( attribute "MATERIAL" "X7R"
					( Origin gFrontEnd )
				)
				( attribute "PACK_TYPE" "0402V"
					( Origin gFrontEnd )
				)
				( attribute "PART_NUMBER" "A36096-030"
					( Origin gFrontEnd )
				)
				( attribute "PHYS_PAGE" "113"
					( Origin gFrontEnd )
				)
				( attribute "ROOM" "DEBUG"
					( Origin gFrontEnd )
				)
				( attribute "ROT" "2"
					( Origin gFrontEnd )
				)
				( attribute "SEC" "1"
					( Origin gFrontEnd )
				)
				( attribute "SEC_TYPE" "0402V"
					( Origin gFrontEnd )
				)
				( attribute "TOLERANCE" "10%"
					( Origin gFrontEnd )
				)
				( attribute "VALUE" "0.1UF"
					( Origin gFrontEnd )
				)
				( attribute "VER" "1"
					( Origin gFrontEnd )
				)
				( attribute "VOLTAGE" "16V"
					( Units "uVoltage" "V" 1.000000)
					( Origin gFrontEnd )
				)
				( attribute "XY" "(2125,2650)"
					( Origin gFrontEnd )
				)
				( attribute "CHIPS_PART_NAME" "CAP_A"
					( Origin gPackager )
				)
				( attribute "CDS_PART_NAME" "CAP_A_0402V-0.1UF,16V,10%,X7R,A"
					( Origin gPackager )
				)
				( attribute "POP" "NOPOP"
					( Origin gFrontEnd )
				)
				( objectStatus "C1M33" )
			)
			( gate "@baseboard_fab2_lib.baseboard_fab2(sch_1):page113_i250"
				( attribute "BOM_COST" "DEBUG"
					( Origin gFrontEnd )
				)
				( attribute "CDS_LIB" "dev_discrete"
					( Origin gPackager )
				)
				( attribute "CDS_LOCATION" "C6M6"
					( Origin gPackager )
				)
				( attribute "CDS_SEC" "1"
					( Origin gPackager )
				)
				( attribute "LOCATION" "C6M6"
					( Origin gFrontEnd )
				)
				( attribute "MATERIAL" "X7R"
					( Origin gFrontEnd )
				)
				( attribute "PACK_TYPE" "0402V"
					( Origin gFrontEnd )
				)
				( attribute "PART_NUMBER" "A36096-030"
					( Origin gFrontEnd )
				)
				( attribute "PHYS_PAGE" "113"
					( Origin gFrontEnd )
				)
				( attribute "ROOM" "DEBUG"
					( Origin gFrontEnd )
				)
				( attribute "ROT" "2"
					( Origin gFrontEnd )
				)
				( attribute "SEC" "1"
					( Origin gFrontEnd )
				)
				( attribute "SEC_TYPE" "0402V"
					( Origin gFrontEnd )
				)
				( attribute "TOLERANCE" "10%"
					( Origin gFrontEnd )
				)
				( attribute "VALUE" "0.1UF"
					( Origin gFrontEnd )
				)
				( attribute "VER" "1"
					( Origin gFrontEnd )
				)
				( attribute "VOLTAGE" "16V"
					( Units "uVoltage" "V" 1.000000)
					( Origin gFrontEnd )
				)
				( attribute "XY" "(2150,1825)"
					( Origin gFrontEnd )
				)
				( attribute "CHIPS_PART_NAME" "CAP_A"
					( Origin gPackager )
				)
				( attribute "CDS_PART_NAME" "CAP_A_0402V-0.1UF,16V,10%,X7R,A"
					( Origin gPackager )
				)
				( attribute "POP" "NOPOP"
					( Origin gFrontEnd )
				)
				( objectStatus "C6M6" )
			)
			( gate "@baseboard_fab2_lib.baseboard_fab2(sch_1):page113_i255"
				( attribute "BOM_COST" "DEBUG"
					( Origin gFrontEnd )
				)
				( attribute "CDS_LIB" "mstr_analog"
					( Origin gPackager )
				)
				( attribute "CDS_LOCATION" "U2M1"
					( Origin gPackager )
				)
				( attribute "CDS_SEC" "1"
					( Origin gPackager )
				)
				( attribute "LOCATION" "U2M1"
					( Origin gFrontEnd )
				)
				( attribute "MATERIAL" "IC"
					( Origin gFrontEnd )
				)
				( attribute "PACK_TYPE" "SMLF"
					( Origin gFrontEnd )
				)
				( attribute "PART_NUMBER" "C99406-001"
					( Origin gFrontEnd )
				)
				( attribute "PHYS_PAGE" "113"
					( Origin gFrontEnd )
				)
				( attribute "ROOM" "DEBUG"
					( Origin gFrontEnd )
				)
				( attribute "ROT" "2"
					( Origin gFrontEnd )
				)
				( attribute "SEC" "1"
					( Origin gFrontEnd )
				)
				( attribute "SEC_TYPE" "SMLF"
					( Origin gFrontEnd )
				)
				( attribute "VER" "1"
					( Origin gFrontEnd )
				)
				( attribute "XY" "(-2125,2325)"
					( Origin gFrontEnd )
				)
				( attribute "CHIPS_PART_NAME" "NC7SB3157"
					( Origin gPackager )
				)
				( attribute "CDS_PART_NAME" "NC7SB3157_SMLF-IC,C99406-001"
					( Origin gPackager )
				)
				( attribute "GROUP" "MCP"
					( Origin gFrontEnd )
				)
				( objectStatus "U2M1" )
			)
			( gate "@baseboard_fab2_lib.baseboard_fab2(sch_1):page113_i265"
				( attribute "BOM_COST" "DEBUG"
					( Origin gFrontEnd )
				)
				( attribute "CDS_LIB" "dev_discrete"
					( Origin gPackager )
				)
				( attribute "CDS_LOCATION" "C1M34"
					( Origin gPackager )
				)
				( attribute "CDS_SEC" "1"
					( Origin gPackager )
				)
				( attribute "LOCATION" "C1M34"
					( Origin gFrontEnd )
				)
				( attribute "MATERIAL" "X7R"
					( Origin gFrontEnd )
				)
				( attribute "PACK_TYPE" "0402V"
					( Origin gFrontEnd )
				)
				( attribute "PART_NUMBER" "A36096-045"
					( Origin gFrontEnd )
				)
				( attribute "PHYS_PAGE" "113"
					( Origin gFrontEnd )
				)
				( attribute "ROOM" "DEBUG"
					( Origin gFrontEnd )
				)
				( attribute "ROT" "2"
					( Origin gFrontEnd )
				)
				( attribute "SEC" "1"
					( Origin gFrontEnd )
				)
				( attribute "SEC_TYPE" "0402V"
					( Origin gFrontEnd )
				)
				( attribute "TOLERANCE" "10%"
					( Origin gFrontEnd )
				)
				( attribute "VALUE" "0.01UF"
					( Origin gFrontEnd )
				)
				( attribute "VER" "1"
					( Origin gFrontEnd )
				)
				( attribute "VOLTAGE" "25V"
					( Units "uVoltage" "V" 1.000000)
					( Origin gFrontEnd )
				)
				( attribute "XY" "(-1275,1825)"
					( Origin gFrontEnd )
				)
				( attribute "CHIPS_PART_NAME" "CAP_A"
					( Origin gPackager )
				)
				( attribute "CDS_PART_NAME" "CAP_A_0402V-0.01UF,25V,10%,X7RA"
					( Origin gPackager )
				)
				( attribute "GROUP" "MCP"
					( Origin gFrontEnd )
				)
				( objectStatus "C1M34" )
			)
			( gate "@baseboard_fab2_lib.baseboard_fab2(sch_1):page113_i266"
				( attribute "BOM_COST" "DEBUG"
					( Origin gFrontEnd )
				)
				( attribute "CDS_LIB" "dev_discrete"
					( Origin gPackager )
				)
				( attribute "CDS_LOCATION" "C1M35"
					( Origin gPackager )
				)
				( attribute "CDS_SEC" "1"
					( Origin gPackager )
				)
				( attribute "LOCATION" "C1M35"
					( Origin gFrontEnd )
				)
				( attribute "MATERIAL" "X7R"
					( Origin gFrontEnd )
				)
				( attribute "PACK_TYPE" "0402V"
					( Origin gFrontEnd )
				)
				( attribute "PART_NUMBER" "A36096-045"
					( Origin gFrontEnd )
				)
				( attribute "PHYS_PAGE" "113"
					( Origin gFrontEnd )
				)
				( attribute "ROOM" "DEBUG"
					( Origin gFrontEnd )
				)
				( attribute "ROT" "2"
					( Origin gFrontEnd )
				)
				( attribute "SEC" "1"
					( Origin gFrontEnd )
				)
				( attribute "SEC_TYPE" "0402V"
					( Origin gFrontEnd )
				)
				( attribute "TOLERANCE" "10%"
					( Origin gFrontEnd )
				)
				( attribute "VALUE" "0.01UF"
					( Origin gFrontEnd )
				)
				( attribute "VER" "1"
					( Origin gFrontEnd )
				)
				( attribute "VOLTAGE" "25V"
					( Units "uVoltage" "V" 1.000000)
					( Origin gFrontEnd )
				)
				( attribute "XY" "(-1600,1825)"
					( Origin gFrontEnd )
				)
				( attribute "CHIPS_PART_NAME" "CAP_A"
					( Origin gPackager )
				)
				( attribute "CDS_PART_NAME" "CAP_A_0402V-0.01UF,25V,10%,X7RA"
					( Origin gPackager )
				)
				( attribute "GROUP" "MCP"
					( Origin gFrontEnd )
				)
				( objectStatus "C1M35" )
			)
			( gate "@baseboard_fab2_lib.baseboard_fab2(sch_1):page113_i267"
				( attribute "BOM_COST" "DEBUG"
					( Origin gFrontEnd )
				)
				( attribute "CDS_LIB" "dev_discrete"
					( Origin gPackager )
				)
				( attribute "CDS_LOCATION" "C1L20"
					( Origin gPackager )
				)
				( attribute "CDS_SEC" "1"
					( Origin gPackager )
				)
				( attribute "LOCATION" "C1L20"
					( Origin gFrontEnd )
				)
				( attribute "MATERIAL" "X7R"
					( Origin gFrontEnd )
				)
				( attribute "PACK_TYPE" "0402V"
					( Origin gFrontEnd )
				)
				( attribute "PART_NUMBER" "A36096-045"
					( Origin gFrontEnd )
				)
				( attribute "PHYS_PAGE" "113"
					( Origin gFrontEnd )
				)
				( attribute "ROOM" "DEBUG"
					( Origin gFrontEnd )
				)
				( attribute "ROT" "2"
					( Origin gFrontEnd )
				)
				( attribute "SEC" "1"
					( Origin gFrontEnd )
				)
				( attribute "SEC_TYPE" "0402V"
					( Origin gFrontEnd )
				)
				( attribute "TOLERANCE" "10%"
					( Origin gFrontEnd )
				)
				( attribute "VALUE" "0.01UF"
					( Origin gFrontEnd )
				)
				( attribute "VER" "1"
					( Origin gFrontEnd )
				)
				( attribute "VOLTAGE" "25V"
					( Units "uVoltage" "V" 1.000000)
					( Origin gFrontEnd )
				)
				( attribute "XY" "(3025,3650)"
					( Origin gFrontEnd )
				)
				( attribute "CHIPS_PART_NAME" "CAP_A"
					( Origin gPackager )
				)
				( attribute "CDS_PART_NAME" "CAP_A_0402V-0.01UF,25V,10%,X7RA"
					( Origin gPackager )
				)
				( attribute "GROUP" "MCP"
					( Origin gFrontEnd )
				)
				( objectStatus "C1L20" )
			)
			( gate "@baseboard_fab2_lib.baseboard_fab2(sch_1):page114_i40"
				( attribute "BOM_COST" "SB"
					( Origin gFrontEnd )
				)
				( attribute "CDS_LIB" "mstr_u_proc"
					( Origin gPackager )
				)
				( attribute "CDS_LOCATION" "U7C1"
					( Origin gPackager )
				)
				( attribute "CDS_SEC" "1"
					( Origin gPackager )
				)
				( attribute "LOCATION" "U7C1"
					( Origin gFrontEnd )
				)
				( attribute "MATERIAL" "IC"
					( Origin gFrontEnd )
				)
				( attribute "PACK_TYPE" "BGA1"
					( Origin gFrontEnd )
				)
				( attribute "PART_NUMBER" "H91415-002"
					( Origin gFrontEnd )
				)
				( attribute "PHYS_PAGE" "114"
					( Origin gFrontEnd )
				)
				( attribute "ROOM" "SB"
					( Origin gFrontEnd )
				)
				( attribute "ROT" "0"
					( Origin gFrontEnd )
				)
				( attribute "SEC" "1"
					( Origin gFrontEnd )
				)
				( attribute "SEC_TYPE" "BGA1"
					( Origin gFrontEnd )
				)
				( attribute "VER" "1"
					( Origin gFrontEnd )
				)
				( attribute "XY" "(525,2150)"
					( Origin gFrontEnd )
				)
				( attribute "CHIPS_PART_NAME" "LBG_CORE_QAT_EXT_D"
					( Origin gPackager )
				)
				( attribute "CDS_PART_NAME" "LBG_CORE_QAT_EXT_D_BGA1-IC,H91A"
					( Origin gPackager )
				)
				( objectStatus "U7C1" )
			)
			( gate "@baseboard_fab2_lib.baseboard_fab2(sch_1):page212_i146"
				( attribute "BOM_COST" "PROC_VRD_PVCCIO_CPU0"
					( Origin gFrontEnd )
				)
				( attribute "CDS_LIB" "mstr_discrete"
					( Origin gPackager )
				)
				( attribute "CDS_LOCATION" "C3N38"
					( Origin gPackager )
				)
				( attribute "CDS_SEC" "1"
					( Origin gPackager )
				)
				( attribute "LOCATION" "C3N38"
					( Origin gFrontEnd )
				)
				( attribute "MATERIAL" "ALUM"
					( Origin gFrontEnd )
				)
				( attribute "PACK_TYPE" "3018"
					( Origin gFrontEnd )
				)
				( attribute "PART_NUMBER" "699013-049"
					( Origin gFrontEnd )
				)
				( attribute "PHYS_PAGE" "212"
					( Origin gFrontEnd )
				)
				( attribute "ROOM" "PVCCIO_CPU0"
					( Origin gFrontEnd )
				)
				( attribute "ROT" "2"
					( Origin gFrontEnd )
				)
				( attribute "SEC" "1"
					( Origin gPackager )
				)
				( attribute "TOLERANCE" "20%"
					( Origin gFrontEnd )
				)
				( attribute "VALUE" "470UF"
					( Origin gFrontEnd )
				)
				( attribute "VER" "1"
					( Origin gFrontEnd )
				)
				( attribute "VOLTAGE" "2.5V"
					( Units "uVoltage" "V" 1.000000)
					( Origin gFrontEnd )
				)
				( attribute "XY" "(1950,1300)"
					( Origin gFrontEnd )
				)
				( attribute "CHIPS_PART_NAME" "CAPP"
					( Origin gPackager )
				)
				( attribute "CDS_PART_NAME" "CAPP_3018-470UF,2.5V,20%,ALUM,A"
					( Origin gPackager )
				)
				( attribute "GROUP" "PWR_BULK_CAP"
					( Origin gFrontEnd )
				)
				( objectStatus "C3N38" )
			)
			( gate "@baseboard_fab2_lib.baseboard_fab2(sch_1):page114_i47"
				( attribute "BOM_COST" "SYS_CLOCK"
					( Origin gFrontEnd )
				)
				( attribute "CDS_LIB" "mstr_discrete"
					( Origin gPackager )
				)
				( attribute "CDS_LOCATION" "C7C5"
					( Origin gPackager )
				)
				( attribute "CDS_SEC" "1"
					( Origin gPackager )
				)
				( attribute "LOCATION" "C7C5"
					( Origin gFrontEnd )
				)
				( attribute "MATERIAL" "COG"
					( Origin gFrontEnd )
				)
				( attribute "PACK_TYPE" "0402LF"
					( Origin gFrontEnd )
				)
				( attribute "PART_NUMBER" "A36095-047"
					( Origin gFrontEnd )
				)
				( attribute "PHYS_PAGE" "114"
					( Origin gFrontEnd )
				)
				( attribute "ROOM" "SB"
					( Origin gFrontEnd )
				)
				( attribute "ROT" "0"
					( Origin gFrontEnd )
				)
				( attribute "SEC" "1"
					( Origin gFrontEnd )
				)
				( attribute "SEC_TYPE" "0402LF"
					( Origin gFrontEnd )
				)
				( attribute "TOLERANCE" "5%"
					( Origin gFrontEnd )
				)
				( attribute "VALUE" "15.0PF"
					( Origin gFrontEnd )
				)
				( attribute "VER" "1"
					( Origin gFrontEnd )
				)
				( attribute "VOLTAGE" "50V"
					( Units "uVoltage" "V" 1.000000)
					( Origin gFrontEnd )
				)
				( attribute "XY" "(-1525,-200)"
					( Origin gFrontEnd )
				)
				( attribute "CHIPS_PART_NAME" "CAP"
					( Origin gPackager )
				)
				( attribute "CDS_PART_NAME" "CAP_0402LF-15.0PF,50V,5%,COG,AA"
					( Origin gPackager )
				)
				( attribute "CONFIG" "78.6R864.1FL"
					( Origin gFrontEnd )
				)
				( attribute "NEW_VALUE" "6.8PF"
					( Origin gFrontEnd )
				)
				( objectStatus "C7C5" )
			)
			( gate "@baseboard_fab2_lib.baseboard_fab2(sch_1):page114_i48"
				( attribute "CDS_LIB" "mstr_discrete"
					( Origin gPackager )
				)
				( attribute "CDS_LOCATION" "R7C1"
					( Origin gPackager )
				)
				( attribute "CDS_SEC" "1"
					( Origin gPackager )
				)
				( attribute "LOCATION" "R7C1"
					( Origin gFrontEnd )
				)
				( attribute "MATERIAL" "CHIP"
					( Origin gFrontEnd )
				)
				( attribute "PACK_TYPE" "0603"
					( Origin gFrontEnd )
				)
				( attribute "PART_NUMBER" "G22369-010"
					( Origin gFrontEnd )
				)
				( attribute "PHYS_PAGE" "114"
					( Origin gFrontEnd )
				)
				( attribute "ROOM" "SB"
					( Origin gFrontEnd )
				)
				( attribute "ROT" "0"
					( Origin gFrontEnd )
				)
				( attribute "SEC" "1"
					( Origin gFrontEnd )
				)
				( attribute "SEC_TYPE" "0603"
					( Origin gFrontEnd )
				)
				( attribute "TOLERANCE" "0.1%"
					( Origin gFrontEnd )
				)
				( attribute "VALUE" "200K"
					( Origin gFrontEnd )
				)
				( attribute "VER" "1"
					( Origin gFrontEnd )
				)
				( attribute "WATTAGE" "1/10W"
					( Origin gFrontEnd )
				)
				( attribute "XY" "(-1775,475)"
					( Origin gFrontEnd )
				)
				( attribute "CHIPS_PART_NAME" "RES"
					( Origin gPackager )
				)
				( attribute "CDS_PART_NAME" "RES_0603-200K,0.1%,1/10W,CHIP,A"
					( Origin gPackager )
				)
				( objectStatus "R7C1" )
			)
			( gate "@baseboard_fab2_lib.baseboard_fab2(sch_1):page114_i49"
				( attribute "CDS_LIB" "mstr_discrete"
					( Origin gPackager )
				)
				( attribute "CDS_LOCATION" "Y7C1"
					( Origin gPackager )
				)
				( attribute "CDS_SEC" "1"
					( Origin gPackager )
				)
				( attribute "LOCATION" "Y7C1"
					( Origin gFrontEnd )
				)
				( attribute "MATERIAL" "IC"
					( Origin gFrontEnd )
				)
				( attribute "PACK_TYPE" "2013"
					( Origin gFrontEnd )
				)
				( attribute "PART_NUMBER" "D71700-058"
					( Origin gFrontEnd )
				)
				( attribute "PHYS_PAGE" "114"
					( Origin gFrontEnd )
				)
				( attribute "ROOM" "SB"
					( Origin gFrontEnd )
				)
				( attribute "ROT" "0"
					( Origin gFrontEnd )
				)
				( attribute "SEC" "1"
					( Origin gFrontEnd )
				)
				( attribute "SEC_TYPE" "2013"
					( Origin gFrontEnd )
				)
				( attribute "VALUE" "48.000MHZ"
					( Origin gFrontEnd )
				)
				( attribute "VER" "1"
					( Origin gFrontEnd )
				)
				( attribute "XY" "(-1775,150)"
					( Origin gFrontEnd )
				)
				( attribute "CHIPS_PART_NAME" "CRYSTAL"
					( Origin gPackager )
				)
				( attribute "CDS_PART_NAME" "CRYSTAL_2013-48.000MHZ,IC,D717A"
					( Origin gPackager )
				)
				( objectStatus "Y7C1" )
			)
			( gate "@baseboard_fab2_lib.baseboard_fab2(sch_1):page114_i50"
				( attribute "BOM_COST" "SYS_CLOCK"
					( Origin gFrontEnd )
				)
				( attribute "CDS_LIB" "mstr_discrete"
					( Origin gPackager )
				)
				( attribute "CDS_LOCATION" "C7C4"
					( Origin gPackager )
				)
				( attribute "CDS_SEC" "1"
					( Origin gPackager )
				)
				( attribute "LOCATION" "C7C4"
					( Origin gFrontEnd )
				)
				( attribute "MATERIAL" "COG"
					( Origin gFrontEnd )
				)
				( attribute "PACK_TYPE" "0402LF"
					( Origin gFrontEnd )
				)
				( attribute "PART_NUMBER" "A36095-047"
					( Origin gFrontEnd )
				)
				( attribute "PHYS_PAGE" "114"
					( Origin gFrontEnd )
				)
				( attribute "ROOM" "SB"
					( Origin gFrontEnd )
				)
				( attribute "ROT" "0"
					( Origin gFrontEnd )
				)
				( attribute "SEC" "1"
					( Origin gFrontEnd )
				)
				( attribute "SEC_TYPE" "0402LF"
					( Origin gFrontEnd )
				)
				( attribute "TOLERANCE" "5%"
					( Origin gFrontEnd )
				)
				( attribute "VALUE" "15.0PF"
					( Origin gFrontEnd )
				)
				( attribute "VER" "1"
					( Origin gFrontEnd )
				)
				( attribute "VOLTAGE" "50V"
					( Units "uVoltage" "V" 1.000000)
					( Origin gFrontEnd )
				)
				( attribute "XY" "(-2025,-200)"
					( Origin gFrontEnd )
				)
				( attribute "CHIPS_PART_NAME" "CAP"
					( Origin gPackager )
				)
				( attribute "CDS_PART_NAME" "CAP_0402LF-15.0PF,50V,5%,COG,AA"
					( Origin gPackager )
				)
				( attribute "CONFIG" "78.6R864.1FL"
					( Origin gFrontEnd )
				)
				( attribute "NEW_VALUE" "6.8PF"
					( Origin gFrontEnd )
				)
				( objectStatus "C7C4" )
			)
			( gate "@baseboard_fab2_lib.baseboard_fab2(sch_1):page114_i54"
				( attribute "BOM_COST" "SYS_CLOCK"
					( Origin gFrontEnd )
				)
				( attribute "CDS_LIB" "mstr_discrete"
					( Origin gPackager )
				)
				( attribute "CDS_LOCATION" "R7C6"
					( Origin gPackager )
				)
				( attribute "CDS_SEC" "1"
					( Origin gPackager )
				)
				( attribute "LOCATION" "R7C6"
					( Origin gFrontEnd )
				)
				( attribute "MATERIAL" "CHIP"
					( Origin gFrontEnd )
				)
				( attribute "PACK_TYPE" "0603"
					( Origin gFrontEnd )
				)
				( attribute "PART_NUMBER" "G22026-112"
					( Origin gFrontEnd )
				)
				( attribute "PHYS_PAGE" "114"
					( Origin gFrontEnd )
				)
				( attribute "ROOM" "SB"
					( Origin gFrontEnd )
				)
				( attribute "ROT" "0"
					( Origin gFrontEnd )
				)
				( attribute "SEC" "1"
					( Origin gPackager )
				)
				( attribute "TOLERANCE" "1.0%"
					( Origin gFrontEnd )
				)
				( attribute "VALUE" "10M"
					( Origin gFrontEnd )
				)
				( attribute "VER" "1"
					( Origin gFrontEnd )
				)
				( attribute "WATTAGE" "1/10W"
					( Origin gFrontEnd )
				)
				( attribute "XY" "(-25,475)"
					( Origin gFrontEnd )
				)
				( attribute "CHIPS_PART_NAME" "RES"
					( Origin gPackager )
				)
				( attribute "CDS_PART_NAME" "RES_0603-10M,1.0%,1/10W,CHIP,GA"
					( Origin gPackager )
				)
				( objectStatus "R7C6" )
			)
			( gate "@baseboard_fab2_lib.baseboard_fab2(sch_1):page114_i55"
				( attribute "CDS_LIB" "mstr_discrete"
					( Origin gPackager )
				)
				( attribute "CDS_LOCATION" "Y7C2"
					( Origin gPackager )
				)
				( attribute "CDS_SEC" "1"
					( Origin gPackager )
				)
				( attribute "LOCATION" "Y7C2"
					( Origin gFrontEnd )
				)
				( attribute "MATERIAL" "IC"
					( Origin gFrontEnd )
				)
				( attribute "PACK_TYPE" "SM"
					( Origin gFrontEnd )
				)
				( attribute "PART_NUMBER" "C13544-023"
					( Origin gFrontEnd )
				)
				( attribute "PHYS_PAGE" "114"
					( Origin gFrontEnd )
				)
				( attribute "ROOM" "SB"
					( Origin gFrontEnd )
				)
				( attribute "ROT" "0"
					( Origin gFrontEnd )
				)
				( attribute "SEC" "1"
					( Origin gFrontEnd )
				)
				( attribute "SEC_TYPE" "SM"
					( Origin gFrontEnd )
				)
				( attribute "VALUE" "32.768KHZ"
					( Origin gFrontEnd )
				)
				( attribute "VER" "1"
					( Origin gFrontEnd )
				)
				( attribute "XY" "(-25,125)"
					( Origin gFrontEnd )
				)
				( attribute "CHIPS_PART_NAME" "CRYSTAL"
					( Origin gPackager )
				)
				( attribute "CDS_PART_NAME" "CRYSTAL_SM-32.768KHZ,IC,C13544A"
					( Origin gPackager )
				)
				( objectStatus "Y7C2" )
			)
			( gate "@baseboard_fab2_lib.baseboard_fab2(sch_1):page212_i145"
				( attribute "BOM_COST" "PROC_VRD_PVCCIO_CPU0"
					( Origin gFrontEnd )
				)
				( attribute "CDS_LIB" "mstr_discrete"
					( Origin gPackager )
				)
				( attribute "CDS_LOCATION" "C3N26"
					( Origin gPackager )
				)
				( attribute "CDS_SEC" "1"
					( Origin gPackager )
				)
				( attribute "LOCATION" "C3N26"
					( Origin gFrontEnd )
				)
				( attribute "MATERIAL" "ALUM"
					( Origin gFrontEnd )
				)
				( attribute "PACK_TYPE" "3018"
					( Origin gFrontEnd )
				)
				( attribute "PART_NUMBER" "699013-049"
					( Origin gFrontEnd )
				)
				( attribute "PHYS_PAGE" "212"
					( Origin gFrontEnd )
				)
				( attribute "ROOM" "PVCCIO_CPU0"
					( Origin gFrontEnd )
				)
				( attribute "ROT" "2"
					( Origin gFrontEnd )
				)
				( attribute "SEC" "1"
					( Origin gPackager )
				)
				( attribute "TOLERANCE" "20%"
					( Origin gFrontEnd )
				)
				( attribute "VALUE" "470UF"
					( Origin gFrontEnd )
				)
				( attribute "VER" "1"
					( Origin gFrontEnd )
				)
				( attribute "VOLTAGE" "2.5V"
					( Units "uVoltage" "V" 1.000000)
					( Origin gFrontEnd )
				)
				( attribute "XY" "(1400,1300)"
					( Origin gFrontEnd )
				)
				( attribute "CHIPS_PART_NAME" "CAPP"
					( Origin gPackager )
				)
				( attribute "CDS_PART_NAME" "CAPP_3018-470UF,2.5V,20%,ALUM,A"
					( Origin gPackager )
				)
				( attribute "GROUP" "PWR_BULK_CAP"
					( Origin gFrontEnd )
				)
				( objectStatus "C3N26" )
			)
			( gate "@baseboard_fab2_lib.baseboard_fab2(sch_1):page114_i110"
				( attribute "CDS_LIB" "mstr_discrete"
					( Origin gPackager )
				)
				( attribute "CDS_LOCATION" "R8B20"
					( Origin gPackager )
				)
				( attribute "CDS_SEC" "1"
					( Origin gPackager )
				)
				( attribute "LOCATION" "R8B20"
					( Origin gFrontEnd )
				)
				( attribute "MATERIAL" "CHIP"
					( Origin gFrontEnd )
				)
				( attribute "PACK_TYPE" "0402"
					( Origin gFrontEnd )
				)
				( attribute "PART_NUMBER" "G21796-066"
					( Origin gFrontEnd )
				)
				( attribute "PHYS_PAGE" "114"
					( Origin gFrontEnd )
				)
				( attribute "ROOM" "SB"
					( Origin gFrontEnd )
				)
				( attribute "ROT" "0"
					( Origin gFrontEnd )
				)
				( attribute "SEC" "1"
					( Origin gFrontEnd )
				)
				( attribute "SEC_TYPE" "0402"
					( Origin gFrontEnd )
				)
				( attribute "TOLERANCE" "1%"
					( Origin gFrontEnd )
				)
				( attribute "VALUE" "10.0"
					( Origin gFrontEnd )
				)
				( attribute "VER" "1"
					( Origin gFrontEnd )
				)
				( attribute "WATTAGE" "1/16W"
					( Origin gFrontEnd )
				)
				( attribute "XY" "(2300,1350)"
					( Origin gFrontEnd )
				)
				( attribute "CHIPS_PART_NAME" "RES"
					( Origin gPackager )
				)
				( attribute "CDS_PART_NAME" "RES_0402-10.0,1%,1/16W,CHIP,G2A"
					( Origin gPackager )
				)
				( objectStatus "R8B20" )
			)
			( gate "@baseboard_fab2_lib.baseboard_fab2(sch_1):page114_i124"
				( attribute "CDS_LIB" "mstr_discrete"
					( Origin gPackager )
				)
				( attribute "CDS_LOCATION" "R8B21"
					( Origin gPackager )
				)
				( attribute "CDS_SEC" "1"
					( Origin gPackager )
				)
				( attribute "LOCATION" "R8B21"
					( Origin gFrontEnd )
				)
				( attribute "MATERIAL" "EMPTY"
					( Origin gFrontEnd )
				)
				( attribute "PACK_TYPE" "0402"
					( Origin gFrontEnd )
				)
				( attribute "PART_NUMBER" "G21796-047"
					( Origin gFrontEnd )
				)
				( attribute "PHYS_PAGE" "114"
					( Origin gFrontEnd )
				)
				( attribute "ROOM" "SB"
					( Origin gFrontEnd )
				)
				( attribute "ROT" "0"
					( Origin gFrontEnd )
				)
				( attribute "SEC" "1"
					( Origin gFrontEnd )
				)
				( attribute "SEC_TYPE" "0402"
					( Origin gFrontEnd )
				)
				( attribute "TOLERANCE" "1%"
					( Origin gFrontEnd )
				)
				( attribute "VALUE" "49.9"
					( Origin gFrontEnd )
				)
				( attribute "VER" "2"
					( Origin gFrontEnd )
				)
				( attribute "WATTAGE" "1/16W"
					( Origin gFrontEnd )
				)
				( attribute "XY" "(2900,1100)"
					( Origin gFrontEnd )
				)
				( attribute "CHIPS_PART_NAME" "RES"
					( Origin gPackager )
				)
				( attribute "CDS_PART_NAME" "RES_0402-49.9,1%,1/16W,EMPTY,GA"
					( Origin gPackager )
				)
				( objectStatus "R8B21" )
			)
			( gate "@baseboard_fab2_lib.baseboard_fab2(sch_1):page114_i149"
				( attribute "CDS_LIB" "mstr_discrete"
					( Origin gPackager )
				)
				( attribute "CDS_LOCATION" "R3N1"
					( Origin gPackager )
				)
				( attribute "LOCATION" "R3N1"
					( Origin gFrontEnd )
				)
				( attribute "MATERIAL" "CHIP"
					( Origin gFrontEnd )
				)
				( attribute "PACK_TYPE" "0402"
					( Origin gFrontEnd )
				)
				( attribute "PART_NUMBER" "G21796-276"
					( Origin gFrontEnd )
				)
				( attribute "PHYS_PAGE" "114"
					( Origin gFrontEnd )
				)
				( attribute "ROOM" "SB"
					( Origin gFrontEnd )
				)
				( attribute "ROT" "0"
					( Origin gFrontEnd )
				)
				( attribute "SEC" "1"
					( Origin gFrontEnd )
				)
				( attribute "TOLERANCE" "1.0%"
					( Origin gFrontEnd )
				)
				( attribute "VALUE" "169"
					( Origin gFrontEnd )
				)
				( attribute "VER" "2"
					( Origin gFrontEnd )
				)
				( attribute "WATTAGE" "1/16W"
					( Origin gFrontEnd )
				)
				( attribute "XY" "(-3150,2750)"
					( Origin gFrontEnd )
				)
				( attribute "CHIPS_PART_NAME" "RES"
					( Origin gPackager )
				)
				( attribute "CDS_PART_NAME" "RES_0402-169,1.0%,1/16W,CHIP,GA"
					( Origin gPackager )
				)
				( attribute "SEC_TYPE" "0402"
					( Origin gFrontEnd )
				)
				( attribute "CDS_SEC" "1"
					( Origin gPackager )
				)
				( objectStatus "R3N1" )
			)
			( gate "@baseboard_fab2_lib.baseboard_fab2(sch_1):page115_i74"
				( attribute "BOM_COST" "SB"
					( Origin gFrontEnd )
				)
				( attribute "CDS_LIB" "mstr_u_proc"
					( Origin gPackager )
				)
				( attribute "CDS_LOCATION" "U7C1"
					( Origin gPackager )
				)
				( attribute "CDS_SEC" "2"
					( Origin gPackager )
				)
				( attribute "LOCATION" "U7C1"
					( Origin gFrontEnd )
				)
				( attribute "MATERIAL" "IC"
					( Origin gFrontEnd )
				)
				( attribute "PACK_TYPE" "BGA1"
					( Origin gFrontEnd )
				)
				( attribute "PART_NUMBER" "H91415-002"
					( Origin gFrontEnd )
				)
				( attribute "PHYS_PAGE" "115"
					( Origin gFrontEnd )
				)
				( attribute "ROOM" "SB"
					( Origin gFrontEnd )
				)
				( attribute "ROT" "0"
					( Origin gFrontEnd )
				)
				( attribute "SEC" "2"
					( Origin gFrontEnd )
				)
				( attribute "SEC_TYPE" "BGA1"
					( Origin gFrontEnd )
				)
				( attribute "VER" "2"
					( Origin gFrontEnd )
				)
				( attribute "XY" "(-4000,2500)"
					( Origin gFrontEnd )
				)
				( attribute "CHIPS_PART_NAME" "LBG_CORE_QAT_EXT_D"
					( Origin gPackager )
				)
				( attribute "CDS_PART_NAME" "LBG_CORE_QAT_EXT_D_BGA1-IC,H91A"
					( Origin gPackager )
				)
				( objectStatus "U7C1" )
			)
			( gate "@baseboard_fab2_lib.baseboard_fab2(sch_1):page115_i90"
				( attribute "CDS_LIB" "mstr_discrete"
					( Origin gPackager )
				)
				( attribute "CDS_LOCATION" "R8B9"
					( Origin gPackager )
				)
				( attribute "CDS_SEC" "1"
					( Origin gPackager )
				)
				( attribute "LOCATION" "R8B9"
					( Origin gFrontEnd )
				)
				( attribute "MATERIAL" "CHIP"
					( Origin gFrontEnd )
				)
				( attribute "PACK_TYPE" "0402"
					( Origin gFrontEnd )
				)
				( attribute "PART_NUMBER" "G21796-341"
					( Origin gFrontEnd )
				)
				( attribute "PHYS_PAGE" "115"
					( Origin gFrontEnd )
				)
				( attribute "ROOM" "SB"
					( Origin gFrontEnd )
				)
				( attribute "ROT" "0"
					( Origin gFrontEnd )
				)
				( attribute "SEC" "1"
					( Origin gFrontEnd )
				)
				( attribute "SEC_TYPE" "0402"
					( Origin gFrontEnd )
				)
				( attribute "TOLERANCE" "1%"
					( Origin gFrontEnd )
				)
				( attribute "VALUE" "113"
					( Origin gFrontEnd )
				)
				( attribute "VER" "2"
					( Origin gFrontEnd )
				)
				( attribute "WATTAGE" "1/16W"
					( Origin gFrontEnd )
				)
				( attribute "XY" "(-5750,1775)"
					( Origin gFrontEnd )
				)
				( attribute "CHIPS_PART_NAME" "RES"
					( Origin gPackager )
				)
				( attribute "CDS_PART_NAME" "RES_0402-113,1%,1/16W,CHIP,G21A"
					( Origin gPackager )
				)
				( objectStatus "R8B9" )
			)
			( gate "@baseboard_fab2_lib.baseboard_fab2(sch_1):page115_i114"
				( attribute "CDS_LIB" "mstr_discrete"
					( Origin gPackager )
				)
				( attribute "CDS_LOCATION" "R8B32"
					( Origin gPackager )
				)
				( attribute "CDS_SEC" "1"
					( Origin gPackager )
				)
				( attribute "LOCATION" "R8B32"
					( Origin gFrontEnd )
				)
				( attribute "MATERIAL" "CHIP"
					( Origin gFrontEnd )
				)
				( attribute "PACK_TYPE" "0402"
					( Origin gFrontEnd )
				)
				( attribute "PART_NUMBER" "G21796-016"
					( Origin gFrontEnd )
				)
				( attribute "PHYS_PAGE" "115"
					( Origin gFrontEnd )
				)
				( attribute "ROT" "0"
					( Origin gFrontEnd )
				)
				( attribute "SEC" "1"
					( Origin gFrontEnd )
				)
				( attribute "SEC_TYPE" "0402"
					( Origin gFrontEnd )
				)
				( attribute "TOLERANCE" "1%"
					( Origin gFrontEnd )
				)
				( attribute "VALUE" "10.0K"
					( Origin gFrontEnd )
				)
				( attribute "VER" "2"
					( Origin gFrontEnd )
				)
				( attribute "WATTAGE" "1/16W"
					( Origin gFrontEnd )
				)
				( attribute "XY" "(-5425,1775)"
					( Origin gFrontEnd )
				)
				( attribute "CHIPS_PART_NAME" "RES"
					( Origin gPackager )
				)
				( attribute "CDS_PART_NAME" "RES_0402-10.0K,1%,1/16W,CHIP,GA"
					( Origin gPackager )
				)
				( objectStatus "R8B32" )
			)
			( gate "@baseboard_fab2_lib.baseboard_fab2(sch_1):page116_i108"
				( attribute "CDS_LIB" "mstr_discrete"
					( Origin gPackager )
				)
				( attribute "CDS_LOCATION" "R3M11"
					( Origin gPackager )
				)
				( attribute "CDS_SEC" "1"
					( Origin gPackager )
				)
				( attribute "LOCATION" "R3M11"
					( Origin gFrontEnd )
				)
				( attribute "MATERIAL" "CHIP"
					( Origin gFrontEnd )
				)
				( attribute "NO_XNET_CONNECTION" "1"
					( Origin gFrontEnd )
				)
				( attribute "PACK_TYPE" "0402"
					( Origin gFrontEnd )
				)
				( attribute "PART_NUMBER" "G21796-017"
					( Origin gFrontEnd )
				)
				( attribute "PHYS_PAGE" "116"
					( Origin gFrontEnd )
				)
				( attribute "ROOM" "SB"
					( Origin gFrontEnd )
				)
				( attribute "ROT" "2"
					( Origin gFrontEnd )
				)
				( attribute "SEC" "1"
					( Origin gFrontEnd )
				)
				( attribute "SEC_TYPE" "0402"
					( Origin gFrontEnd )
				)
				( attribute "TOLERANCE" "1%"
					( Origin gFrontEnd )
				)
				( attribute "VALUE" "100.0"
					( Origin gFrontEnd )
				)
				( attribute "VER" "2"
					( Origin gFrontEnd )
				)
				( attribute "WATTAGE" "1/16W"
					( Origin gFrontEnd )
				)
				( attribute "XY" "(-7550,2150)"
					( Origin gFrontEnd )
				)
				( attribute "CHIPS_PART_NAME" "RES"
					( Origin gPackager )
				)
				( attribute "CDS_PART_NAME" "RES_0402-100.0,1%,1/16W,CHIP,GA"
					( Origin gPackager )
				)
				( objectStatus "R3M11" )
			)
			( gate "@baseboard_fab2_lib.baseboard_fab2(sch_1):page116_i181"
				( attribute "CDS_LIB" "mstr_discrete"
					( Origin gPackager )
				)
				( attribute "CDS_LOCATION" "R3M12"
					( Origin gPackager )
				)
				( attribute "CDS_SEC" "1"
					( Origin gPackager )
				)
				( attribute "LOCATION" "R3M12"
					( Origin gFrontEnd )
				)
				( attribute "MATERIAL" "CHIP"
					( Origin gFrontEnd )
				)
				( attribute "NO_XNET_CONNECTION" "1"
					( Origin gFrontEnd )
				)
				( attribute "PACK_TYPE" "0402"
					( Origin gFrontEnd )
				)
				( attribute "PART_NUMBER" "G21796-017"
					( Origin gFrontEnd )
				)
				( attribute "PHYS_PAGE" "116"
					( Origin gFrontEnd )
				)
				( attribute "ROOM" "SB"
					( Origin gFrontEnd )
				)
				( attribute "ROT" "2"
					( Origin gFrontEnd )
				)
				( attribute "SEC" "1"
					( Origin gFrontEnd )
				)
				( attribute "SEC_TYPE" "0402"
					( Origin gFrontEnd )
				)
				( attribute "TOLERANCE" "1%"
					( Origin gFrontEnd )
				)
				( attribute "VALUE" "100.0"
					( Origin gFrontEnd )
				)
				( attribute "VER" "2"
					( Origin gFrontEnd )
				)
				( attribute "WATTAGE" "1/16W"
					( Origin gFrontEnd )
				)
				( attribute "XY" "(-7125,2150)"
					( Origin gFrontEnd )
				)
				( attribute "CHIPS_PART_NAME" "RES"
					( Origin gPackager )
				)
				( attribute "CDS_PART_NAME" "RES_0402-100.0,1%,1/16W,CHIP,GA"
					( Origin gPackager )
				)
				( objectStatus "R3M12" )
			)
			( gate "@baseboard_fab2_lib.baseboard_fab2(sch_1):page145_i159"
				( attribute "BOM_COST" "PROC_SIDEBAND"
					( Origin gFrontEnd )
				)
				( attribute "CDS_LIB" "dev_discrete"
					( Origin gPackager )
				)
				( attribute "CDS_LOCATION" "C25W21"
					( Origin gPackager )
				)
				( attribute "CDS_SEC" "1"
					( Origin gPackager )
				)
				( attribute "LOCATION" "C25W21"
					( Origin gFrontEnd )
				)
				( attribute "MATERIAL" "X7R"
					( Origin gFrontEnd )
				)
				( attribute "PACK_TYPE" "0402V"
					( Origin gFrontEnd )
				)
				( attribute "PART_NUMBER" "A36096-030"
					( Origin gFrontEnd )
				)
				( attribute "PHYS_PAGE" "145"
					( Origin gFrontEnd )
				)
				( attribute "ROOM" "PROC_SIDEBAND"
					( Origin gFrontEnd )
				)
				( attribute "ROT" "1"
					( Origin gFrontEnd )
				)
				( attribute "SEC" "1"
					( Origin gFrontEnd )
				)
				( attribute "SEC_TYPE" "0402V"
					( Origin gFrontEnd )
				)
				( attribute "TOLERANCE" "10%"
					( Origin gFrontEnd )
				)
				( attribute "VALUE" "0.1UF"
					( Origin gFrontEnd )
				)
				( attribute "VER" "1"
					( Origin gFrontEnd )
				)
				( attribute "VOLTAGE" "16V"
					( Units "uVoltage" "V" 1.000000)
					( Origin gFrontEnd )
				)
				( attribute "XY" "(-1650,-3900)"
					( Origin gFrontEnd )
				)
				( attribute "CHIPS_PART_NAME" "CAP_A"
					( Origin gPackager )
				)
				( attribute "CDS_PART_NAME" "CAP_A_0402V-0.1UF,16V,10%,X7R,A"
					( Origin gPackager )
				)
				( attribute "GROUP" "AST2500"
					( Origin gFrontEnd )
				)
				( objectStatus "C25W21" )
			)
			( gate "@baseboard_fab2_lib.baseboard_fab2(sch_1):page145_i158"
				( attribute "BOM_COST" "PROC_SIDEBAND"
					( Origin gFrontEnd )
				)
				( attribute "CDS_LIB" "dev_discrete"
					( Origin gPackager )
				)
				( attribute "CDS_LOCATION" "C25W20"
					( Origin gPackager )
				)
				( attribute "CDS_SEC" "1"
					( Origin gPackager )
				)
				( attribute "LOCATION" "C25W20"
					( Origin gFrontEnd )
				)
				( attribute "MATERIAL" "X7R"
					( Origin gFrontEnd )
				)
				( attribute "PACK_TYPE" "0402V"
					( Origin gFrontEnd )
				)
				( attribute "PART_NUMBER" "A36096-030"
					( Origin gFrontEnd )
				)
				( attribute "PHYS_PAGE" "145"
					( Origin gFrontEnd )
				)
				( attribute "ROOM" "PROC_SIDEBAND"
					( Origin gFrontEnd )
				)
				( attribute "ROT" "1"
					( Origin gFrontEnd )
				)
				( attribute "SEC" "1"
					( Origin gFrontEnd )
				)
				( attribute "SEC_TYPE" "0402V"
					( Origin gFrontEnd )
				)
				( attribute "TOLERANCE" "10%"
					( Origin gFrontEnd )
				)
				( attribute "VALUE" "0.1UF"
					( Origin gFrontEnd )
				)
				( attribute "VER" "1"
					( Origin gFrontEnd )
				)
				( attribute "VOLTAGE" "16V"
					( Units "uVoltage" "V" 1.000000)
					( Origin gFrontEnd )
				)
				( attribute "XY" "(-1650,-3550)"
					( Origin gFrontEnd )
				)
				( attribute "CHIPS_PART_NAME" "CAP_A"
					( Origin gPackager )
				)
				( attribute "CDS_PART_NAME" "CAP_A_0402V-0.1UF,16V,10%,X7R,A"
					( Origin gPackager )
				)
				( attribute "GROUP" "AST2500"
					( Origin gFrontEnd )
				)
				( objectStatus "C25W20" )
			)
			( gate "@baseboard_fab2_lib.baseboard_fab2(sch_1):page116_i220"
				( attribute "BOM_COST" "SB"
					( Origin gFrontEnd )
				)
				( attribute "CDS_LIB" "mstr_u_proc"
					( Origin gPackager )
				)
				( attribute "CDS_LOCATION" "U7C1"
					( Origin gPackager )
				)
				( attribute "CDS_SEC" "3"
					( Origin gPackager )
				)
				( attribute "LOCATION" "U7C1"
					( Origin gFrontEnd )
				)
				( attribute "MATERIAL" "IC"
					( Origin gFrontEnd )
				)
				( attribute "PACK_TYPE" "BGA1"
					( Origin gFrontEnd )
				)
				( attribute "PART_NUMBER" "H91415-002"
					( Origin gFrontEnd )
				)
				( attribute "PHYS_PAGE" "116"
					( Origin gFrontEnd )
				)
				( attribute "ROOM" "SB"
					( Origin gFrontEnd )
				)
				( attribute "ROT" "0"
					( Origin gFrontEnd )
				)
				( attribute "SEC" "3"
					( Origin gFrontEnd )
				)
				( attribute "SEC_TYPE" "BGA1"
					( Origin gFrontEnd )
				)
				( attribute "VER" "3"
					( Origin gFrontEnd )
				)
				( attribute "XY" "(-4025,2850)"
					( Origin gFrontEnd )
				)
				( attribute "CHIPS_PART_NAME" "LBG_CORE_QAT_EXT_D"
					( Origin gPackager )
				)
				( attribute "CDS_PART_NAME" "LBG_CORE_QAT_EXT_D_BGA1-IC,H91A"
					( Origin gPackager )
				)
				( objectStatus "U7C1" )
			)
			( gate "@baseboard_fab2_lib.baseboard_fab2(sch_1):page116_i229"
				( attribute "CDS_LIB" "mstr_discrete"
					( Origin gPackager )
				)
				( attribute "CDS_LOCATION" "R7B8"
					( Origin gPackager )
				)
				( attribute "CDS_SEC" "1"
					( Origin gPackager )
				)
				( attribute "LOCATION" "R7B8"
					( Origin gFrontEnd )
				)
				( attribute "MATERIAL" "EMPTY"
					( Origin gFrontEnd )
				)
				( attribute "PACK_TYPE" "0402"
					( Origin gFrontEnd )
				)
				( attribute "PART_NUMBER" "G21796-016"
					( Origin gFrontEnd )
				)
				( attribute "PHYS_PAGE" "116"
					( Origin gFrontEnd )
				)
				( attribute "ROOM" "SB"
					( Origin gFrontEnd )
				)
				( attribute "ROT" "0"
					( Origin gFrontEnd )
				)
				( attribute "SEC" "1"
					( Origin gFrontEnd )
				)
				( attribute "SEC_TYPE" "0402"
					( Origin gFrontEnd )
				)
				( attribute "TOLERANCE" "1%"
					( Origin gFrontEnd )
				)
				( attribute "VALUE" "10.0K"
					( Origin gFrontEnd )
				)
				( attribute "VER" "2"
					( Origin gFrontEnd )
				)
				( attribute "WATTAGE" "1/16W"
					( Origin gFrontEnd )
				)
				( attribute "XY" "(-2125,1400)"
					( Origin gFrontEnd )
				)
				( attribute "CHIPS_PART_NAME" "RES"
					( Origin gPackager )
				)
				( attribute "CDS_PART_NAME" "RES_0402-10.0K,1%,1/16W,EMPTY,A"
					( Origin gPackager )
				)
				( objectStatus "R7B8" )
			)
			( gate "@baseboard_fab2_lib.baseboard_fab2(sch_1):page116_i230"
				( attribute "CDS_LIB" "mstr_discrete"
					( Origin gPackager )
				)
				( attribute "CDS_LOCATION" "R7B7"
					( Origin gPackager )
				)
				( attribute "CDS_SEC" "1"
					( Origin gPackager )
				)
				( attribute "LOCATION" "R7B7"
					( Origin gFrontEnd )
				)
				( attribute "MATERIAL" "EMPTY"
					( Origin gFrontEnd )
				)
				( attribute "PACK_TYPE" "0402"
					( Origin gFrontEnd )
				)
				( attribute "PART_NUMBER" "G21796-016"
					( Origin gFrontEnd )
				)
				( attribute "PHYS_PAGE" "116"
					( Origin gFrontEnd )
				)
				( attribute "ROOM" "SB"
					( Origin gFrontEnd )
				)
				( attribute "ROT" "0"
					( Origin gFrontEnd )
				)
				( attribute "SEC" "1"
					( Origin gFrontEnd )
				)
				( attribute "SEC_TYPE" "0402"
					( Origin gFrontEnd )
				)
				( attribute "TOLERANCE" "1%"
					( Origin gFrontEnd )
				)
				( attribute "VALUE" "10.0K"
					( Origin gFrontEnd )
				)
				( attribute "VER" "2"
					( Origin gFrontEnd )
				)
				( attribute "WATTAGE" "1/16W"
					( Origin gFrontEnd )
				)
				( attribute "XY" "(-1825,1400)"
					( Origin gFrontEnd )
				)
				( attribute "CHIPS_PART_NAME" "RES"
					( Origin gPackager )
				)
				( attribute "CDS_PART_NAME" "RES_0402-10.0K,1%,1/16W,EMPTY,A"
					( Origin gPackager )
				)
				( objectStatus "R7B7" )
			)
			( gate "@baseboard_fab2_lib.baseboard_fab2(sch_1):page116_i234"
				( attribute "CDS_LIB" "mstr_discrete"
					( Origin gPackager )
				)
				( attribute "CDS_LOCATION" "R3M9"
					( Origin gPackager )
				)
				( attribute "CDS_SEC" "1"
					( Origin gPackager )
				)
				( attribute "LOCATION" "R3M9"
					( Origin gFrontEnd )
				)
				( attribute "MATERIAL" "CHIP"
					( Origin gFrontEnd )
				)
				( attribute "PACK_TYPE" "0402"
					( Origin gFrontEnd )
				)
				( attribute "PART_NUMBER" "G21796-010"
					( Origin gFrontEnd )
				)
				( attribute "PHYS_PAGE" "116"
					( Origin gFrontEnd )
				)
				( attribute "ROOM" "SB"
					( Origin gFrontEnd )
				)
				( attribute "ROT" "0"
					( Origin gFrontEnd )
				)
				( attribute "SEC" "1"
					( Origin gPackager )
				)
				( attribute "TOLERANCE" "1%"
					( Origin gFrontEnd )
				)
				( attribute "VALUE" "100.0K"
					( Origin gFrontEnd )
				)
				( attribute "VER" "2"
					( Origin gFrontEnd )
				)
				( attribute "WATTAGE" "1/16W"
					( Origin gFrontEnd )
				)
				( attribute "XY" "(-6250,750)"
					( Origin gFrontEnd )
				)
				( attribute "CHIPS_PART_NAME" "RES"
					( Origin gPackager )
				)
				( attribute "CDS_PART_NAME" "RES_0402-100.0K,1%,1/16W,CHIP,A"
					( Origin gPackager )
				)
				( attribute "POP" "NOPOP"
					( Origin gFrontEnd )
				)
				( objectStatus "R3M9" )
			)
			( gate "@baseboard_fab2_lib.baseboard_fab2(sch_1):page116_i235"
				( attribute "CDS_LIB" "mstr_discrete"
					( Origin gPackager )
				)
				( attribute "CDS_LOCATION" "R3M8"
					( Origin gPackager )
				)
				( attribute "CDS_SEC" "1"
					( Origin gPackager )
				)
				( attribute "LOCATION" "R3M8"
					( Origin gFrontEnd )
				)
				( attribute "MATERIAL" "CHIP"
					( Origin gFrontEnd )
				)
				( attribute "PACK_TYPE" "0402"
					( Origin gFrontEnd )
				)
				( attribute "PART_NUMBER" "G21796-010"
					( Origin gFrontEnd )
				)
				( attribute "PHYS_PAGE" "116"
					( Origin gFrontEnd )
				)
				( attribute "ROOM" "SB"
					( Origin gFrontEnd )
				)
				( attribute "ROT" "0"
					( Origin gFrontEnd )
				)
				( attribute "SEC" "1"
					( Origin gPackager )
				)
				( attribute "TOLERANCE" "1%"
					( Origin gFrontEnd )
				)
				( attribute "VALUE" "100.0K"
					( Origin gFrontEnd )
				)
				( attribute "VER" "2"
					( Origin gFrontEnd )
				)
				( attribute "WATTAGE" "1/16W"
					( Origin gFrontEnd )
				)
				( attribute "XY" "(-5900,750)"
					( Origin gFrontEnd )
				)
				( attribute "CHIPS_PART_NAME" "RES"
					( Origin gPackager )
				)
				( attribute "CDS_PART_NAME" "RES_0402-100.0K,1%,1/16W,CHIP,A"
					( Origin gPackager )
				)
				( attribute "POP" "NOPOP"
					( Origin gFrontEnd )
				)
				( objectStatus "R3M8" )
			)
			( gate "@baseboard_fab2_lib.baseboard_fab2(sch_1):page117_i9"
				( attribute "BOM_COST" "SB"
					( Origin gFrontEnd )
				)
				( attribute "CDS_LIB" "mstr_u_proc"
					( Origin gPackager )
				)
				( attribute "CDS_LOCATION" "U7C1"
					( Origin gPackager )
				)
				( attribute "CDS_SEC" "4"
					( Origin gPackager )
				)
				( attribute "LOCATION" "U7C1"
					( Origin gFrontEnd )
				)
				( attribute "MATERIAL" "IC"
					( Origin gFrontEnd )
				)
				( attribute "PACK_TYPE" "BGA1"
					( Origin gFrontEnd )
				)
				( attribute "PART_NUMBER" "H91415-002"
					( Origin gFrontEnd )
				)
				( attribute "PHYS_PAGE" "117"
					( Origin gFrontEnd )
				)
				( attribute "ROOM" "SB"
					( Origin gFrontEnd )
				)
				( attribute "ROT" "0"
					( Origin gFrontEnd )
				)
				( attribute "SEC" "4"
					( Origin gFrontEnd )
				)
				( attribute "SEC_TYPE" "BGA1"
					( Origin gFrontEnd )
				)
				( attribute "VER" "4"
					( Origin gFrontEnd )
				)
				( attribute "XY" "(-3925,2150)"
					( Origin gFrontEnd )
				)
				( attribute "CHIPS_PART_NAME" "LBG_CORE_QAT_EXT_D"
					( Origin gPackager )
				)
				( attribute "CDS_PART_NAME" "LBG_CORE_QAT_EXT_D_BGA1-IC,H91A"
					( Origin gPackager )
				)
				( objectStatus "U7C1" )
			)
			( gate "@baseboard_fab2_lib.baseboard_fab2(sch_1):page118_i66"
				( attribute "BOM_COST" "SB"
					( Origin gFrontEnd )
				)
				( attribute "CDS_LIB" "mstr_discrete"
					( Origin gPackager )
				)
				( attribute "CDS_LOCATION" "R3N9"
					( Origin gPackager )
				)
				( attribute "CDS_SEC" "1"
					( Origin gPackager )
				)
				( attribute "LOCATION" "R3N9"
					( Origin gFrontEnd )
				)
				( attribute "MATERIAL" "CHIP"
					( Origin gFrontEnd )
				)
				( attribute "PACK_TYPE" "0402"
					( Origin gFrontEnd )
				)
				( attribute "PART_NUMBER" "G21796-066"
					( Origin gFrontEnd )
				)
				( attribute "PHYS_PAGE" "118"
					( Origin gFrontEnd )
				)
				( attribute "ROOM" "SB"
					( Origin gFrontEnd )
				)
				( attribute "ROT" "0"
					( Origin gFrontEnd )
				)
				( attribute "SEC" "1"
					( Origin gFrontEnd )
				)
				( attribute "SEC_TYPE" "0402"
					( Origin gFrontEnd )
				)
				( attribute "TOLERANCE" "1%"
					( Origin gFrontEnd )
				)
				( attribute "VALUE" "10.0"
					( Origin gFrontEnd )
				)
				( attribute "VER" "1"
					( Origin gFrontEnd )
				)
				( attribute "WATTAGE" "1/16W"
					( Origin gFrontEnd )
				)
				( attribute "XY" "(-1575,2675)"
					( Origin gFrontEnd )
				)
				( attribute "CHIPS_PART_NAME" "RES"
					( Origin gPackager )
				)
				( attribute "CDS_PART_NAME" "RES_0402-10.0,1%,1/16W,CHIP,G2A"
					( Origin gPackager )
				)
				( objectStatus "R3N9" )
			)
			( gate "@baseboard_fab2_lib.baseboard_fab2(sch_1):page118_i67"
				( attribute "BOM_COST" "SB"
					( Origin gFrontEnd )
				)
				( attribute "CDS_LIB" "mstr_discrete"
					( Origin gPackager )
				)
				( attribute "CDS_LOCATION" "R3N14"
					( Origin gPackager )
				)
				( attribute "CDS_SEC" "1"
					( Origin gPackager )
				)
				( attribute "LOCATION" "R3N14"
					( Origin gFrontEnd )
				)
				( attribute "MATERIAL" "EMPTY"
					( Origin gFrontEnd )
				)
				( attribute "PACK_TYPE" "0402"
					( Origin gFrontEnd )
				)
				( attribute "PART_NUMBER" "G21796-047"
					( Origin gFrontEnd )
				)
				( attribute "PHYS_PAGE" "118"
					( Origin gFrontEnd )
				)
				( attribute "ROOM" "SB"
					( Origin gFrontEnd )
				)
				( attribute "ROT" "0"
					( Origin gFrontEnd )
				)
				( attribute "SEC" "1"
					( Origin gFrontEnd )
				)
				( attribute "SEC_TYPE" "0402"
					( Origin gFrontEnd )
				)
				( attribute "TOLERANCE" "1%"
					( Origin gFrontEnd )
				)
				( attribute "VALUE" "49.9"
					( Origin gFrontEnd )
				)
				( attribute "VER" "2"
					( Origin gFrontEnd )
				)
				( attribute "WATTAGE" "1/16W"
					( Origin gFrontEnd )
				)
				( attribute "XY" "(-1075,2475)"
					( Origin gFrontEnd )
				)
				( attribute "CHIPS_PART_NAME" "RES"
					( Origin gPackager )
				)
				( attribute "CDS_PART_NAME" "RES_0402-49.9,1%,1/16W,EMPTY,GA"
					( Origin gPackager )
				)
				( objectStatus "R3N14" )
			)
			( gate "@baseboard_fab2_lib.baseboard_fab2(sch_1):page118_i71"
				( attribute "BOM_COST" "SB"
					( Origin gFrontEnd )
				)
				( attribute "CDS_LIB" "mstr_discrete"
					( Origin gPackager )
				)
				( attribute "CDS_LOCATION" "R3N13"
					( Origin gPackager )
				)
				( attribute "CDS_SEC" "1"
					( Origin gPackager )
				)
				( attribute "LOCATION" "R3N13"
					( Origin gFrontEnd )
				)
				( attribute "MATERIAL" "CHIP"
					( Origin gFrontEnd )
				)
				( attribute "PACK_TYPE" "0402"
					( Origin gFrontEnd )
				)
				( attribute "PART_NUMBER" "G21796-072"
					( Origin gFrontEnd )
				)
				( attribute "PHYS_PAGE" "118"
					( Origin gFrontEnd )
				)
				( attribute "ROOM" "SB"
					( Origin gFrontEnd )
				)
				( attribute "ROT" "0"
					( Origin gFrontEnd )
				)
				( attribute "SEC" "1"
					( Origin gFrontEnd )
				)
				( attribute "SEC_TYPE" "0402"
					( Origin gFrontEnd )
				)
				( attribute "TOLERANCE" "1%"
					( Origin gFrontEnd )
				)
				( attribute "VALUE" "4.75K"
					( Origin gFrontEnd )
				)
				( attribute "VER" "2"
					( Origin gFrontEnd )
				)
				( attribute "WATTAGE" "1/16W"
					( Origin gFrontEnd )
				)
				( attribute "XY" "(-2300,4650)"
					( Origin gFrontEnd )
				)
				( attribute "CHIPS_PART_NAME" "RES"
					( Origin gPackager )
				)
				( attribute "CDS_PART_NAME" "RES_0402-4.75K,1%,1/16W,CHIP,GA"
					( Origin gPackager )
				)
				( objectStatus "R3N13" )
			)
			( gate "@baseboard_fab2_lib.baseboard_fab2(sch_1):page118_i73"
				( attribute "BOM_COST" "SB"
					( Origin gFrontEnd )
				)
				( attribute "CDS_LIB" "mstr_u_proc"
					( Origin gPackager )
				)
				( attribute "CDS_LOCATION" "U7C1"
					( Origin gPackager )
				)
				( attribute "LOCATION" "U7C1"
					( Origin gFrontEnd )
				)
				( attribute "MATERIAL" "IC"
					( Origin gFrontEnd )
				)
				( attribute "PACK_TYPE" "BGA1"
					( Origin gFrontEnd )
				)
				( attribute "PART_NUMBER" "H91415-002"
					( Origin gFrontEnd )
				)
				( attribute "PHYS_PAGE" "118"
					( Origin gFrontEnd )
				)
				( attribute "ROOM" "SB"
					( Origin gFrontEnd )
				)
				( attribute "ROT" "0"
					( Origin gFrontEnd )
				)
				( attribute "SEC" "5"
					( Origin gFrontEnd )
				)
				( attribute "SEC_TYPE" "BGA1"
					( Origin gFrontEnd )
				)
				( attribute "VER" "5"
					( Origin gFrontEnd )
				)
				( attribute "XY" "(-4025,3025)"
					( Origin gFrontEnd )
				)
				( attribute "CHIPS_PART_NAME" "LBG_CORE_QAT_EXT_D"
					( Origin gPackager )
				)
				( attribute "CDS_PART_NAME" "LBG_CORE_QAT_EXT_D_BGA1-IC,H91A"
					( Origin gPackager )
				)
				( attribute "CDS_SEC" "5"
					( Origin gPackager )
				)
				( objectStatus "U7C1" )
			)
			( gate "@baseboard_fab2_lib.baseboard_fab2(sch_1):page118_i76"
				( attribute "BOM_COST" "SB"
					( Origin gFrontEnd )
				)
				( attribute "CDS_LIB" "mstr_discrete"
					( Origin gPackager )
				)
				( attribute "CDS_LOCATION" "Y8C1"
					( Origin gPackager )
				)
				( attribute "CDS_SEC" "1"
					( Origin gPackager )
				)
				( attribute "LOCATION" "Y8C1"
					( Origin gFrontEnd )
				)
				( attribute "MATERIAL" "IC"
					( Origin gFrontEnd )
				)
				( attribute "PACK_TYPE" "2013"
					( Origin gFrontEnd )
				)
				( attribute "PART_NUMBER" "H19611-001"
					( Origin gFrontEnd )
				)
				( attribute "PHYS_PAGE" "118"
					( Origin gFrontEnd )
				)
				( attribute "ROOM" "SB"
					( Origin gFrontEnd )
				)
				( attribute "ROT" "0"
					( Origin gFrontEnd )
				)
				( attribute "SEC" "1"
					( Origin gFrontEnd )
				)
				( attribute "SEC_TYPE" "2013"
					( Origin gFrontEnd )
				)
				( attribute "VALUE" "25.000MHZ"
					( Origin gFrontEnd )
				)
				( attribute "VER" "1"
					( Origin gFrontEnd )
				)
				( attribute "XY" "(-7400,850)"
					( Origin gFrontEnd )
				)
				( attribute "CHIPS_PART_NAME" "CRYSTAL"
					( Origin gPackager )
				)
				( attribute "CDS_PART_NAME" "CRYSTAL_2013-25.000MHZ,IC,H196A"
					( Origin gPackager )
				)
				( objectStatus "Y8C1" )
			)
			( gate "@baseboard_fab2_lib.baseboard_fab2(sch_1):page118_i96"
				( attribute "CDS_LIB" "mstr_discrete"
					( Origin gPackager )
				)
				( attribute "CDS_LOCATION" "R2N4"
					( Origin gPackager )
				)
				( attribute "CDS_SEC" "1"
					( Origin gPackager )
				)
				( attribute "LOCATION" "R2N4"
					( Origin gFrontEnd )
				)
				( attribute "MATERIAL" "CHIP"
					( Origin gFrontEnd )
				)
				( attribute "PACK_TYPE" "0402"
					( Origin gFrontEnd )
				)
				( attribute "PART_NUMBER" "G85996-004"
					( Origin gFrontEnd )
				)
				( attribute "PHYS_PAGE" "118"
					( Origin gFrontEnd )
				)
				( attribute "ROOM" "SB"
					( Origin gFrontEnd )
				)
				( attribute "ROT" "0"
					( Origin gFrontEnd )
				)
				( attribute "SEC" "1"
					( Origin gFrontEnd )
				)
				( attribute "SEC_TYPE" "0402"
					( Origin gFrontEnd )
				)
				( attribute "TOLERANCE" "0.1%"
					( Origin gFrontEnd )
				)
				( attribute "VALUE" "1.0K"
					( Origin gFrontEnd )
				)
				( attribute "VER" "2"
					( Origin gFrontEnd )
				)
				( attribute "WATTAGE" "1/16W"
					( Origin gFrontEnd )
				)
				( attribute "XY" "(-7225,2175)"
					( Origin gFrontEnd )
				)
				( attribute "CHIPS_PART_NAME" "RES"
					( Origin gPackager )
				)
				( attribute "CDS_PART_NAME" "RES_0402-1.0K,0.1%,1/16W,CHIP,A"
					( Origin gPackager )
				)
				( objectStatus "R2N4" )
			)
			( gate "@baseboard_fab2_lib.baseboard_fab2(sch_1):page118_i99"
				( attribute "CDS_LIB" "mstr_discrete"
					( Origin gPackager )
				)
				( attribute "CDS_LOCATION" "R2M6"
					( Origin gPackager )
				)
				( attribute "CDS_SEC" "1"
					( Origin gPackager )
				)
				( attribute "LOCATION" "R2M6"
					( Origin gFrontEnd )
				)
				( attribute "MATERIAL" "CHIP"
					( Origin gFrontEnd )
				)
				( attribute "PACK_TYPE" "0402"
					( Origin gFrontEnd )
				)
				( attribute "PART_NUMBER" "G85996-004"
					( Origin gFrontEnd )
				)
				( attribute "PHYS_PAGE" "118"
					( Origin gFrontEnd )
				)
				( attribute "ROOM" "SB"
					( Origin gFrontEnd )
				)
				( attribute "ROT" "0"
					( Origin gFrontEnd )
				)
				( attribute "SEC" "1"
					( Origin gFrontEnd )
				)
				( attribute "SEC_TYPE" "0402"
					( Origin gFrontEnd )
				)
				( attribute "TOLERANCE" "0.1%"
					( Origin gFrontEnd )
				)
				( attribute "VALUE" "1.0K"
					( Origin gFrontEnd )
				)
				( attribute "VER" "1"
					( Origin gFrontEnd )
				)
				( attribute "WATTAGE" "1/16W"
					( Origin gFrontEnd )
				)
				( attribute "XY" "(-1700,1875)"
					( Origin gFrontEnd )
				)
				( attribute "CHIPS_PART_NAME" "RES"
					( Origin gPackager )
				)
				( attribute "CDS_PART_NAME" "RES_0402-1.0K,0.1%,1/16W,CHIP,A"
					( Origin gPackager )
				)
				( objectStatus "R2M6" )
			)
			( gate "@baseboard_fab2_lib.baseboard_fab2(sch_1):page118_i120"
				( attribute "BOM_COST" "SB"
					( Origin gFrontEnd )
				)
				( attribute "CDS_LIB" "mstr_discrete"
					( Origin gPackager )
				)
				( attribute "CDS_LOCATION" "R8C24"
					( Origin gPackager )
				)
				( attribute "CDS_SEC" "1"
					( Origin gPackager )
				)
				( attribute "LOCATION" "R8C24"
					( Origin gFrontEnd )
				)
				( attribute "MATERIAL" "CHIP"
					( Origin gFrontEnd )
				)
				( attribute "PACK_TYPE" "0402"
					( Origin gFrontEnd )
				)
				( attribute "PART_NUMBER" "G21497-005"
					( Origin gFrontEnd )
				)
				( attribute "PHYS_PAGE" "118"
					( Origin gFrontEnd )
				)
				( attribute "ROOM" "SB"
					( Origin gFrontEnd )
				)
				( attribute "ROT" "0"
					( Origin gFrontEnd )
				)
				( attribute "SEC" "1"
					( Origin gFrontEnd )
				)
				( attribute "SEC_TYPE" "0402"
					( Origin gFrontEnd )
				)
				( attribute "TOLERANCE" "5%"
					( Origin gFrontEnd )
				)
				( attribute "VALUE" "0.0"
					( Origin gFrontEnd )
				)
				( attribute "VER" "1"
					( Origin gFrontEnd )
				)
				( attribute "WATTAGE" "1/16W"
					( Origin gFrontEnd )
				)
				( attribute "XY" "(-1675,900)"
					( Origin gFrontEnd )
				)
				( attribute "CHIPS_PART_NAME" "RES"
					( Origin gPackager )
				)
				( attribute "CDS_PART_NAME" "RES_0402-0.0,5%,1/16W,CHIP,G21A"
					( Origin gPackager )
				)
				( objectStatus "R8C24" )
			)
			( gate "@baseboard_fab2_lib.baseboard_fab2(sch_1):page118_i125"
				( attribute "BOM_COST" "SB"
					( Origin gFrontEnd )
				)
				( attribute "CDS_LIB" "mstr_discrete"
					( Origin gPackager )
				)
				( attribute "CDS_LOCATION" "R8C23"
					( Origin gPackager )
				)
				( attribute "CDS_SEC" "1"
					( Origin gPackager )
				)
				( attribute "LOCATION" "R8C23"
					( Origin gFrontEnd )
				)
				( attribute "MATERIAL" "EMPTY"
					( Origin gFrontEnd )
				)
				( attribute "PACK_TYPE" "0402"
					( Origin gFrontEnd )
				)
				( attribute "PART_NUMBER" "G21497-005"
					( Origin gFrontEnd )
				)
				( attribute "PHYS_PAGE" "118"
					( Origin gFrontEnd )
				)
				( attribute "ROOM" "SB"
					( Origin gFrontEnd )
				)
				( attribute "ROT" "0"
					( Origin gFrontEnd )
				)
				( attribute "SEC" "1"
					( Origin gFrontEnd )
				)
				( attribute "SEC_TYPE" "0402"
					( Origin gFrontEnd )
				)
				( attribute "TOLERANCE" "5%"
					( Origin gFrontEnd )
				)
				( attribute "VALUE" "0.0"
					( Origin gFrontEnd )
				)
				( attribute "VER" "1"
					( Origin gFrontEnd )
				)
				( attribute "WATTAGE" "1/16W"
					( Origin gFrontEnd )
				)
				( attribute "XY" "(-1675,675)"
					( Origin gFrontEnd )
				)
				( attribute "CHIPS_PART_NAME" "RES"
					( Origin gPackager )
				)
				( attribute "CDS_PART_NAME" "RES_0402-0.0,5%,1/16W,EMPTY,G2A"
					( Origin gPackager )
				)
				( objectStatus "R8C23" )
			)
			( gate "@baseboard_fab2_lib.baseboard_fab2(sch_1):page118_i128"
				( attribute "BOM_COST" "SB"
					( Origin gFrontEnd )
				)
				( attribute "CDS_LIB" "mstr_discrete"
					( Origin gPackager )
				)
				( attribute "CDS_LOCATION" "R2N6"
					( Origin gPackager )
				)
				( attribute "CDS_SEC" "1"
					( Origin gPackager )
				)
				( attribute "LOCATION" "R2N6"
					( Origin gFrontEnd )
				)
				( attribute "MATERIAL" "CHIP"
					( Origin gFrontEnd )
				)
				( attribute "PACK_TYPE" "0402"
					( Origin gFrontEnd )
				)
				( attribute "PART_NUMBER" "G21796-016"
					( Origin gFrontEnd )
				)
				( attribute "PHYS_PAGE" "118"
					( Origin gFrontEnd )
				)
				( attribute "ROOM" "SB"
					( Origin gFrontEnd )
				)
				( attribute "ROT" "0"
					( Origin gFrontEnd )
				)
				( attribute "SEC" "1"
					( Origin gFrontEnd )
				)
				( attribute "SEC_TYPE" "0402"
					( Origin gFrontEnd )
				)
				( attribute "TOLERANCE" "1%"
					( Origin gFrontEnd )
				)
				( attribute "VALUE" "10.0K"
					( Origin gFrontEnd )
				)
				( attribute "VER" "2"
					( Origin gFrontEnd )
				)
				( attribute "WATTAGE" "1/16W"
					( Origin gFrontEnd )
				)
				( attribute "XY" "(-2200,1100)"
					( Origin gFrontEnd )
				)
				( attribute "CHIPS_PART_NAME" "RES"
					( Origin gPackager )
				)
				( attribute "CDS_PART_NAME" "RES_0402-10.0K,1%,1/16W,CHIP,GA"
					( Origin gPackager )
				)
				( objectStatus "R2N6" )
			)
			( gate "@baseboard_fab2_lib.baseboard_fab2(sch_1):page118_i131"
				( attribute "BOM_COST" "SB"
					( Origin gFrontEnd )
				)
				( attribute "CDS_LIB" "mstr_discrete"
					( Origin gPackager )
				)
				( attribute "CDS_LOCATION" "R7D23"
					( Origin gPackager )
				)
				( attribute "CDS_SEC" "1"
					( Origin gPackager )
				)
				( attribute "LOCATION" "R7D23"
					( Origin gFrontEnd )
				)
				( attribute "MATERIAL" "CHIP"
					( Origin gFrontEnd )
				)
				( attribute "PACK_TYPE" "0402"
					( Origin gFrontEnd )
				)
				( attribute "PART_NUMBER" "G21497-005"
					( Origin gFrontEnd )
				)
				( attribute "PHYS_PAGE" "118"
					( Origin gFrontEnd )
				)
				( attribute "ROOM" "SB"
					( Origin gFrontEnd )
				)
				( attribute "ROT" "0"
					( Origin gFrontEnd )
				)
				( attribute "SEC" "1"
					( Origin gFrontEnd )
				)
				( attribute "SEC_TYPE" "0402"
					( Origin gFrontEnd )
				)
				( attribute "TOLERANCE" "5%"
					( Origin gFrontEnd )
				)
				( attribute "VALUE" "0.0"
					( Origin gFrontEnd )
				)
				( attribute "VER" "1"
					( Origin gFrontEnd )
				)
				( attribute "WATTAGE" "1/16W"
					( Origin gFrontEnd )
				)
				( attribute "XY" "(-6625,3975)"
					( Origin gFrontEnd )
				)
				( attribute "CHIPS_PART_NAME" "RES"
					( Origin gPackager )
				)
				( attribute "CDS_PART_NAME" "RES_0402-0.0,5%,1/16W,CHIP,G21A"
					( Origin gPackager )
				)
				( attribute "POP" "NOPOP"
					( Origin gFrontEnd )
				)
				( objectStatus "R7D23" )
			)
			( gate "@baseboard_fab2_lib.baseboard_fab2(sch_1):page118_i136"
				( attribute "BOM_COST" "SB"
					( Origin gFrontEnd )
				)
				( attribute "CDS_LIB" "dev_discrete"
					( Origin gPackager )
				)
				( attribute "CDS_LOCATION" "C7D1"
					( Origin gPackager )
				)
				( attribute "CDS_SEC" "1"
					( Origin gPackager )
				)
				( attribute "LOCATION" "C7D1"
					( Origin gFrontEnd )
				)
				( attribute "MATERIAL" "X7R"
					( Origin gFrontEnd )
				)
				( attribute "PACK_TYPE" "0402V"
					( Origin gFrontEnd )
				)
				( attribute "PART_NUMBER" "A36096-030"
					( Origin gFrontEnd )
				)
				( attribute "PHYS_PAGE" "118"
					( Origin gFrontEnd )
				)
				( attribute "ROOM" "SB"
					( Origin gFrontEnd )
				)
				( attribute "ROT" "0"
					( Origin gFrontEnd )
				)
				( attribute "SEC" "1"
					( Origin gFrontEnd )
				)
				( attribute "SEC_TYPE" "0402V"
					( Origin gFrontEnd )
				)
				( attribute "TOLERANCE" "10%"
					( Origin gFrontEnd )
				)
				( attribute "VALUE" "0.1UF"
					( Origin gFrontEnd )
				)
				( attribute "VER" "1"
					( Origin gFrontEnd )
				)
				( attribute "VOLTAGE" "16V"
					( Units "uVoltage" "V" 1.000000)
					( Origin gFrontEnd )
				)
				( attribute "XY" "(-5200,375)"
					( Origin gFrontEnd )
				)
				( attribute "CHIPS_PART_NAME" "CAP_A"
					( Origin gPackager )
				)
				( attribute "CDS_PART_NAME" "CAP_A_0402V-0.1UF,16V,10%,X7R,A"
					( Origin gPackager )
				)
				( objectStatus "C7D1" )
			)
			( gate "@baseboard_fab2_lib.baseboard_fab2(sch_1):page118_i142"
				( attribute "BOM_COST" "DEBUG"
					( Origin gFrontEnd )
				)
				( attribute "CDS_LIB" "mstr_ttl"
					( Origin gPackager )
				)
				( attribute "CDS_LOCATION" "U7D1"
					( Origin gPackager )
				)
				( attribute "CDS_SEC" "1"
					( Origin gPackager )
				)
				( attribute "LOCATION" "U7D1"
					( Origin gFrontEnd )
				)
				( attribute "MATERIAL" "IC"
					( Origin gFrontEnd )
				)
				( attribute "PACK_TYPE" "SMLF"
					( Origin gFrontEnd )
				)
				( attribute "PART_NUMBER" "C88177-001"
					( Origin gFrontEnd )
				)
				( attribute "PHYS_PAGE" "118"
					( Origin gFrontEnd )
				)
				( attribute "ROOM" "DEBUG"
					( Origin gFrontEnd )
				)
				( attribute "ROT" "0"
					( Origin gFrontEnd )
				)
				( attribute "SEC" "1"
					( Origin gPackager )
				)
				( attribute "VER" "1"
					( Origin gFrontEnd )
				)
				( attribute "XY" "(-4575,1075)"
					( Origin gFrontEnd )
				)
				( attribute "CHIPS_PART_NAME" "74CBTLV1G125"
					( Origin gPackager )
				)
				( attribute "CDS_PART_NAME" "74CBTLV1G125_SMLF-IC,C88177-00A"
					( Origin gPackager )
				)
				( objectStatus "U7D1" )
			)
			( gate "@baseboard_fab2_lib.baseboard_fab2(sch_1):page118_i144"
				( attribute "BOM_COST" "SB"
					( Origin gFrontEnd )
				)
				( attribute "CDS_LIB" "mstr_discrete"
					( Origin gPackager )
				)
				( attribute "CDS_LOCATION" "R7C23"
					( Origin gPackager )
				)
				( attribute "CDS_SEC" "1"
					( Origin gPackager )
				)
				( attribute "LOCATION" "R7C23"
					( Origin gFrontEnd )
				)
				( attribute "MATERIAL" "CHIP"
					( Origin gFrontEnd )
				)
				( attribute "PACK_TYPE" "0402"
					( Origin gFrontEnd )
				)
				( attribute "PART_NUMBER" "G21796-016"
					( Origin gFrontEnd )
				)
				( attribute "PHYS_PAGE" "118"
					( Origin gFrontEnd )
				)
				( attribute "ROOM" "SB"
					( Origin gFrontEnd )
				)
				( attribute "ROT" "0"
					( Origin gFrontEnd )
				)
				( attribute "SEC" "1"
					( Origin gFrontEnd )
				)
				( attribute "SEC_TYPE" "0402"
					( Origin gFrontEnd )
				)
				( attribute "TOLERANCE" "1%"
					( Origin gFrontEnd )
				)
				( attribute "VALUE" "10.0K"
					( Origin gFrontEnd )
				)
				( attribute "VER" "2"
					( Origin gFrontEnd )
				)
				( attribute "WATTAGE" "1/16W"
					( Origin gFrontEnd )
				)
				( attribute "XY" "(-5175,1275)"
					( Origin gFrontEnd )
				)
				( attribute "CHIPS_PART_NAME" "RES"
					( Origin gPackager )
				)
				( attribute "CDS_PART_NAME" "RES_0402-10.0K,1%,1/16W,CHIP,GA"
					( Origin gPackager )
				)
				( objectStatus "R7C23" )
			)
			( gate "@baseboard_fab2_lib.baseboard_fab2(sch_1):page119_i115"
				( attribute "BOM_COST" "SB"
					( Origin gFrontEnd )
				)
				( attribute "CDS_LIB" "mstr_u_proc"
					( Origin gPackager )
				)
				( attribute "CDS_LOCATION" "U7C1"
					( Origin gPackager )
				)
				( attribute "CDS_SEC" "6"
					( Origin gPackager )
				)
				( attribute "LOCATION" "U7C1"
					( Origin gFrontEnd )
				)
				( attribute "MATERIAL" "IC"
					( Origin gFrontEnd )
				)
				( attribute "PACK_TYPE" "BGA1"
					( Origin gFrontEnd )
				)
				( attribute "PART_NUMBER" "H91415-002"
					( Origin gFrontEnd )
				)
				( attribute "PHYS_PAGE" "119"
					( Origin gFrontEnd )
				)
				( attribute "ROOM" "SB"
					( Origin gFrontEnd )
				)
				( attribute "ROT" "0"
					( Origin gFrontEnd )
				)
				( attribute "SEC" "6"
					( Origin gFrontEnd )
				)
				( attribute "SEC_TYPE" "BGA1"
					( Origin gFrontEnd )
				)
				( attribute "VER" "6"
					( Origin gFrontEnd )
				)
				( attribute "XY" "(-4100,3200)"
					( Origin gFrontEnd )
				)
				( attribute "CHIPS_PART_NAME" "LBG_CORE_QAT_EXT_D"
					( Origin gPackager )
				)
				( attribute "CDS_PART_NAME" "LBG_CORE_QAT_EXT_D_BGA1-IC,H91A"
					( Origin gPackager )
				)
				( objectStatus "U7C1" )
			)
			( gate "@baseboard_fab2_lib.baseboard_fab2(sch_1):page119_i172"
				( attribute "CDS_LIB" "mstr_discrete"
					( Origin gPackager )
				)
				( attribute "CDS_LOCATION" "R2M3"
					( Origin gPackager )
				)
				( attribute "CDS_SEC" "1"
					( Origin gPackager )
				)
				( attribute "LOCATION" "R2M3"
					( Origin gFrontEnd )
				)
				( attribute "MATERIAL" "CHIP"
					( Origin gFrontEnd )
				)
				( attribute "PACK_TYPE" "0402"
					( Origin gFrontEnd )
				)
				( attribute "PART_NUMBER" "G21796-074"
					( Origin gFrontEnd )
				)
				( attribute "PHYS_PAGE" "119"
					( Origin gFrontEnd )
				)
				( attribute "ROOM" "CPLD"
					( Origin gFrontEnd )
				)
				( attribute "ROT" "0"
					( Origin gFrontEnd )
				)
				( attribute "SEC" "1"
					( Origin gFrontEnd )
				)
				( attribute "SEC_TYPE" "0402"
					( Origin gFrontEnd )
				)
				( attribute "TOLERANCE" "1%"
					( Origin gFrontEnd )
				)
				( attribute "VALUE" "33.2"
					( Origin gFrontEnd )
				)
				( attribute "VER" "1"
					( Origin gFrontEnd )
				)
				( attribute "WATTAGE" "1/16W"
					( Origin gFrontEnd )
				)
				( attribute "XY" "(-1450,2200)"
					( Origin gFrontEnd )
				)
				( attribute "CHIPS_PART_NAME" "RES"
					( Origin gPackager )
				)
				( attribute "CDS_PART_NAME" "RES_0402-33.2,1%,1/16W,CHIP,G2A"
					( Origin gPackager )
				)
				( objectStatus "R2M3" )
			)
			( gate "@baseboard_fab2_lib.baseboard_fab2(sch_1):page119_i173"
				( attribute "CDS_LIB" "mstr_discrete"
					( Origin gPackager )
				)
				( attribute "CDS_LOCATION" "R2N1"
					( Origin gPackager )
				)
				( attribute "CDS_SEC" "1"
					( Origin gPackager )
				)
				( attribute "LOCATION" "R2N1"
					( Origin gFrontEnd )
				)
				( attribute "MATERIAL" "CHIP"
					( Origin gFrontEnd )
				)
				( attribute "PACK_TYPE" "0402"
					( Origin gFrontEnd )
				)
				( attribute "PART_NUMBER" "G21796-074"
					( Origin gFrontEnd )
				)
				( attribute "PHYS_PAGE" "119"
					( Origin gFrontEnd )
				)
				( attribute "ROOM" "CPLD"
					( Origin gFrontEnd )
				)
				( attribute "ROT" "0"
					( Origin gFrontEnd )
				)
				( attribute "SEC" "1"
					( Origin gFrontEnd )
				)
				( attribute "SEC_TYPE" "0402"
					( Origin gFrontEnd )
				)
				( attribute "TOLERANCE" "1%"
					( Origin gFrontEnd )
				)
				( attribute "VALUE" "33.2"
					( Origin gFrontEnd )
				)
				( attribute "VER" "1"
					( Origin gFrontEnd )
				)
				( attribute "WATTAGE" "1/16W"
					( Origin gFrontEnd )
				)
				( attribute "XY" "(-1550,4400)"
					( Origin gFrontEnd )
				)
				( attribute "CHIPS_PART_NAME" "RES"
					( Origin gPackager )
				)
				( attribute "CDS_PART_NAME" "RES_0402-33.2,1%,1/16W,CHIP,G2A"
					( Origin gPackager )
				)
				( objectStatus "R2N1" )
			)
			( gate "@baseboard_fab2_lib.baseboard_fab2(sch_1):page119_i174"
				( attribute "CDS_LIB" "mstr_discrete"
					( Origin gPackager )
				)
				( attribute "CDS_LOCATION" "R2M7"
					( Origin gPackager )
				)
				( attribute "CDS_SEC" "1"
					( Origin gPackager )
				)
				( attribute "LOCATION" "R2M7"
					( Origin gFrontEnd )
				)
				( attribute "MATERIAL" "CHIP"
					( Origin gFrontEnd )
				)
				( attribute "PACK_TYPE" "0402"
					( Origin gFrontEnd )
				)
				( attribute "PART_NUMBER" "G21796-074"
					( Origin gFrontEnd )
				)
				( attribute "PHYS_PAGE" "119"
					( Origin gFrontEnd )
				)
				( attribute "ROOM" "CPLD"
					( Origin gFrontEnd )
				)
				( attribute "ROT" "0"
					( Origin gFrontEnd )
				)
				( attribute "SEC" "1"
					( Origin gFrontEnd )
				)
				( attribute "SEC_TYPE" "0402"
					( Origin gFrontEnd )
				)
				( attribute "TOLERANCE" "1%"
					( Origin gFrontEnd )
				)
				( attribute "VALUE" "33.2"
					( Origin gFrontEnd )
				)
				( attribute "VER" "1"
					( Origin gFrontEnd )
				)
				( attribute "WATTAGE" "1/16W"
					( Origin gFrontEnd )
				)
				( attribute "XY" "(-1475,2950)"
					( Origin gFrontEnd )
				)
				( attribute "CHIPS_PART_NAME" "RES"
					( Origin gPackager )
				)
				( attribute "CDS_PART_NAME" "RES_0402-33.2,1%,1/16W,CHIP,G2A"
					( Origin gPackager )
				)
				( objectStatus "R2M7" )
			)
			( gate "@baseboard_fab2_lib.baseboard_fab2(sch_1):page119_i175"
				( attribute "BOM_COST" "SB"
					( Origin gFrontEnd )
				)
				( attribute "CDS_LIB" "mstr_discrete"
					( Origin gPackager )
				)
				( attribute "CDS_LOCATION" "Q9A2"
					( Origin gPackager )
				)
				( attribute "CDS_SEC" "1"
					( Origin gPackager )
				)
				( attribute "LOCATION" "Q9A2"
					( Origin gFrontEnd )
				)
				( attribute "MATERIAL" "FET"
					( Origin gFrontEnd )
				)
				( attribute "PACK_TYPE" "SMLF"
					( Origin gFrontEnd )
				)
				( attribute "PART_NUMBER" "E40049-001"
					( Origin gFrontEnd )
				)
				( attribute "PHYS_PAGE" "119"
					( Origin gFrontEnd )
				)
				( attribute "ROOM" "SB"
					( Origin gFrontEnd )
				)
				( attribute "ROT" "0"
					( Origin gFrontEnd )
				)
				( attribute "SEC" "1"
					( Origin gFrontEnd )
				)
				( attribute "SEC_TYPE" "SMLF"
					( Origin gFrontEnd )
				)
				( attribute "VALUE" "NTJD4001N"
					( Origin gFrontEnd )
				)
				( attribute "VER" "5"
					( Origin gFrontEnd )
				)
				( attribute "XY" "(-4725,725)"
					( Origin gFrontEnd )
				)
				( attribute "CHIPS_PART_NAME" "FET_N_DUAL"
					( Origin gPackager )
				)
				( attribute "CDS_PART_NAME" "FET_N_DUAL_SMLF-NTJD4001N,FET,A"
					( Origin gPackager )
				)
				( objectStatus "Q9A2" )
			)
			( gate "@baseboard_fab2_lib.baseboard_fab2(sch_1):page119_i178"
				( attribute "BOM_COST" "SB"
					( Origin gFrontEnd )
				)
				( attribute "CDS_LIB" "mstr_discrete"
					( Origin gPackager )
				)
				( attribute "CDS_LOCATION" "R9A20"
					( Origin gPackager )
				)
				( attribute "CDS_SEC" "1"
					( Origin gPackager )
				)
				( attribute "LOCATION" "R9A20"
					( Origin gFrontEnd )
				)
				( attribute "MATERIAL" "CHIP"
					( Origin gFrontEnd )
				)
				( attribute "PACK_TYPE" "0402"
					( Origin gFrontEnd )
				)
				( attribute "PART_NUMBER" "G21796-271"
					( Origin gFrontEnd )
				)
				( attribute "PHYS_PAGE" "119"
					( Origin gFrontEnd )
				)
				( attribute "ROOM" "SB"
					( Origin gFrontEnd )
				)
				( attribute "ROT" "0"
					( Origin gFrontEnd )
				)
				( attribute "SEC" "1"
					( Origin gFrontEnd )
				)
				( attribute "SEC_TYPE" "0402"
					( Origin gFrontEnd )
				)
				( attribute "TOLERANCE" "1.0%"
					( Origin gFrontEnd )
				)
				( attribute "VALUE" "221"
					( Origin gFrontEnd )
				)
				( attribute "VER" "1"
					( Origin gFrontEnd )
				)
				( attribute "WATTAGE" "1/16W"
					( Origin gFrontEnd )
				)
				( attribute "XY" "(-2900,1525)"
					( Origin gFrontEnd )
				)
				( attribute "CHIPS_PART_NAME" "RES"
					( Origin gPackager )
				)
				( attribute "CDS_PART_NAME" "RES_0402-221,1.0%,1/16W,CHIP,GA"
					( Origin gPackager )
				)
				( objectStatus "R9A20" )
			)
			( gate "@baseboard_fab2_lib.baseboard_fab2(sch_1):page119_i179"
				( attribute "BOM_COST" "SB"
					( Origin gFrontEnd )
				)
				( attribute "CDS_LIB" "mstr_discrete"
					( Origin gPackager )
				)
				( attribute "CDS_LOCATION" "DS9A5"
					( Origin gPackager )
				)
				( attribute "CDS_SEC" "1"
					( Origin gPackager )
				)
				( attribute "COLOR" "GREEN"
					( Origin gFrontEnd )
				)
				( attribute "LOCATION" "DS9A5"
					( Origin gFrontEnd )
				)
				( attribute "MATERIAL" "IC"
					( Origin gFrontEnd )
				)
				( attribute "PACK_TYPE" "A1LF"
					( Origin gFrontEnd )
				)
				( attribute "PART_NUMBER" "C97278-010"
					( Origin gFrontEnd )
				)
				( attribute "PHYS_PAGE" "119"
					( Origin gFrontEnd )
				)
				( attribute "ROOM" "SB"
					( Origin gFrontEnd )
				)
				( attribute "ROT" "0"
					( Origin gFrontEnd )
				)
				( attribute "SEC" "1"
					( Origin gFrontEnd )
				)
				( attribute "SEC_TYPE" "A1LF"
					( Origin gFrontEnd )
				)
				( attribute "VER" "3"
					( Origin gFrontEnd )
				)
				( attribute "XY" "(-3550,1525)"
					( Origin gFrontEnd )
				)
				( attribute "CHIPS_PART_NAME" "LED"
					( Origin gPackager )
				)
				( attribute "CDS_PART_NAME" "LED_A1LF-GREEN,IC,C97278-010"
					( Origin gPackager )
				)
				( objectStatus "DS9A5" )
			)
			( gate "@baseboard_fab2_lib.baseboard_fab2(sch_1):page119_i180"
				( attribute "BOM_COST" "SB"
					( Origin gFrontEnd )
				)
				( attribute "CDS_LIB" "mstr_discrete"
					( Origin gPackager )
				)
				( attribute "CDS_LOCATION" "Q9A2"
					( Origin gPackager )
				)
				( attribute "CDS_SEC" "2"
					( Origin gPackager )
				)
				( attribute "LOCATION" "Q9A2"
					( Origin gFrontEnd )
				)
				( attribute "MATERIAL" "FET"
					( Origin gFrontEnd )
				)
				( attribute "PACK_TYPE" "SMLF"
					( Origin gFrontEnd )
				)
				( attribute "PART_NUMBER" "E40049-001"
					( Origin gFrontEnd )
				)
				( attribute "PHYS_PAGE" "119"
					( Origin gFrontEnd )
				)
				( attribute "ROOM" "SB"
					( Origin gFrontEnd )
				)
				( attribute "ROT" "0"
					( Origin gFrontEnd )
				)
				( attribute "SEC" "2"
					( Origin gFrontEnd )
				)
				( attribute "SEC_TYPE" "SMLF"
					( Origin gFrontEnd )
				)
				( attribute "VALUE" "NTJD4001N"
					( Origin gFrontEnd )
				)
				( attribute "VER" "5"
					( Origin gFrontEnd )
				)
				( attribute "XY" "(-3950,1200)"
					( Origin gFrontEnd )
				)
				( attribute "CHIPS_PART_NAME" "FET_N_DUAL"
					( Origin gPackager )
				)
				( attribute "CDS_PART_NAME" "FET_N_DUAL_SMLF-NTJD4001N,FET,A"
					( Origin gPackager )
				)
				( objectStatus "Q9A2" )
			)
			( gate "@baseboard_fab2_lib.baseboard_fab2(sch_1):page119_i183"
				( attribute "BOM_COST" "SB"
					( Origin gFrontEnd )
				)
				( attribute "CDS_LIB" "mstr_discrete"
					( Origin gPackager )
				)
				( attribute "CDS_LOCATION" "R9A18"
					( Origin gPackager )
				)
				( attribute "CDS_SEC" "1"
					( Origin gPackager )
				)
				( attribute "LOCATION" "R9A18"
					( Origin gFrontEnd )
				)
				( attribute "MATERIAL" "CHIP"
					( Origin gFrontEnd )
				)
				( attribute "PACK_TYPE" "0402"
					( Origin gFrontEnd )
				)
				( attribute "PART_NUMBER" "G21796-072"
					( Origin gFrontEnd )
				)
				( attribute "PHYS_PAGE" "119"
					( Origin gFrontEnd )
				)
				( attribute "ROOM" "SB"
					( Origin gFrontEnd )
				)
				( attribute "ROT" "0"
					( Origin gFrontEnd )
				)
				( attribute "SEC" "1"
					( Origin gFrontEnd )
				)
				( attribute "SEC_TYPE" "0402"
					( Origin gFrontEnd )
				)
				( attribute "TOLERANCE" "1%"
					( Origin gFrontEnd )
				)
				( attribute "VALUE" "4.75K"
					( Origin gFrontEnd )
				)
				( attribute "VER" "2"
					( Origin gFrontEnd )
				)
				( attribute "WATTAGE" "1/16W"
					( Origin gFrontEnd )
				)
				( attribute "XY" "(-4725,1350)"
					( Origin gFrontEnd )
				)
				( attribute "CHIPS_PART_NAME" "RES"
					( Origin gPackager )
				)
				( attribute "CDS_PART_NAME" "RES_0402-4.75K,1%,1/16W,CHIP,GA"
					( Origin gPackager )
				)
				( objectStatus "R9A18" )
			)
			( gate "@baseboard_fab2_lib.baseboard_fab2(sch_1):page119_i186"
				( attribute "BOM_COST" "SB"
					( Origin gFrontEnd )
				)
				( attribute "CDS_LIB" "mstr_discrete"
					( Origin gPackager )
				)
				( attribute "CDS_LOCATION" "R9A21"
					( Origin gPackager )
				)
				( attribute "CDS_SEC" "1"
					( Origin gPackager )
				)
				( attribute "LOCATION" "R9A21"
					( Origin gFrontEnd )
				)
				( attribute "MATERIAL" "CHIP"
					( Origin gFrontEnd )
				)
				( attribute "PACK_TYPE" "0402"
					( Origin gFrontEnd )
				)
				( attribute "PART_NUMBER" "G21796-072"
					( Origin gFrontEnd )
				)
				( attribute "PHYS_PAGE" "119"
					( Origin gFrontEnd )
				)
				( attribute "ROOM" "SB"
					( Origin gFrontEnd )
				)
				( attribute "ROT" "0"
					( Origin gFrontEnd )
				)
				( attribute "SEC" "1"
					( Origin gFrontEnd )
				)
				( attribute "SEC_TYPE" "0402"
					( Origin gFrontEnd )
				)
				( attribute "TOLERANCE" "1%"
					( Origin gFrontEnd )
				)
				( attribute "VALUE" "4.75K"
					( Origin gFrontEnd )
				)
				( attribute "VER" "2"
					( Origin gFrontEnd )
				)
				( attribute "WATTAGE" "1/16W"
					( Origin gFrontEnd )
				)
				( attribute "XY" "(-5175,900)"
					( Origin gFrontEnd )
				)
				( attribute "CHIPS_PART_NAME" "RES"
					( Origin gPackager )
				)
				( attribute "CDS_PART_NAME" "RES_0402-4.75K,1%,1/16W,CHIP,GA"
					( Origin gPackager )
				)
				( objectStatus "R9A21" )
			)
			( gate "@baseboard_fab2_lib.baseboard_fab2(sch_1):page119_i189"
				( attribute "BOM_COST" "SM_CONTROLLER"
					( Origin gFrontEnd )
				)
				( attribute "CDS_LIB" "mstr_discrete"
					( Origin gPackager )
				)
				( attribute "CDS_LOCATION" "R7C26"
					( Origin gPackager )
				)
				( attribute "CDS_SEC" "1"
					( Origin gPackager )
				)
				( attribute "LOCATION" "R7C26"
					( Origin gFrontEnd )
				)
				( attribute "MATERIAL" "CHIP"
					( Origin gFrontEnd )
				)
				( attribute "PACK_TYPE" "0402"
					( Origin gFrontEnd )
				)
				( attribute "PART_NUMBER" "G21796-074"
					( Origin gFrontEnd )
				)
				( attribute "PHYS_PAGE" "119"
					( Origin gFrontEnd )
				)
				( attribute "ROOM" "SYS_CLOCK"
					( Origin gFrontEnd )
				)
				( attribute "ROT" "0"
					( Origin gFrontEnd )
				)
				( attribute "SEC" "1"
					( Origin gFrontEnd )
				)
				( attribute "SEC_TYPE" "0402"
					( Origin gFrontEnd )
				)
				( attribute "TOLERANCE" "1%"
					( Origin gFrontEnd )
				)
				( attribute "VALUE" "33.2"
					( Origin gFrontEnd )
				)
				( attribute "VER" "1"
					( Origin gFrontEnd )
				)
				( attribute "WATTAGE" "1/16W"
					( Origin gFrontEnd )
				)
				( attribute "XY" "(-6750,3700)"
					( Origin gFrontEnd )
				)
				( attribute "CHIPS_PART_NAME" "RES"
					( Origin gPackager )
				)
				( attribute "CDS_PART_NAME" "RES_0402-33.2,1%,1/16W,CHIP,G2A"
					( Origin gPackager )
				)
				( objectStatus "R7C26" )
			)
			( gate "@baseboard_fab2_lib.baseboard_fab2(sch_1):page119_i213"
				( attribute "CDS_LIB" "mstr_discrete"
					( Origin gPackager )
				)
				( attribute "CDS_LOCATION" "R2U48"
					( Origin gPackager )
				)
				( attribute "CDS_SEC" "1"
					( Origin gPackager )
				)
				( attribute "LOCATION" "R2U48"
					( Origin gFrontEnd )
				)
				( attribute "MATERIAL" "CHIP"
					( Origin gFrontEnd )
				)
				( attribute "PACK_TYPE" "0402"
					( Origin gFrontEnd )
				)
				( attribute "PART_NUMBER" "G21796-072"
					( Origin gFrontEnd )
				)
				( attribute "PHYS_PAGE" "119"
					( Origin gFrontEnd )
				)
				( attribute "ROT" "0"
					( Origin gFrontEnd )
				)
				( attribute "SEC" "1"
					( Origin gFrontEnd )
				)
				( attribute "SEC_TYPE" "0402"
					( Origin gFrontEnd )
				)
				( attribute "TOLERANCE" "1%"
					( Origin gFrontEnd )
				)
				( attribute "VALUE" "4.75K"
					( Origin gFrontEnd )
				)
				( attribute "VER" "2"
					( Origin gFrontEnd )
				)
				( attribute "WATTAGE" "1/16W"
					( Origin gFrontEnd )
				)
				( attribute "XY" "(-1700,4725)"
					( Origin gFrontEnd )
				)
				( attribute "CHIPS_PART_NAME" "RES"
					( Origin gPackager )
				)
				( attribute "CDS_PART_NAME" "RES_0402-4.75K,1%,1/16W,CHIP,GA"
					( Origin gPackager )
				)
				( objectStatus "R2U48" )
			)
			( gate "@baseboard_fab2_lib.baseboard_fab2(sch_1):page119_i229"
				( attribute "BOM_COST" "PROC_SIDEBAND"
					( Origin gFrontEnd )
				)
				( attribute "CDS_LIB" "mstr_discrete"
					( Origin gPackager )
				)
				( attribute "CDS_LOCATION" "R7W17"
					( Origin gPackager )
				)
				( attribute "CDS_SEC" "1"
					( Origin gPackager )
				)
				( attribute "LOCATION" "R7W17"
					( Origin gFrontEnd )
				)
				( attribute "MATERIAL" "CHIP"
					( Origin gFrontEnd )
				)
				( attribute "PACK_TYPE" "0402"
					( Origin gFrontEnd )
				)
				( attribute "PART_NUMBER" "G21497-005"
					( Origin gFrontEnd )
				)
				( attribute "PHYS_PAGE" "119"
					( Origin gFrontEnd )
				)
				( attribute "ROOM" "CPU0"
					( Origin gFrontEnd )
				)
				( attribute "ROT" "0"
					( Origin gFrontEnd )
				)
				( attribute "SEC" "1"
					( Origin gFrontEnd )
				)
				( attribute "SEC_TYPE" "0402"
					( Origin gFrontEnd )
				)
				( attribute "TOLERANCE" "5%"
					( Origin gFrontEnd )
				)
				( attribute "VALUE" "0.0"
					( Origin gFrontEnd )
				)
				( attribute "VER" "1"
					( Origin gFrontEnd )
				)
				( attribute "WATTAGE" "1/16W"
					( Origin gFrontEnd )
				)
				( attribute "XY" "(-1550,4250)"
					( Origin gFrontEnd )
				)
				( attribute "CHIPS_PART_NAME" "RES"
					( Origin gPackager )
				)
				( attribute "CDS_PART_NAME" "RES_0402-0.0,5%,1/16W,CHIP,G21A"
					( Origin gPackager )
				)
				( objectStatus "R7W17" )
			)
			( gate "@baseboard_fab2_lib.baseboard_fab2(sch_1):page120_i147"
				( attribute "BOM_COST" "SB"
					( Origin gFrontEnd )
				)
				( attribute "CDS_LIB" "mstr_u_proc"
					( Origin gPackager )
				)
				( attribute "CDS_LOCATION" "U7C1"
					( Origin gPackager )
				)
				( attribute "CDS_SEC" "7"
					( Origin gPackager )
				)
				( attribute "LOCATION" "U7C1"
					( Origin gFrontEnd )
				)
				( attribute "MATERIAL" "IC"
					( Origin gFrontEnd )
				)
				( attribute "PACK_TYPE" "BGA1"
					( Origin gFrontEnd )
				)
				( attribute "PART_NUMBER" "H91415-002"
					( Origin gFrontEnd )
				)
				( attribute "PHYS_PAGE" "120"
					( Origin gFrontEnd )
				)
				( attribute "ROOM" "SB"
					( Origin gFrontEnd )
				)
				( attribute "ROT" "0"
					( Origin gFrontEnd )
				)
				( attribute "SEC" "7"
					( Origin gFrontEnd )
				)
				( attribute "SEC_TYPE" "BGA1"
					( Origin gFrontEnd )
				)
				( attribute "VER" "7"
					( Origin gFrontEnd )
				)
				( attribute "XY" "(-3750,2800)"
					( Origin gFrontEnd )
				)
				( attribute "CHIPS_PART_NAME" "LBG_CORE_QAT_EXT_D"
					( Origin gPackager )
				)
				( attribute "CDS_PART_NAME" "LBG_CORE_QAT_EXT_D_BGA1-IC,H91A"
					( Origin gPackager )
				)
				( objectStatus "U7C1" )
			)
			( gate "@baseboard_fab2_lib.baseboard_fab2(sch_1):page120_i276"
				( attribute "BOM_COST" "PROC_SIDEBAND"
					( Origin gFrontEnd )
				)
				( attribute "CDS_LIB" "mstr_discrete"
					( Origin gPackager )
				)
				( attribute "CDS_LOCATION" "R7W16"
					( Origin gPackager )
				)
				( attribute "CDS_SEC" "1"
					( Origin gPackager )
				)
				( attribute "LOCATION" "R7W16"
					( Origin gFrontEnd )
				)
				( attribute "MATERIAL" "CHIP"
					( Origin gFrontEnd )
				)
				( attribute "PACK_TYPE" "0402"
					( Origin gFrontEnd )
				)
				( attribute "PART_NUMBER" "G21497-005"
					( Origin gFrontEnd )
				)
				( attribute "PHYS_PAGE" "120"
					( Origin gFrontEnd )
				)
				( attribute "ROOM" "CPU0"
					( Origin gFrontEnd )
				)
				( attribute "ROT" "0"
					( Origin gFrontEnd )
				)
				( attribute "SEC" "1"
					( Origin gFrontEnd )
				)
				( attribute "SEC_TYPE" "0402"
					( Origin gFrontEnd )
				)
				( attribute "TOLERANCE" "5%"
					( Origin gFrontEnd )
				)
				( attribute "VALUE" "0.0"
					( Origin gFrontEnd )
				)
				( attribute "VER" "1"
					( Origin gFrontEnd )
				)
				( attribute "WATTAGE" "1/16W"
					( Origin gFrontEnd )
				)
				( attribute "XY" "(-950,2700)"
					( Origin gFrontEnd )
				)
				( attribute "CHIPS_PART_NAME" "RES"
					( Origin gPackager )
				)
				( attribute "CDS_PART_NAME" "RES_0402-0.0,5%,1/16W,CHIP,G21A"
					( Origin gPackager )
				)
				( objectStatus "R7W16" )
			)
			( gate "@baseboard_fab2_lib.baseboard_fab2(sch_1):page120_i218"
				( attribute "CDS_LIB" "mstr_discrete"
					( Origin gPackager )
				)
				( attribute "CDS_LOCATION" "R2M1"
					( Origin gPackager )
				)
				( attribute "LOCATION" "R2M1"
					( Origin gFrontEnd )
				)
				( attribute "MATERIAL" "CHIP"
					( Origin gFrontEnd )
				)
				( attribute "PACK_TYPE" "0402"
					( Origin gFrontEnd )
				)
				( attribute "PART_NUMBER" "G21796-074"
					( Origin gFrontEnd )
				)
				( attribute "PHYS_PAGE" "120"
					( Origin gFrontEnd )
				)
				( attribute "ROOM" "CPLD"
					( Origin gFrontEnd )
				)
				( attribute "ROT" "0"
					( Origin gFrontEnd )
				)
				( attribute "SEC" "1"
					( Origin gFrontEnd )
				)
				( attribute "SEC_TYPE" "0402"
					( Origin gFrontEnd )
				)
				( attribute "TOLERANCE" "1%"
					( Origin gFrontEnd )
				)
				( attribute "VALUE" "33.2"
					( Origin gFrontEnd )
				)
				( attribute "VER" "1"
					( Origin gFrontEnd )
				)
				( attribute "WATTAGE" "1/16W"
					( Origin gFrontEnd )
				)
				( attribute "XY" "(-6650,3850)"
					( Origin gFrontEnd )
				)
				( attribute "CHIPS_PART_NAME" "RES"
					( Origin gPackager )
				)
				( attribute "CDS_PART_NAME" "RES_0402-33.2,1%,1/16W,CHIP,G2A"
					( Origin gPackager )
				)
				( attribute "CDS_SEC" "1"
					( Origin gPackager )
				)
				( objectStatus "R2M1" )
			)
			( gate "@baseboard_fab2_lib.baseboard_fab2(sch_1):page120_i219"
				( attribute "CDS_LIB" "mstr_discrete"
					( Origin gPackager )
				)
				( attribute "CDS_LOCATION" "R2N26"
					( Origin gPackager )
				)
				( attribute "CDS_SEC" "1"
					( Origin gPackager )
				)
				( attribute "LOCATION" "R2N26"
					( Origin gFrontEnd )
				)
				( attribute "MATERIAL" "CHIP"
					( Origin gFrontEnd )
				)
				( attribute "PACK_TYPE" "0402"
					( Origin gFrontEnd )
				)
				( attribute "PART_NUMBER" "G21796-074"
					( Origin gFrontEnd )
				)
				( attribute "PHYS_PAGE" "120"
					( Origin gFrontEnd )
				)
				( attribute "ROOM" "CPLD"
					( Origin gFrontEnd )
				)
				( attribute "ROT" "0"
					( Origin gFrontEnd )
				)
				( attribute "SEC" "1"
					( Origin gFrontEnd )
				)
				( attribute "SEC_TYPE" "0402"
					( Origin gFrontEnd )
				)
				( attribute "TOLERANCE" "1%"
					( Origin gFrontEnd )
				)
				( attribute "VALUE" "33.2"
					( Origin gFrontEnd )
				)
				( attribute "VER" "1"
					( Origin gFrontEnd )
				)
				( attribute "WATTAGE" "1/16W"
					( Origin gFrontEnd )
				)
				( attribute "XY" "(-6100,2050)"
					( Origin gFrontEnd )
				)
				( attribute "CHIPS_PART_NAME" "RES"
					( Origin gPackager )
				)
				( attribute "CDS_PART_NAME" "RES_0402-33.2,1%,1/16W,CHIP,G2A"
					( Origin gPackager )
				)
				( objectStatus "R2N26" )
			)
			( gate "@baseboard_fab2_lib.baseboard_fab2(sch_1):page121_i31"
				( attribute "CDS_LIB" "mstr_discrete"
					( Origin gPackager )
				)
				( attribute "CDS_LOCATION" "R7C15"
					( Origin gPackager )
				)
				( attribute "CDS_SEC" "1"
					( Origin gPackager )
				)
				( attribute "LOCATION" "R7C15"
					( Origin gFrontEnd )
				)
				( attribute "MATERIAL" "CHIP"
					( Origin gFrontEnd )
				)
				( attribute "PACK_TYPE" "0402"
					( Origin gFrontEnd )
				)
				( attribute "PART_NUMBER" "G21497-005"
					( Origin gFrontEnd )
				)
				( attribute "PHYS_PAGE" "121"
					( Origin gFrontEnd )
				)
				( attribute "ROOM" "SB"
					( Origin gFrontEnd )
				)
				( attribute "ROT" "0"
					( Origin gFrontEnd )
				)
				( attribute "SEC" "1"
					( Origin gPackager )
				)
				( attribute "TOLERANCE" "5%"
					( Origin gFrontEnd )
				)
				( attribute "VALUE" "0.0"
					( Origin gFrontEnd )
				)
				( attribute "VER" "1"
					( Origin gFrontEnd )
				)
				( attribute "WATTAGE" "1/16W"
					( Origin gFrontEnd )
				)
				( attribute "XY" "(-1925,3150)"
					( Origin gFrontEnd )
				)
				( attribute "CHIPS_PART_NAME" "RES"
					( Origin gPackager )
				)
				( attribute "CDS_PART_NAME" "RES_0402-0.0,5%,1/16W,CHIP,G21A"
					( Origin gPackager )
				)
				( objectStatus "R7C15" )
			)
			( gate "@baseboard_fab2_lib.baseboard_fab2(sch_1):page121_i33"
				( attribute "CDS_LIB" "mstr_discrete"
					( Origin gPackager )
				)
				( attribute "CDS_LOCATION" "R7C16"
					( Origin gPackager )
				)
				( attribute "CDS_SEC" "1"
					( Origin gPackager )
				)
				( attribute "LOCATION" "R7C16"
					( Origin gFrontEnd )
				)
				( attribute "MATERIAL" "CHIP"
					( Origin gFrontEnd )
				)
				( attribute "PACK_TYPE" "0402"
					( Origin gFrontEnd )
				)
				( attribute "PART_NUMBER" "G21796-074"
					( Origin gFrontEnd )
				)
				( attribute "PHYS_PAGE" "121"
					( Origin gFrontEnd )
				)
				( attribute "ROOM" "SB"
					( Origin gFrontEnd )
				)
				( attribute "ROT" "0"
					( Origin gFrontEnd )
				)
				( attribute "SEC" "1"
					( Origin gPackager )
				)
				( attribute "TOLERANCE" "1%"
					( Origin gFrontEnd )
				)
				( attribute "VALUE" "33.2"
					( Origin gFrontEnd )
				)
				( attribute "VER" "1"
					( Origin gFrontEnd )
				)
				( attribute "WATTAGE" "1/16W"
					( Origin gFrontEnd )
				)
				( attribute "XY" "(-1950,3550)"
					( Origin gFrontEnd )
				)
				( attribute "CHIPS_PART_NAME" "RES"
					( Origin gPackager )
				)
				( attribute "CDS_PART_NAME" "RES_0402-33.2,1%,1/16W,CHIP,G2A"
					( Origin gPackager )
				)
				( objectStatus "R7C16" )
			)
			( gate "@baseboard_fab2_lib.baseboard_fab2(sch_1):page121_i34"
				( attribute "BOM_COST" "SB"
					( Origin gFrontEnd )
				)
				( attribute "CDS_LIB" "mstr_u_proc"
					( Origin gPackager )
				)
				( attribute "CDS_LOCATION" "U7C1"
					( Origin gPackager )
				)
				( attribute "CDS_SEC" "8"
					( Origin gPackager )
				)
				( attribute "LOCATION" "U7C1"
					( Origin gFrontEnd )
				)
				( attribute "MATERIAL" "IC"
					( Origin gFrontEnd )
				)
				( attribute "PACK_TYPE" "BGA1"
					( Origin gFrontEnd )
				)
				( attribute "PART_NUMBER" "H91415-002"
					( Origin gFrontEnd )
				)
				( attribute "PHYS_PAGE" "121"
					( Origin gFrontEnd )
				)
				( attribute "ROOM" "SB"
					( Origin gFrontEnd )
				)
				( attribute "ROT" "0"
					( Origin gFrontEnd )
				)
				( attribute "SEC" "8"
					( Origin gFrontEnd )
				)
				( attribute "SEC_TYPE" "BGA1"
					( Origin gFrontEnd )
				)
				( attribute "VER" "8"
					( Origin gFrontEnd )
				)
				( attribute "XY" "(-4050,2800)"
					( Origin gFrontEnd )
				)
				( attribute "CHIPS_PART_NAME" "LBG_CORE_QAT_EXT_D"
					( Origin gPackager )
				)
				( attribute "CDS_PART_NAME" "LBG_CORE_QAT_EXT_D_BGA1-IC,H91A"
					( Origin gPackager )
				)
				( objectStatus "U7C1" )
			)
			( gate "@baseboard_fab2_lib.baseboard_fab2(sch_1):page121_i35"
				( attribute "CDS_LIB" "mstr_discrete"
					( Origin gPackager )
				)
				( attribute "CDS_LOCATION" "R8C26"
					( Origin gPackager )
				)
				( attribute "CDS_SEC" "1"
					( Origin gPackager )
				)
				( attribute "LOCATION" "R8C26"
					( Origin gFrontEnd )
				)
				( attribute "MATERIAL" "CHIP"
					( Origin gFrontEnd )
				)
				( attribute "PACK_TYPE" "0402"
					( Origin gFrontEnd )
				)
				( attribute "PART_NUMBER" "G21796-017"
					( Origin gFrontEnd )
				)
				( attribute "PHYS_PAGE" "121"
					( Origin gFrontEnd )
				)
				( attribute "ROOM" "SB"
					( Origin gFrontEnd )
				)
				( attribute "ROT" "0"
					( Origin gFrontEnd )
				)
				( attribute "SEC" "1"
					( Origin gFrontEnd )
				)
				( attribute "SEC_TYPE" "0402"
					( Origin gFrontEnd )
				)
				( attribute "TOLERANCE" "1%"
					( Origin gFrontEnd )
				)
				( attribute "VALUE" "100.0"
					( Origin gFrontEnd )
				)
				( attribute "VER" "2"
					( Origin gFrontEnd )
				)
				( attribute "WATTAGE" "1/16W"
					( Origin gFrontEnd )
				)
				( attribute "XY" "(-7750,3675)"
					( Origin gFrontEnd )
				)
				( attribute "CHIPS_PART_NAME" "RES"
					( Origin gPackager )
				)
				( attribute "CDS_PART_NAME" "RES_0402-100.0,1%,1/16W,CHIP,GA"
					( Origin gPackager )
				)
				( objectStatus "R8C26" )
			)
			( gate "@baseboard_fab2_lib.baseboard_fab2(sch_1):page121_i37"
				( attribute "CDS_LIB" "mstr_discrete"
					( Origin gPackager )
				)
				( attribute "CDS_LOCATION" "R3N10"
					( Origin gPackager )
				)
				( attribute "CDS_SEC" "1"
					( Origin gPackager )
				)
				( attribute "LOCATION" "R3N10"
					( Origin gFrontEnd )
				)
				( attribute "MATERIAL" "CHIP"
					( Origin gFrontEnd )
				)
				( attribute "PACK_TYPE" "0402"
					( Origin gFrontEnd )
				)
				( attribute "PART_NUMBER" "G21796-016"
					( Origin gFrontEnd )
				)
				( attribute "PHYS_PAGE" "121"
					( Origin gFrontEnd )
				)
				( attribute "ROOM" "SB"
					( Origin gFrontEnd )
				)
				( attribute "ROT" "0"
					( Origin gFrontEnd )
				)
				( attribute "SEC" "1"
					( Origin gFrontEnd )
				)
				( attribute "SEC_TYPE" "0402"
					( Origin gFrontEnd )
				)
				( attribute "TOLERANCE" "1%"
					( Origin gFrontEnd )
				)
				( attribute "VALUE" "10.0K"
					( Origin gFrontEnd )
				)
				( attribute "VER" "2"
					( Origin gFrontEnd )
				)
				( attribute "WATTAGE" "1/16W"
					( Origin gFrontEnd )
				)
				( attribute "XY" "(-8075,2525)"
					( Origin gFrontEnd )
				)
				( attribute "CHIPS_PART_NAME" "RES"
					( Origin gPackager )
				)
				( attribute "CDS_PART_NAME" "RES_0402-10.0K,1%,1/16W,CHIP,GA"
					( Origin gPackager )
				)
				( objectStatus "R3N10" )
			)
			( gate "@baseboard_fab2_lib.baseboard_fab2(sch_1):page121_i73"
				( attribute "BOM_COST" "NT_GBE_BASE"
					( Origin gFrontEnd )
				)
				( attribute "CDS_LIB" "mstr_discrete"
					( Origin gPackager )
				)
				( attribute "CDS_LOCATION" "R7C20"
					( Origin gPackager )
				)
				( attribute "CDS_SEC" "1"
					( Origin gPackager )
				)
				( attribute "LOCATION" "R7C20"
					( Origin gFrontEnd )
				)
				( attribute "MATERIAL" "CHIP"
					( Origin gFrontEnd )
				)
				( attribute "PACK_TYPE" "0402"
					( Origin gFrontEnd )
				)
				( attribute "PART_NUMBER" "G21796-016"
					( Origin gFrontEnd )
				)
				( attribute "PHYS_PAGE" "121"
					( Origin gFrontEnd )
				)
				( attribute "ROOM" "NIC_SPRV"
					( Origin gFrontEnd )
				)
				( attribute "ROT" "0"
					( Origin gFrontEnd )
				)
				( attribute "SEC" "1"
					( Origin gFrontEnd )
				)
				( attribute "SEC_TYPE" "0402"
					( Origin gFrontEnd )
				)
				( attribute "TOLERANCE" "1%"
					( Origin gFrontEnd )
				)
				( attribute "VALUE" "10.0K"
					( Origin gFrontEnd )
				)
				( attribute "VER" "2"
					( Origin gFrontEnd )
				)
				( attribute "WATTAGE" "1/16W"
					( Origin gFrontEnd )
				)
				( attribute "XY" "(-8125,950)"
					( Origin gFrontEnd )
				)
				( attribute "CHIPS_PART_NAME" "RES"
					( Origin gPackager )
				)
				( attribute "CDS_PART_NAME" "RES_0402-10.0K,1%,1/16W,CHIP,GA"
					( Origin gPackager )
				)
				( objectStatus "R7C20" )
			)
			( gate "@baseboard_fab2_lib.baseboard_fab2(sch_1):page121_i89"
				( attribute "CDS_LIB" "mstr_discrete"
					( Origin gPackager )
				)
				( attribute "CDS_LOCATION" "R3P3"
					( Origin gPackager )
				)
				( attribute "CDS_SEC" "1"
					( Origin gPackager )
				)
				( attribute "LOCATION" "R3P3"
					( Origin gFrontEnd )
				)
				( attribute "MATERIAL" "CHIP"
					( Origin gFrontEnd )
				)
				( attribute "PACK_TYPE" "0402"
					( Origin gFrontEnd )
				)
				( attribute "PART_NUMBER" "G21497-005"
					( Origin gFrontEnd )
				)
				( attribute "PHYS_PAGE" "121"
					( Origin gFrontEnd )
				)
				( attribute "ROT" "0"
					( Origin gFrontEnd )
				)
				( attribute "SEC" "1"
					( Origin gFrontEnd )
				)
				( attribute "SEC_TYPE" "0402"
					( Origin gFrontEnd )
				)
				( attribute "TOLERANCE" "5%"
					( Origin gFrontEnd )
				)
				( attribute "VALUE" "0.0"
					( Origin gFrontEnd )
				)
				( attribute "VER" "1"
					( Origin gFrontEnd )
				)
				( attribute "WATTAGE" "1/16W"
					( Origin gFrontEnd )
				)
				( attribute "XY" "(-5100,550)"
					( Origin gFrontEnd )
				)
				( attribute "CHIPS_PART_NAME" "RES"
					( Origin gPackager )
				)
				( attribute "CDS_PART_NAME" "RES_0402-0.0,5%,1/16W,CHIP,G21A"
					( Origin gPackager )
				)
				( objectStatus "R3P3" )
			)
			( gate "@baseboard_fab2_lib.baseboard_fab2(sch_1):page121_i90"
				( attribute "CDS_LIB" "mstr_discrete"
					( Origin gPackager )
				)
				( attribute "CDS_LOCATION" "R3P2"
					( Origin gPackager )
				)
				( attribute "CDS_SEC" "1"
					( Origin gPackager )
				)
				( attribute "LOCATION" "R3P2"
					( Origin gFrontEnd )
				)
				( attribute "MATERIAL" "CHIP"
					( Origin gFrontEnd )
				)
				( attribute "PACK_TYPE" "0402"
					( Origin gFrontEnd )
				)
				( attribute "PART_NUMBER" "G21497-005"
					( Origin gFrontEnd )
				)
				( attribute "PHYS_PAGE" "121"
					( Origin gFrontEnd )
				)
				( attribute "ROT" "0"
					( Origin gFrontEnd )
				)
				( attribute "SEC" "1"
					( Origin gFrontEnd )
				)
				( attribute "SEC_TYPE" "0402"
					( Origin gFrontEnd )
				)
				( attribute "TOLERANCE" "5%"
					( Origin gFrontEnd )
				)
				( attribute "VALUE" "0.0"
					( Origin gFrontEnd )
				)
				( attribute "VER" "1"
					( Origin gFrontEnd )
				)
				( attribute "WATTAGE" "1/16W"
					( Origin gFrontEnd )
				)
				( attribute "XY" "(-5100,850)"
					( Origin gFrontEnd )
				)
				( attribute "CHIPS_PART_NAME" "RES"
					( Origin gPackager )
				)
				( attribute "CDS_PART_NAME" "RES_0402-0.0,5%,1/16W,CHIP,G21A"
					( Origin gPackager )
				)
				( objectStatus "R3P2" )
			)
			( gate "@baseboard_fab2_lib.baseboard_fab2(sch_1):page121_i91"
				( attribute "CDS_LIB" "mstr_discrete"
					( Origin gPackager )
				)
				( attribute "CDS_LOCATION" "R2P1"
					( Origin gPackager )
				)
				( attribute "CDS_SEC" "1"
					( Origin gPackager )
				)
				( attribute "LOCATION" "R2P1"
					( Origin gFrontEnd )
				)
				( attribute "MATERIAL" "CHIP"
					( Origin gFrontEnd )
				)
				( attribute "PACK_TYPE" "0402"
					( Origin gFrontEnd )
				)
				( attribute "PART_NUMBER" "G21497-005"
					( Origin gFrontEnd )
				)
				( attribute "PHYS_PAGE" "121"
					( Origin gFrontEnd )
				)
				( attribute "ROT" "0"
					( Origin gFrontEnd )
				)
				( attribute "SEC" "1"
					( Origin gFrontEnd )
				)
				( attribute "SEC_TYPE" "0402"
					( Origin gFrontEnd )
				)
				( attribute "TOLERANCE" "5%"
					( Origin gFrontEnd )
				)
				( attribute "VALUE" "0.0"
					( Origin gFrontEnd )
				)
				( attribute "VER" "1"
					( Origin gFrontEnd )
				)
				( attribute "WATTAGE" "1/16W"
					( Origin gFrontEnd )
				)
				( attribute "XY" "(-5100,700)"
					( Origin gFrontEnd )
				)
				( attribute "CHIPS_PART_NAME" "RES"
					( Origin gPackager )
				)
				( attribute "CDS_PART_NAME" "RES_0402-0.0,5%,1/16W,CHIP,G21A"
					( Origin gPackager )
				)
				( objectStatus "R2P1" )
			)
			( gate "@baseboard_fab2_lib.baseboard_fab2(sch_1):page121_i98"
				( attribute "CDS_LIB" "mstr_discrete"
					( Origin gPackager )
				)
				( attribute "CDS_LOCATION" "R7C14"
					( Origin gPackager )
				)
				( attribute "CDS_SEC" "1"
					( Origin gPackager )
				)
				( attribute "LOCATION" "R7C14"
					( Origin gFrontEnd )
				)
				( attribute "MATERIAL" "CHIP"
					( Origin gFrontEnd )
				)
				( attribute "PACK_TYPE" "0402"
					( Origin gFrontEnd )
				)
				( attribute "PART_NUMBER" "G21796-074"
					( Origin gFrontEnd )
				)
				( attribute "PHYS_PAGE" "121"
					( Origin gFrontEnd )
				)
				( attribute "ROOM" "SB"
					( Origin gFrontEnd )
				)
				( attribute "ROT" "0"
					( Origin gFrontEnd )
				)
				( attribute "SEC" "1"
					( Origin gFrontEnd )
				)
				( attribute "SEC_TYPE" "0402"
					( Origin gFrontEnd )
				)
				( attribute "TOLERANCE" "1%"
					( Origin gFrontEnd )
				)
				( attribute "VALUE" "33.2"
					( Origin gFrontEnd )
				)
				( attribute "VER" "1"
					( Origin gFrontEnd )
				)
				( attribute "WATTAGE" "1/16W"
					( Origin gFrontEnd )
				)
				( attribute "XY" "(-5100,1025)"
					( Origin gFrontEnd )
				)
				( attribute "CHIPS_PART_NAME" "RES"
					( Origin gPackager )
				)
				( attribute "CDS_PART_NAME" "RES_0402-33.2,1%,1/16W,CHIP,G2A"
					( Origin gPackager )
				)
				( objectStatus "R7C14" )
			)
			( gate "@baseboard_fab2_lib.baseboard_fab2(sch_1):page121_i101"
				( attribute "CDS_LIB" "mstr_discrete"
					( Origin gPackager )
				)
				( attribute "CDS_LOCATION" "R8D11"
					( Origin gPackager )
				)
				( attribute "CDS_SEC" "1"
					( Origin gPackager )
				)
				( attribute "LOCATION" "R8D11"
					( Origin gFrontEnd )
				)
				( attribute "MATERIAL" "CHIP"
					( Origin gFrontEnd )
				)
				( attribute "PACK_TYPE" "0402"
					( Origin gFrontEnd )
				)
				( attribute "PART_NUMBER" "G21796-074"
					( Origin gFrontEnd )
				)
				( attribute "PHYS_PAGE" "121"
					( Origin gFrontEnd )
				)
				( attribute "ROOM" "SB"
					( Origin gFrontEnd )
				)
				( attribute "ROT" "0"
					( Origin gFrontEnd )
				)
				( attribute "SEC" "1"
					( Origin gFrontEnd )
				)
				( attribute "SEC_TYPE" "0402"
					( Origin gFrontEnd )
				)
				( attribute "TOLERANCE" "1%"
					( Origin gFrontEnd )
				)
				( attribute "VALUE" "33.2"
					( Origin gFrontEnd )
				)
				( attribute "VER" "1"
					( Origin gFrontEnd )
				)
				( attribute "WATTAGE" "1/16W"
					( Origin gFrontEnd )
				)
				( attribute "XY" "(-5100,1175)"
					( Origin gFrontEnd )
				)
				( attribute "CHIPS_PART_NAME" "RES"
					( Origin gPackager )
				)
				( attribute "CDS_PART_NAME" "RES_0402-33.2,1%,1/16W,CHIP,G2A"
					( Origin gPackager )
				)
				( objectStatus "R8D11" )
			)
			( gate "@baseboard_fab2_lib.baseboard_fab2(sch_1):page122_i63"
				( attribute "BOM_COST" "SB"
					( Origin gFrontEnd )
				)
				( attribute "CDS_LIB" "mstr_u_proc"
					( Origin gPackager )
				)
				( attribute "CDS_LOCATION" "U7C1"
					( Origin gPackager )
				)
				( attribute "CDS_SEC" "9"
					( Origin gPackager )
				)
				( attribute "LOCATION" "U7C1"
					( Origin gFrontEnd )
				)
				( attribute "MATERIAL" "IC"
					( Origin gFrontEnd )
				)
				( attribute "PACK_TYPE" "BGA1"
					( Origin gFrontEnd )
				)
				( attribute "PART_NUMBER" "H91415-002"
					( Origin gFrontEnd )
				)
				( attribute "PHYS_PAGE" "122"
					( Origin gFrontEnd )
				)
				( attribute "ROOM" "SB"
					( Origin gFrontEnd )
				)
				( attribute "ROT" "0"
					( Origin gFrontEnd )
				)
				( attribute "SEC" "9"
					( Origin gFrontEnd )
				)
				( attribute "SEC_TYPE" "BGA1"
					( Origin gFrontEnd )
				)
				( attribute "VER" "9"
					( Origin gFrontEnd )
				)
				( attribute "XY" "(-3900,3075)"
					( Origin gFrontEnd )
				)
				( attribute "CHIPS_PART_NAME" "LBG_CORE_QAT_EXT_D"
					( Origin gPackager )
				)
				( attribute "CDS_PART_NAME" "LBG_CORE_QAT_EXT_D_BGA1-IC,H91A"
					( Origin gPackager )
				)
				( objectStatus "U7C1" )
			)
			( gate "@baseboard_fab2_lib.baseboard_fab2(sch_1):page123_i13"
				( attribute "BOM_COST" "SB"
					( Origin gFrontEnd )
				)
				( attribute "CDS_LIB" "mstr_u_proc"
					( Origin gPackager )
				)
				( attribute "CDS_LOCATION" "U7C1"
					( Origin gPackager )
				)
				( attribute "CDS_SEC" "11"
					( Origin gPackager )
				)
				( attribute "LOCATION" "U7C1"
					( Origin gFrontEnd )
				)
				( attribute "MATERIAL" "IC"
					( Origin gFrontEnd )
				)
				( attribute "PACK_TYPE" "BGA1"
					( Origin gFrontEnd )
				)
				( attribute "PART_NUMBER" "H91415-002"
					( Origin gFrontEnd )
				)
				( attribute "PHYS_PAGE" "123"
					( Origin gFrontEnd )
				)
				( attribute "ROOM" "SB"
					( Origin gFrontEnd )
				)
				( attribute "ROT" "0"
					( Origin gFrontEnd )
				)
				( attribute "SEC" "11"
					( Origin gFrontEnd )
				)
				( attribute "SEC_TYPE" "BGA1"
					( Origin gFrontEnd )
				)
				( attribute "VER" "11"
					( Origin gFrontEnd )
				)
				( attribute "XY" "(-1625,2575)"
					( Origin gFrontEnd )
				)
				( attribute "CHIPS_PART_NAME" "LBG_CORE_QAT_EXT_D"
					( Origin gPackager )
				)
				( attribute "CDS_PART_NAME" "LBG_CORE_QAT_EXT_D_BGA1-IC,H91A"
					( Origin gPackager )
				)
				( objectStatus "U7C1" )
			)
			( gate "@baseboard_fab2_lib.baseboard_fab2(sch_1):page123_i21"
				( attribute "BOM_COST" "SB"
					( Origin gFrontEnd )
				)
				( attribute "CDS_LIB" "mstr_u_proc"
					( Origin gPackager )
				)
				( attribute "CDS_LOCATION" "U7C1"
					( Origin gPackager )
				)
				( attribute "CDS_SEC" "10"
					( Origin gPackager )
				)
				( attribute "LOCATION" "U7C1"
					( Origin gFrontEnd )
				)
				( attribute "MATERIAL" "IC"
					( Origin gFrontEnd )
				)
				( attribute "PACK_TYPE" "BGA1"
					( Origin gFrontEnd )
				)
				( attribute "PART_NUMBER" "H91415-002"
					( Origin gFrontEnd )
				)
				( attribute "PHYS_PAGE" "123"
					( Origin gFrontEnd )
				)
				( attribute "ROOM" "SB"
					( Origin gFrontEnd )
				)
				( attribute "ROT" "0"
					( Origin gFrontEnd )
				)
				( attribute "SEC" "10"
					( Origin gFrontEnd )
				)
				( attribute "SEC_TYPE" "BGA1"
					( Origin gFrontEnd )
				)
				( attribute "VER" "10"
					( Origin gFrontEnd )
				)
				( attribute "XY" "(-5375,2600)"
					( Origin gFrontEnd )
				)
				( attribute "CHIPS_PART_NAME" "LBG_CORE_QAT_EXT_D"
					( Origin gPackager )
				)
				( attribute "CDS_PART_NAME" "LBG_CORE_QAT_EXT_D_BGA1-IC,H91A"
					( Origin gPackager )
				)
				( objectStatus "U7C1" )
			)
			( gate "@baseboard_fab2_lib.baseboard_fab2(sch_1):page124_i15"
				( attribute "BOM_COST" "SB"
					( Origin gFrontEnd )
				)
				( attribute "CDS_LIB" "mstr_u_proc"
					( Origin gPackager )
				)
				( attribute "CDS_LOCATION" "U7C1"
					( Origin gPackager )
				)
				( attribute "CDS_SEC" "14"
					( Origin gPackager )
				)
				( attribute "LOCATION" "U7C1"
					( Origin gFrontEnd )
				)
				( attribute "MATERIAL" "IC"
					( Origin gFrontEnd )
				)
				( attribute "PACK_TYPE" "BGA1"
					( Origin gFrontEnd )
				)
				( attribute "PART_NUMBER" "H91415-002"
					( Origin gFrontEnd )
				)
				( attribute "PHYS_PAGE" "124"
					( Origin gFrontEnd )
				)
				( attribute "ROOM" "SB"
					( Origin gFrontEnd )
				)
				( attribute "ROT" "0"
					( Origin gFrontEnd )
				)
				( attribute "SEC" "14"
					( Origin gFrontEnd )
				)
				( attribute "SEC_TYPE" "BGA1"
					( Origin gFrontEnd )
				)
				( attribute "VER" "14"
					( Origin gFrontEnd )
				)
				( attribute "XY" "(1200,2700)"
					( Origin gFrontEnd )
				)
				( attribute "CHIPS_PART_NAME" "LBG_CORE_QAT_EXT_D"
					( Origin gPackager )
				)
				( attribute "CDS_PART_NAME" "LBG_CORE_QAT_EXT_D_BGA1-IC,H91A"
					( Origin gPackager )
				)
				( objectStatus "U7C1" )
			)
			( gate "@baseboard_fab2_lib.baseboard_fab2(sch_1):page124_i16"
				( attribute "BOM_COST" "SB"
					( Origin gFrontEnd )
				)
				( attribute "CDS_LIB" "mstr_u_proc"
					( Origin gPackager )
				)
				( attribute "CDS_LOCATION" "U7C1"
					( Origin gPackager )
				)
				( attribute "CDS_SEC" "13"
					( Origin gPackager )
				)
				( attribute "LOCATION" "U7C1"
					( Origin gFrontEnd )
				)
				( attribute "MATERIAL" "IC"
					( Origin gFrontEnd )
				)
				( attribute "PACK_TYPE" "BGA1"
					( Origin gFrontEnd )
				)
				( attribute "PART_NUMBER" "H91415-002"
					( Origin gFrontEnd )
				)
				( attribute "PHYS_PAGE" "124"
					( Origin gFrontEnd )
				)
				( attribute "ROOM" "SB"
					( Origin gFrontEnd )
				)
				( attribute "ROT" "0"
					( Origin gFrontEnd )
				)
				( attribute "SEC" "13"
					( Origin gFrontEnd )
				)
				( attribute "SEC_TYPE" "BGA1"
					( Origin gFrontEnd )
				)
				( attribute "VER" "13"
					( Origin gFrontEnd )
				)
				( attribute "XY" "(-1475,2725)"
					( Origin gFrontEnd )
				)
				( attribute "CHIPS_PART_NAME" "LBG_CORE_QAT_EXT_D"
					( Origin gPackager )
				)
				( attribute "CDS_PART_NAME" "LBG_CORE_QAT_EXT_D_BGA1-IC,H91A"
					( Origin gPackager )
				)
				( objectStatus "U7C1" )
			)
			( gate "@baseboard_fab2_lib.baseboard_fab2(sch_1):page124_i17"
				( attribute "BOM_COST" "SB"
					( Origin gFrontEnd )
				)
				( attribute "CDS_LIB" "mstr_u_proc"
					( Origin gPackager )
				)
				( attribute "CDS_LOCATION" "U7C1"
					( Origin gPackager )
				)
				( attribute "CDS_SEC" "12"
					( Origin gPackager )
				)
				( attribute "LOCATION" "U7C1"
					( Origin gFrontEnd )
				)
				( attribute "MATERIAL" "IC"
					( Origin gFrontEnd )
				)
				( attribute "PACK_TYPE" "BGA1"
					( Origin gFrontEnd )
				)
				( attribute "PART_NUMBER" "H91415-002"
					( Origin gFrontEnd )
				)
				( attribute "PHYS_PAGE" "124"
					( Origin gFrontEnd )
				)
				( attribute "ROOM" "SB"
					( Origin gFrontEnd )
				)
				( attribute "ROT" "0"
					( Origin gFrontEnd )
				)
				( attribute "SEC" "12"
					( Origin gFrontEnd )
				)
				( attribute "SEC_TYPE" "BGA1"
					( Origin gFrontEnd )
				)
				( attribute "VER" "12"
					( Origin gFrontEnd )
				)
				( attribute "XY" "(-4000,2700)"
					( Origin gFrontEnd )
				)
				( attribute "CHIPS_PART_NAME" "LBG_CORE_QAT_EXT_D"
					( Origin gPackager )
				)
				( attribute "CDS_PART_NAME" "LBG_CORE_QAT_EXT_D_BGA1-IC,H91A"
					( Origin gPackager )
				)
				( objectStatus "U7C1" )
			)
			( gate "@baseboard_fab2_lib.baseboard_fab2(sch_1):page125_i11"
				( attribute "BOM_COST" "SB"
					( Origin gFrontEnd )
				)
				( attribute "CDS_LIB" "mstr_discrete"
					( Origin gPackager )
				)
				( attribute "CDS_LOCATION" "R2R11"
					( Origin gPackager )
				)
				( attribute "CDS_SEC" "1"
					( Origin gPackager )
				)
				( attribute "LOCATION" "R2R11"
					( Origin gFrontEnd )
				)
				( attribute "MATERIAL" "EMPTY"
					( Origin gFrontEnd )
				)
				( attribute "PACK_TYPE" "0402"
					( Origin gFrontEnd )
				)
				( attribute "PART_NUMBER" "G21796-026"
					( Origin gFrontEnd )
				)
				( attribute "PHYS_PAGE" "125"
					( Origin gFrontEnd )
				)
				( attribute "ROOM" "SB"
					( Origin gFrontEnd )
				)
				( attribute "ROT" "0"
					( Origin gFrontEnd )
				)
				( attribute "SEC" "1"
					( Origin gPackager )
				)
				( attribute "TOLERANCE" "1%"
					( Origin gFrontEnd )
				)
				( attribute "VALUE" "1.00K"
					( Origin gFrontEnd )
				)
				( attribute "VER" "2"
					( Origin gFrontEnd )
				)
				( attribute "WATTAGE" "1/16W"
					( Origin gFrontEnd )
				)
				( attribute "XY" "(1750,3050)"
					( Origin gFrontEnd )
				)
				( attribute "CHIPS_PART_NAME" "RES"
					( Origin gPackager )
				)
				( attribute "CDS_PART_NAME" "RES_0402-1.00K,1%,1/16W,EMPTY,A"
					( Origin gPackager )
				)
				( objectStatus "R2R11" )
			)
			( gate "@baseboard_fab2_lib.baseboard_fab2(sch_1):page125_i21"
				( attribute "BOM_COST" "SB"
					( Origin gFrontEnd )
				)
				( attribute "CDS_LIB" "mstr_discrete"
					( Origin gPackager )
				)
				( attribute "CDS_LOCATION" "R8E6"
					( Origin gPackager )
				)
				( attribute "CDS_SEC" "1"
					( Origin gPackager )
				)
				( attribute "LOCATION" "R8E6"
					( Origin gFrontEnd )
				)
				( attribute "MATERIAL" "EMPTY"
					( Origin gFrontEnd )
				)
				( attribute "PACK_TYPE" "0402"
					( Origin gFrontEnd )
				)
				( attribute "PART_NUMBER" "G21796-026"
					( Origin gFrontEnd )
				)
				( attribute "PHYS_PAGE" "125"
					( Origin gFrontEnd )
				)
				( attribute "ROOM" "SB"
					( Origin gFrontEnd )
				)
				( attribute "ROT" "0"
					( Origin gFrontEnd )
				)
				( attribute "SEC" "1"
					( Origin gFrontEnd )
				)
				( attribute "SEC_TYPE" "0402"
					( Origin gFrontEnd )
				)
				( attribute "TOLERANCE" "1%"
					( Origin gFrontEnd )
				)
				( attribute "VALUE" "1.00K"
					( Origin gFrontEnd )
				)
				( attribute "VER" "2"
					( Origin gFrontEnd )
				)
				( attribute "WATTAGE" "1/16W"
					( Origin gFrontEnd )
				)
				( attribute "XY" "(-950,3150)"
					( Origin gFrontEnd )
				)
				( attribute "CHIPS_PART_NAME" "RES"
					( Origin gPackager )
				)
				( attribute "CDS_PART_NAME" "RES_0402-1.00K,1%,1/16W,EMPTY,A"
					( Origin gPackager )
				)
				( objectStatus "R8E6" )
			)
			( gate "@baseboard_fab2_lib.baseboard_fab2(sch_1):page125_i24"
				( attribute "BOM_COST" "SB"
					( Origin gFrontEnd )
				)
				( attribute "CDS_LIB" "mstr_discrete"
					( Origin gPackager )
				)
				( attribute "CDS_LOCATION" "R8E4"
					( Origin gPackager )
				)
				( attribute "CDS_SEC" "1"
					( Origin gPackager )
				)
				( attribute "LOCATION" "R8E4"
					( Origin gFrontEnd )
				)
				( attribute "MATERIAL" "EMPTY"
					( Origin gFrontEnd )
				)
				( attribute "PACK_TYPE" "0402"
					( Origin gFrontEnd )
				)
				( attribute "PART_NUMBER" "G21796-026"
					( Origin gFrontEnd )
				)
				( attribute "PHYS_PAGE" "125"
					( Origin gFrontEnd )
				)
				( attribute "ROOM" "SB"
					( Origin gFrontEnd )
				)
				( attribute "ROT" "0"
					( Origin gFrontEnd )
				)
				( attribute "SEC" "1"
					( Origin gPackager )
				)
				( attribute "TOLERANCE" "1%"
					( Origin gFrontEnd )
				)
				( attribute "VALUE" "1.00K"
					( Origin gFrontEnd )
				)
				( attribute "VER" "2"
					( Origin gFrontEnd )
				)
				( attribute "WATTAGE" "1/16W"
					( Origin gFrontEnd )
				)
				( attribute "XY" "(-950,2750)"
					( Origin gFrontEnd )
				)
				( attribute "CHIPS_PART_NAME" "RES"
					( Origin gPackager )
				)
				( attribute "CDS_PART_NAME" "RES_0402-1.00K,1%,1/16W,EMPTY,A"
					( Origin gPackager )
				)
				( objectStatus "R8E4" )
			)
			( gate "@baseboard_fab2_lib.baseboard_fab2(sch_1):page125_i40"
				( attribute "BOM_COST" "SB"
					( Origin gFrontEnd )
				)
				( attribute "CDS_LIB" "mstr_discrete"
					( Origin gPackager )
				)
				( attribute "CDS_LOCATION" "R8C18"
					( Origin gPackager )
				)
				( attribute "CDS_SEC" "1"
					( Origin gPackager )
				)
				( attribute "LOCATION" "R8C18"
					( Origin gFrontEnd )
				)
				( attribute "MATERIAL" "CHIP"
					( Origin gFrontEnd )
				)
				( attribute "PACK_TYPE" "0402"
					( Origin gFrontEnd )
				)
				( attribute "PART_NUMBER" "G21796-026"
					( Origin gFrontEnd )
				)
				( attribute "PHYS_PAGE" "125"
					( Origin gFrontEnd )
				)
				( attribute "ROOM" "SB"
					( Origin gFrontEnd )
				)
				( attribute "ROT" "0"
					( Origin gFrontEnd )
				)
				( attribute "SEC" "1"
					( Origin gPackager )
				)
				( attribute "TOLERANCE" "1%"
					( Origin gFrontEnd )
				)
				( attribute "VALUE" "1.00K"
					( Origin gFrontEnd )
				)
				( attribute "VER" "2"
					( Origin gFrontEnd )
				)
				( attribute "WATTAGE" "1/16W"
					( Origin gFrontEnd )
				)
				( attribute "XY" "(-3225,2525)"
					( Origin gFrontEnd )
				)
				( attribute "CHIPS_PART_NAME" "RES"
					( Origin gPackager )
				)
				( attribute "CDS_PART_NAME" "RES_0402-1.00K,1%,1/16W,CHIP,GA"
					( Origin gPackager )
				)
				( objectStatus "R8C18" )
			)
			( gate "@baseboard_fab2_lib.baseboard_fab2(sch_1):page125_i41"
				( attribute "BOM_COST" "SB"
					( Origin gFrontEnd )
				)
				( attribute "CDS_LIB" "mstr_discrete"
					( Origin gPackager )
				)
				( attribute "CDS_LOCATION" "R8C17"
					( Origin gPackager )
				)
				( attribute "CDS_SEC" "1"
					( Origin gPackager )
				)
				( attribute "LOCATION" "R8C17"
					( Origin gFrontEnd )
				)
				( attribute "MATERIAL" "EMPTY"
					( Origin gFrontEnd )
				)
				( attribute "PACK_TYPE" "0402"
					( Origin gFrontEnd )
				)
				( attribute "PART_NUMBER" "G21796-026"
					( Origin gFrontEnd )
				)
				( attribute "PHYS_PAGE" "125"
					( Origin gFrontEnd )
				)
				( attribute "ROOM" "SB"
					( Origin gFrontEnd )
				)
				( attribute "ROT" "0"
					( Origin gFrontEnd )
				)
				( attribute "SEC" "1"
					( Origin gFrontEnd )
				)
				( attribute "SEC_TYPE" "0402"
					( Origin gFrontEnd )
				)
				( attribute "TOLERANCE" "1%"
					( Origin gFrontEnd )
				)
				( attribute "VALUE" "1.00K"
					( Origin gFrontEnd )
				)
				( attribute "VER" "2"
					( Origin gFrontEnd )
				)
				( attribute "WATTAGE" "1/16W"
					( Origin gFrontEnd )
				)
				( attribute "XY" "(-3225,2200)"
					( Origin gFrontEnd )
				)
				( attribute "CHIPS_PART_NAME" "RES"
					( Origin gPackager )
				)
				( attribute "CDS_PART_NAME" "RES_0402-1.00K,1%,1/16W,EMPTY,A"
					( Origin gPackager )
				)
				( objectStatus "R8C17" )
			)
			( gate "@baseboard_fab2_lib.baseboard_fab2(sch_1):page125_i50"
				( attribute "BOM_COST" "SB"
					( Origin gFrontEnd )
				)
				( attribute "CDS_LIB" "mstr_discrete"
					( Origin gPackager )
				)
				( attribute "CDS_LOCATION" "R8D5"
					( Origin gPackager )
				)
				( attribute "CDS_SEC" "1"
					( Origin gPackager )
				)
				( attribute "LOCATION" "R8D5"
					( Origin gFrontEnd )
				)
				( attribute "MATERIAL" "EMPTY"
					( Origin gFrontEnd )
				)
				( attribute "PACK_TYPE" "0402"
					( Origin gFrontEnd )
				)
				( attribute "PART_NUMBER" "G21796-026"
					( Origin gFrontEnd )
				)
				( attribute "PHYS_PAGE" "125"
					( Origin gFrontEnd )
				)
				( attribute "ROOM" "SB"
					( Origin gFrontEnd )
				)
				( attribute "ROT" "0"
					( Origin gFrontEnd )
				)
				( attribute "SEC" "1"
					( Origin gPackager )
				)
				( attribute "TOLERANCE" "1%"
					( Origin gFrontEnd )
				)
				( attribute "VALUE" "1.00K"
					( Origin gFrontEnd )
				)
				( attribute "VER" "2"
					( Origin gFrontEnd )
				)
				( attribute "WATTAGE" "1/16W"
					( Origin gFrontEnd )
				)
				( attribute "XY" "(-925,4450)"
					( Origin gFrontEnd )
				)
				( attribute "CHIPS_PART_NAME" "RES"
					( Origin gPackager )
				)
				( attribute "CDS_PART_NAME" "RES_0402-1.00K,1%,1/16W,EMPTY,A"
					( Origin gPackager )
				)
				( objectStatus "R8D5" )
			)
			( gate "@baseboard_fab2_lib.baseboard_fab2(sch_1):page125_i60"
				( attribute "BOM_COST" "SB"
					( Origin gFrontEnd )
				)
				( attribute "CDS_LIB" "mstr_discrete"
					( Origin gPackager )
				)
				( attribute "CDS_LOCATION" "R7D13"
					( Origin gPackager )
				)
				( attribute "CDS_SEC" "1"
					( Origin gPackager )
				)
				( attribute "LOCATION" "R7D13"
					( Origin gFrontEnd )
				)
				( attribute "MATERIAL" "EMPTY"
					( Origin gFrontEnd )
				)
				( attribute "PACK_TYPE" "0402"
					( Origin gFrontEnd )
				)
				( attribute "PART_NUMBER" "G21796-345"
					( Origin gFrontEnd )
				)
				( attribute "PHYS_PAGE" "125"
					( Origin gFrontEnd )
				)
				( attribute "ROOM" "SB"
					( Origin gFrontEnd )
				)
				( attribute "ROT" "0"
					( Origin gFrontEnd )
				)
				( attribute "SEC" "1"
					( Origin gPackager )
				)
				( attribute "TOLERANCE" "1%"
					( Origin gFrontEnd )
				)
				( attribute "VALUE" "8.2K"
					( Origin gFrontEnd )
				)
				( attribute "VER" "2"
					( Origin gFrontEnd )
				)
				( attribute "WATTAGE" "1/16W"
					( Origin gFrontEnd )
				)
				( attribute "XY" "(-3275,4975)"
					( Origin gFrontEnd )
				)
				( attribute "CHIPS_PART_NAME" "RES"
					( Origin gPackager )
				)
				( attribute "CDS_PART_NAME" "RES_0402-8.2K,1%,1/16W,EMPTY,GA"
					( Origin gPackager )
				)
				( objectStatus "R7D13" )
			)
			( gate "@baseboard_fab2_lib.baseboard_fab2(sch_1):page145_i160"
				( attribute "BOM_COST" "PROC_SIDEBAND"
					( Origin gFrontEnd )
				)
				( attribute "CDS_LIB" "mstr_discrete"
					( Origin gPackager )
				)
				( attribute "CDS_LOCATION" "R25W141"
					( Origin gPackager )
				)
				( attribute "CDS_SEC" "1"
					( Origin gPackager )
				)
				( attribute "LOCATION" "R25W141"
					( Origin gFrontEnd )
				)
				( attribute "MATERIAL" "CHIP"
					( Origin gFrontEnd )
				)
				( attribute "PACK_TYPE" "0402"
					( Origin gFrontEnd )
				)
				( attribute "PART_NUMBER" "G21497-005"
					( Origin gFrontEnd )
				)
				( attribute "PHYS_PAGE" "145"
					( Origin gFrontEnd )
				)
				( attribute "ROOM" "CPU0"
					( Origin gFrontEnd )
				)
				( attribute "ROT" "0"
					( Origin gFrontEnd )
				)
				( attribute "SEC" "1"
					( Origin gFrontEnd )
				)
				( attribute "SEC_TYPE" "0402"
					( Origin gFrontEnd )
				)
				( attribute "TOLERANCE" "5%"
					( Origin gFrontEnd )
				)
				( attribute "VALUE" "0.0"
					( Origin gFrontEnd )
				)
				( attribute "VER" "1"
					( Origin gFrontEnd )
				)
				( attribute "WATTAGE" "1/16W"
					( Origin gFrontEnd )
				)
				( attribute "XY" "(-5950,-3450)"
					( Origin gFrontEnd )
				)
				( attribute "CHIPS_PART_NAME" "RES"
					( Origin gPackager )
				)
				( attribute "CDS_PART_NAME" "RES_0402-0.0,5%,1/16W,CHIP,G21A"
					( Origin gPackager )
				)
				( attribute "GROUP" "AST2500"
					( Origin gFrontEnd )
				)
				( objectStatus "R25W141" )
			)
			( gate "@baseboard_fab2_lib.baseboard_fab2(sch_1):page125_i72"
				( attribute "BOM_COST" "SB"
					( Origin gFrontEnd )
				)
				( attribute "CDS_LIB" "mstr_discrete"
					( Origin gPackager )
				)
				( attribute "CDS_LOCATION" "R3N2"
					( Origin gPackager )
				)
				( attribute "CDS_SEC" "1"
					( Origin gPackager )
				)
				( attribute "LOCATION" "R3N2"
					( Origin gFrontEnd )
				)
				( attribute "MATERIAL" "EMPTY"
					( Origin gFrontEnd )
				)
				( attribute "PACK_TYPE" "0402"
					( Origin gFrontEnd )
				)
				( attribute "PART_NUMBER" "G21796-072"
					( Origin gFrontEnd )
				)
				( attribute "PHYS_PAGE" "125"
					( Origin gFrontEnd )
				)
				( attribute "ROOM" "BMC_MISC"
					( Origin gFrontEnd )
				)
				( attribute "ROT" "0"
					( Origin gFrontEnd )
				)
				( attribute "SEC" "1"
					( Origin gFrontEnd )
				)
				( attribute "SEC_TYPE" "0402"
					( Origin gFrontEnd )
				)
				( attribute "TOLERANCE" "1%"
					( Origin gFrontEnd )
				)
				( attribute "VALUE" "4.75K"
					( Origin gFrontEnd )
				)
				( attribute "VER" "2"
					( Origin gFrontEnd )
				)
				( attribute "WATTAGE" "1/16W"
					( Origin gFrontEnd )
				)
				( attribute "XY" "(400,4600)"
					( Origin gFrontEnd )
				)
				( attribute "CHIPS_PART_NAME" "RES"
					( Origin gPackager )
				)
				( attribute "CDS_PART_NAME" "RES_0402-4.75K,1%,1/16W,EMPTY,A"
					( Origin gPackager )
				)
				( objectStatus "R3N2" )
			)
			( gate "@baseboard_fab2_lib.baseboard_fab2(sch_1):page125_i78"
				( attribute "BOM_COST" "SB"
					( Origin gFrontEnd )
				)
				( attribute "CDS_LIB" "mstr_discrete"
					( Origin gPackager )
				)
				( attribute "CDS_LOCATION" "R3N17"
					( Origin gPackager )
				)
				( attribute "CDS_SEC" "1"
					( Origin gPackager )
				)
				( attribute "LOCATION" "R3N17"
					( Origin gFrontEnd )
				)
				( attribute "MATERIAL" "EMPTY"
					( Origin gFrontEnd )
				)
				( attribute "PACK_TYPE" "0402"
					( Origin gFrontEnd )
				)
				( attribute "PART_NUMBER" "G21796-026"
					( Origin gFrontEnd )
				)
				( attribute "PHYS_PAGE" "125"
					( Origin gFrontEnd )
				)
				( attribute "ROOM" "SB"
					( Origin gFrontEnd )
				)
				( attribute "ROT" "0"
					( Origin gFrontEnd )
				)
				( attribute "SEC" "1"
					( Origin gFrontEnd )
				)
				( attribute "SEC_TYPE" "0402"
					( Origin gFrontEnd )
				)
				( attribute "TOLERANCE" "1%"
					( Origin gFrontEnd )
				)
				( attribute "VALUE" "1.00K"
					( Origin gFrontEnd )
				)
				( attribute "VER" "2"
					( Origin gFrontEnd )
				)
				( attribute "WATTAGE" "1/16W"
					( Origin gFrontEnd )
				)
				( attribute "XY" "(1850,1875)"
					( Origin gFrontEnd )
				)
				( attribute "CHIPS_PART_NAME" "RES"
					( Origin gPackager )
				)
				( attribute "CDS_PART_NAME" "RES_0402-1.00K,1%,1/16W,EMPTY,A"
					( Origin gPackager )
				)
				( objectStatus "R3N17" )
			)
			( gate "@baseboard_fab2_lib.baseboard_fab2(sch_1):page125_i83"
				( attribute "BOM_COST" "SB"
					( Origin gFrontEnd )
				)
				( attribute "CDS_LIB" "mstr_discrete"
					( Origin gPackager )
				)
				( attribute "CDS_LOCATION" "R2N14"
					( Origin gPackager )
				)
				( attribute "CDS_SEC" "1"
					( Origin gPackager )
				)
				( attribute "LOCATION" "R2N14"
					( Origin gFrontEnd )
				)
				( attribute "MATERIAL" "EMPTY"
					( Origin gFrontEnd )
				)
				( attribute "PACK_TYPE" "0402"
					( Origin gFrontEnd )
				)
				( attribute "PART_NUMBER" "G21796-026"
					( Origin gFrontEnd )
				)
				( attribute "PHYS_PAGE" "125"
					( Origin gFrontEnd )
				)
				( attribute "ROOM" "SB"
					( Origin gFrontEnd )
				)
				( attribute "ROT" "0"
					( Origin gFrontEnd )
				)
				( attribute "SEC" "1"
					( Origin gFrontEnd )
				)
				( attribute "SEC_TYPE" "0402"
					( Origin gFrontEnd )
				)
				( attribute "TOLERANCE" "1%"
					( Origin gFrontEnd )
				)
				( attribute "VALUE" "1.00K"
					( Origin gFrontEnd )
				)
				( attribute "VER" "2"
					( Origin gFrontEnd )
				)
				( attribute "WATTAGE" "1/16W"
					( Origin gFrontEnd )
				)
				( attribute "XY" "(-925,1525)"
					( Origin gFrontEnd )
				)
				( attribute "CHIPS_PART_NAME" "RES"
					( Origin gPackager )
				)
				( attribute "CDS_PART_NAME" "RES_0402-1.00K,1%,1/16W,EMPTY,A"
					( Origin gPackager )
				)
				( objectStatus "R2N14" )
			)
			( gate "@baseboard_fab2_lib.baseboard_fab2(sch_1):page126_i6"
				( attribute "BOM_COST" "SB"
					( Origin gFrontEnd )
				)
				( attribute "CDS_LIB" "mstr_discrete"
					( Origin gPackager )
				)
				( attribute "CDS_LOCATION" "R7D19"
					( Origin gPackager )
				)
				( attribute "CDS_SEC" "1"
					( Origin gPackager )
				)
				( attribute "LOCATION" "R7D19"
					( Origin gFrontEnd )
				)
				( attribute "MATERIAL" "EMPTY"
					( Origin gFrontEnd )
				)
				( attribute "PACK_TYPE" "0402"
					( Origin gFrontEnd )
				)
				( attribute "PART_NUMBER" "G21796-026"
					( Origin gFrontEnd )
				)
				( attribute "PHYS_PAGE" "126"
					( Origin gFrontEnd )
				)
				( attribute "ROOM" "SB"
					( Origin gFrontEnd )
				)
				( attribute "ROT" "0"
					( Origin gFrontEnd )
				)
				( attribute "SEC" "1"
					( Origin gFrontEnd )
				)
				( attribute "SEC_TYPE" "0402"
					( Origin gFrontEnd )
				)
				( attribute "TOLERANCE" "1%"
					( Origin gFrontEnd )
				)
				( attribute "VALUE" "1.00K"
					( Origin gFrontEnd )
				)
				( attribute "VER" "2"
					( Origin gFrontEnd )
				)
				( attribute "WATTAGE" "1/16W"
					( Origin gFrontEnd )
				)
				( attribute "XY" "(-6200,2350)"
					( Origin gFrontEnd )
				)
				( attribute "CHIPS_PART_NAME" "RES"
					( Origin gPackager )
				)
				( attribute "CDS_PART_NAME" "RES_0402-1.00K,1%,1/16W,EMPTY,A"
					( Origin gPackager )
				)
				( objectStatus "R7D19" )
			)
			( gate "@baseboard_fab2_lib.baseboard_fab2(sch_1):page197_i110"
				( attribute "ATTRIBUTE" "665KOHM"
					( Origin gFrontEnd )
				)
				( attribute "CDS_LIB" "w_hdl"
					( Origin gPackager )
				)
				( attribute "CDS_LMAN_SYM_OUTLINE" "-50,75,50,-75"
					( Origin gPackager )
				)
				( attribute "LOCATION" "R12W20"
					( Origin gFrontEnd )
				)
				( attribute "PACK_TYPE" "SMD-RG2"
					( Origin gFrontEnd )
				)
				( attribute "PART_NUMBER" "064.6653D.06DD"
					( Origin gFrontEnd )
				)
				( attribute "PHYS_PAGE" "197"
					( Origin gFrontEnd )
				)
				( attribute "POP" "NOPOP"
					( Origin gFrontEnd )
				)
				( attribute "RATED" "1/16W"
					( Origin gFrontEnd )
				)
				( attribute "ROT" "1"
					( Origin gFrontEnd )
				)
				( attribute "SEC" "1"
					( Origin gFrontEnd )
				)
				( attribute "SEC_TYPE" "SMD-RG2"
					( Origin gFrontEnd )
				)
				( attribute "TOLERANCE" "0.1%"
					( Origin gFrontEnd )
				)
				( attribute "VALUE" "665KR2B-GP"
					( Origin gFrontEnd )
				)
				( attribute "VER" "1"
					( Origin gFrontEnd )
				)
				( attribute "XY" "(-1700,1700)"
					( Origin gFrontEnd )
				)
				( attribute "CHIPS_PART_NAME" "665KR2B-GP"
					( Origin gPackager )
				)
				( attribute "CDS_PART_NAME" "665KR2B-GP_SMD-RG2-665KR2B-GP,A"
					( Origin gPackager )
				)
				( attribute "PACK_SIZE" "0402"
					( Origin gFrontEnd )
				)
				( attribute "CDS_LOCATION" "R12W20"
					( Origin gPackager )
				)
				( attribute "CDS_SEC" "1"
					( Origin gPackager )
				)
				( objectStatus "R12W20" )
			)
			( gate "@baseboard_fab2_lib.baseboard_fab2(sch_1):page126_i12"
				( attribute "BOM_COST" "SM_CONTROLLER"
					( Origin gFrontEnd )
				)
				( attribute "CDS_LIB" "mstr_discrete"
					( Origin gPackager )
				)
				( attribute "CDS_LOCATION" "R1D35"
					( Origin gPackager )
				)
				( attribute "CDS_SEC" "1"
					( Origin gPackager )
				)
				( attribute "LOCATION" "R1D35"
					( Origin gFrontEnd )
				)
				( attribute "MATERIAL" "CHIP"
					( Origin gFrontEnd )
				)
				( attribute "PACK_TYPE" "0402"
					( Origin gFrontEnd )
				)
				( attribute "PART_NUMBER" "G21796-072"
					( Origin gFrontEnd )
				)
				( attribute "PHYS_PAGE" "126"
					( Origin gFrontEnd )
				)
				( attribute "ROOM" "BMC_MISC"
					( Origin gFrontEnd )
				)
				( attribute "ROT" "0"
					( Origin gFrontEnd )
				)
				( attribute "SEC" "1"
					( Origin gFrontEnd )
				)
				( attribute "SEC_TYPE" "0402"
					( Origin gFrontEnd )
				)
				( attribute "TOLERANCE" "1%"
					( Origin gFrontEnd )
				)
				( attribute "VALUE" "4.75K"
					( Origin gFrontEnd )
				)
				( attribute "VER" "2"
					( Origin gFrontEnd )
				)
				( attribute "WATTAGE" "1/16W"
					( Origin gFrontEnd )
				)
				( attribute "XY" "(-6200,2775)"
					( Origin gFrontEnd )
				)
				( attribute "CHIPS_PART_NAME" "RES"
					( Origin gPackager )
				)
				( attribute "CDS_PART_NAME" "RES_0402-4.75K,1%,1/16W,CHIP,GA"
					( Origin gPackager )
				)
				( objectStatus "R1D35" )
			)
			( gate "@baseboard_fab2_lib.baseboard_fab2(sch_1):page126_i13"
				( attribute "CDS_LIB" "mstr_discrete"
					( Origin gPackager )
				)
				( attribute "CDS_LOCATION" "Q8E2"
					( Origin gPackager )
				)
				( attribute "CDS_SEC" "1"
					( Origin gPackager )
				)
				( attribute "LOCATION" "Q8E2"
					( Origin gFrontEnd )
				)
				( attribute "MATERIAL" "FET"
					( Origin gFrontEnd )
				)
				( attribute "PACK_TYPE" "SOT23LF"
					( Origin gFrontEnd )
				)
				( attribute "PART_NUMBER" "C79254-001"
					( Origin gFrontEnd )
				)
				( attribute "PHYS_PAGE" "126"
					( Origin gFrontEnd )
				)
				( attribute "ROT" "0"
					( Origin gFrontEnd )
				)
				( attribute "SEC" "1"
					( Origin gFrontEnd )
				)
				( attribute "SEC_TYPE" "SOT23LF"
					( Origin gFrontEnd )
				)
				( attribute "VALUE" "2N7002"
					( Origin gFrontEnd )
				)
				( attribute "VER" "8"
					( Origin gFrontEnd )
				)
				( attribute "XY" "(-3625,3925)"
					( Origin gFrontEnd )
				)
				( attribute "CHIPS_PART_NAME" "FET_N"
					( Origin gPackager )
				)
				( attribute "CDS_PART_NAME" "FET_N_SOT23LF-2N7002,FET,C7925A"
					( Origin gPackager )
				)
				( objectStatus "Q8E2" )
			)
			( gate "@baseboard_fab2_lib.baseboard_fab2(sch_1):page126_i20"
				( attribute "BOM_COST" "SM_CONTROLLER"
					( Origin gFrontEnd )
				)
				( attribute "CDS_LIB" "mstr_discrete"
					( Origin gPackager )
				)
				( attribute "CDS_LOCATION" "R8C9"
					( Origin gPackager )
				)
				( attribute "CDS_SEC" "1"
					( Origin gPackager )
				)
				( attribute "LOCATION" "R8C9"
					( Origin gFrontEnd )
				)
				( attribute "MATERIAL" "CHIP"
					( Origin gFrontEnd )
				)
				( attribute "PACK_TYPE" "0402"
					( Origin gFrontEnd )
				)
				( attribute "PART_NUMBER" "G21796-072"
					( Origin gFrontEnd )
				)
				( attribute "PHYS_PAGE" "126"
					( Origin gFrontEnd )
				)
				( attribute "ROOM" "BMC_MISC"
					( Origin gFrontEnd )
				)
				( attribute "ROT" "0"
					( Origin gFrontEnd )
				)
				( attribute "SEC" "1"
					( Origin gFrontEnd )
				)
				( attribute "SEC_TYPE" "0402"
					( Origin gFrontEnd )
				)
				( attribute "TOLERANCE" "1%"
					( Origin gFrontEnd )
				)
				( attribute "VALUE" "4.75K"
					( Origin gFrontEnd )
				)
				( attribute "VER" "2"
					( Origin gFrontEnd )
				)
				( attribute "WATTAGE" "1/16W"
					( Origin gFrontEnd )
				)
				( attribute "XY" "(-3625,4425)"
					( Origin gFrontEnd )
				)
				( attribute "CHIPS_PART_NAME" "RES"
					( Origin gPackager )
				)
				( attribute "CDS_PART_NAME" "RES_0402-4.75K,1%,1/16W,CHIP,GA"
					( Origin gPackager )
				)
				( objectStatus "R8C9" )
			)
			( gate "@baseboard_fab2_lib.baseboard_fab2(sch_1):page126_i22"
				( attribute "CDS_LIB" "mstr_discrete"
					( Origin gPackager )
				)
				( attribute "CDS_LOCATION" "R3P62"
					( Origin gPackager )
				)
				( attribute "CDS_SEC" "1"
					( Origin gPackager )
				)
				( attribute "LOCATION" "R3P62"
					( Origin gFrontEnd )
				)
				( attribute "MATERIAL" "EMPTY"
					( Origin gFrontEnd )
				)
				( attribute "PACK_TYPE" "0402"
					( Origin gFrontEnd )
				)
				( attribute "PART_NUMBER" "G21796-072"
					( Origin gFrontEnd )
				)
				( attribute "PHYS_PAGE" "126"
					( Origin gFrontEnd )
				)
				( attribute "ROT" "0"
					( Origin gFrontEnd )
				)
				( attribute "SEC" "1"
					( Origin gFrontEnd )
				)
				( attribute "SEC_TYPE" "0402"
					( Origin gFrontEnd )
				)
				( attribute "TOLERANCE" "1%"
					( Origin gFrontEnd )
				)
				( attribute "VALUE" "4.75K"
					( Origin gFrontEnd )
				)
				( attribute "VER" "2"
					( Origin gFrontEnd )
				)
				( attribute "WATTAGE" "1/16W"
					( Origin gFrontEnd )
				)
				( attribute "XY" "(-4525,2725)"
					( Origin gFrontEnd )
				)
				( attribute "CHIPS_PART_NAME" "RES"
					( Origin gPackager )
				)
				( attribute "CDS_PART_NAME" "RES_0402-4.75K,1%,1/16W,EMPTY,A"
					( Origin gPackager )
				)
				( objectStatus "R3P62" )
			)
			( gate "@baseboard_fab2_lib.baseboard_fab2(sch_1):page126_i23"
				( attribute "CDS_LIB" "mstr_discrete"
					( Origin gPackager )
				)
				( attribute "CDS_LOCATION" "R3P64"
					( Origin gPackager )
				)
				( attribute "CDS_SEC" "1"
					( Origin gPackager )
				)
				( attribute "LOCATION" "R3P64"
					( Origin gFrontEnd )
				)
				( attribute "MATERIAL" "EMPTY"
					( Origin gFrontEnd )
				)
				( attribute "PACK_TYPE" "0402"
					( Origin gFrontEnd )
				)
				( attribute "PART_NUMBER" "G21796-026"
					( Origin gFrontEnd )
				)
				( attribute "PHYS_PAGE" "126"
					( Origin gFrontEnd )
				)
				( attribute "ROT" "0"
					( Origin gFrontEnd )
				)
				( attribute "SEC" "1"
					( Origin gFrontEnd )
				)
				( attribute "SEC_TYPE" "0402"
					( Origin gFrontEnd )
				)
				( attribute "TOLERANCE" "1%"
					( Origin gFrontEnd )
				)
				( attribute "VALUE" "1.00K"
					( Origin gFrontEnd )
				)
				( attribute "VER" "2"
					( Origin gFrontEnd )
				)
				( attribute "WATTAGE" "1/16W"
					( Origin gFrontEnd )
				)
				( attribute "XY" "(-4525,2275)"
					( Origin gFrontEnd )
				)
				( attribute "CHIPS_PART_NAME" "RES"
					( Origin gPackager )
				)
				( attribute "CDS_PART_NAME" "RES_0402-1.00K,1%,1/16W,EMPTY,A"
					( Origin gPackager )
				)
				( objectStatus "R3P64" )
			)
			( gate "@baseboard_fab2_lib.baseboard_fab2(sch_1):page127_i8"
				( attribute "BOM_COST" "SB"
					( Origin gFrontEnd )
				)
				( attribute "CDS_LIB" "mstr_discrete"
					( Origin gPackager )
				)
				( attribute "CDS_LOCATION" "FB3M1"
					( Origin gPackager )
				)
				( attribute "CDS_SEC" "1"
					( Origin gPackager )
				)
				( attribute "LOCATION" "FB3M1"
					( Origin gFrontEnd )
				)
				( attribute "MATERIAL" "FB"
					( Origin gFrontEnd )
				)
				( attribute "PACK_TYPE" "SM"
					( Origin gFrontEnd )
				)
				( attribute "PART_NUMBER" "693286-027"
					( Origin gFrontEnd )
				)
				( attribute "PHYS_PAGE" "127"
					( Origin gFrontEnd )
				)
				( attribute "ROOM" "SB_FILTER_PLL0"
					( Origin gFrontEnd )
				)
				( attribute "ROT" "0"
					( Origin gFrontEnd )
				)
				( attribute "SEC" "1"
					( Origin gFrontEnd )
				)
				( attribute "SEC_TYPE" "SM"
					( Origin gFrontEnd )
				)
				( attribute "VALUE" "120"
					( Origin gFrontEnd )
				)
				( attribute "VER" "1"
					( Origin gFrontEnd )
				)
				( attribute "XY" "(-4050,-850)"
					( Origin gFrontEnd )
				)
				( attribute "CHIPS_PART_NAME" "FERRITE"
					( Origin gPackager )
				)
				( attribute "CDS_PART_NAME" "FERRITE_SM-120,FB,693286-027"
					( Origin gPackager )
				)
				( objectStatus "FB3M1" )
			)
			( gate "@baseboard_fab2_lib.baseboard_fab2(sch_1):page127_i9"
				( attribute "BOM_COST" "SB"
					( Origin gFrontEnd )
				)
				( attribute "CDS_LIB" "dev_discrete"
					( Origin gPackager )
				)
				( attribute "CDS_LOCATION" "C3M21"
					( Origin gPackager )
				)
				( attribute "CDS_SEC" "1"
					( Origin gPackager )
				)
				( attribute "LOCATION" "C3M21"
					( Origin gFrontEnd )
				)
				( attribute "MATERIAL" "X6S"
					( Origin gFrontEnd )
				)
				( attribute "PACK_TYPE" "0402V"
					( Origin gFrontEnd )
				)
				( attribute "PART_NUMBER" "D97712-004"
					( Origin gFrontEnd )
				)
				( attribute "PHYS_PAGE" "127"
					( Origin gFrontEnd )
				)
				( attribute "ROOM" "SB_FILTER_PLL0"
					( Origin gFrontEnd )
				)
				( attribute "ROT" "2"
					( Origin gFrontEnd )
				)
				( attribute "SEC" "1"
					( Origin gFrontEnd )
				)
				( attribute "SEC_TYPE" "0402V"
					( Origin gFrontEnd )
				)
				( attribute "TOLERANCE" "10%"
					( Origin gFrontEnd )
				)
				( attribute "VALUE" "1.0UF"
					( Origin gFrontEnd )
				)
				( attribute "VER" "1"
					( Origin gFrontEnd )
				)
				( attribute "VOLTAGE" "6.3V"
					( Units "uVoltage" "V" 1.000000)
					( Origin gFrontEnd )
				)
				( attribute "XY" "(-4300,-1050)"
					( Origin gFrontEnd )
				)
				( attribute "CHIPS_PART_NAME" "CAP_A"
					( Origin gPackager )
				)
				( attribute "CDS_PART_NAME" "CAP_A_0402V-1.0UF,6.3V,10%,X6SA"
					( Origin gPackager )
				)
				( objectStatus "C3M21" )
			)
			( gate "@baseboard_fab2_lib.baseboard_fab2(sch_1):page127_i17"
				( attribute "BOM_COST" "SB"
					( Origin gFrontEnd )
				)
				( attribute "CDS_LIB" "mstr_discrete"
					( Origin gPackager )
				)
				( attribute "CDS_LOCATION" "FB3M2"
					( Origin gPackager )
				)
				( attribute "CDS_SEC" "1"
					( Origin gPackager )
				)
				( attribute "LOCATION" "FB3M2"
					( Origin gFrontEnd )
				)
				( attribute "MATERIAL" "FB"
					( Origin gFrontEnd )
				)
				( attribute "PACK_TYPE" "SM"
					( Origin gFrontEnd )
				)
				( attribute "PART_NUMBER" "693286-027"
					( Origin gFrontEnd )
				)
				( attribute "PHYS_PAGE" "127"
					( Origin gFrontEnd )
				)
				( attribute "ROOM" "SB_FILTER_PLL1"
					( Origin gFrontEnd )
				)
				( attribute "ROT" "0"
					( Origin gFrontEnd )
				)
				( attribute "SEC" "1"
					( Origin gFrontEnd )
				)
				( attribute "SEC_TYPE" "SM"
					( Origin gFrontEnd )
				)
				( attribute "VALUE" "120"
					( Origin gFrontEnd )
				)
				( attribute "VER" "1"
					( Origin gFrontEnd )
				)
				( attribute "XY" "(-4025,-2050)"
					( Origin gFrontEnd )
				)
				( attribute "CHIPS_PART_NAME" "FERRITE"
					( Origin gPackager )
				)
				( attribute "CDS_PART_NAME" "FERRITE_SM-120,FB,693286-027"
					( Origin gPackager )
				)
				( objectStatus "FB3M2" )
			)
			( gate "@baseboard_fab2_lib.baseboard_fab2(sch_1):page127_i18"
				( attribute "BOM_COST" "SB"
					( Origin gFrontEnd )
				)
				( attribute "CDS_LIB" "dev_discrete"
					( Origin gPackager )
				)
				( attribute "CDS_LOCATION" "C3M22"
					( Origin gPackager )
				)
				( attribute "CDS_SEC" "1"
					( Origin gPackager )
				)
				( attribute "LOCATION" "C3M22"
					( Origin gFrontEnd )
				)
				( attribute "MATERIAL" "X6S"
					( Origin gFrontEnd )
				)
				( attribute "PACK_TYPE" "0402V"
					( Origin gFrontEnd )
				)
				( attribute "PART_NUMBER" "D97712-004"
					( Origin gFrontEnd )
				)
				( attribute "PHYS_PAGE" "127"
					( Origin gFrontEnd )
				)
				( attribute "ROOM" "SB_FILTER_PLL1"
					( Origin gFrontEnd )
				)
				( attribute "ROT" "2"
					( Origin gFrontEnd )
				)
				( attribute "SEC" "1"
					( Origin gFrontEnd )
				)
				( attribute "SEC_TYPE" "0402V"
					( Origin gFrontEnd )
				)
				( attribute "TOLERANCE" "10%"
					( Origin gFrontEnd )
				)
				( attribute "VALUE" "1.0UF"
					( Origin gFrontEnd )
				)
				( attribute "VER" "1"
					( Origin gFrontEnd )
				)
				( attribute "VOLTAGE" "6.3V"
					( Units "uVoltage" "V" 1.000000)
					( Origin gFrontEnd )
				)
				( attribute "XY" "(-4275,-2250)"
					( Origin gFrontEnd )
				)
				( attribute "CHIPS_PART_NAME" "CAP_A"
					( Origin gPackager )
				)
				( attribute "CDS_PART_NAME" "CAP_A_0402V-1.0UF,6.3V,10%,X6SA"
					( Origin gPackager )
				)
				( objectStatus "C3M22" )
			)
			( gate "@baseboard_fab2_lib.baseboard_fab2(sch_1):page127_i26"
				( attribute "BOM_COST" "SB"
					( Origin gFrontEnd )
				)
				( attribute "CDS_LIB" "mstr_discrete"
					( Origin gPackager )
				)
				( attribute "CDS_LOCATION" "FB3M3"
					( Origin gPackager )
				)
				( attribute "CDS_SEC" "1"
					( Origin gPackager )
				)
				( attribute "LOCATION" "FB3M3"
					( Origin gFrontEnd )
				)
				( attribute "MATERIAL" "FB"
					( Origin gFrontEnd )
				)
				( attribute "PACK_TYPE" "SM"
					( Origin gFrontEnd )
				)
				( attribute "PART_NUMBER" "693286-027"
					( Origin gFrontEnd )
				)
				( attribute "PHYS_PAGE" "127"
					( Origin gFrontEnd )
				)
				( attribute "ROOM" "SB_FILTER_XTAL"
					( Origin gFrontEnd )
				)
				( attribute "ROT" "0"
					( Origin gFrontEnd )
				)
				( attribute "SEC" "1"
					( Origin gFrontEnd )
				)
				( attribute "SEC_TYPE" "SM"
					( Origin gFrontEnd )
				)
				( attribute "VALUE" "120"
					( Origin gFrontEnd )
				)
				( attribute "VER" "1"
					( Origin gFrontEnd )
				)
				( attribute "XY" "(-4000,-3350)"
					( Origin gFrontEnd )
				)
				( attribute "CHIPS_PART_NAME" "FERRITE"
					( Origin gPackager )
				)
				( attribute "CDS_PART_NAME" "FERRITE_SM-120,FB,693286-027"
					( Origin gPackager )
				)
				( objectStatus "FB3M3" )
			)
			( gate "@baseboard_fab2_lib.baseboard_fab2(sch_1):page127_i27"
				( attribute "BOM_COST" "SB"
					( Origin gFrontEnd )
				)
				( attribute "CDS_LIB" "dev_discrete"
					( Origin gPackager )
				)
				( attribute "CDS_LOCATION" "C3M30"
					( Origin gPackager )
				)
				( attribute "CDS_SEC" "1"
					( Origin gPackager )
				)
				( attribute "LOCATION" "C3M30"
					( Origin gFrontEnd )
				)
				( attribute "MATERIAL" "X6S"
					( Origin gFrontEnd )
				)
				( attribute "PACK_TYPE" "0402V"
					( Origin gFrontEnd )
				)
				( attribute "PART_NUMBER" "D97712-004"
					( Origin gFrontEnd )
				)
				( attribute "PHYS_PAGE" "127"
					( Origin gFrontEnd )
				)
				( attribute "ROOM" "SB_FILTER_XTAL"
					( Origin gFrontEnd )
				)
				( attribute "ROT" "2"
					( Origin gFrontEnd )
				)
				( attribute "SEC" "1"
					( Origin gFrontEnd )
				)
				( attribute "SEC_TYPE" "0402V"
					( Origin gFrontEnd )
				)
				( attribute "TOLERANCE" "10%"
					( Origin gFrontEnd )
				)
				( attribute "VALUE" "1.0UF"
					( Origin gFrontEnd )
				)
				( attribute "VER" "1"
					( Origin gFrontEnd )
				)
				( attribute "VOLTAGE" "6.3V"
					( Units "uVoltage" "V" 1.000000)
					( Origin gFrontEnd )
				)
				( attribute "XY" "(-4250,-3550)"
					( Origin gFrontEnd )
				)
				( attribute "CHIPS_PART_NAME" "CAP_A"
					( Origin gPackager )
				)
				( attribute "CDS_PART_NAME" "CAP_A_0402V-1.0UF,6.3V,10%,X6SA"
					( Origin gPackager )
				)
				( objectStatus "C3M30" )
			)
			( gate "@baseboard_fab2_lib.baseboard_fab2(sch_1):page127_i43"
				( attribute "BOM_COST" "SB"
					( Origin gFrontEnd )
				)
				( attribute "CDS_LIB" "mstr_discrete"
					( Origin gPackager )
				)
				( attribute "CDS_LOCATION" "C2M5"
					( Origin gPackager )
				)
				( attribute "CDS_SEC" "1"
					( Origin gPackager )
				)
				( attribute "LOCATION" "C2M5"
					( Origin gFrontEnd )
				)
				( attribute "MATERIAL" "X6S"
					( Origin gFrontEnd )
				)
				( attribute "PACK_TYPE" "0603LF"
					( Origin gFrontEnd )
				)
				( attribute "PART_NUMBER" "E15431-001"
					( Origin gFrontEnd )
				)
				( attribute "PHYS_PAGE" "127"
					( Origin gFrontEnd )
				)
				( attribute "ROOM" "SB_FILTER_VM20"
					( Origin gFrontEnd )
				)
				( attribute "ROT" "0"
					( Origin gFrontEnd )
				)
				( attribute "SEC" "1"
					( Origin gFrontEnd )
				)
				( attribute "SEC_TYPE" "0603LF"
					( Origin gFrontEnd )
				)
				( attribute "TOLERANCE" "20%"
					( Origin gFrontEnd )
				)
				( attribute "VALUE" "10UF"
					( Origin gFrontEnd )
				)
				( attribute "VER" "1"
					( Origin gFrontEnd )
				)
				( attribute "VOLTAGE" "4V"
					( Units "uVoltage" "V" 1.000000)
					( Origin gFrontEnd )
				)
				( attribute "XY" "(1850,-1375)"
					( Origin gFrontEnd )
				)
				( attribute "CHIPS_PART_NAME" "CAP"
					( Origin gPackager )
				)
				( attribute "CDS_PART_NAME" "CAP_0603LF-10UF,4V,20%,X6S,E15A"
					( Origin gPackager )
				)
				( objectStatus "C2M5" )
			)
			( gate "@baseboard_fab2_lib.baseboard_fab2(sch_1):page127_i44"
				( attribute "BOM_COST" "SB"
					( Origin gFrontEnd )
				)
				( attribute "CDS_LIB" "dev_discrete"
					( Origin gPackager )
				)
				( attribute "CDS_LOCATION" "C2M7"
					( Origin gPackager )
				)
				( attribute "CDS_SEC" "1"
					( Origin gPackager )
				)
				( attribute "LOCATION" "C2M7"
					( Origin gFrontEnd )
				)
				( attribute "MATERIAL" "X6S"
					( Origin gFrontEnd )
				)
				( attribute "PACK_TYPE" "0402V"
					( Origin gFrontEnd )
				)
				( attribute "PART_NUMBER" "D97712-004"
					( Origin gFrontEnd )
				)
				( attribute "PHYS_PAGE" "127"
					( Origin gFrontEnd )
				)
				( attribute "ROOM" "SB_FILTER_VM20"
					( Origin gFrontEnd )
				)
				( attribute "ROT" "0"
					( Origin gFrontEnd )
				)
				( attribute "SEC" "1"
					( Origin gFrontEnd )
				)
				( attribute "SEC_TYPE" "0402V"
					( Origin gFrontEnd )
				)
				( attribute "TOLERANCE" "10%"
					( Origin gFrontEnd )
				)
				( attribute "VALUE" "1.0UF"
					( Origin gFrontEnd )
				)
				( attribute "VER" "1"
					( Origin gFrontEnd )
				)
				( attribute "VOLTAGE" "6.3V"
					( Units "uVoltage" "V" 1.000000)
					( Origin gFrontEnd )
				)
				( attribute "XY" "(1400,-1375)"
					( Origin gFrontEnd )
				)
				( attribute "CHIPS_PART_NAME" "CAP_A"
					( Origin gPackager )
				)
				( attribute "CDS_PART_NAME" "CAP_A_0402V-1.0UF,6.3V,10%,X6SA"
					( Origin gPackager )
				)
				( objectStatus "C2M7" )
			)
			( gate "@baseboard_fab2_lib.baseboard_fab2(sch_1):page127_i46"
				( attribute "BOM_COST" "SB"
					( Origin gFrontEnd )
				)
				( attribute "CDS_LIB" "mstr_discrete"
					( Origin gPackager )
				)
				( attribute "CDS_LOCATION" "FB2M1"
					( Origin gPackager )
				)
				( attribute "CDS_SEC" "1"
					( Origin gPackager )
				)
				( attribute "LOCATION" "FB2M1"
					( Origin gFrontEnd )
				)
				( attribute "MATERIAL" "FB"
					( Origin gFrontEnd )
				)
				( attribute "PACK_TYPE" "SM"
					( Origin gFrontEnd )
				)
				( attribute "PART_NUMBER" "693286-027"
					( Origin gFrontEnd )
				)
				( attribute "PHYS_PAGE" "127"
					( Origin gFrontEnd )
				)
				( attribute "ROOM" "SB_FILTER_VM20"
					( Origin gFrontEnd )
				)
				( attribute "ROT" "0"
					( Origin gFrontEnd )
				)
				( attribute "SEC" "1"
					( Origin gFrontEnd )
				)
				( attribute "SEC_TYPE" "SM"
					( Origin gFrontEnd )
				)
				( attribute "VALUE" "120"
					( Origin gFrontEnd )
				)
				( attribute "VER" "1"
					( Origin gFrontEnd )
				)
				( attribute "XY" "(1150,-1175)"
					( Origin gFrontEnd )
				)
				( attribute "CHIPS_PART_NAME" "FERRITE"
					( Origin gPackager )
				)
				( attribute "CDS_PART_NAME" "FERRITE_SM-120,FB,693286-027"
					( Origin gPackager )
				)
				( objectStatus "FB2M1" )
			)
			( gate "@baseboard_fab2_lib.baseboard_fab2(sch_1):page127_i49"
				( attribute "BOM_COST" "SB"
					( Origin gFrontEnd )
				)
				( attribute "CDS_LIB" "mstr_discrete"
					( Origin gPackager )
				)
				( attribute "CDS_LOCATION" "C2M10"
					( Origin gPackager )
				)
				( attribute "CDS_SEC" "1"
					( Origin gPackager )
				)
				( attribute "LOCATION" "C2M10"
					( Origin gFrontEnd )
				)
				( attribute "MATERIAL" "X6S"
					( Origin gFrontEnd )
				)
				( attribute "PACK_TYPE" "0603LF"
					( Origin gFrontEnd )
				)
				( attribute "PART_NUMBER" "E15431-001"
					( Origin gFrontEnd )
				)
				( attribute "PHYS_PAGE" "127"
					( Origin gFrontEnd )
				)
				( attribute "ROOM" "SB_FILTER_VM26"
					( Origin gFrontEnd )
				)
				( attribute "ROT" "0"
					( Origin gFrontEnd )
				)
				( attribute "SEC" "1"
					( Origin gFrontEnd )
				)
				( attribute "SEC_TYPE" "0603LF"
					( Origin gFrontEnd )
				)
				( attribute "TOLERANCE" "20%"
					( Origin gFrontEnd )
				)
				( attribute "VALUE" "10UF"
					( Origin gFrontEnd )
				)
				( attribute "VER" "1"
					( Origin gFrontEnd )
				)
				( attribute "VOLTAGE" "4V"
					( Units "uVoltage" "V" 1.000000)
					( Origin gFrontEnd )
				)
				( attribute "XY" "(-500,-1400)"
					( Origin gFrontEnd )
				)
				( attribute "CHIPS_PART_NAME" "CAP"
					( Origin gPackager )
				)
				( attribute "CDS_PART_NAME" "CAP_0603LF-10UF,4V,20%,X6S,E15A"
					( Origin gPackager )
				)
				( objectStatus "C2M10" )
			)
			( gate "@baseboard_fab2_lib.baseboard_fab2(sch_1):page127_i50"
				( attribute "BOM_COST" "SB"
					( Origin gFrontEnd )
				)
				( attribute "CDS_LIB" "dev_discrete"
					( Origin gPackager )
				)
				( attribute "CDS_LOCATION" "C2M9"
					( Origin gPackager )
				)
				( attribute "CDS_SEC" "1"
					( Origin gPackager )
				)
				( attribute "LOCATION" "C2M9"
					( Origin gFrontEnd )
				)
				( attribute "MATERIAL" "X6S"
					( Origin gFrontEnd )
				)
				( attribute "PACK_TYPE" "0402V"
					( Origin gFrontEnd )
				)
				( attribute "PART_NUMBER" "D97712-004"
					( Origin gFrontEnd )
				)
				( attribute "PHYS_PAGE" "127"
					( Origin gFrontEnd )
				)
				( attribute "ROOM" "SB_FILTER_VM26"
					( Origin gFrontEnd )
				)
				( attribute "ROT" "0"
					( Origin gFrontEnd )
				)
				( attribute "SEC" "1"
					( Origin gFrontEnd )
				)
				( attribute "SEC_TYPE" "0402V"
					( Origin gFrontEnd )
				)
				( attribute "TOLERANCE" "10%"
					( Origin gFrontEnd )
				)
				( attribute "VALUE" "1.0UF"
					( Origin gFrontEnd )
				)
				( attribute "VER" "1"
					( Origin gFrontEnd )
				)
				( attribute "VOLTAGE" "6.3V"
					( Units "uVoltage" "V" 1.000000)
					( Origin gFrontEnd )
				)
				( attribute "XY" "(-1000,-1400)"
					( Origin gFrontEnd )
				)
				( attribute "CHIPS_PART_NAME" "CAP_A"
					( Origin gPackager )
				)
				( attribute "CDS_PART_NAME" "CAP_A_0402V-1.0UF,6.3V,10%,X6SA"
					( Origin gPackager )
				)
				( objectStatus "C2M9" )
			)
			( gate "@baseboard_fab2_lib.baseboard_fab2(sch_1):page127_i56"
				( attribute "BOM_COST" "SB"
					( Origin gFrontEnd )
				)
				( attribute "CDS_LIB" "mstr_discrete"
					( Origin gPackager )
				)
				( attribute "CDS_LOCATION" "FB3M4"
					( Origin gPackager )
				)
				( attribute "CDS_SEC" "1"
					( Origin gPackager )
				)
				( attribute "LOCATION" "FB3M4"
					( Origin gFrontEnd )
				)
				( attribute "MATERIAL" "FB"
					( Origin gFrontEnd )
				)
				( attribute "PACK_TYPE" "SM"
					( Origin gFrontEnd )
				)
				( attribute "PART_NUMBER" "693286-027"
					( Origin gFrontEnd )
				)
				( attribute "PHYS_PAGE" "127"
					( Origin gFrontEnd )
				)
				( attribute "ROOM" "SB_FILTER_ISCLK"
					( Origin gFrontEnd )
				)
				( attribute "ROT" "0"
					( Origin gFrontEnd )
				)
				( attribute "SEC" "1"
					( Origin gFrontEnd )
				)
				( attribute "SEC_TYPE" "SM"
					( Origin gFrontEnd )
				)
				( attribute "VALUE" "120"
					( Origin gFrontEnd )
				)
				( attribute "VER" "1"
					( Origin gFrontEnd )
				)
				( attribute "XY" "(1150,-3075)"
					( Origin gFrontEnd )
				)
				( attribute "CHIPS_PART_NAME" "FERRITE"
					( Origin gPackager )
				)
				( attribute "CDS_PART_NAME" "FERRITE_SM-120,FB,693286-027"
					( Origin gPackager )
				)
				( objectStatus "FB3M4" )
			)
			( gate "@baseboard_fab2_lib.baseboard_fab2(sch_1):page127_i57"
				( attribute "BOM_COST" "SB"
					( Origin gFrontEnd )
				)
				( attribute "CDS_LIB" "dev_discrete"
					( Origin gPackager )
				)
				( attribute "CDS_LOCATION" "C3M31"
					( Origin gPackager )
				)
				( attribute "CDS_SEC" "1"
					( Origin gPackager )
				)
				( attribute "LOCATION" "C3M31"
					( Origin gFrontEnd )
				)
				( attribute "MATERIAL" "X6S"
					( Origin gFrontEnd )
				)
				( attribute "PACK_TYPE" "0402V"
					( Origin gFrontEnd )
				)
				( attribute "PART_NUMBER" "D97712-004"
					( Origin gFrontEnd )
				)
				( attribute "PHYS_PAGE" "127"
					( Origin gFrontEnd )
				)
				( attribute "ROOM" "SB_FILTER_ISCLK"
					( Origin gFrontEnd )
				)
				( attribute "ROT" "2"
					( Origin gFrontEnd )
				)
				( attribute "SEC" "1"
					( Origin gFrontEnd )
				)
				( attribute "SEC_TYPE" "0402V"
					( Origin gFrontEnd )
				)
				( attribute "TOLERANCE" "10%"
					( Origin gFrontEnd )
				)
				( attribute "VALUE" "1.0UF"
					( Origin gFrontEnd )
				)
				( attribute "VER" "1"
					( Origin gFrontEnd )
				)
				( attribute "VOLTAGE" "6.3V"
					( Units "uVoltage" "V" 1.000000)
					( Origin gFrontEnd )
				)
				( attribute "XY" "(950,-3275)"
					( Origin gFrontEnd )
				)
				( attribute "CHIPS_PART_NAME" "CAP_A"
					( Origin gPackager )
				)
				( attribute "CDS_PART_NAME" "CAP_A_0402V-1.0UF,6.3V,10%,X6SA"
					( Origin gPackager )
				)
				( objectStatus "C3M31" )
			)
			( gate "@baseboard_fab2_lib.baseboard_fab2(sch_1):page127_i64"
				( attribute "BOM_COST" "SB"
					( Origin gFrontEnd )
				)
				( attribute "CDS_LIB" "mstr_discrete"
					( Origin gPackager )
				)
				( attribute "CDS_LOCATION" "C2N6"
					( Origin gPackager )
				)
				( attribute "CDS_SEC" "1"
					( Origin gPackager )
				)
				( attribute "LOCATION" "C2N6"
					( Origin gFrontEnd )
				)
				( attribute "MATERIAL" "X6S"
					( Origin gFrontEnd )
				)
				( attribute "PACK_TYPE" "0603LF"
					( Origin gFrontEnd )
				)
				( attribute "PART_NUMBER" "E15431-001"
					( Origin gFrontEnd )
				)
				( attribute "PHYS_PAGE" "127"
					( Origin gFrontEnd )
				)
				( attribute "ROOM" "SB_FILTER_KR_PLL"
					( Origin gFrontEnd )
				)
				( attribute "ROT" "0"
					( Origin gFrontEnd )
				)
				( attribute "SEC" "1"
					( Origin gFrontEnd )
				)
				( attribute "SEC_TYPE" "0603LF"
					( Origin gFrontEnd )
				)
				( attribute "TOLERANCE" "20%"
					( Origin gFrontEnd )
				)
				( attribute "VALUE" "10UF"
					( Origin gFrontEnd )
				)
				( attribute "VER" "1"
					( Origin gFrontEnd )
				)
				( attribute "VOLTAGE" "4V"
					( Units "uVoltage" "V" 1.000000)
					( Origin gFrontEnd )
				)
				( attribute "XY" "(-500,-3300)"
					( Origin gFrontEnd )
				)
				( attribute "CHIPS_PART_NAME" "CAP"
					( Origin gPackager )
				)
				( attribute "CDS_PART_NAME" "CAP_0603LF-10UF,4V,20%,X6S,E15A"
					( Origin gPackager )
				)
				( objectStatus "C2N6" )
			)
			( gate "@baseboard_fab2_lib.baseboard_fab2(sch_1):page127_i65"
				( attribute "BOM_COST" "SB"
					( Origin gFrontEnd )
				)
				( attribute "CDS_LIB" "dev_discrete"
					( Origin gPackager )
				)
				( attribute "CDS_LOCATION" "C2N5"
					( Origin gPackager )
				)
				( attribute "CDS_SEC" "1"
					( Origin gPackager )
				)
				( attribute "LOCATION" "C2N5"
					( Origin gFrontEnd )
				)
				( attribute "MATERIAL" "X6S"
					( Origin gFrontEnd )
				)
				( attribute "PACK_TYPE" "0402V"
					( Origin gFrontEnd )
				)
				( attribute "PART_NUMBER" "D97712-004"
					( Origin gFrontEnd )
				)
				( attribute "PHYS_PAGE" "127"
					( Origin gFrontEnd )
				)
				( attribute "ROOM" "SB_FILTER_KR_PLL"
					( Origin gFrontEnd )
				)
				( attribute "ROT" "0"
					( Origin gFrontEnd )
				)
				( attribute "SEC" "1"
					( Origin gFrontEnd )
				)
				( attribute "SEC_TYPE" "0402V"
					( Origin gFrontEnd )
				)
				( attribute "TOLERANCE" "10%"
					( Origin gFrontEnd )
				)
				( attribute "VALUE" "1.0UF"
					( Origin gFrontEnd )
				)
				( attribute "VER" "1"
					( Origin gFrontEnd )
				)
				( attribute "VOLTAGE" "6.3V"
					( Units "uVoltage" "V" 1.000000)
					( Origin gFrontEnd )
				)
				( attribute "XY" "(-1000,-3300)"
					( Origin gFrontEnd )
				)
				( attribute "CHIPS_PART_NAME" "CAP_A"
					( Origin gPackager )
				)
				( attribute "CDS_PART_NAME" "CAP_A_0402V-1.0UF,6.3V,10%,X6SA"
					( Origin gPackager )
				)
				( objectStatus "C2N5" )
			)
			( gate "@baseboard_fab2_lib.baseboard_fab2(sch_1):page127_i69"
				( attribute "BOM_COST" "SB"
					( Origin gFrontEnd )
				)
				( attribute "CDS_LIB" "mstr_discrete"
					( Origin gPackager )
				)
				( attribute "CDS_LOCATION" "FB2M2"
					( Origin gPackager )
				)
				( attribute "CDS_SEC" "1"
					( Origin gPackager )
				)
				( attribute "LOCATION" "FB2M2"
					( Origin gFrontEnd )
				)
				( attribute "MATERIAL" "FB"
					( Origin gFrontEnd )
				)
				( attribute "PACK_TYPE" "SM"
					( Origin gFrontEnd )
				)
				( attribute "PART_NUMBER" "693286-027"
					( Origin gFrontEnd )
				)
				( attribute "PHYS_PAGE" "127"
					( Origin gFrontEnd )
				)
				( attribute "ROOM" "SB_FILTER_VM26"
					( Origin gFrontEnd )
				)
				( attribute "ROT" "0"
					( Origin gFrontEnd )
				)
				( attribute "SEC" "1"
					( Origin gFrontEnd )
				)
				( attribute "SEC_TYPE" "SM"
					( Origin gFrontEnd )
				)
				( attribute "VALUE" "120"
					( Origin gFrontEnd )
				)
				( attribute "VER" "1"
					( Origin gFrontEnd )
				)
				( attribute "XY" "(-1225,-1200)"
					( Origin gFrontEnd )
				)
				( attribute "CHIPS_PART_NAME" "FERRITE"
					( Origin gPackager )
				)
				( attribute "CDS_PART_NAME" "FERRITE_SM-120,FB,693286-027"
					( Origin gPackager )
				)
				( objectStatus "FB2M2" )
			)
			( gate "@baseboard_fab2_lib.baseboard_fab2(sch_1):page127_i71"
				( attribute "BOM_COST" "SB"
					( Origin gFrontEnd )
				)
				( attribute "CDS_LIB" "mstr_discrete"
					( Origin gPackager )
				)
				( attribute "CDS_LOCATION" "L2M1"
					( Origin gPackager )
				)
				( attribute "CDS_SEC" "1"
					( Origin gPackager )
				)
				( attribute "LOCATION" "L2M1"
					( Origin gFrontEnd )
				)
				( attribute "MATERIAL" "IND"
					( Origin gFrontEnd )
				)
				( attribute "PACK_TYPE" "SMT"
					( Origin gFrontEnd )
				)
				( attribute "PART_NUMBER" "721891-082"
					( Origin gFrontEnd )
				)
				( attribute "PHYS_PAGE" "127"
					( Origin gFrontEnd )
				)
				( attribute "ROOM" "SB_FILTER_KR_PLL"
					( Origin gFrontEnd )
				)
				( attribute "ROT" "0"
					( Origin gFrontEnd )
				)
				( attribute "SEC" "1"
					( Origin gFrontEnd )
				)
				( attribute "SEC_TYPE" "SMT"
					( Origin gFrontEnd )
				)
				( attribute "VALUE" "0.022UH"
					( Origin gFrontEnd )
				)
				( attribute "VER" "1"
					( Origin gFrontEnd )
				)
				( attribute "XY" "(-1250,-3100)"
					( Origin gFrontEnd )
				)
				( attribute "CHIPS_PART_NAME" "INDUCTOR"
					( Origin gPackager )
				)
				( attribute "CDS_PART_NAME" "INDUCTOR_SMT-0.022UH,IND,72189A"
					( Origin gPackager )
				)
				( objectStatus "L2M1" )
			)
			( gate "@baseboard_fab2_lib.baseboard_fab2(sch_1):page127_i74"
				( attribute "BOM_COST" "SB"
					( Origin gFrontEnd )
				)
				( attribute "CDS_LIB" "dev_discrete"
					( Origin gPackager )
				)
				( attribute "CDS_LOCATION" "C2M8"
					( Origin gPackager )
				)
				( attribute "CDS_SEC" "1"
					( Origin gPackager )
				)
				( attribute "LOCATION" "C2M8"
					( Origin gFrontEnd )
				)
				( attribute "MATERIAL" "X6S"
					( Origin gFrontEnd )
				)
				( attribute "PACK_TYPE" "0402V"
					( Origin gFrontEnd )
				)
				( attribute "PART_NUMBER" "D97712-004"
					( Origin gFrontEnd )
				)
				( attribute "PHYS_PAGE" "127"
					( Origin gFrontEnd )
				)
				( attribute "ROOM" "SB_FILTER_VM26"
					( Origin gFrontEnd )
				)
				( attribute "ROT" "2"
					( Origin gFrontEnd )
				)
				( attribute "SEC" "1"
					( Origin gFrontEnd )
				)
				( attribute "SEC_TYPE" "0402V"
					( Origin gFrontEnd )
				)
				( attribute "TOLERANCE" "10%"
					( Origin gFrontEnd )
				)
				( attribute "VALUE" "1.0UF"
					( Origin gFrontEnd )
				)
				( attribute "VER" "1"
					( Origin gFrontEnd )
				)
				( attribute "VOLTAGE" "6.3V"
					( Units "uVoltage" "V" 1.000000)
					( Origin gFrontEnd )
				)
				( attribute "XY" "(-1450,-1400)"
					( Origin gFrontEnd )
				)
				( attribute "CHIPS_PART_NAME" "CAP_A"
					( Origin gPackager )
				)
				( attribute "CDS_PART_NAME" "CAP_A_0402V-1.0UF,6.3V,10%,X6SA"
					( Origin gPackager )
				)
				( objectStatus "C2M8" )
			)
			( gate "@baseboard_fab2_lib.baseboard_fab2(sch_1):page127_i76"
				( attribute "BOM_COST" "SB"
					( Origin gFrontEnd )
				)
				( attribute "CDS_LIB" "dev_discrete"
					( Origin gPackager )
				)
				( attribute "CDS_LOCATION" "C2M6"
					( Origin gPackager )
				)
				( attribute "CDS_SEC" "1"
					( Origin gPackager )
				)
				( attribute "LOCATION" "C2M6"
					( Origin gFrontEnd )
				)
				( attribute "MATERIAL" "X6S"
					( Origin gFrontEnd )
				)
				( attribute "PACK_TYPE" "0402V"
					( Origin gFrontEnd )
				)
				( attribute "PART_NUMBER" "D97712-004"
					( Origin gFrontEnd )
				)
				( attribute "PHYS_PAGE" "127"
					( Origin gFrontEnd )
				)
				( attribute "ROOM" "SB_FILTER_VM20"
					( Origin gFrontEnd )
				)
				( attribute "ROT" "2"
					( Origin gFrontEnd )
				)
				( attribute "SEC" "1"
					( Origin gFrontEnd )
				)
				( attribute "SEC_TYPE" "0402V"
					( Origin gFrontEnd )
				)
				( attribute "TOLERANCE" "10%"
					( Origin gFrontEnd )
				)
				( attribute "VALUE" "1.0UF"
					( Origin gFrontEnd )
				)
				( attribute "VER" "1"
					( Origin gFrontEnd )
				)
				( attribute "VOLTAGE" "6.3V"
					( Units "uVoltage" "V" 1.000000)
					( Origin gFrontEnd )
				)
				( attribute "XY" "(950,-1375)"
					( Origin gFrontEnd )
				)
				( attribute "CHIPS_PART_NAME" "CAP_A"
					( Origin gPackager )
				)
				( attribute "CDS_PART_NAME" "CAP_A_0402V-1.0UF,6.3V,10%,X6SA"
					( Origin gPackager )
				)
				( objectStatus "C2M6" )
			)
			( gate "@baseboard_fab2_lib.baseboard_fab2(sch_1):page127_i78"
				( attribute "BOM_COST" "SB"
					( Origin gFrontEnd )
				)
				( attribute "CDS_LIB" "dev_discrete"
					( Origin gPackager )
				)
				( attribute "CDS_LOCATION" "C2M25"
					( Origin gPackager )
				)
				( attribute "CDS_SEC" "1"
					( Origin gPackager )
				)
				( attribute "LOCATION" "C2M25"
					( Origin gFrontEnd )
				)
				( attribute "MATERIAL" "X6S"
					( Origin gFrontEnd )
				)
				( attribute "PACK_TYPE" "0402V"
					( Origin gFrontEnd )
				)
				( attribute "PART_NUMBER" "D97712-004"
					( Origin gFrontEnd )
				)
				( attribute "PHYS_PAGE" "127"
					( Origin gFrontEnd )
				)
				( attribute "ROOM" "SB_FILTER_KR_PLL"
					( Origin gFrontEnd )
				)
				( attribute "ROT" "2"
					( Origin gFrontEnd )
				)
				( attribute "SEC" "1"
					( Origin gFrontEnd )
				)
				( attribute "SEC_TYPE" "0402V"
					( Origin gFrontEnd )
				)
				( attribute "TOLERANCE" "10%"
					( Origin gFrontEnd )
				)
				( attribute "VALUE" "1.0UF"
					( Origin gFrontEnd )
				)
				( attribute "VER" "1"
					( Origin gFrontEnd )
				)
				( attribute "VOLTAGE" "6.3V"
					( Units "uVoltage" "V" 1.000000)
					( Origin gFrontEnd )
				)
				( attribute "XY" "(-1450,-3300)"
					( Origin gFrontEnd )
				)
				( attribute "CHIPS_PART_NAME" "CAP_A"
					( Origin gPackager )
				)
				( attribute "CDS_PART_NAME" "CAP_A_0402V-1.0UF,6.3V,10%,X6SA"
					( Origin gPackager )
				)
				( objectStatus "C2M25" )
			)
			( gate "@baseboard_fab2_lib.baseboard_fab2(sch_1):page127_i80"
				( attribute "BOM_COST" "SB"
					( Origin gFrontEnd )
				)
				( attribute "CDS_LIB" "dev_discrete"
					( Origin gPackager )
				)
				( attribute "CDS_LOCATION" "C3M29"
					( Origin gPackager )
				)
				( attribute "CDS_SEC" "1"
					( Origin gPackager )
				)
				( attribute "LOCATION" "C3M29"
					( Origin gFrontEnd )
				)
				( attribute "MATERIAL" "X6S"
					( Origin gFrontEnd )
				)
				( attribute "PACK_TYPE" "0402V"
					( Origin gFrontEnd )
				)
				( attribute "PART_NUMBER" "D97712-004"
					( Origin gFrontEnd )
				)
				( attribute "PHYS_PAGE" "127"
					( Origin gFrontEnd )
				)
				( attribute "ROOM" "SB_FILTER_ISCLK"
					( Origin gFrontEnd )
				)
				( attribute "ROT" "0"
					( Origin gFrontEnd )
				)
				( attribute "SEC" "1"
					( Origin gFrontEnd )
				)
				( attribute "SEC_TYPE" "0402V"
					( Origin gFrontEnd )
				)
				( attribute "TOLERANCE" "10%"
					( Origin gFrontEnd )
				)
				( attribute "VALUE" "1.0UF"
					( Origin gFrontEnd )
				)
				( attribute "VER" "1"
					( Origin gFrontEnd )
				)
				( attribute "VOLTAGE" "6.3V"
					( Units "uVoltage" "V" 1.000000)
					( Origin gFrontEnd )
				)
				( attribute "XY" "(1400,-3275)"
					( Origin gFrontEnd )
				)
				( attribute "CHIPS_PART_NAME" "CAP_A"
					( Origin gPackager )
				)
				( attribute "CDS_PART_NAME" "CAP_A_0402V-1.0UF,6.3V,10%,X6SA"
					( Origin gPackager )
				)
				( objectStatus "C3M29" )
			)
			( gate "@baseboard_fab2_lib.baseboard_fab2(sch_1):page127_i81"
				( attribute "BOM_COST" "SB"
					( Origin gFrontEnd )
				)
				( attribute "CDS_LIB" "mstr_discrete"
					( Origin gPackager )
				)
				( attribute "CDS_LOCATION" "C3M24"
					( Origin gPackager )
				)
				( attribute "CDS_SEC" "1"
					( Origin gPackager )
				)
				( attribute "LOCATION" "C3M24"
					( Origin gFrontEnd )
				)
				( attribute "MATERIAL" "X6S"
					( Origin gFrontEnd )
				)
				( attribute "PACK_TYPE" "0603LF"
					( Origin gFrontEnd )
				)
				( attribute "PART_NUMBER" "E15431-001"
					( Origin gFrontEnd )
				)
				( attribute "PHYS_PAGE" "127"
					( Origin gFrontEnd )
				)
				( attribute "ROOM" "SB_FILTER_ISCLK"
					( Origin gFrontEnd )
				)
				( attribute "ROT" "0"
					( Origin gFrontEnd )
				)
				( attribute "SEC" "1"
					( Origin gFrontEnd )
				)
				( attribute "SEC_TYPE" "0603LF"
					( Origin gFrontEnd )
				)
				( attribute "TOLERANCE" "20%"
					( Origin gFrontEnd )
				)
				( attribute "VALUE" "10UF"
					( Origin gFrontEnd )
				)
				( attribute "VER" "1"
					( Origin gFrontEnd )
				)
				( attribute "VOLTAGE" "4V"
					( Units "uVoltage" "V" 1.000000)
					( Origin gFrontEnd )
				)
				( attribute "XY" "(1700,-3275)"
					( Origin gFrontEnd )
				)
				( attribute "CHIPS_PART_NAME" "CAP"
					( Origin gPackager )
				)
				( attribute "CDS_PART_NAME" "CAP_0603LF-10UF,4V,20%,X6S,E15A"
					( Origin gPackager )
				)
				( objectStatus "C3M24" )
			)
			( gate "@baseboard_fab2_lib.baseboard_fab2(sch_1):page127_i82"
				( attribute "BOM_COST" "SB"
					( Origin gFrontEnd )
				)
				( attribute "CDS_LIB" "mstr_discrete"
					( Origin gPackager )
				)
				( attribute "CDS_LOCATION" "C3M23"
					( Origin gPackager )
				)
				( attribute "CDS_SEC" "1"
					( Origin gPackager )
				)
				( attribute "LOCATION" "C3M23"
					( Origin gFrontEnd )
				)
				( attribute "MATERIAL" "X6S"
					( Origin gFrontEnd )
				)
				( attribute "PACK_TYPE" "0603LF"
					( Origin gFrontEnd )
				)
				( attribute "PART_NUMBER" "E15431-001"
					( Origin gFrontEnd )
				)
				( attribute "PHYS_PAGE" "127"
					( Origin gFrontEnd )
				)
				( attribute "ROOM" "SB_FILTER_XTAL"
					( Origin gFrontEnd )
				)
				( attribute "ROT" "0"
					( Origin gFrontEnd )
				)
				( attribute "SEC" "1"
					( Origin gFrontEnd )
				)
				( attribute "SEC_TYPE" "0603LF"
					( Origin gFrontEnd )
				)
				( attribute "TOLERANCE" "20%"
					( Origin gFrontEnd )
				)
				( attribute "VALUE" "10UF"
					( Origin gFrontEnd )
				)
				( attribute "VER" "1"
					( Origin gFrontEnd )
				)
				( attribute "VOLTAGE" "4V"
					( Units "uVoltage" "V" 1.000000)
					( Origin gFrontEnd )
				)
				( attribute "XY" "(-2550,-3600)"
					( Origin gFrontEnd )
				)
				( attribute "CHIPS_PART_NAME" "CAP"
					( Origin gPackager )
				)
				( attribute "CDS_PART_NAME" "CAP_0603LF-10UF,4V,20%,X6S,E15A"
					( Origin gPackager )
				)
				( objectStatus "C3M23" )
			)
			( gate "@baseboard_fab2_lib.baseboard_fab2(sch_1):page127_i83"
				( attribute "BOM_COST" "SB"
					( Origin gFrontEnd )
				)
				( attribute "CDS_LIB" "dev_discrete"
					( Origin gPackager )
				)
				( attribute "CDS_LOCATION" "C3M27"
					( Origin gPackager )
				)
				( attribute "CDS_SEC" "1"
					( Origin gPackager )
				)
				( attribute "LOCATION" "C3M27"
					( Origin gFrontEnd )
				)
				( attribute "MATERIAL" "X6S"
					( Origin gFrontEnd )
				)
				( attribute "PACK_TYPE" "0402V"
					( Origin gFrontEnd )
				)
				( attribute "PART_NUMBER" "D97712-004"
					( Origin gFrontEnd )
				)
				( attribute "PHYS_PAGE" "127"
					( Origin gFrontEnd )
				)
				( attribute "ROOM" "SB_FILTER_XTAL"
					( Origin gFrontEnd )
				)
				( attribute "ROT" "0"
					( Origin gFrontEnd )
				)
				( attribute "SEC" "1"
					( Origin gFrontEnd )
				)
				( attribute "SEC_TYPE" "0402V"
					( Origin gFrontEnd )
				)
				( attribute "TOLERANCE" "10%"
					( Origin gFrontEnd )
				)
				( attribute "VALUE" "1.0UF"
					( Origin gFrontEnd )
				)
				( attribute "VER" "1"
					( Origin gFrontEnd )
				)
				( attribute "VOLTAGE" "6.3V"
					( Units "uVoltage" "V" 1.000000)
					( Origin gFrontEnd )
				)
				( attribute "XY" "(-3400,-3550)"
					( Origin gFrontEnd )
				)
				( attribute "CHIPS_PART_NAME" "CAP_A"
					( Origin gPackager )
				)
				( attribute "CDS_PART_NAME" "CAP_A_0402V-1.0UF,6.3V,10%,X6SA"
					( Origin gPackager )
				)
				( objectStatus "C3M27" )
			)
			( gate "@baseboard_fab2_lib.baseboard_fab2(sch_1):page127_i84"
				( attribute "BOM_COST" "SB"
					( Origin gFrontEnd )
				)
				( attribute "CDS_LIB" "dev_discrete"
					( Origin gPackager )
				)
				( attribute "CDS_LOCATION" "C3M20"
					( Origin gPackager )
				)
				( attribute "CDS_SEC" "1"
					( Origin gPackager )
				)
				( attribute "LOCATION" "C3M20"
					( Origin gFrontEnd )
				)
				( attribute "MATERIAL" "X6S"
					( Origin gFrontEnd )
				)
				( attribute "PACK_TYPE" "0402V"
					( Origin gFrontEnd )
				)
				( attribute "PART_NUMBER" "D97712-004"
					( Origin gFrontEnd )
				)
				( attribute "PHYS_PAGE" "127"
					( Origin gFrontEnd )
				)
				( attribute "ROOM" "SB_FILTER_PLL1"
					( Origin gFrontEnd )
				)
				( attribute "ROT" "0"
					( Origin gFrontEnd )
				)
				( attribute "SEC" "1"
					( Origin gFrontEnd )
				)
				( attribute "SEC_TYPE" "0402V"
					( Origin gFrontEnd )
				)
				( attribute "TOLERANCE" "10%"
					( Origin gFrontEnd )
				)
				( attribute "VALUE" "1.0UF"
					( Origin gFrontEnd )
				)
				( attribute "VER" "1"
					( Origin gFrontEnd )
				)
				( attribute "VOLTAGE" "6.3V"
					( Units "uVoltage" "V" 1.000000)
					( Origin gFrontEnd )
				)
				( attribute "XY" "(-3425,-2250)"
					( Origin gFrontEnd )
				)
				( attribute "CHIPS_PART_NAME" "CAP_A"
					( Origin gPackager )
				)
				( attribute "CDS_PART_NAME" "CAP_A_0402V-1.0UF,6.3V,10%,X6SA"
					( Origin gPackager )
				)
				( objectStatus "C3M20" )
			)
			( gate "@baseboard_fab2_lib.baseboard_fab2(sch_1):page127_i85"
				( attribute "BOM_COST" "SB"
					( Origin gFrontEnd )
				)
				( attribute "CDS_LIB" "mstr_discrete"
					( Origin gPackager )
				)
				( attribute "CDS_LOCATION" "C3M18"
					( Origin gPackager )
				)
				( attribute "CDS_SEC" "1"
					( Origin gPackager )
				)
				( attribute "LOCATION" "C3M18"
					( Origin gFrontEnd )
				)
				( attribute "MATERIAL" "X6S"
					( Origin gFrontEnd )
				)
				( attribute "PACK_TYPE" "0603LF"
					( Origin gFrontEnd )
				)
				( attribute "PART_NUMBER" "E15431-001"
					( Origin gFrontEnd )
				)
				( attribute "PHYS_PAGE" "127"
					( Origin gFrontEnd )
				)
				( attribute "ROOM" "SB_FILTER_PLL1"
					( Origin gFrontEnd )
				)
				( attribute "ROT" "0"
					( Origin gFrontEnd )
				)
				( attribute "SEC" "1"
					( Origin gFrontEnd )
				)
				( attribute "SEC_TYPE" "0603LF"
					( Origin gFrontEnd )
				)
				( attribute "TOLERANCE" "20%"
					( Origin gFrontEnd )
				)
				( attribute "VALUE" "10UF"
					( Origin gFrontEnd )
				)
				( attribute "VER" "1"
					( Origin gFrontEnd )
				)
				( attribute "VOLTAGE" "4V"
					( Units "uVoltage" "V" 1.000000)
					( Origin gFrontEnd )
				)
				( attribute "XY" "(-2575,-2325)"
					( Origin gFrontEnd )
				)
				( attribute "CHIPS_PART_NAME" "CAP"
					( Origin gPackager )
				)
				( attribute "CDS_PART_NAME" "CAP_0603LF-10UF,4V,20%,X6S,E15A"
					( Origin gPackager )
				)
				( objectStatus "C3M18" )
			)
			( gate "@baseboard_fab2_lib.baseboard_fab2(sch_1):page127_i86"
				( attribute "BOM_COST" "SB"
					( Origin gFrontEnd )
				)
				( attribute "CDS_LIB" "mstr_discrete"
					( Origin gPackager )
				)
				( attribute "CDS_LOCATION" "C3M17"
					( Origin gPackager )
				)
				( attribute "CDS_SEC" "1"
					( Origin gPackager )
				)
				( attribute "LOCATION" "C3M17"
					( Origin gFrontEnd )
				)
				( attribute "MATERIAL" "X6S"
					( Origin gFrontEnd )
				)
				( attribute "PACK_TYPE" "0603LF"
					( Origin gFrontEnd )
				)
				( attribute "PART_NUMBER" "E15431-001"
					( Origin gFrontEnd )
				)
				( attribute "PHYS_PAGE" "127"
					( Origin gFrontEnd )
				)
				( attribute "ROOM" "SB_FILTER_PLL0"
					( Origin gFrontEnd )
				)
				( attribute "ROT" "0"
					( Origin gFrontEnd )
				)
				( attribute "SEC" "1"
					( Origin gFrontEnd )
				)
				( attribute "SEC_TYPE" "0603LF"
					( Origin gFrontEnd )
				)
				( attribute "TOLERANCE" "20%"
					( Origin gFrontEnd )
				)
				( attribute "VALUE" "10UF"
					( Origin gFrontEnd )
				)
				( attribute "VER" "1"
					( Origin gFrontEnd )
				)
				( attribute "VOLTAGE" "4V"
					( Units "uVoltage" "V" 1.000000)
					( Origin gFrontEnd )
				)
				( attribute "XY" "(-2575,-1075)"
					( Origin gFrontEnd )
				)
				( attribute "CHIPS_PART_NAME" "CAP"
					( Origin gPackager )
				)
				( attribute "CDS_PART_NAME" "CAP_0603LF-10UF,4V,20%,X6S,E15A"
					( Origin gPackager )
				)
				( objectStatus "C3M17" )
			)
			( gate "@baseboard_fab2_lib.baseboard_fab2(sch_1):page127_i87"
				( attribute "BOM_COST" "SB"
					( Origin gFrontEnd )
				)
				( attribute "CDS_LIB" "dev_discrete"
					( Origin gPackager )
				)
				( attribute "CDS_LOCATION" "C3M19"
					( Origin gPackager )
				)
				( attribute "CDS_SEC" "1"
					( Origin gPackager )
				)
				( attribute "LOCATION" "C3M19"
					( Origin gFrontEnd )
				)
				( attribute "MATERIAL" "X6S"
					( Origin gFrontEnd )
				)
				( attribute "PACK_TYPE" "0402V"
					( Origin gFrontEnd )
				)
				( attribute "PART_NUMBER" "D97712-004"
					( Origin gFrontEnd )
				)
				( attribute "PHYS_PAGE" "127"
					( Origin gFrontEnd )
				)
				( attribute "ROOM" "SB_FILTER_PLL0"
					( Origin gFrontEnd )
				)
				( attribute "ROT" "0"
					( Origin gFrontEnd )
				)
				( attribute "SEC" "1"
					( Origin gFrontEnd )
				)
				( attribute "SEC_TYPE" "0402V"
					( Origin gFrontEnd )
				)
				( attribute "TOLERANCE" "10%"
					( Origin gFrontEnd )
				)
				( attribute "VALUE" "1.0UF"
					( Origin gFrontEnd )
				)
				( attribute "VER" "1"
					( Origin gFrontEnd )
				)
				( attribute "VOLTAGE" "6.3V"
					( Units "uVoltage" "V" 1.000000)
					( Origin gFrontEnd )
				)
				( attribute "XY" "(-3450,-1050)"
					( Origin gFrontEnd )
				)
				( attribute "CHIPS_PART_NAME" "CAP_A"
					( Origin gPackager )
				)
				( attribute "CDS_PART_NAME" "CAP_A_0402V-1.0UF,6.3V,10%,X6SA"
					( Origin gPackager )
				)
				( objectStatus "C3M19" )
			)
			( gate "@baseboard_fab2_lib.baseboard_fab2(sch_1):page129_i35"
				( attribute "BOM_COST" "SB"
					( Origin gFrontEnd )
				)
				( attribute "CDS_LIB" "mstr_discrete"
					( Origin gPackager )
				)
				( attribute "CDS_LOCATION" "C7B25"
					( Origin gPackager )
				)
				( attribute "CDS_SEC" "1"
					( Origin gPackager )
				)
				( attribute "LOCATION" "C7B25"
					( Origin gFrontEnd )
				)
				( attribute "MATERIAL" "X7R"
					( Origin gFrontEnd )
				)
				( attribute "PACK_TYPE" "0402"
					( Origin gFrontEnd )
				)
				( attribute "PART_NUMBER" "A36096-155"
					( Origin gFrontEnd )
				)
				( attribute "PHYS_PAGE" "129"
					( Origin gFrontEnd )
				)
				( attribute "ROOM" "DMI"
					( Origin gFrontEnd )
				)
				( attribute "ROT" "1"
					( Origin gFrontEnd )
				)
				( attribute "SEC" "1"
					( Origin gPackager )
				)
				( attribute "TOLERANCE" "10%"
					( Origin gFrontEnd )
				)
				( attribute "VALUE" "0.22UF"
					( Origin gFrontEnd )
				)
				( attribute "VER" "1"
					( Origin gFrontEnd )
				)
				( attribute "VOLTAGE" "16V"
					( Units "uVoltage" "V" 1.000000)
					( Origin gFrontEnd )
				)
				( attribute "XY" "(-3650,4925)"
					( Origin gFrontEnd )
				)
				( attribute "CHIPS_PART_NAME" "CAP"
					( Origin gPackager )
				)
				( attribute "CDS_PART_NAME" "CAP_0402-0.22UF,16V,10%,X7R,A3A"
					( Origin gPackager )
				)
				( objectStatus "C7B25" )
			)
			( gate "@baseboard_fab2_lib.baseboard_fab2(sch_1):page129_i69"
				( attribute "BOM_COST" "SB"
					( Origin gFrontEnd )
				)
				( attribute "CDS_LIB" "mstr_discrete"
					( Origin gPackager )
				)
				( attribute "CDS_LOCATION" "C7B27"
					( Origin gPackager )
				)
				( attribute "CDS_SEC" "1"
					( Origin gPackager )
				)
				( attribute "LOCATION" "C7B27"
					( Origin gFrontEnd )
				)
				( attribute "MATERIAL" "X7R"
					( Origin gFrontEnd )
				)
				( attribute "PACK_TYPE" "0402"
					( Origin gFrontEnd )
				)
				( attribute "PART_NUMBER" "A36096-155"
					( Origin gFrontEnd )
				)
				( attribute "PHYS_PAGE" "129"
					( Origin gFrontEnd )
				)
				( attribute "ROOM" "DMI"
					( Origin gFrontEnd )
				)
				( attribute "ROT" "1"
					( Origin gFrontEnd )
				)
				( attribute "SEC" "1"
					( Origin gPackager )
				)
				( attribute "TOLERANCE" "10%"
					( Origin gFrontEnd )
				)
				( attribute "VALUE" "0.22UF"
					( Origin gFrontEnd )
				)
				( attribute "VER" "1"
					( Origin gFrontEnd )
				)
				( attribute "VOLTAGE" "16V"
					( Units "uVoltage" "V" 1.000000)
					( Origin gFrontEnd )
				)
				( attribute "XY" "(-3300,4725)"
					( Origin gFrontEnd )
				)
				( attribute "CHIPS_PART_NAME" "CAP"
					( Origin gPackager )
				)
				( attribute "CDS_PART_NAME" "CAP_0402-0.22UF,16V,10%,X7R,A3A"
					( Origin gPackager )
				)
				( objectStatus "C7B27" )
			)
			( gate "@baseboard_fab2_lib.baseboard_fab2(sch_1):page129_i70"
				( attribute "BOM_COST" "SB"
					( Origin gFrontEnd )
				)
				( attribute "CDS_LIB" "mstr_discrete"
					( Origin gPackager )
				)
				( attribute "CDS_LOCATION" "C7B28"
					( Origin gPackager )
				)
				( attribute "CDS_SEC" "1"
					( Origin gPackager )
				)
				( attribute "LOCATION" "C7B28"
					( Origin gFrontEnd )
				)
				( attribute "MATERIAL" "X7R"
					( Origin gFrontEnd )
				)
				( attribute "PACK_TYPE" "0402"
					( Origin gFrontEnd )
				)
				( attribute "PART_NUMBER" "A36096-155"
					( Origin gFrontEnd )
				)
				( attribute "PHYS_PAGE" "129"
					( Origin gFrontEnd )
				)
				( attribute "ROOM" "DMI"
					( Origin gFrontEnd )
				)
				( attribute "ROT" "1"
					( Origin gFrontEnd )
				)
				( attribute "SEC" "1"
					( Origin gPackager )
				)
				( attribute "TOLERANCE" "10%"
					( Origin gFrontEnd )
				)
				( attribute "VALUE" "0.22UF"
					( Origin gFrontEnd )
				)
				( attribute "VER" "1"
					( Origin gFrontEnd )
				)
				( attribute "VOLTAGE" "16V"
					( Units "uVoltage" "V" 1.000000)
					( Origin gFrontEnd )
				)
				( attribute "XY" "(-3650,4525)"
					( Origin gFrontEnd )
				)
				( attribute "CHIPS_PART_NAME" "CAP"
					( Origin gPackager )
				)
				( attribute "CDS_PART_NAME" "CAP_0402-0.22UF,16V,10%,X7R,A3A"
					( Origin gPackager )
				)
				( objectStatus "C7B28" )
			)
			( gate "@baseboard_fab2_lib.baseboard_fab2(sch_1):page129_i71"
				( attribute "BOM_COST" "SB"
					( Origin gFrontEnd )
				)
				( attribute "CDS_LIB" "mstr_discrete"
					( Origin gPackager )
				)
				( attribute "CDS_LOCATION" "C7C2"
					( Origin gPackager )
				)
				( attribute "CDS_SEC" "1"
					( Origin gPackager )
				)
				( attribute "LOCATION" "C7C2"
					( Origin gFrontEnd )
				)
				( attribute "MATERIAL" "X7R"
					( Origin gFrontEnd )
				)
				( attribute "PACK_TYPE" "0402"
					( Origin gFrontEnd )
				)
				( attribute "PART_NUMBER" "A36096-155"
					( Origin gFrontEnd )
				)
				( attribute "PHYS_PAGE" "129"
					( Origin gFrontEnd )
				)
				( attribute "ROOM" "DMI"
					( Origin gFrontEnd )
				)
				( attribute "ROT" "1"
					( Origin gFrontEnd )
				)
				( attribute "SEC" "1"
					( Origin gPackager )
				)
				( attribute "TOLERANCE" "10%"
					( Origin gFrontEnd )
				)
				( attribute "VALUE" "0.22UF"
					( Origin gFrontEnd )
				)
				( attribute "VER" "1"
					( Origin gFrontEnd )
				)
				( attribute "VOLTAGE" "16V"
					( Units "uVoltage" "V" 1.000000)
					( Origin gFrontEnd )
				)
				( attribute "XY" "(-3300,4325)"
					( Origin gFrontEnd )
				)
				( attribute "CHIPS_PART_NAME" "CAP"
					( Origin gPackager )
				)
				( attribute "CDS_PART_NAME" "CAP_0402-0.22UF,16V,10%,X7R,A3A"
					( Origin gPackager )
				)
				( objectStatus "C7C2" )
			)
			( gate "@baseboard_fab2_lib.baseboard_fab2(sch_1):page129_i72"
				( attribute "BOM_COST" "SB"
					( Origin gFrontEnd )
				)
				( attribute "CDS_LIB" "mstr_discrete"
					( Origin gPackager )
				)
				( attribute "CDS_LOCATION" "C3M40"
					( Origin gPackager )
				)
				( attribute "CDS_SEC" "1"
					( Origin gPackager )
				)
				( attribute "LOCATION" "C3M40"
					( Origin gFrontEnd )
				)
				( attribute "MATERIAL" "X7R"
					( Origin gFrontEnd )
				)
				( attribute "PACK_TYPE" "0402"
					( Origin gFrontEnd )
				)
				( attribute "PART_NUMBER" "A36096-155"
					( Origin gFrontEnd )
				)
				( attribute "PHYS_PAGE" "129"
					( Origin gFrontEnd )
				)
				( attribute "ROOM" "DMI"
					( Origin gFrontEnd )
				)
				( attribute "ROT" "1"
					( Origin gFrontEnd )
				)
				( attribute "SEC" "1"
					( Origin gPackager )
				)
				( attribute "TOLERANCE" "10%"
					( Origin gFrontEnd )
				)
				( attribute "VALUE" "0.22UF"
					( Origin gFrontEnd )
				)
				( attribute "VER" "1"
					( Origin gFrontEnd )
				)
				( attribute "VOLTAGE" "16V"
					( Units "uVoltage" "V" 1.000000)
					( Origin gFrontEnd )
				)
				( attribute "XY" "(-3300,3375)"
					( Origin gFrontEnd )
				)
				( attribute "CHIPS_PART_NAME" "CAP"
					( Origin gPackager )
				)
				( attribute "CDS_PART_NAME" "CAP_0402-0.22UF,16V,10%,X7R,A3A"
					( Origin gPackager )
				)
				( objectStatus "C3M40" )
			)
			( gate "@baseboard_fab2_lib.baseboard_fab2(sch_1):page129_i73"
				( attribute "BOM_COST" "SB"
					( Origin gFrontEnd )
				)
				( attribute "CDS_LIB" "mstr_discrete"
					( Origin gPackager )
				)
				( attribute "CDS_LOCATION" "C3M37"
					( Origin gPackager )
				)
				( attribute "CDS_SEC" "1"
					( Origin gPackager )
				)
				( attribute "LOCATION" "C3M37"
					( Origin gFrontEnd )
				)
				( attribute "MATERIAL" "X7R"
					( Origin gFrontEnd )
				)
				( attribute "PACK_TYPE" "0402"
					( Origin gFrontEnd )
				)
				( attribute "PART_NUMBER" "A36096-155"
					( Origin gFrontEnd )
				)
				( attribute "PHYS_PAGE" "129"
					( Origin gFrontEnd )
				)
				( attribute "ROOM" "DMI"
					( Origin gFrontEnd )
				)
				( attribute "ROT" "1"
					( Origin gFrontEnd )
				)
				( attribute "SEC" "1"
					( Origin gPackager )
				)
				( attribute "TOLERANCE" "10%"
					( Origin gFrontEnd )
				)
				( attribute "VALUE" "0.22UF"
					( Origin gFrontEnd )
				)
				( attribute "VER" "1"
					( Origin gFrontEnd )
				)
				( attribute "VOLTAGE" "16V"
					( Units "uVoltage" "V" 1.000000)
					( Origin gFrontEnd )
				)
				( attribute "XY" "(-3650,3575)"
					( Origin gFrontEnd )
				)
				( attribute "CHIPS_PART_NAME" "CAP"
					( Origin gPackager )
				)
				( attribute "CDS_PART_NAME" "CAP_0402-0.22UF,16V,10%,X7R,A3A"
					( Origin gPackager )
				)
				( objectStatus "C3M37" )
			)
			( gate "@baseboard_fab2_lib.baseboard_fab2(sch_1):page129_i74"
				( attribute "BOM_COST" "SB"
					( Origin gFrontEnd )
				)
				( attribute "CDS_LIB" "mstr_discrete"
					( Origin gPackager )
				)
				( attribute "CDS_LOCATION" "C3N9"
					( Origin gPackager )
				)
				( attribute "CDS_SEC" "1"
					( Origin gPackager )
				)
				( attribute "LOCATION" "C3N9"
					( Origin gFrontEnd )
				)
				( attribute "MATERIAL" "X7R"
					( Origin gFrontEnd )
				)
				( attribute "PACK_TYPE" "0402"
					( Origin gFrontEnd )
				)
				( attribute "PART_NUMBER" "A36096-155"
					( Origin gFrontEnd )
				)
				( attribute "PHYS_PAGE" "129"
					( Origin gFrontEnd )
				)
				( attribute "ROOM" "DMI"
					( Origin gFrontEnd )
				)
				( attribute "ROT" "1"
					( Origin gFrontEnd )
				)
				( attribute "SEC" "1"
					( Origin gPackager )
				)
				( attribute "TOLERANCE" "10%"
					( Origin gFrontEnd )
				)
				( attribute "VALUE" "0.22UF"
					( Origin gFrontEnd )
				)
				( attribute "VER" "1"
					( Origin gFrontEnd )
				)
				( attribute "VOLTAGE" "16V"
					( Units "uVoltage" "V" 1.000000)
					( Origin gFrontEnd )
				)
				( attribute "XY" "(-3300,3775)"
					( Origin gFrontEnd )
				)
				( attribute "CHIPS_PART_NAME" "CAP"
					( Origin gPackager )
				)
				( attribute "CDS_PART_NAME" "CAP_0402-0.22UF,16V,10%,X7R,A3A"
					( Origin gPackager )
				)
				( objectStatus "C3N9" )
			)
			( gate "@baseboard_fab2_lib.baseboard_fab2(sch_1):page129_i75"
				( attribute "BOM_COST" "SB"
					( Origin gFrontEnd )
				)
				( attribute "CDS_LIB" "mstr_discrete"
					( Origin gPackager )
				)
				( attribute "CDS_LOCATION" "C3N8"
					( Origin gPackager )
				)
				( attribute "CDS_SEC" "1"
					( Origin gPackager )
				)
				( attribute "LOCATION" "C3N8"
					( Origin gFrontEnd )
				)
				( attribute "MATERIAL" "X7R"
					( Origin gFrontEnd )
				)
				( attribute "PACK_TYPE" "0402"
					( Origin gFrontEnd )
				)
				( attribute "PART_NUMBER" "A36096-155"
					( Origin gFrontEnd )
				)
				( attribute "PHYS_PAGE" "129"
					( Origin gFrontEnd )
				)
				( attribute "ROOM" "DMI"
					( Origin gFrontEnd )
				)
				( attribute "ROT" "1"
					( Origin gFrontEnd )
				)
				( attribute "SEC" "1"
					( Origin gPackager )
				)
				( attribute "TOLERANCE" "10%"
					( Origin gFrontEnd )
				)
				( attribute "VALUE" "0.22UF"
					( Origin gFrontEnd )
				)
				( attribute "VER" "1"
					( Origin gFrontEnd )
				)
				( attribute "VOLTAGE" "16V"
					( Units "uVoltage" "V" 1.000000)
					( Origin gFrontEnd )
				)
				( attribute "XY" "(-3650,3975)"
					( Origin gFrontEnd )
				)
				( attribute "CHIPS_PART_NAME" "CAP"
					( Origin gPackager )
				)
				( attribute "CDS_PART_NAME" "CAP_0402-0.22UF,16V,10%,X7R,A3A"
					( Origin gPackager )
				)
				( objectStatus "C3N8" )
			)
			( gate "@baseboard_fab2_lib.baseboard_fab2(sch_1):page129_i76"
				( attribute "BOM_COST" "SB"
					( Origin gFrontEnd )
				)
				( attribute "CDS_LIB" "mstr_discrete"
					( Origin gPackager )
				)
				( attribute "CDS_LOCATION" "C7C3"
					( Origin gPackager )
				)
				( attribute "CDS_SEC" "1"
					( Origin gPackager )
				)
				( attribute "LOCATION" "C7C3"
					( Origin gFrontEnd )
				)
				( attribute "MATERIAL" "X7R"
					( Origin gFrontEnd )
				)
				( attribute "PACK_TYPE" "0402"
					( Origin gFrontEnd )
				)
				( attribute "PART_NUMBER" "A36096-155"
					( Origin gFrontEnd )
				)
				( attribute "PHYS_PAGE" "129"
					( Origin gFrontEnd )
				)
				( attribute "ROOM" "DMI"
					( Origin gFrontEnd )
				)
				( attribute "ROT" "1"
					( Origin gFrontEnd )
				)
				( attribute "SEC" "1"
					( Origin gPackager )
				)
				( attribute "TOLERANCE" "10%"
					( Origin gFrontEnd )
				)
				( attribute "VALUE" "0.22UF"
					( Origin gFrontEnd )
				)
				( attribute "VER" "1"
					( Origin gFrontEnd )
				)
				( attribute "VOLTAGE" "16V"
					( Units "uVoltage" "V" 1.000000)
					( Origin gFrontEnd )
				)
				( attribute "XY" "(750,4325)"
					( Origin gFrontEnd )
				)
				( attribute "CHIPS_PART_NAME" "CAP"
					( Origin gPackager )
				)
				( attribute "CDS_PART_NAME" "CAP_0402-0.22UF,16V,10%,X7R,A3A"
					( Origin gPackager )
				)
				( objectStatus "C7C3" )
			)
			( gate "@baseboard_fab2_lib.baseboard_fab2(sch_1):page129_i77"
				( attribute "BOM_COST" "SB"
					( Origin gFrontEnd )
				)
				( attribute "CDS_LIB" "mstr_discrete"
					( Origin gPackager )
				)
				( attribute "CDS_LOCATION" "C7C1"
					( Origin gPackager )
				)
				( attribute "CDS_SEC" "1"
					( Origin gPackager )
				)
				( attribute "LOCATION" "C7C1"
					( Origin gFrontEnd )
				)
				( attribute "MATERIAL" "X7R"
					( Origin gFrontEnd )
				)
				( attribute "PACK_TYPE" "0402"
					( Origin gFrontEnd )
				)
				( attribute "PART_NUMBER" "A36096-155"
					( Origin gFrontEnd )
				)
				( attribute "PHYS_PAGE" "129"
					( Origin gFrontEnd )
				)
				( attribute "ROOM" "DMI"
					( Origin gFrontEnd )
				)
				( attribute "ROT" "1"
					( Origin gFrontEnd )
				)
				( attribute "SEC" "1"
					( Origin gPackager )
				)
				( attribute "TOLERANCE" "10%"
					( Origin gFrontEnd )
				)
				( attribute "VALUE" "0.22UF"
					( Origin gFrontEnd )
				)
				( attribute "VER" "1"
					( Origin gFrontEnd )
				)
				( attribute "VOLTAGE" "16V"
					( Units "uVoltage" "V" 1.000000)
					( Origin gFrontEnd )
				)
				( attribute "XY" "(400,4525)"
					( Origin gFrontEnd )
				)
				( attribute "CHIPS_PART_NAME" "CAP"
					( Origin gPackager )
				)
				( attribute "CDS_PART_NAME" "CAP_0402-0.22UF,16V,10%,X7R,A3A"
					( Origin gPackager )
				)
				( objectStatus "C7C1" )
			)
			( gate "@baseboard_fab2_lib.baseboard_fab2(sch_1):page129_i78"
				( attribute "BOM_COST" "SB"
					( Origin gFrontEnd )
				)
				( attribute "CDS_LIB" "mstr_discrete"
					( Origin gPackager )
				)
				( attribute "CDS_LOCATION" "C7B29"
					( Origin gPackager )
				)
				( attribute "CDS_SEC" "1"
					( Origin gPackager )
				)
				( attribute "LOCATION" "C7B29"
					( Origin gFrontEnd )
				)
				( attribute "MATERIAL" "X7R"
					( Origin gFrontEnd )
				)
				( attribute "PACK_TYPE" "0402"
					( Origin gFrontEnd )
				)
				( attribute "PART_NUMBER" "A36096-155"
					( Origin gFrontEnd )
				)
				( attribute "PHYS_PAGE" "129"
					( Origin gFrontEnd )
				)
				( attribute "ROOM" "DMI"
					( Origin gFrontEnd )
				)
				( attribute "ROT" "1"
					( Origin gFrontEnd )
				)
				( attribute "SEC" "1"
					( Origin gPackager )
				)
				( attribute "TOLERANCE" "10%"
					( Origin gFrontEnd )
				)
				( attribute "VALUE" "0.22UF"
					( Origin gFrontEnd )
				)
				( attribute "VER" "1"
					( Origin gFrontEnd )
				)
				( attribute "VOLTAGE" "16V"
					( Units "uVoltage" "V" 1.000000)
					( Origin gFrontEnd )
				)
				( attribute "XY" "(750,4725)"
					( Origin gFrontEnd )
				)
				( attribute "CHIPS_PART_NAME" "CAP"
					( Origin gPackager )
				)
				( attribute "CDS_PART_NAME" "CAP_0402-0.22UF,16V,10%,X7R,A3A"
					( Origin gPackager )
				)
				( objectStatus "C7B29" )
			)
			( gate "@baseboard_fab2_lib.baseboard_fab2(sch_1):page129_i79"
				( attribute "BOM_COST" "SB"
					( Origin gFrontEnd )
				)
				( attribute "CDS_LIB" "mstr_discrete"
					( Origin gPackager )
				)
				( attribute "CDS_LOCATION" "C7B26"
					( Origin gPackager )
				)
				( attribute "CDS_SEC" "1"
					( Origin gPackager )
				)
				( attribute "LOCATION" "C7B26"
					( Origin gFrontEnd )
				)
				( attribute "MATERIAL" "X7R"
					( Origin gFrontEnd )
				)
				( attribute "PACK_TYPE" "0402"
					( Origin gFrontEnd )
				)
				( attribute "PART_NUMBER" "A36096-155"
					( Origin gFrontEnd )
				)
				( attribute "PHYS_PAGE" "129"
					( Origin gFrontEnd )
				)
				( attribute "ROOM" "DMI"
					( Origin gFrontEnd )
				)
				( attribute "ROT" "1"
					( Origin gFrontEnd )
				)
				( attribute "SEC" "1"
					( Origin gPackager )
				)
				( attribute "TOLERANCE" "10%"
					( Origin gFrontEnd )
				)
				( attribute "VALUE" "0.22UF"
					( Origin gFrontEnd )
				)
				( attribute "VER" "1"
					( Origin gFrontEnd )
				)
				( attribute "VOLTAGE" "16V"
					( Units "uVoltage" "V" 1.000000)
					( Origin gFrontEnd )
				)
				( attribute "XY" "(400,4925)"
					( Origin gFrontEnd )
				)
				( attribute "CHIPS_PART_NAME" "CAP"
					( Origin gPackager )
				)
				( attribute "CDS_PART_NAME" "CAP_0402-0.22UF,16V,10%,X7R,A3A"
					( Origin gPackager )
				)
				( objectStatus "C7B26" )
			)
			( gate "@baseboard_fab2_lib.baseboard_fab2(sch_1):page129_i80"
				( attribute "BOM_COST" "SB"
					( Origin gFrontEnd )
				)
				( attribute "CDS_LIB" "mstr_discrete"
					( Origin gPackager )
				)
				( attribute "CDS_LOCATION" "C3M44"
					( Origin gPackager )
				)
				( attribute "CDS_SEC" "1"
					( Origin gPackager )
				)
				( attribute "LOCATION" "C3M44"
					( Origin gFrontEnd )
				)
				( attribute "MATERIAL" "X7R"
					( Origin gFrontEnd )
				)
				( attribute "PACK_TYPE" "0402"
					( Origin gFrontEnd )
				)
				( attribute "PART_NUMBER" "A36096-155"
					( Origin gFrontEnd )
				)
				( attribute "PHYS_PAGE" "129"
					( Origin gFrontEnd )
				)
				( attribute "ROOM" "DMI"
					( Origin gFrontEnd )
				)
				( attribute "ROT" "1"
					( Origin gFrontEnd )
				)
				( attribute "SEC" "1"
					( Origin gPackager )
				)
				( attribute "TOLERANCE" "10%"
					( Origin gFrontEnd )
				)
				( attribute "VALUE" "0.22UF"
					( Origin gFrontEnd )
				)
				( attribute "VER" "1"
					( Origin gFrontEnd )
				)
				( attribute "VOLTAGE" "16V"
					( Units "uVoltage" "V" 1.000000)
					( Origin gFrontEnd )
				)
				( attribute "XY" "(750,3375)"
					( Origin gFrontEnd )
				)
				( attribute "CHIPS_PART_NAME" "CAP"
					( Origin gPackager )
				)
				( attribute "CDS_PART_NAME" "CAP_0402-0.22UF,16V,10%,X7R,A3A"
					( Origin gPackager )
				)
				( objectStatus "C3M44" )
			)
			( gate "@baseboard_fab2_lib.baseboard_fab2(sch_1):page129_i81"
				( attribute "BOM_COST" "SB"
					( Origin gFrontEnd )
				)
				( attribute "CDS_LIB" "mstr_discrete"
					( Origin gPackager )
				)
				( attribute "CDS_LOCATION" "C3M41"
					( Origin gPackager )
				)
				( attribute "CDS_SEC" "1"
					( Origin gPackager )
				)
				( attribute "LOCATION" "C3M41"
					( Origin gFrontEnd )
				)
				( attribute "MATERIAL" "X7R"
					( Origin gFrontEnd )
				)
				( attribute "PACK_TYPE" "0402"
					( Origin gFrontEnd )
				)
				( attribute "PART_NUMBER" "A36096-155"
					( Origin gFrontEnd )
				)
				( attribute "PHYS_PAGE" "129"
					( Origin gFrontEnd )
				)
				( attribute "ROOM" "DMI"
					( Origin gFrontEnd )
				)
				( attribute "ROT" "1"
					( Origin gFrontEnd )
				)
				( attribute "SEC" "1"
					( Origin gPackager )
				)
				( attribute "TOLERANCE" "10%"
					( Origin gFrontEnd )
				)
				( attribute "VALUE" "0.22UF"
					( Origin gFrontEnd )
				)
				( attribute "VER" "1"
					( Origin gFrontEnd )
				)
				( attribute "VOLTAGE" "16V"
					( Units "uVoltage" "V" 1.000000)
					( Origin gFrontEnd )
				)
				( attribute "XY" "(400,3575)"
					( Origin gFrontEnd )
				)
				( attribute "CHIPS_PART_NAME" "CAP"
					( Origin gPackager )
				)
				( attribute "CDS_PART_NAME" "CAP_0402-0.22UF,16V,10%,X7R,A3A"
					( Origin gPackager )
				)
				( objectStatus "C3M41" )
			)
			( gate "@baseboard_fab2_lib.baseboard_fab2(sch_1):page129_i82"
				( attribute "BOM_COST" "SB"
					( Origin gFrontEnd )
				)
				( attribute "CDS_LIB" "mstr_discrete"
					( Origin gPackager )
				)
				( attribute "CDS_LOCATION" "C3M45"
					( Origin gPackager )
				)
				( attribute "CDS_SEC" "1"
					( Origin gPackager )
				)
				( attribute "LOCATION" "C3M45"
					( Origin gFrontEnd )
				)
				( attribute "MATERIAL" "X7R"
					( Origin gFrontEnd )
				)
				( attribute "PACK_TYPE" "0402"
					( Origin gFrontEnd )
				)
				( attribute "PART_NUMBER" "A36096-155"
					( Origin gFrontEnd )
				)
				( attribute "PHYS_PAGE" "129"
					( Origin gFrontEnd )
				)
				( attribute "ROOM" "DMI"
					( Origin gFrontEnd )
				)
				( attribute "ROT" "1"
					( Origin gFrontEnd )
				)
				( attribute "SEC" "1"
					( Origin gPackager )
				)
				( attribute "TOLERANCE" "10%"
					( Origin gFrontEnd )
				)
				( attribute "VALUE" "0.22UF"
					( Origin gFrontEnd )
				)
				( attribute "VER" "1"
					( Origin gFrontEnd )
				)
				( attribute "VOLTAGE" "16V"
					( Units "uVoltage" "V" 1.000000)
					( Origin gFrontEnd )
				)
				( attribute "XY" "(750,3775)"
					( Origin gFrontEnd )
				)
				( attribute "CHIPS_PART_NAME" "CAP"
					( Origin gPackager )
				)
				( attribute "CDS_PART_NAME" "CAP_0402-0.22UF,16V,10%,X7R,A3A"
					( Origin gPackager )
				)
				( objectStatus "C3M45" )
			)
			( gate "@baseboard_fab2_lib.baseboard_fab2(sch_1):page129_i83"
				( attribute "BOM_COST" "SB"
					( Origin gFrontEnd )
				)
				( attribute "CDS_LIB" "mstr_discrete"
					( Origin gPackager )
				)
				( attribute "CDS_LOCATION" "C3N13"
					( Origin gPackager )
				)
				( attribute "CDS_SEC" "1"
					( Origin gPackager )
				)
				( attribute "LOCATION" "C3N13"
					( Origin gFrontEnd )
				)
				( attribute "MATERIAL" "X7R"
					( Origin gFrontEnd )
				)
				( attribute "PACK_TYPE" "0402"
					( Origin gFrontEnd )
				)
				( attribute "PART_NUMBER" "A36096-155"
					( Origin gFrontEnd )
				)
				( attribute "PHYS_PAGE" "129"
					( Origin gFrontEnd )
				)
				( attribute "ROOM" "DMI"
					( Origin gFrontEnd )
				)
				( attribute "ROT" "1"
					( Origin gFrontEnd )
				)
				( attribute "SEC" "1"
					( Origin gPackager )
				)
				( attribute "TOLERANCE" "10%"
					( Origin gFrontEnd )
				)
				( attribute "VALUE" "0.22UF"
					( Origin gFrontEnd )
				)
				( attribute "VER" "1"
					( Origin gFrontEnd )
				)
				( attribute "VOLTAGE" "16V"
					( Units "uVoltage" "V" 1.000000)
					( Origin gFrontEnd )
				)
				( attribute "XY" "(400,3975)"
					( Origin gFrontEnd )
				)
				( attribute "CHIPS_PART_NAME" "CAP"
					( Origin gPackager )
				)
				( attribute "CDS_PART_NAME" "CAP_0402-0.22UF,16V,10%,X7R,A3A"
					( Origin gPackager )
				)
				( objectStatus "C3N13" )
			)
			( gate "@baseboard_fab2_lib.baseboard_fab2(sch_1):page130_i2"
				( attribute "BOM_COST" "SB"
					( Origin gFrontEnd )
				)
				( attribute "CDS_LIB" "mstr_discrete"
					( Origin gPackager )
				)
				( attribute "CDS_LOCATION" "C7D2"
					( Origin gPackager )
				)
				( attribute "CDS_SEC" "1"
					( Origin gPackager )
				)
				( attribute "LOCATION" "C7D2"
					( Origin gFrontEnd )
				)
				( attribute "MATERIAL" "X6S"
					( Origin gFrontEnd )
				)
				( attribute "PACK_TYPE" "0603"
					( Origin gFrontEnd )
				)
				( attribute "PART_NUMBER" "E15431-002"
					( Origin gFrontEnd )
				)
				( attribute "PHYS_PAGE" "130"
					( Origin gFrontEnd )
				)
				( attribute "ROOM" "SB_DECOUPLING"
					( Origin gFrontEnd )
				)
				( attribute "ROT" "0"
					( Origin gFrontEnd )
				)
				( attribute "SEC" "1"
					( Origin gFrontEnd )
				)
				( attribute "SEC_TYPE" "0603"
					( Origin gFrontEnd )
				)
				( attribute "TOLERANCE" "20%"
					( Origin gFrontEnd )
				)
				( attribute "VALUE" "10UF"
					( Origin gFrontEnd )
				)
				( attribute "VER" "1"
					( Origin gFrontEnd )
				)
				( attribute "VOLTAGE" "6.3V"
					( Units "uVoltage" "V" 1.000000)
					( Origin gFrontEnd )
				)
				( attribute "XY" "(1125,5003)"
					( Origin gFrontEnd )
				)
				( attribute "CHIPS_PART_NAME" "CAP"
					( Origin gPackager )
				)
				( attribute "CDS_PART_NAME" "CAP_0603-10UF,6.3V,20%,X6S,E15A"
					( Origin gPackager )
				)
				( objectStatus "C7D2" )
			)
			( gate "@baseboard_fab2_lib.baseboard_fab2(sch_1):page130_i4"
				( attribute "BOM_COST" "SB"
					( Origin gFrontEnd )
				)
				( attribute "CDS_LIB" "dev_discrete"
					( Origin gPackager )
				)
				( attribute "CDS_LOCATION" "C2N26"
					( Origin gPackager )
				)
				( attribute "CDS_SEC" "1"
					( Origin gPackager )
				)
				( attribute "LOCATION" "C2N26"
					( Origin gFrontEnd )
				)
				( attribute "MATERIAL" "X6S"
					( Origin gFrontEnd )
				)
				( attribute "PACK_TYPE" "0402V"
					( Origin gFrontEnd )
				)
				( attribute "PART_NUMBER" "D97712-004"
					( Origin gFrontEnd )
				)
				( attribute "PHYS_PAGE" "130"
					( Origin gFrontEnd )
				)
				( attribute "ROOM" "SB_DECOUPLING"
					( Origin gFrontEnd )
				)
				( attribute "ROT" "0"
					( Origin gFrontEnd )
				)
				( attribute "SEC" "1"
					( Origin gPackager )
				)
				( attribute "TOLERANCE" "10%"
					( Origin gFrontEnd )
				)
				( attribute "VALUE" "1.0UF"
					( Origin gFrontEnd )
				)
				( attribute "VER" "1"
					( Origin gFrontEnd )
				)
				( attribute "VOLTAGE" "6.3V"
					( Units "uVoltage" "V" 1.000000)
					( Origin gFrontEnd )
				)
				( attribute "XY" "(1725,2650)"
					( Origin gFrontEnd )
				)
				( attribute "CHIPS_PART_NAME" "CAP_A"
					( Origin gPackager )
				)
				( attribute "CDS_PART_NAME" "CAP_A_0402V-1.0UF,6.3V,10%,X6SA"
					( Origin gPackager )
				)
				( objectStatus "C2N26" )
			)
			( gate "@baseboard_fab2_lib.baseboard_fab2(sch_1):page130_i7"
				( attribute "BOM_COST" "SB"
					( Origin gFrontEnd )
				)
				( attribute "CDS_LIB" "dev_discrete"
					( Origin gPackager )
				)
				( attribute "CDS_LOCATION" "C2N19"
					( Origin gPackager )
				)
				( attribute "CDS_SEC" "1"
					( Origin gPackager )
				)
				( attribute "LOCATION" "C2N19"
					( Origin gFrontEnd )
				)
				( attribute "MATERIAL" "X6S"
					( Origin gFrontEnd )
				)
				( attribute "PACK_TYPE" "0402V"
					( Origin gFrontEnd )
				)
				( attribute "PART_NUMBER" "D97712-004"
					( Origin gFrontEnd )
				)
				( attribute "PHYS_PAGE" "130"
					( Origin gFrontEnd )
				)
				( attribute "ROOM" "SB_DECOUPLING"
					( Origin gFrontEnd )
				)
				( attribute "ROT" "0"
					( Origin gFrontEnd )
				)
				( attribute "SEC" "1"
					( Origin gPackager )
				)
				( attribute "TOLERANCE" "10%"
					( Origin gFrontEnd )
				)
				( attribute "VALUE" "1.0UF"
					( Origin gFrontEnd )
				)
				( attribute "VER" "1"
					( Origin gFrontEnd )
				)
				( attribute "VOLTAGE" "6.3V"
					( Units "uVoltage" "V" 1.000000)
					( Origin gFrontEnd )
				)
				( attribute "XY" "(1175,3900)"
					( Origin gFrontEnd )
				)
				( attribute "CHIPS_PART_NAME" "CAP_A"
					( Origin gPackager )
				)
				( attribute "CDS_PART_NAME" "CAP_A_0402V-1.0UF,6.3V,10%,X6SA"
					( Origin gPackager )
				)
				( objectStatus "C2N19" )
			)
			( gate "@baseboard_fab2_lib.baseboard_fab2(sch_1):page130_i8"
				( attribute "BOM_COST" "SB"
					( Origin gFrontEnd )
				)
				( attribute "CDS_LIB" "mstr_discrete"
					( Origin gPackager )
				)
				( attribute "CDS_LOCATION" "C2N24"
					( Origin gPackager )
				)
				( attribute "CDS_SEC" "1"
					( Origin gPackager )
				)
				( attribute "LOCATION" "C2N24"
					( Origin gFrontEnd )
				)
				( attribute "MATERIAL" "X6S"
					( Origin gFrontEnd )
				)
				( attribute "PACK_TYPE" "0603"
					( Origin gFrontEnd )
				)
				( attribute "PART_NUMBER" "E15431-002"
					( Origin gFrontEnd )
				)
				( attribute "PHYS_PAGE" "130"
					( Origin gFrontEnd )
				)
				( attribute "ROOM" "SB_DECOUPLING"
					( Origin gFrontEnd )
				)
				( attribute "ROT" "0"
					( Origin gFrontEnd )
				)
				( attribute "SEC" "1"
					( Origin gPackager )
				)
				( attribute "TOLERANCE" "20%"
					( Origin gFrontEnd )
				)
				( attribute "VALUE" "10UF"
					( Origin gFrontEnd )
				)
				( attribute "VER" "1"
					( Origin gFrontEnd )
				)
				( attribute "VOLTAGE" "6.3V"
					( Units "uVoltage" "V" 1.000000)
					( Origin gFrontEnd )
				)
				( attribute "XY" "(1300,2650)"
					( Origin gFrontEnd )
				)
				( attribute "CHIPS_PART_NAME" "CAP"
					( Origin gPackager )
				)
				( attribute "CDS_PART_NAME" "CAP_0603-10UF,6.3V,20%,X6S,E15A"
					( Origin gPackager )
				)
				( objectStatus "C2N24" )
			)
			( gate "@baseboard_fab2_lib.baseboard_fab2(sch_1):page130_i9"
				( attribute "BOM_COST" "SB"
					( Origin gFrontEnd )
				)
				( attribute "CDS_LIB" "mstr_discrete"
					( Origin gPackager )
				)
				( attribute "CDS_LOCATION" "C2N22"
					( Origin gPackager )
				)
				( attribute "CDS_SEC" "1"
					( Origin gPackager )
				)
				( attribute "LOCATION" "C2N22"
					( Origin gFrontEnd )
				)
				( attribute "MATERIAL" "X6S"
					( Origin gFrontEnd )
				)
				( attribute "PACK_TYPE" "0603"
					( Origin gFrontEnd )
				)
				( attribute "PART_NUMBER" "E15431-002"
					( Origin gFrontEnd )
				)
				( attribute "PHYS_PAGE" "130"
					( Origin gFrontEnd )
				)
				( attribute "ROOM" "SB_DECOUPLING"
					( Origin gFrontEnd )
				)
				( attribute "ROT" "0"
					( Origin gFrontEnd )
				)
				( attribute "SEC" "1"
					( Origin gPackager )
				)
				( attribute "TOLERANCE" "20%"
					( Origin gFrontEnd )
				)
				( attribute "VALUE" "10UF"
					( Origin gFrontEnd )
				)
				( attribute "VER" "1"
					( Origin gFrontEnd )
				)
				( attribute "VOLTAGE" "6.3V"
					( Units "uVoltage" "V" 1.000000)
					( Origin gFrontEnd )
				)
				( attribute "XY" "(875,2650)"
					( Origin gFrontEnd )
				)
				( attribute "CHIPS_PART_NAME" "CAP"
					( Origin gPackager )
				)
				( attribute "CDS_PART_NAME" "CAP_0603-10UF,6.3V,20%,X6S,E15A"
					( Origin gPackager )
				)
				( objectStatus "C2N22" )
			)
			( gate "@baseboard_fab2_lib.baseboard_fab2(sch_1):page130_i12"
				( attribute "BOM_COST" "SB"
					( Origin gFrontEnd )
				)
				( attribute "CDS_LIB" "dev_discrete"
					( Origin gPackager )
				)
				( attribute "CDS_LOCATION" "C2N20"
					( Origin gPackager )
				)
				( attribute "CDS_SEC" "1"
					( Origin gPackager )
				)
				( attribute "LOCATION" "C2N20"
					( Origin gFrontEnd )
				)
				( attribute "MATERIAL" "X6S"
					( Origin gFrontEnd )
				)
				( attribute "PACK_TYPE" "0402V"
					( Origin gFrontEnd )
				)
				( attribute "PART_NUMBER" "D97712-004"
					( Origin gFrontEnd )
				)
				( attribute "PHYS_PAGE" "130"
					( Origin gFrontEnd )
				)
				( attribute "ROOM" "SB_DECOUPLING"
					( Origin gFrontEnd )
				)
				( attribute "ROT" "0"
					( Origin gFrontEnd )
				)
				( attribute "SEC" "1"
					( Origin gPackager )
				)
				( attribute "TOLERANCE" "10%"
					( Origin gFrontEnd )
				)
				( attribute "VALUE" "1.0UF"
					( Origin gFrontEnd )
				)
				( attribute "VER" "1"
					( Origin gFrontEnd )
				)
				( attribute "VOLTAGE" "6.3V"
					( Units "uVoltage" "V" 1.000000)
					( Origin gFrontEnd )
				)
				( attribute "XY" "(1925,1600)"
					( Origin gFrontEnd )
				)
				( attribute "CHIPS_PART_NAME" "CAP_A"
					( Origin gPackager )
				)
				( attribute "CDS_PART_NAME" "CAP_A_0402V-1.0UF,6.3V,10%,X6SA"
					( Origin gPackager )
				)
				( objectStatus "C2N20" )
			)
			( gate "@baseboard_fab2_lib.baseboard_fab2(sch_1):page130_i15"
				( attribute "BOM_COST" "SB"
					( Origin gFrontEnd )
				)
				( attribute "CDS_LIB" "mstr_discrete"
					( Origin gPackager )
				)
				( attribute "CDS_LOCATION" "C2N21"
					( Origin gPackager )
				)
				( attribute "CDS_SEC" "1"
					( Origin gPackager )
				)
				( attribute "LOCATION" "C2N21"
					( Origin gFrontEnd )
				)
				( attribute "MATERIAL" "X6S"
					( Origin gFrontEnd )
				)
				( attribute "PACK_TYPE" "0603"
					( Origin gFrontEnd )
				)
				( attribute "PART_NUMBER" "E15431-002"
					( Origin gFrontEnd )
				)
				( attribute "PHYS_PAGE" "130"
					( Origin gFrontEnd )
				)
				( attribute "ROOM" "SB_DECOUPLING"
					( Origin gFrontEnd )
				)
				( attribute "ROT" "0"
					( Origin gFrontEnd )
				)
				( attribute "SEC" "1"
					( Origin gPackager )
				)
				( attribute "TOLERANCE" "20%"
					( Origin gFrontEnd )
				)
				( attribute "VALUE" "10UF"
					( Origin gFrontEnd )
				)
				( attribute "VER" "1"
					( Origin gFrontEnd )
				)
				( attribute "VOLTAGE" "6.3V"
					( Units "uVoltage" "V" 1.000000)
					( Origin gFrontEnd )
				)
				( attribute "XY" "(425,2650)"
					( Origin gFrontEnd )
				)
				( attribute "CHIPS_PART_NAME" "CAP"
					( Origin gPackager )
				)
				( attribute "CDS_PART_NAME" "CAP_0603-10UF,6.3V,20%,X6S,E15A"
					( Origin gPackager )
				)
				( objectStatus "C2N21" )
			)
			( gate "@baseboard_fab2_lib.baseboard_fab2(sch_1):page130_i16"
				( attribute "BOM_COST" "SB"
					( Origin gFrontEnd )
				)
				( attribute "CDS_LIB" "dev_discrete"
					( Origin gPackager )
				)
				( attribute "CDS_LOCATION" "C3N29"
					( Origin gPackager )
				)
				( attribute "CDS_SEC" "1"
					( Origin gPackager )
				)
				( attribute "LOCATION" "C3N29"
					( Origin gFrontEnd )
				)
				( attribute "MATERIAL" "X7R"
					( Origin gFrontEnd )
				)
				( attribute "PACK_TYPE" "0402V"
					( Origin gFrontEnd )
				)
				( attribute "PART_NUMBER" "A36096-030"
					( Origin gFrontEnd )
				)
				( attribute "PHYS_PAGE" "130"
					( Origin gFrontEnd )
				)
				( attribute "ROOM" "SB_DECOUPLING"
					( Origin gFrontEnd )
				)
				( attribute "ROT" "2"
					( Origin gFrontEnd )
				)
				( attribute "SEC" "1"
					( Origin gPackager )
				)
				( attribute "TOLERANCE" "10%"
					( Origin gFrontEnd )
				)
				( attribute "VALUE" "0.1UF"
					( Origin gFrontEnd )
				)
				( attribute "VER" "1"
					( Origin gFrontEnd )
				)
				( attribute "VOLTAGE" "16V"
					( Units "uVoltage" "V" 1.000000)
					( Origin gFrontEnd )
				)
				( attribute "XY" "(0,2025)"
					( Origin gFrontEnd )
				)
				( attribute "CHIPS_PART_NAME" "CAP_A"
					( Origin gPackager )
				)
				( attribute "CDS_PART_NAME" "CAP_A_0402V-0.1UF,16V,10%,X7R,A"
					( Origin gPackager )
				)
				( objectStatus "C3N29" )
			)
			( gate "@baseboard_fab2_lib.baseboard_fab2(sch_1):page130_i19"
				( attribute "BOM_COST" "SB"
					( Origin gFrontEnd )
				)
				( attribute "CDS_LIB" "mstr_discrete"
					( Origin gPackager )
				)
				( attribute "CDS_LOCATION" "C8C3"
					( Origin gPackager )
				)
				( attribute "CDS_SEC" "1"
					( Origin gPackager )
				)
				( attribute "LOCATION" "C8C3"
					( Origin gFrontEnd )
				)
				( attribute "MATERIAL" "X6S"
					( Origin gFrontEnd )
				)
				( attribute "PACK_TYPE" "0603"
					( Origin gFrontEnd )
				)
				( attribute "PART_NUMBER" "E15431-002"
					( Origin gFrontEnd )
				)
				( attribute "PHYS_PAGE" "130"
					( Origin gFrontEnd )
				)
				( attribute "ROOM" "SB_DECOUPLING"
					( Origin gFrontEnd )
				)
				( attribute "ROT" "0"
					( Origin gFrontEnd )
				)
				( attribute "SEC" "1"
					( Origin gPackager )
				)
				( attribute "TOLERANCE" "20%"
					( Origin gFrontEnd )
				)
				( attribute "VALUE" "10UF"
					( Origin gFrontEnd )
				)
				( attribute "VER" "1"
					( Origin gFrontEnd )
				)
				( attribute "VOLTAGE" "6.3V"
					( Units "uVoltage" "V" 1.000000)
					( Origin gFrontEnd )
				)
				( attribute "XY" "(-2550,4925)"
					( Origin gFrontEnd )
				)
				( attribute "CHIPS_PART_NAME" "CAP"
					( Origin gPackager )
				)
				( attribute "CDS_PART_NAME" "CAP_0603-10UF,6.3V,20%,X6S,E15A"
					( Origin gPackager )
				)
				( objectStatus "C8C3" )
			)
			( gate "@baseboard_fab2_lib.baseboard_fab2(sch_1):page130_i20"
				( attribute "BOM_COST" "SB"
					( Origin gFrontEnd )
				)
				( attribute "CDS_LIB" "mstr_discrete"
					( Origin gPackager )
				)
				( attribute "CDS_LOCATION" "C8C4"
					( Origin gPackager )
				)
				( attribute "CDS_SEC" "1"
					( Origin gPackager )
				)
				( attribute "LOCATION" "C8C4"
					( Origin gFrontEnd )
				)
				( attribute "MATERIAL" "X6S"
					( Origin gFrontEnd )
				)
				( attribute "PACK_TYPE" "0603"
					( Origin gFrontEnd )
				)
				( attribute "PART_NUMBER" "E15431-002"
					( Origin gFrontEnd )
				)
				( attribute "PHYS_PAGE" "130"
					( Origin gFrontEnd )
				)
				( attribute "ROOM" "SB_DECOUPLING"
					( Origin gFrontEnd )
				)
				( attribute "ROT" "0"
					( Origin gFrontEnd )
				)
				( attribute "SEC" "1"
					( Origin gPackager )
				)
				( attribute "TOLERANCE" "20%"
					( Origin gFrontEnd )
				)
				( attribute "VALUE" "10UF"
					( Origin gFrontEnd )
				)
				( attribute "VER" "1"
					( Origin gFrontEnd )
				)
				( attribute "VOLTAGE" "6.3V"
					( Units "uVoltage" "V" 1.000000)
					( Origin gFrontEnd )
				)
				( attribute "XY" "(-2975,4925)"
					( Origin gFrontEnd )
				)
				( attribute "CHIPS_PART_NAME" "CAP"
					( Origin gPackager )
				)
				( attribute "CDS_PART_NAME" "CAP_0603-10UF,6.3V,20%,X6S,E15A"
					( Origin gPackager )
				)
				( objectStatus "C8C4" )
			)
			( gate "@baseboard_fab2_lib.baseboard_fab2(sch_1):page130_i21"
				( attribute "BOM_COST" "SB"
					( Origin gFrontEnd )
				)
				( attribute "CDS_LIB" "mstr_discrete"
					( Origin gPackager )
				)
				( attribute "CDS_LOCATION" "C8C5"
					( Origin gPackager )
				)
				( attribute "CDS_SEC" "1"
					( Origin gPackager )
				)
				( attribute "LOCATION" "C8C5"
					( Origin gFrontEnd )
				)
				( attribute "MATERIAL" "X6S"
					( Origin gFrontEnd )
				)
				( attribute "PACK_TYPE" "0603"
					( Origin gFrontEnd )
				)
				( attribute "PART_NUMBER" "E15431-002"
					( Origin gFrontEnd )
				)
				( attribute "PHYS_PAGE" "130"
					( Origin gFrontEnd )
				)
				( attribute "ROOM" "SB_DECOUPLING"
					( Origin gFrontEnd )
				)
				( attribute "ROT" "0"
					( Origin gFrontEnd )
				)
				( attribute "SEC" "1"
					( Origin gPackager )
				)
				( attribute "TOLERANCE" "20%"
					( Origin gFrontEnd )
				)
				( attribute "VALUE" "10UF"
					( Origin gFrontEnd )
				)
				( attribute "VER" "1"
					( Origin gFrontEnd )
				)
				( attribute "VOLTAGE" "6.3V"
					( Units "uVoltage" "V" 1.000000)
					( Origin gFrontEnd )
				)
				( attribute "XY" "(-3375,4925)"
					( Origin gFrontEnd )
				)
				( attribute "CHIPS_PART_NAME" "CAP"
					( Origin gPackager )
				)
				( attribute "CDS_PART_NAME" "CAP_0603-10UF,6.3V,20%,X6S,E15A"
					( Origin gPackager )
				)
				( objectStatus "C8C5" )
			)
			( gate "@baseboard_fab2_lib.baseboard_fab2(sch_1):page130_i22"
				( attribute "BOM_COST" "SB"
					( Origin gFrontEnd )
				)
				( attribute "CDS_LIB" "mstr_discrete"
					( Origin gPackager )
				)
				( attribute "CDS_LOCATION" "C8C6"
					( Origin gPackager )
				)
				( attribute "CDS_SEC" "1"
					( Origin gPackager )
				)
				( attribute "LOCATION" "C8C6"
					( Origin gFrontEnd )
				)
				( attribute "MATERIAL" "X6S"
					( Origin gFrontEnd )
				)
				( attribute "PACK_TYPE" "0603"
					( Origin gFrontEnd )
				)
				( attribute "PART_NUMBER" "E15431-002"
					( Origin gFrontEnd )
				)
				( attribute "PHYS_PAGE" "130"
					( Origin gFrontEnd )
				)
				( attribute "ROOM" "SB_DECOUPLING"
					( Origin gFrontEnd )
				)
				( attribute "ROT" "0"
					( Origin gFrontEnd )
				)
				( attribute "SEC" "1"
					( Origin gPackager )
				)
				( attribute "TOLERANCE" "20%"
					( Origin gFrontEnd )
				)
				( attribute "VALUE" "10UF"
					( Origin gFrontEnd )
				)
				( attribute "VER" "1"
					( Origin gFrontEnd )
				)
				( attribute "VOLTAGE" "6.3V"
					( Units "uVoltage" "V" 1.000000)
					( Origin gFrontEnd )
				)
				( attribute "XY" "(-3775,4925)"
					( Origin gFrontEnd )
				)
				( attribute "CHIPS_PART_NAME" "CAP"
					( Origin gPackager )
				)
				( attribute "CDS_PART_NAME" "CAP_0603-10UF,6.3V,20%,X6S,E15A"
					( Origin gPackager )
				)
				( objectStatus "C8C6" )
			)
			( gate "@baseboard_fab2_lib.baseboard_fab2(sch_1):page130_i24"
				( attribute "BOM_COST" "SB"
					( Origin gFrontEnd )
				)
				( attribute "CDS_LIB" "mstr_discrete"
					( Origin gPackager )
				)
				( attribute "CDS_LOCATION" "C2N23"
					( Origin gPackager )
				)
				( attribute "CDS_SEC" "1"
					( Origin gPackager )
				)
				( attribute "LOCATION" "C2N23"
					( Origin gFrontEnd )
				)
				( attribute "MATERIAL" "X6S"
					( Origin gFrontEnd )
				)
				( attribute "PACK_TYPE" "0603"
					( Origin gFrontEnd )
				)
				( attribute "PART_NUMBER" "E15431-002"
					( Origin gFrontEnd )
				)
				( attribute "PHYS_PAGE" "130"
					( Origin gFrontEnd )
				)
				( attribute "ROOM" "SB_DECOUPLING"
					( Origin gFrontEnd )
				)
				( attribute "ROT" "0"
					( Origin gFrontEnd )
				)
				( attribute "SEC" "1"
					( Origin gPackager )
				)
				( attribute "TOLERANCE" "20%"
					( Origin gFrontEnd )
				)
				( attribute "VALUE" "10UF"
					( Origin gFrontEnd )
				)
				( attribute "VER" "1"
					( Origin gFrontEnd )
				)
				( attribute "VOLTAGE" "6.3V"
					( Units "uVoltage" "V" 1.000000)
					( Origin gFrontEnd )
				)
				( attribute "XY" "(-4175,4925)"
					( Origin gFrontEnd )
				)
				( attribute "CHIPS_PART_NAME" "CAP"
					( Origin gPackager )
				)
				( attribute "CDS_PART_NAME" "CAP_0603-10UF,6.3V,20%,X6S,E15A"
					( Origin gPackager )
				)
				( objectStatus "C2N23" )
			)
			( gate "@baseboard_fab2_lib.baseboard_fab2(sch_1):page130_i25"
				( attribute "BOM_COST" "SB"
					( Origin gFrontEnd )
				)
				( attribute "CDS_LIB" "mstr_discrete"
					( Origin gPackager )
				)
				( attribute "CDS_LOCATION" "C2N14"
					( Origin gPackager )
				)
				( attribute "CDS_SEC" "1"
					( Origin gPackager )
				)
				( attribute "LOCATION" "C2N14"
					( Origin gFrontEnd )
				)
				( attribute "MATERIAL" "X6S"
					( Origin gFrontEnd )
				)
				( attribute "PACK_TYPE" "0603"
					( Origin gFrontEnd )
				)
				( attribute "PART_NUMBER" "E15431-002"
					( Origin gFrontEnd )
				)
				( attribute "PHYS_PAGE" "130"
					( Origin gFrontEnd )
				)
				( attribute "ROOM" "SB_DECOUPLING"
					( Origin gFrontEnd )
				)
				( attribute "ROT" "0"
					( Origin gFrontEnd )
				)
				( attribute "SEC" "1"
					( Origin gPackager )
				)
				( attribute "TOLERANCE" "20%"
					( Origin gFrontEnd )
				)
				( attribute "VALUE" "10UF"
					( Origin gFrontEnd )
				)
				( attribute "VER" "1"
					( Origin gFrontEnd )
				)
				( attribute "VOLTAGE" "6.3V"
					( Units "uVoltage" "V" 1.000000)
					( Origin gFrontEnd )
				)
				( attribute "XY" "(-4575,4925)"
					( Origin gFrontEnd )
				)
				( attribute "CHIPS_PART_NAME" "CAP"
					( Origin gPackager )
				)
				( attribute "CDS_PART_NAME" "CAP_0603-10UF,6.3V,20%,X6S,E15A"
					( Origin gPackager )
				)
				( objectStatus "C2N14" )
			)
			( gate "@baseboard_fab2_lib.baseboard_fab2(sch_1):page130_i28"
				( attribute "BOM_COST" "SB"
					( Origin gFrontEnd )
				)
				( attribute "CDS_LIB" "mstr_discrete"
					( Origin gPackager )
				)
				( attribute "CDS_LOCATION" "C2N17"
					( Origin gPackager )
				)
				( attribute "CDS_SEC" "1"
					( Origin gPackager )
				)
				( attribute "LOCATION" "C2N17"
					( Origin gFrontEnd )
				)
				( attribute "MATERIAL" "X6S"
					( Origin gFrontEnd )
				)
				( attribute "PACK_TYPE" "0603"
					( Origin gFrontEnd )
				)
				( attribute "PART_NUMBER" "E15431-002"
					( Origin gFrontEnd )
				)
				( attribute "PHYS_PAGE" "130"
					( Origin gFrontEnd )
				)
				( attribute "ROOM" "SB_DECOUPLING"
					( Origin gFrontEnd )
				)
				( attribute "ROT" "0"
					( Origin gFrontEnd )
				)
				( attribute "SEC" "1"
					( Origin gPackager )
				)
				( attribute "TOLERANCE" "20%"
					( Origin gFrontEnd )
				)
				( attribute "VALUE" "10UF"
					( Origin gFrontEnd )
				)
				( attribute "VER" "1"
					( Origin gFrontEnd )
				)
				( attribute "VOLTAGE" "6.3V"
					( Units "uVoltage" "V" 1.000000)
					( Origin gFrontEnd )
				)
				( attribute "XY" "(-1475,3925)"
					( Origin gFrontEnd )
				)
				( attribute "CHIPS_PART_NAME" "CAP"
					( Origin gPackager )
				)
				( attribute "CDS_PART_NAME" "CAP_0603-10UF,6.3V,20%,X6S,E15A"
					( Origin gPackager )
				)
				( objectStatus "C2N17" )
			)
			( gate "@baseboard_fab2_lib.baseboard_fab2(sch_1):page130_i29"
				( attribute "BOM_COST" "SB"
					( Origin gFrontEnd )
				)
				( attribute "CDS_LIB" "dev_discrete"
					( Origin gPackager )
				)
				( attribute "CDS_LOCATION" "C2N18"
					( Origin gPackager )
				)
				( attribute "CDS_SEC" "1"
					( Origin gPackager )
				)
				( attribute "LOCATION" "C2N18"
					( Origin gFrontEnd )
				)
				( attribute "MATERIAL" "X6S"
					( Origin gFrontEnd )
				)
				( attribute "PACK_TYPE" "0402V"
					( Origin gFrontEnd )
				)
				( attribute "PART_NUMBER" "D97712-004"
					( Origin gFrontEnd )
				)
				( attribute "PHYS_PAGE" "130"
					( Origin gFrontEnd )
				)
				( attribute "ROOM" "SB_DECOUPLING"
					( Origin gFrontEnd )
				)
				( attribute "ROT" "0"
					( Origin gFrontEnd )
				)
				( attribute "SEC" "1"
					( Origin gPackager )
				)
				( attribute "TOLERANCE" "10%"
					( Origin gFrontEnd )
				)
				( attribute "VALUE" "1.0UF"
					( Origin gFrontEnd )
				)
				( attribute "VER" "1"
					( Origin gFrontEnd )
				)
				( attribute "VOLTAGE" "6.3V"
					( Units "uVoltage" "V" 1.000000)
					( Origin gFrontEnd )
				)
				( attribute "XY" "(-3450,3925)"
					( Origin gFrontEnd )
				)
				( attribute "CHIPS_PART_NAME" "CAP_A"
					( Origin gPackager )
				)
				( attribute "CDS_PART_NAME" "CAP_A_0402V-1.0UF,6.3V,10%,X6SA"
					( Origin gPackager )
				)
				( objectStatus "C2N18" )
			)
			( gate "@baseboard_fab2_lib.baseboard_fab2(sch_1):page130_i30"
				( attribute "BOM_COST" "SB"
					( Origin gFrontEnd )
				)
				( attribute "CDS_LIB" "dev_discrete"
					( Origin gPackager )
				)
				( attribute "CDS_LOCATION" "C8B2"
					( Origin gPackager )
				)
				( attribute "CDS_SEC" "1"
					( Origin gPackager )
				)
				( attribute "LOCATION" "C8B2"
					( Origin gFrontEnd )
				)
				( attribute "MATERIAL" "X6S"
					( Origin gFrontEnd )
				)
				( attribute "PACK_TYPE" "0603V"
					( Origin gFrontEnd )
				)
				( attribute "PART_NUMBER" "E15431-004"
					( Origin gFrontEnd )
				)
				( attribute "PHYS_PAGE" "130"
					( Origin gFrontEnd )
				)
				( attribute "ROOM" "SB_DECOUPLING"
					( Origin gFrontEnd )
				)
				( attribute "ROT" "0"
					( Origin gFrontEnd )
				)
				( attribute "SEC" "1"
					( Origin gPackager )
				)
				( attribute "TOLERANCE" "20%"
					( Origin gFrontEnd )
				)
				( attribute "VALUE" "22.0UF"
					( Origin gFrontEnd )
				)
				( attribute "VER" "1"
					( Origin gFrontEnd )
				)
				( attribute "VOLTAGE" "4V"
					( Units "uVoltage" "V" 1.000000)
					( Origin gFrontEnd )
				)
				( attribute "XY" "(-3100,2750)"
					( Origin gFrontEnd )
				)
				( attribute "CHIPS_PART_NAME" "CAP_A"
					( Origin gPackager )
				)
				( attribute "CDS_PART_NAME" "CAP_A_0603V-22.0UF,4V,20%,X6S,A"
					( Origin gPackager )
				)
				( objectStatus "C8B2" )
			)
			( gate "@baseboard_fab2_lib.baseboard_fab2(sch_1):page130_i32"
				( attribute "BOM_COST" "SB"
					( Origin gFrontEnd )
				)
				( attribute "CDS_LIB" "dev_discrete"
					( Origin gPackager )
				)
				( attribute "CDS_LOCATION" "C8B3"
					( Origin gPackager )
				)
				( attribute "CDS_SEC" "1"
					( Origin gPackager )
				)
				( attribute "LOCATION" "C8B3"
					( Origin gFrontEnd )
				)
				( attribute "MATERIAL" "X6S"
					( Origin gFrontEnd )
				)
				( attribute "PACK_TYPE" "0603V"
					( Origin gFrontEnd )
				)
				( attribute "PART_NUMBER" "E15431-004"
					( Origin gFrontEnd )
				)
				( attribute "PHYS_PAGE" "130"
					( Origin gFrontEnd )
				)
				( attribute "ROOM" "SB_DECOUPLING"
					( Origin gFrontEnd )
				)
				( attribute "ROT" "0"
					( Origin gFrontEnd )
				)
				( attribute "SEC" "1"
					( Origin gPackager )
				)
				( attribute "TOLERANCE" "20%"
					( Origin gFrontEnd )
				)
				( attribute "VALUE" "22.0UF"
					( Origin gFrontEnd )
				)
				( attribute "VER" "1"
					( Origin gFrontEnd )
				)
				( attribute "VOLTAGE" "4V"
					( Units "uVoltage" "V" 1.000000)
					( Origin gFrontEnd )
				)
				( attribute "XY" "(-1975,1900)"
					( Origin gFrontEnd )
				)
				( attribute "CHIPS_PART_NAME" "CAP_A"
					( Origin gPackager )
				)
				( attribute "CDS_PART_NAME" "CAP_A_0603V-22.0UF,4V,20%,X6S,A"
					( Origin gPackager )
				)
				( objectStatus "C8B3" )
			)
			( gate "@baseboard_fab2_lib.baseboard_fab2(sch_1):page130_i34"
				( attribute "BOM_COST" "SB"
					( Origin gFrontEnd )
				)
				( attribute "CDS_LIB" "dev_discrete"
					( Origin gPackager )
				)
				( attribute "CDS_LOCATION" "C2N25"
					( Origin gPackager )
				)
				( attribute "CDS_SEC" "1"
					( Origin gPackager )
				)
				( attribute "LOCATION" "C2N25"
					( Origin gFrontEnd )
				)
				( attribute "MATERIAL" "X6S"
					( Origin gFrontEnd )
				)
				( attribute "PACK_TYPE" "0402V"
					( Origin gFrontEnd )
				)
				( attribute "PART_NUMBER" "D97712-004"
					( Origin gFrontEnd )
				)
				( attribute "PHYS_PAGE" "130"
					( Origin gFrontEnd )
				)
				( attribute "ROOM" "SB_DECOUPLING"
					( Origin gFrontEnd )
				)
				( attribute "ROT" "0"
					( Origin gFrontEnd )
				)
				( attribute "SEC" "1"
					( Origin gPackager )
				)
				( attribute "TOLERANCE" "10%"
					( Origin gFrontEnd )
				)
				( attribute "VALUE" "1.0UF"
					( Origin gFrontEnd )
				)
				( attribute "VER" "1"
					( Origin gFrontEnd )
				)
				( attribute "VOLTAGE" "6.3V"
					( Units "uVoltage" "V" 1.000000)
					( Origin gFrontEnd )
				)
				( attribute "XY" "(-3825,3925)"
					( Origin gFrontEnd )
				)
				( attribute "CHIPS_PART_NAME" "CAP_A"
					( Origin gPackager )
				)
				( attribute "CDS_PART_NAME" "CAP_A_0402V-1.0UF,6.3V,10%,X6SA"
					( Origin gPackager )
				)
				( objectStatus "C2N25" )
			)
			( gate "@baseboard_fab2_lib.baseboard_fab2(sch_1):page130_i37"
				( attribute "BOM_COST" "SB"
					( Origin gFrontEnd )
				)
				( attribute "CDS_LIB" "dev_discrete"
					( Origin gPackager )
				)
				( attribute "CDS_LOCATION" "C2M16"
					( Origin gPackager )
				)
				( attribute "CDS_SEC" "1"
					( Origin gPackager )
				)
				( attribute "LOCATION" "C2M16"
					( Origin gFrontEnd )
				)
				( attribute "MATERIAL" "X6S"
					( Origin gFrontEnd )
				)
				( attribute "PACK_TYPE" "0402V"
					( Origin gFrontEnd )
				)
				( attribute "PART_NUMBER" "D97712-004"
					( Origin gFrontEnd )
				)
				( attribute "PHYS_PAGE" "130"
					( Origin gFrontEnd )
				)
				( attribute "ROOM" "SB_DECOUPLING"
					( Origin gFrontEnd )
				)
				( attribute "ROT" "0"
					( Origin gFrontEnd )
				)
				( attribute "SEC" "1"
					( Origin gPackager )
				)
				( attribute "TOLERANCE" "10%"
					( Origin gFrontEnd )
				)
				( attribute "VALUE" "1.0UF"
					( Origin gFrontEnd )
				)
				( attribute "VER" "1"
					( Origin gFrontEnd )
				)
				( attribute "VOLTAGE" "6.3V"
					( Units "uVoltage" "V" 1.000000)
					( Origin gFrontEnd )
				)
				( attribute "XY" "(-4200,3925)"
					( Origin gFrontEnd )
				)
				( attribute "CHIPS_PART_NAME" "CAP_A"
					( Origin gPackager )
				)
				( attribute "CDS_PART_NAME" "CAP_A_0402V-1.0UF,6.3V,10%,X6SA"
					( Origin gPackager )
				)
				( objectStatus "C2M16" )
			)
			( gate "@baseboard_fab2_lib.baseboard_fab2(sch_1):page130_i38"
				( attribute "BOM_COST" "SB"
					( Origin gFrontEnd )
				)
				( attribute "CDS_LIB" "dev_discrete"
					( Origin gPackager )
				)
				( attribute "CDS_LOCATION" "C7D3"
					( Origin gPackager )
				)
				( attribute "CDS_SEC" "1"
					( Origin gPackager )
				)
				( attribute "LOCATION" "C7D3"
					( Origin gFrontEnd )
				)
				( attribute "MATERIAL" "X6S"
					( Origin gFrontEnd )
				)
				( attribute "PACK_TYPE" "0603V"
					( Origin gFrontEnd )
				)
				( attribute "PART_NUMBER" "E15431-004"
					( Origin gFrontEnd )
				)
				( attribute "PHYS_PAGE" "130"
					( Origin gFrontEnd )
				)
				( attribute "ROOM" "SB_DECOUPLING"
					( Origin gFrontEnd )
				)
				( attribute "ROT" "0"
					( Origin gFrontEnd )
				)
				( attribute "SEC" "1"
					( Origin gPackager )
				)
				( attribute "TOLERANCE" "20%"
					( Origin gFrontEnd )
				)
				( attribute "VALUE" "22.0UF"
					( Origin gFrontEnd )
				)
				( attribute "VER" "1"
					( Origin gFrontEnd )
				)
				( attribute "VOLTAGE" "4V"
					( Units "uVoltage" "V" 1.000000)
					( Origin gFrontEnd )
				)
				( attribute "XY" "(-3525,2750)"
					( Origin gFrontEnd )
				)
				( attribute "CHIPS_PART_NAME" "CAP_A"
					( Origin gPackager )
				)
				( attribute "CDS_PART_NAME" "CAP_A_0603V-22.0UF,4V,20%,X6S,A"
					( Origin gPackager )
				)
				( objectStatus "C7D3" )
			)
			( gate "@baseboard_fab2_lib.baseboard_fab2(sch_1):page130_i39"
				( attribute "BOM_COST" "SB"
					( Origin gFrontEnd )
				)
				( attribute "CDS_LIB" "dev_discrete"
					( Origin gPackager )
				)
				( attribute "CDS_LOCATION" "C8B4"
					( Origin gPackager )
				)
				( attribute "CDS_SEC" "1"
					( Origin gPackager )
				)
				( attribute "LOCATION" "C8B4"
					( Origin gFrontEnd )
				)
				( attribute "MATERIAL" "X6S"
					( Origin gFrontEnd )
				)
				( attribute "PACK_TYPE" "0603V"
					( Origin gFrontEnd )
				)
				( attribute "PART_NUMBER" "E15431-004"
					( Origin gFrontEnd )
				)
				( attribute "PHYS_PAGE" "130"
					( Origin gFrontEnd )
				)
				( attribute "ROOM" "SB_DECOUPLING"
					( Origin gFrontEnd )
				)
				( attribute "ROT" "0"
					( Origin gFrontEnd )
				)
				( attribute "SEC" "1"
					( Origin gPackager )
				)
				( attribute "TOLERANCE" "20%"
					( Origin gFrontEnd )
				)
				( attribute "VALUE" "22.0UF"
					( Origin gFrontEnd )
				)
				( attribute "VER" "1"
					( Origin gFrontEnd )
				)
				( attribute "VOLTAGE" "4V"
					( Units "uVoltage" "V" 1.000000)
					( Origin gFrontEnd )
				)
				( attribute "XY" "(-3925,2750)"
					( Origin gFrontEnd )
				)
				( attribute "CHIPS_PART_NAME" "CAP_A"
					( Origin gPackager )
				)
				( attribute "CDS_PART_NAME" "CAP_A_0603V-22.0UF,4V,20%,X6S,A"
					( Origin gPackager )
				)
				( objectStatus "C8B4" )
			)
			( gate "@baseboard_fab2_lib.baseboard_fab2(sch_1):page130_i41"
				( attribute "BOM_COST" "SB"
					( Origin gFrontEnd )
				)
				( attribute "CDS_LIB" "dev_discrete"
					( Origin gPackager )
				)
				( attribute "CDS_LOCATION" "C8B1"
					( Origin gPackager )
				)
				( attribute "CDS_SEC" "1"
					( Origin gPackager )
				)
				( attribute "LOCATION" "C8B1"
					( Origin gFrontEnd )
				)
				( attribute "MATERIAL" "X6S"
					( Origin gFrontEnd )
				)
				( attribute "PACK_TYPE" "0603V"
					( Origin gFrontEnd )
				)
				( attribute "PART_NUMBER" "E15431-004"
					( Origin gFrontEnd )
				)
				( attribute "PHYS_PAGE" "130"
					( Origin gFrontEnd )
				)
				( attribute "ROOM" "SB_DECOUPLING"
					( Origin gFrontEnd )
				)
				( attribute "ROT" "0"
					( Origin gFrontEnd )
				)
				( attribute "SEC" "1"
					( Origin gPackager )
				)
				( attribute "TOLERANCE" "20%"
					( Origin gFrontEnd )
				)
				( attribute "VALUE" "22.0UF"
					( Origin gFrontEnd )
				)
				( attribute "VER" "1"
					( Origin gFrontEnd )
				)
				( attribute "VOLTAGE" "4V"
					( Units "uVoltage" "V" 1.000000)
					( Origin gFrontEnd )
				)
				( attribute "XY" "(-4350,2750)"
					( Origin gFrontEnd )
				)
				( attribute "CHIPS_PART_NAME" "CAP_A"
					( Origin gPackager )
				)
				( attribute "CDS_PART_NAME" "CAP_A_0603V-22.0UF,4V,20%,X6S,A"
					( Origin gPackager )
				)
				( objectStatus "C8B1" )
			)
			( gate "@baseboard_fab2_lib.baseboard_fab2(sch_1):page130_i42"
				( attribute "BOM_COST" "SB"
					( Origin gFrontEnd )
				)
				( attribute "CDS_LIB" "dev_discrete"
					( Origin gPackager )
				)
				( attribute "CDS_LOCATION" "C3N23"
					( Origin gPackager )
				)
				( attribute "CDS_SEC" "1"
					( Origin gPackager )
				)
				( attribute "LOCATION" "C3N23"
					( Origin gFrontEnd )
				)
				( attribute "MATERIAL" "X6S"
					( Origin gFrontEnd )
				)
				( attribute "PACK_TYPE" "0402V"
					( Origin gFrontEnd )
				)
				( attribute "PART_NUMBER" "D97712-004"
					( Origin gFrontEnd )
				)
				( attribute "PHYS_PAGE" "130"
					( Origin gFrontEnd )
				)
				( attribute "ROOM" "SB_DECOUPLING"
					( Origin gFrontEnd )
				)
				( attribute "ROT" "0"
					( Origin gFrontEnd )
				)
				( attribute "SEC" "1"
					( Origin gPackager )
				)
				( attribute "TOLERANCE" "10%"
					( Origin gFrontEnd )
				)
				( attribute "VALUE" "1.0UF"
					( Origin gFrontEnd )
				)
				( attribute "VER" "1"
					( Origin gFrontEnd )
				)
				( attribute "VOLTAGE" "6.3V"
					( Units "uVoltage" "V" 1.000000)
					( Origin gFrontEnd )
				)
				( attribute "XY" "(-4600,3925)"
					( Origin gFrontEnd )
				)
				( attribute "CHIPS_PART_NAME" "CAP_A"
					( Origin gPackager )
				)
				( attribute "CDS_PART_NAME" "CAP_A_0402V-1.0UF,6.3V,10%,X6SA"
					( Origin gPackager )
				)
				( objectStatus "C3N23" )
			)
			( gate "@baseboard_fab2_lib.baseboard_fab2(sch_1):page130_i43"
				( attribute "BOM_COST" "SB"
					( Origin gFrontEnd )
				)
				( attribute "CDS_LIB" "dev_discrete"
					( Origin gPackager )
				)
				( attribute "CDS_LOCATION" "C2M1"
					( Origin gPackager )
				)
				( attribute "CDS_SEC" "1"
					( Origin gPackager )
				)
				( attribute "LOCATION" "C2M1"
					( Origin gFrontEnd )
				)
				( attribute "MATERIAL" "X6S"
					( Origin gFrontEnd )
				)
				( attribute "PACK_TYPE" "0603V"
					( Origin gFrontEnd )
				)
				( attribute "PART_NUMBER" "E15431-004"
					( Origin gFrontEnd )
				)
				( attribute "PHYS_PAGE" "130"
					( Origin gFrontEnd )
				)
				( attribute "ROOM" "SB_DECOUPLING"
					( Origin gFrontEnd )
				)
				( attribute "ROT" "0"
					( Origin gFrontEnd )
				)
				( attribute "SEC" "1"
					( Origin gPackager )
				)
				( attribute "TOLERANCE" "20%"
					( Origin gFrontEnd )
				)
				( attribute "VALUE" "22.0UF"
					( Origin gFrontEnd )
				)
				( attribute "VER" "1"
					( Origin gFrontEnd )
				)
				( attribute "VOLTAGE" "4V"
					( Units "uVoltage" "V" 1.000000)
					( Origin gFrontEnd )
				)
				( attribute "XY" "(-4725,2750)"
					( Origin gFrontEnd )
				)
				( attribute "CHIPS_PART_NAME" "CAP_A"
					( Origin gPackager )
				)
				( attribute "CDS_PART_NAME" "CAP_A_0603V-22.0UF,4V,20%,X6S,A"
					( Origin gPackager )
				)
				( objectStatus "C2M1" )
			)
			( gate "@baseboard_fab2_lib.baseboard_fab2(sch_1):page130_i45"
				( attribute "BOM_COST" "SB"
					( Origin gFrontEnd )
				)
				( attribute "CDS_LIB" "dev_discrete"
					( Origin gPackager )
				)
				( attribute "CDS_LOCATION" "C2M2"
					( Origin gPackager )
				)
				( attribute "CDS_SEC" "1"
					( Origin gPackager )
				)
				( attribute "LOCATION" "C2M2"
					( Origin gFrontEnd )
				)
				( attribute "MATERIAL" "X6S"
					( Origin gFrontEnd )
				)
				( attribute "PACK_TYPE" "0603V"
					( Origin gFrontEnd )
				)
				( attribute "PART_NUMBER" "E15431-004"
					( Origin gFrontEnd )
				)
				( attribute "PHYS_PAGE" "130"
					( Origin gFrontEnd )
				)
				( attribute "ROOM" "SB_DECOUPLING"
					( Origin gFrontEnd )
				)
				( attribute "ROT" "0"
					( Origin gFrontEnd )
				)
				( attribute "SEC" "1"
					( Origin gPackager )
				)
				( attribute "TOLERANCE" "20%"
					( Origin gFrontEnd )
				)
				( attribute "VALUE" "22.0UF"
					( Origin gFrontEnd )
				)
				( attribute "VER" "1"
					( Origin gFrontEnd )
				)
				( attribute "VOLTAGE" "4V"
					( Units "uVoltage" "V" 1.000000)
					( Origin gFrontEnd )
				)
				( attribute "XY" "(-5150,2750)"
					( Origin gFrontEnd )
				)
				( attribute "CHIPS_PART_NAME" "CAP_A"
					( Origin gPackager )
				)
				( attribute "CDS_PART_NAME" "CAP_A_0603V-22.0UF,4V,20%,X6S,A"
					( Origin gPackager )
				)
				( objectStatus "C2M2" )
			)
			( gate "@baseboard_fab2_lib.baseboard_fab2(sch_1):page130_i47"
				( attribute "BOM_COST" "SB"
					( Origin gFrontEnd )
				)
				( attribute "CDS_LIB" "dev_discrete"
					( Origin gPackager )
				)
				( attribute "CDS_LOCATION" "C2N15"
					( Origin gPackager )
				)
				( attribute "CDS_SEC" "1"
					( Origin gPackager )
				)
				( attribute "LOCATION" "C2N15"
					( Origin gFrontEnd )
				)
				( attribute "MATERIAL" "X6S"
					( Origin gFrontEnd )
				)
				( attribute "PACK_TYPE" "0402V"
					( Origin gFrontEnd )
				)
				( attribute "PART_NUMBER" "D97712-004"
					( Origin gFrontEnd )
				)
				( attribute "PHYS_PAGE" "130"
					( Origin gFrontEnd )
				)
				( attribute "ROOM" "SB_DECOUPLING"
					( Origin gFrontEnd )
				)
				( attribute "ROT" "0"
					( Origin gFrontEnd )
				)
				( attribute "SEC" "1"
					( Origin gPackager )
				)
				( attribute "TOLERANCE" "10%"
					( Origin gFrontEnd )
				)
				( attribute "VALUE" "1.0UF"
					( Origin gFrontEnd )
				)
				( attribute "VER" "1"
					( Origin gFrontEnd )
				)
				( attribute "VOLTAGE" "6.3V"
					( Units "uVoltage" "V" 1.000000)
					( Origin gFrontEnd )
				)
				( attribute "XY" "(-3600,1475)"
					( Origin gFrontEnd )
				)
				( attribute "CHIPS_PART_NAME" "CAP_A"
					( Origin gPackager )
				)
				( attribute "CDS_PART_NAME" "CAP_A_0402V-1.0UF,6.3V,10%,X6SA"
					( Origin gPackager )
				)
				( objectStatus "C2N15" )
			)
			( gate "@baseboard_fab2_lib.baseboard_fab2(sch_1):page130_i49"
				( attribute "BOM_COST" "SB"
					( Origin gFrontEnd )
				)
				( attribute "CDS_LIB" "dev_discrete"
					( Origin gPackager )
				)
				( attribute "CDS_LOCATION" "C3N21"
					( Origin gPackager )
				)
				( attribute "CDS_SEC" "1"
					( Origin gPackager )
				)
				( attribute "LOCATION" "C3N21"
					( Origin gFrontEnd )
				)
				( attribute "MATERIAL" "X6S"
					( Origin gFrontEnd )
				)
				( attribute "PACK_TYPE" "0402V"
					( Origin gFrontEnd )
				)
				( attribute "PART_NUMBER" "D97712-004"
					( Origin gFrontEnd )
				)
				( attribute "PHYS_PAGE" "130"
					( Origin gFrontEnd )
				)
				( attribute "ROOM" "SB_DECOUPLING"
					( Origin gFrontEnd )
				)
				( attribute "ROT" "0"
					( Origin gFrontEnd )
				)
				( attribute "SEC" "1"
					( Origin gPackager )
				)
				( attribute "TOLERANCE" "10%"
					( Origin gFrontEnd )
				)
				( attribute "VALUE" "1.0UF"
					( Origin gFrontEnd )
				)
				( attribute "VER" "1"
					( Origin gFrontEnd )
				)
				( attribute "VOLTAGE" "6.3V"
					( Units "uVoltage" "V" 1.000000)
					( Origin gFrontEnd )
				)
				( attribute "XY" "(-3975,1475)"
					( Origin gFrontEnd )
				)
				( attribute "CHIPS_PART_NAME" "CAP_A"
					( Origin gPackager )
				)
				( attribute "CDS_PART_NAME" "CAP_A_0402V-1.0UF,6.3V,10%,X6SA"
					( Origin gPackager )
				)
				( objectStatus "C3N21" )
			)
			( gate "@baseboard_fab2_lib.baseboard_fab2(sch_1):page130_i50"
				( attribute "BOM_COST" "SB"
					( Origin gFrontEnd )
				)
				( attribute "CDS_LIB" "dev_discrete"
					( Origin gPackager )
				)
				( attribute "CDS_LOCATION" "C3N25"
					( Origin gPackager )
				)
				( attribute "CDS_SEC" "1"
					( Origin gPackager )
				)
				( attribute "LOCATION" "C3N25"
					( Origin gFrontEnd )
				)
				( attribute "MATERIAL" "X6S"
					( Origin gFrontEnd )
				)
				( attribute "PACK_TYPE" "0402V"
					( Origin gFrontEnd )
				)
				( attribute "PART_NUMBER" "D97712-004"
					( Origin gFrontEnd )
				)
				( attribute "PHYS_PAGE" "130"
					( Origin gFrontEnd )
				)
				( attribute "ROOM" "SB_DECOUPLING"
					( Origin gFrontEnd )
				)
				( attribute "ROT" "0"
					( Origin gFrontEnd )
				)
				( attribute "SEC" "1"
					( Origin gPackager )
				)
				( attribute "TOLERANCE" "10%"
					( Origin gFrontEnd )
				)
				( attribute "VALUE" "1.0UF"
					( Origin gFrontEnd )
				)
				( attribute "VER" "1"
					( Origin gFrontEnd )
				)
				( attribute "VOLTAGE" "6.3V"
					( Units "uVoltage" "V" 1.000000)
					( Origin gFrontEnd )
				)
				( attribute "XY" "(-4350,1475)"
					( Origin gFrontEnd )
				)
				( attribute "CHIPS_PART_NAME" "CAP_A"
					( Origin gPackager )
				)
				( attribute "CDS_PART_NAME" "CAP_A_0402V-1.0UF,6.3V,10%,X6SA"
					( Origin gPackager )
				)
				( objectStatus "C3N25" )
			)
			( gate "@baseboard_fab2_lib.baseboard_fab2(sch_1):page130_i52"
				( attribute "BOM_COST" "SB"
					( Origin gFrontEnd )
				)
				( attribute "CDS_LIB" "dev_discrete"
					( Origin gPackager )
				)
				( attribute "CDS_LOCATION" "C2N16"
					( Origin gPackager )
				)
				( attribute "CDS_SEC" "1"
					( Origin gPackager )
				)
				( attribute "LOCATION" "C2N16"
					( Origin gFrontEnd )
				)
				( attribute "MATERIAL" "X6S"
					( Origin gFrontEnd )
				)
				( attribute "PACK_TYPE" "0402V"
					( Origin gFrontEnd )
				)
				( attribute "PART_NUMBER" "D97712-004"
					( Origin gFrontEnd )
				)
				( attribute "PHYS_PAGE" "130"
					( Origin gFrontEnd )
				)
				( attribute "ROOM" "SB_DECOUPLING"
					( Origin gFrontEnd )
				)
				( attribute "ROT" "0"
					( Origin gFrontEnd )
				)
				( attribute "SEC" "1"
					( Origin gPackager )
				)
				( attribute "TOLERANCE" "10%"
					( Origin gFrontEnd )
				)
				( attribute "VALUE" "1.0UF"
					( Origin gFrontEnd )
				)
				( attribute "VER" "1"
					( Origin gFrontEnd )
				)
				( attribute "VOLTAGE" "6.3V"
					( Units "uVoltage" "V" 1.000000)
					( Origin gFrontEnd )
				)
				( attribute "XY" "(-4775,1475)"
					( Origin gFrontEnd )
				)
				( attribute "CHIPS_PART_NAME" "CAP_A"
					( Origin gPackager )
				)
				( attribute "CDS_PART_NAME" "CAP_A_0402V-1.0UF,6.3V,10%,X6SA"
					( Origin gPackager )
				)
				( objectStatus "C2N16" )
			)
			( gate "@baseboard_fab2_lib.baseboard_fab2(sch_1):page130_i53"
				( attribute "BOM_COST" "SB"
					( Origin gFrontEnd )
				)
				( attribute "CDS_LIB" "dev_discrete"
					( Origin gPackager )
				)
				( attribute "CDS_LOCATION" "C3N22"
					( Origin gPackager )
				)
				( attribute "CDS_SEC" "1"
					( Origin gPackager )
				)
				( attribute "LOCATION" "C3N22"
					( Origin gFrontEnd )
				)
				( attribute "MATERIAL" "X6S"
					( Origin gFrontEnd )
				)
				( attribute "PACK_TYPE" "0402V"
					( Origin gFrontEnd )
				)
				( attribute "PART_NUMBER" "D97712-004"
					( Origin gFrontEnd )
				)
				( attribute "PHYS_PAGE" "130"
					( Origin gFrontEnd )
				)
				( attribute "ROOM" "SB_DECOUPLING"
					( Origin gFrontEnd )
				)
				( attribute "ROT" "0"
					( Origin gFrontEnd )
				)
				( attribute "SEC" "1"
					( Origin gPackager )
				)
				( attribute "TOLERANCE" "10%"
					( Origin gFrontEnd )
				)
				( attribute "VALUE" "1.0UF"
					( Origin gFrontEnd )
				)
				( attribute "VER" "1"
					( Origin gFrontEnd )
				)
				( attribute "VOLTAGE" "6.3V"
					( Units "uVoltage" "V" 1.000000)
					( Origin gFrontEnd )
				)
				( attribute "XY" "(-5200,1475)"
					( Origin gFrontEnd )
				)
				( attribute "CHIPS_PART_NAME" "CAP_A"
					( Origin gPackager )
				)
				( attribute "CDS_PART_NAME" "CAP_A_0402V-1.0UF,6.3V,10%,X6SA"
					( Origin gPackager )
				)
				( objectStatus "C3N22" )
			)
			( gate "@baseboard_fab2_lib.baseboard_fab2(sch_1):page131_i1"
				( attribute "BOM_COST" "SB"
					( Origin gFrontEnd )
				)
				( attribute "CDS_LIB" "dev_discrete"
					( Origin gPackager )
				)
				( attribute "CDS_LOCATION" "C7B15"
					( Origin gPackager )
				)
				( attribute "CDS_SEC" "1"
					( Origin gPackager )
				)
				( attribute "LOCATION" "C7B15"
					( Origin gFrontEnd )
				)
				( attribute "MATERIAL" "X6S"
					( Origin gFrontEnd )
				)
				( attribute "PACK_TYPE" "0603V"
					( Origin gFrontEnd )
				)
				( attribute "PART_NUMBER" "E15431-004"
					( Origin gFrontEnd )
				)
				( attribute "PHYS_PAGE" "131"
					( Origin gFrontEnd )
				)
				( attribute "ROOM" "SB_DECOUPLING"
					( Origin gFrontEnd )
				)
				( attribute "ROT" "0"
					( Origin gFrontEnd )
				)
				( attribute "SEC" "1"
					( Origin gPackager )
				)
				( attribute "TOLERANCE" "20%"
					( Origin gFrontEnd )
				)
				( attribute "VALUE" "22.0UF"
					( Origin gFrontEnd )
				)
				( attribute "VER" "1"
					( Origin gFrontEnd )
				)
				( attribute "VOLTAGE" "4V"
					( Units "uVoltage" "V" 1.000000)
					( Origin gFrontEnd )
				)
				( attribute "XY" "(975,4975)"
					( Origin gFrontEnd )
				)
				( attribute "CHIPS_PART_NAME" "CAP_A"
					( Origin gPackager )
				)
				( attribute "CDS_PART_NAME" "CAP_A_0603V-22.0UF,4V,20%,X6S,A"
					( Origin gPackager )
				)
				( objectStatus "C7B15" )
			)
			( gate "@baseboard_fab2_lib.baseboard_fab2(sch_1):page131_i2"
				( attribute "BOM_COST" "SB"
					( Origin gFrontEnd )
				)
				( attribute "CDS_LIB" "dev_discrete"
					( Origin gPackager )
				)
				( attribute "CDS_LOCATION" "C7B19"
					( Origin gPackager )
				)
				( attribute "CDS_SEC" "1"
					( Origin gPackager )
				)
				( attribute "LOCATION" "C7B19"
					( Origin gFrontEnd )
				)
				( attribute "MATERIAL" "X6S"
					( Origin gFrontEnd )
				)
				( attribute "PACK_TYPE" "0603V"
					( Origin gFrontEnd )
				)
				( attribute "PART_NUMBER" "E15431-004"
					( Origin gFrontEnd )
				)
				( attribute "PHYS_PAGE" "131"
					( Origin gFrontEnd )
				)
				( attribute "ROOM" "SB_DECOUPLING"
					( Origin gFrontEnd )
				)
				( attribute "ROT" "0"
					( Origin gFrontEnd )
				)
				( attribute "SEC" "1"
					( Origin gPackager )
				)
				( attribute "TOLERANCE" "20%"
					( Origin gFrontEnd )
				)
				( attribute "VALUE" "22.0UF"
					( Origin gFrontEnd )
				)
				( attribute "VER" "1"
					( Origin gFrontEnd )
				)
				( attribute "VOLTAGE" "4V"
					( Units "uVoltage" "V" 1.000000)
					( Origin gFrontEnd )
				)
				( attribute "XY" "(500,4975)"
					( Origin gFrontEnd )
				)
				( attribute "CHIPS_PART_NAME" "CAP_A"
					( Origin gPackager )
				)
				( attribute "CDS_PART_NAME" "CAP_A_0603V-22.0UF,4V,20%,X6S,A"
					( Origin gPackager )
				)
				( objectStatus "C7B19" )
			)
			( gate "@baseboard_fab2_lib.baseboard_fab2(sch_1):page131_i3"
				( attribute "BOM_COST" "SB"
					( Origin gFrontEnd )
				)
				( attribute "CDS_LIB" "dev_discrete"
					( Origin gPackager )
				)
				( attribute "CDS_LOCATION" "C7B16"
					( Origin gPackager )
				)
				( attribute "CDS_SEC" "1"
					( Origin gPackager )
				)
				( attribute "LOCATION" "C7B16"
					( Origin gFrontEnd )
				)
				( attribute "MATERIAL" "X6S"
					( Origin gFrontEnd )
				)
				( attribute "PACK_TYPE" "0603V"
					( Origin gFrontEnd )
				)
				( attribute "PART_NUMBER" "E15431-004"
					( Origin gFrontEnd )
				)
				( attribute "PHYS_PAGE" "131"
					( Origin gFrontEnd )
				)
				( attribute "ROOM" "SB_DECOUPLING"
					( Origin gFrontEnd )
				)
				( attribute "ROT" "0"
					( Origin gFrontEnd )
				)
				( attribute "SEC" "1"
					( Origin gPackager )
				)
				( attribute "TOLERANCE" "20%"
					( Origin gFrontEnd )
				)
				( attribute "VALUE" "22.0UF"
					( Origin gFrontEnd )
				)
				( attribute "VER" "1"
					( Origin gFrontEnd )
				)
				( attribute "VOLTAGE" "4V"
					( Units "uVoltage" "V" 1.000000)
					( Origin gFrontEnd )
				)
				( attribute "XY" "(50,4975)"
					( Origin gFrontEnd )
				)
				( attribute "CHIPS_PART_NAME" "CAP_A"
					( Origin gPackager )
				)
				( attribute "CDS_PART_NAME" "CAP_A_0603V-22.0UF,4V,20%,X6S,A"
					( Origin gPackager )
				)
				( objectStatus "C7B16" )
			)
			( gate "@baseboard_fab2_lib.baseboard_fab2(sch_1):page131_i4"
				( attribute "BOM_COST" "SB"
					( Origin gFrontEnd )
				)
				( attribute "CDS_LIB" "dev_discrete"
					( Origin gPackager )
				)
				( attribute "CDS_LOCATION" "C7B21"
					( Origin gPackager )
				)
				( attribute "CDS_SEC" "1"
					( Origin gPackager )
				)
				( attribute "LOCATION" "C7B21"
					( Origin gFrontEnd )
				)
				( attribute "MATERIAL" "X6S"
					( Origin gFrontEnd )
				)
				( attribute "PACK_TYPE" "0603V"
					( Origin gFrontEnd )
				)
				( attribute "PART_NUMBER" "E15431-004"
					( Origin gFrontEnd )
				)
				( attribute "PHYS_PAGE" "131"
					( Origin gFrontEnd )
				)
				( attribute "ROOM" "SB_DECOUPLING"
					( Origin gFrontEnd )
				)
				( attribute "ROT" "0"
					( Origin gFrontEnd )
				)
				( attribute "SEC" "1"
					( Origin gPackager )
				)
				( attribute "TOLERANCE" "20%"
					( Origin gFrontEnd )
				)
				( attribute "VALUE" "22.0UF"
					( Origin gFrontEnd )
				)
				( attribute "VER" "1"
					( Origin gFrontEnd )
				)
				( attribute "VOLTAGE" "4V"
					( Units "uVoltage" "V" 1.000000)
					( Origin gFrontEnd )
				)
				( attribute "XY" "(-425,4975)"
					( Origin gFrontEnd )
				)
				( attribute "CHIPS_PART_NAME" "CAP_A"
					( Origin gPackager )
				)
				( attribute "CDS_PART_NAME" "CAP_A_0603V-22.0UF,4V,20%,X6S,A"
					( Origin gPackager )
				)
				( objectStatus "C7B21" )
			)
			( gate "@baseboard_fab2_lib.baseboard_fab2(sch_1):page131_i6"
				( attribute "BOM_COST" "SB"
					( Origin gFrontEnd )
				)
				( attribute "CDS_LIB" "dev_discrete"
					( Origin gPackager )
				)
				( attribute "CDS_LOCATION" "C7B20"
					( Origin gPackager )
				)
				( attribute "CDS_SEC" "1"
					( Origin gPackager )
				)
				( attribute "LOCATION" "C7B20"
					( Origin gFrontEnd )
				)
				( attribute "MATERIAL" "X6S"
					( Origin gFrontEnd )
				)
				( attribute "PACK_TYPE" "0603V"
					( Origin gFrontEnd )
				)
				( attribute "PART_NUMBER" "E15431-004"
					( Origin gFrontEnd )
				)
				( attribute "PHYS_PAGE" "131"
					( Origin gFrontEnd )
				)
				( attribute "ROOM" "SB_DECOUPLING"
					( Origin gFrontEnd )
				)
				( attribute "ROT" "0"
					( Origin gFrontEnd )
				)
				( attribute "SEC" "1"
					( Origin gPackager )
				)
				( attribute "TOLERANCE" "20%"
					( Origin gFrontEnd )
				)
				( attribute "VALUE" "22.0UF"
					( Origin gFrontEnd )
				)
				( attribute "VER" "1"
					( Origin gFrontEnd )
				)
				( attribute "VOLTAGE" "4V"
					( Units "uVoltage" "V" 1.000000)
					( Origin gFrontEnd )
				)
				( attribute "XY" "(-875,4975)"
					( Origin gFrontEnd )
				)
				( attribute "CHIPS_PART_NAME" "CAP_A"
					( Origin gPackager )
				)
				( attribute "CDS_PART_NAME" "CAP_A_0603V-22.0UF,4V,20%,X6S,A"
					( Origin gPackager )
				)
				( objectStatus "C7B20" )
			)
			( gate "@baseboard_fab2_lib.baseboard_fab2(sch_1):page131_i7"
				( attribute "BOM_COST" "SB"
					( Origin gFrontEnd )
				)
				( attribute "CDS_LIB" "dev_discrete"
					( Origin gPackager )
				)
				( attribute "CDS_LOCATION" "C7B23"
					( Origin gPackager )
				)
				( attribute "CDS_SEC" "1"
					( Origin gPackager )
				)
				( attribute "LOCATION" "C7B23"
					( Origin gFrontEnd )
				)
				( attribute "MATERIAL" "X6S"
					( Origin gFrontEnd )
				)
				( attribute "PACK_TYPE" "0603V"
					( Origin gFrontEnd )
				)
				( attribute "PART_NUMBER" "E15431-004"
					( Origin gFrontEnd )
				)
				( attribute "PHYS_PAGE" "131"
					( Origin gFrontEnd )
				)
				( attribute "ROOM" "SB_DECOUPLING"
					( Origin gFrontEnd )
				)
				( attribute "ROT" "0"
					( Origin gFrontEnd )
				)
				( attribute "SEC" "1"
					( Origin gPackager )
				)
				( attribute "TOLERANCE" "20%"
					( Origin gFrontEnd )
				)
				( attribute "VALUE" "22.0UF"
					( Origin gFrontEnd )
				)
				( attribute "VER" "1"
					( Origin gFrontEnd )
				)
				( attribute "VOLTAGE" "4V"
					( Units "uVoltage" "V" 1.000000)
					( Origin gFrontEnd )
				)
				( attribute "XY" "(975,4025)"
					( Origin gFrontEnd )
				)
				( attribute "CHIPS_PART_NAME" "CAP_A"
					( Origin gPackager )
				)
				( attribute "CDS_PART_NAME" "CAP_A_0603V-22.0UF,4V,20%,X6S,A"
					( Origin gPackager )
				)
				( objectStatus "C7B23" )
			)
			( gate "@baseboard_fab2_lib.baseboard_fab2(sch_1):page131_i8"
				( attribute "BOM_COST" "SB"
					( Origin gFrontEnd )
				)
				( attribute "CDS_LIB" "dev_discrete"
					( Origin gPackager )
				)
				( attribute "CDS_LOCATION" "C8B10"
					( Origin gPackager )
				)
				( attribute "CDS_SEC" "1"
					( Origin gPackager )
				)
				( attribute "LOCATION" "C8B10"
					( Origin gFrontEnd )
				)
				( attribute "MATERIAL" "X6S"
					( Origin gFrontEnd )
				)
				( attribute "PACK_TYPE" "0603V"
					( Origin gFrontEnd )
				)
				( attribute "PART_NUMBER" "E15431-004"
					( Origin gFrontEnd )
				)
				( attribute "PHYS_PAGE" "131"
					( Origin gFrontEnd )
				)
				( attribute "ROOM" "SB_DECOUPLING"
					( Origin gFrontEnd )
				)
				( attribute "ROT" "0"
					( Origin gFrontEnd )
				)
				( attribute "SEC" "1"
					( Origin gPackager )
				)
				( attribute "TOLERANCE" "20%"
					( Origin gFrontEnd )
				)
				( attribute "VALUE" "22.0UF"
					( Origin gFrontEnd )
				)
				( attribute "VER" "1"
					( Origin gFrontEnd )
				)
				( attribute "VOLTAGE" "4V"
					( Units "uVoltage" "V" 1.000000)
					( Origin gFrontEnd )
				)
				( attribute "XY" "(950,3025)"
					( Origin gFrontEnd )
				)
				( attribute "CHIPS_PART_NAME" "CAP_A"
					( Origin gPackager )
				)
				( attribute "CDS_PART_NAME" "CAP_A_0603V-22.0UF,4V,20%,X6S,A"
					( Origin gPackager )
				)
				( objectStatus "C8B10" )
			)
			( gate "@baseboard_fab2_lib.baseboard_fab2(sch_1):page131_i10"
				( attribute "BOM_COST" "SB"
					( Origin gFrontEnd )
				)
				( attribute "CDS_LIB" "dev_discrete"
					( Origin gPackager )
				)
				( attribute "CDS_LOCATION" "C7B22"
					( Origin gPackager )
				)
				( attribute "CDS_SEC" "1"
					( Origin gPackager )
				)
				( attribute "LOCATION" "C7B22"
					( Origin gFrontEnd )
				)
				( attribute "MATERIAL" "X6S"
					( Origin gFrontEnd )
				)
				( attribute "PACK_TYPE" "0603V"
					( Origin gFrontEnd )
				)
				( attribute "PART_NUMBER" "E15431-004"
					( Origin gFrontEnd )
				)
				( attribute "PHYS_PAGE" "131"
					( Origin gFrontEnd )
				)
				( attribute "ROOM" "SB_DECOUPLING"
					( Origin gFrontEnd )
				)
				( attribute "ROT" "0"
					( Origin gFrontEnd )
				)
				( attribute "SEC" "1"
					( Origin gPackager )
				)
				( attribute "TOLERANCE" "20%"
					( Origin gFrontEnd )
				)
				( attribute "VALUE" "22.0UF"
					( Origin gFrontEnd )
				)
				( attribute "VER" "1"
					( Origin gFrontEnd )
				)
				( attribute "VOLTAGE" "4V"
					( Units "uVoltage" "V" 1.000000)
					( Origin gFrontEnd )
				)
				( attribute "XY" "(500,4025)"
					( Origin gFrontEnd )
				)
				( attribute "CHIPS_PART_NAME" "CAP_A"
					( Origin gPackager )
				)
				( attribute "CDS_PART_NAME" "CAP_A_0603V-22.0UF,4V,20%,X6S,A"
					( Origin gPackager )
				)
				( objectStatus "C7B22" )
			)
			( gate "@baseboard_fab2_lib.baseboard_fab2(sch_1):page131_i11"
				( attribute "BOM_COST" "SB"
					( Origin gFrontEnd )
				)
				( attribute "CDS_LIB" "dev_discrete"
					( Origin gPackager )
				)
				( attribute "CDS_LOCATION" "C7B24"
					( Origin gPackager )
				)
				( attribute "CDS_SEC" "1"
					( Origin gPackager )
				)
				( attribute "LOCATION" "C7B24"
					( Origin gFrontEnd )
				)
				( attribute "MATERIAL" "X6S"
					( Origin gFrontEnd )
				)
				( attribute "PACK_TYPE" "0603V"
					( Origin gFrontEnd )
				)
				( attribute "PART_NUMBER" "E15431-004"
					( Origin gFrontEnd )
				)
				( attribute "PHYS_PAGE" "131"
					( Origin gFrontEnd )
				)
				( attribute "ROOM" "SB_DECOUPLING"
					( Origin gFrontEnd )
				)
				( attribute "ROT" "0"
					( Origin gFrontEnd )
				)
				( attribute "SEC" "1"
					( Origin gPackager )
				)
				( attribute "TOLERANCE" "20%"
					( Origin gFrontEnd )
				)
				( attribute "VALUE" "22.0UF"
					( Origin gFrontEnd )
				)
				( attribute "VER" "1"
					( Origin gFrontEnd )
				)
				( attribute "VOLTAGE" "4V"
					( Units "uVoltage" "V" 1.000000)
					( Origin gFrontEnd )
				)
				( attribute "XY" "(50,4025)"
					( Origin gFrontEnd )
				)
				( attribute "CHIPS_PART_NAME" "CAP_A"
					( Origin gPackager )
				)
				( attribute "CDS_PART_NAME" "CAP_A_0603V-22.0UF,4V,20%,X6S,A"
					( Origin gPackager )
				)
				( objectStatus "C7B24" )
			)
			( gate "@baseboard_fab2_lib.baseboard_fab2(sch_1):page131_i12"
				( attribute "BOM_COST" "SB"
					( Origin gFrontEnd )
				)
				( attribute "CDS_LIB" "dev_discrete"
					( Origin gPackager )
				)
				( attribute "CDS_LOCATION" "C7B18"
					( Origin gPackager )
				)
				( attribute "CDS_SEC" "1"
					( Origin gPackager )
				)
				( attribute "LOCATION" "C7B18"
					( Origin gFrontEnd )
				)
				( attribute "MATERIAL" "X6S"
					( Origin gFrontEnd )
				)
				( attribute "PACK_TYPE" "0603V"
					( Origin gFrontEnd )
				)
				( attribute "PART_NUMBER" "E15431-004"
					( Origin gFrontEnd )
				)
				( attribute "PHYS_PAGE" "131"
					( Origin gFrontEnd )
				)
				( attribute "ROOM" "SB_DECOUPLING"
					( Origin gFrontEnd )
				)
				( attribute "ROT" "0"
					( Origin gFrontEnd )
				)
				( attribute "SEC" "1"
					( Origin gPackager )
				)
				( attribute "TOLERANCE" "20%"
					( Origin gFrontEnd )
				)
				( attribute "VALUE" "22.0UF"
					( Origin gFrontEnd )
				)
				( attribute "VER" "1"
					( Origin gFrontEnd )
				)
				( attribute "VOLTAGE" "4V"
					( Units "uVoltage" "V" 1.000000)
					( Origin gFrontEnd )
				)
				( attribute "XY" "(-425,4025)"
					( Origin gFrontEnd )
				)
				( attribute "CHIPS_PART_NAME" "CAP_A"
					( Origin gPackager )
				)
				( attribute "CDS_PART_NAME" "CAP_A_0603V-22.0UF,4V,20%,X6S,A"
					( Origin gPackager )
				)
				( objectStatus "C7B18" )
			)
			( gate "@baseboard_fab2_lib.baseboard_fab2(sch_1):page131_i14"
				( attribute "BOM_COST" "SB"
					( Origin gFrontEnd )
				)
				( attribute "CDS_LIB" "dev_discrete"
					( Origin gPackager )
				)
				( attribute "CDS_LOCATION" "C8B9"
					( Origin gPackager )
				)
				( attribute "CDS_SEC" "1"
					( Origin gPackager )
				)
				( attribute "LOCATION" "C8B9"
					( Origin gFrontEnd )
				)
				( attribute "MATERIAL" "X6S"
					( Origin gFrontEnd )
				)
				( attribute "PACK_TYPE" "0603V"
					( Origin gFrontEnd )
				)
				( attribute "PART_NUMBER" "E15431-004"
					( Origin gFrontEnd )
				)
				( attribute "PHYS_PAGE" "131"
					( Origin gFrontEnd )
				)
				( attribute "ROOM" "SB_DECOUPLING"
					( Origin gFrontEnd )
				)
				( attribute "ROT" "0"
					( Origin gFrontEnd )
				)
				( attribute "SEC" "1"
					( Origin gPackager )
				)
				( attribute "TOLERANCE" "20%"
					( Origin gFrontEnd )
				)
				( attribute "VALUE" "22.0UF"
					( Origin gFrontEnd )
				)
				( attribute "VER" "1"
					( Origin gFrontEnd )
				)
				( attribute "VOLTAGE" "4V"
					( Units "uVoltage" "V" 1.000000)
					( Origin gFrontEnd )
				)
				( attribute "XY" "(500,3025)"
					( Origin gFrontEnd )
				)
				( attribute "CHIPS_PART_NAME" "CAP_A"
					( Origin gPackager )
				)
				( attribute "CDS_PART_NAME" "CAP_A_0603V-22.0UF,4V,20%,X6S,A"
					( Origin gPackager )
				)
				( objectStatus "C8B9" )
			)
			( gate "@baseboard_fab2_lib.baseboard_fab2(sch_1):page131_i15"
				( attribute "BOM_COST" "SB"
					( Origin gFrontEnd )
				)
				( attribute "CDS_LIB" "dev_discrete"
					( Origin gPackager )
				)
				( attribute "CDS_LOCATION" "C8B11"
					( Origin gPackager )
				)
				( attribute "CDS_SEC" "1"
					( Origin gPackager )
				)
				( attribute "LOCATION" "C8B11"
					( Origin gFrontEnd )
				)
				( attribute "MATERIAL" "X6S"
					( Origin gFrontEnd )
				)
				( attribute "PACK_TYPE" "0603V"
					( Origin gFrontEnd )
				)
				( attribute "PART_NUMBER" "E15431-004"
					( Origin gFrontEnd )
				)
				( attribute "PHYS_PAGE" "131"
					( Origin gFrontEnd )
				)
				( attribute "ROOM" "SB_DECOUPLING"
					( Origin gFrontEnd )
				)
				( attribute "ROT" "0"
					( Origin gFrontEnd )
				)
				( attribute "SEC" "1"
					( Origin gPackager )
				)
				( attribute "TOLERANCE" "20%"
					( Origin gFrontEnd )
				)
				( attribute "VALUE" "22.0UF"
					( Origin gFrontEnd )
				)
				( attribute "VER" "1"
					( Origin gFrontEnd )
				)
				( attribute "VOLTAGE" "4V"
					( Units "uVoltage" "V" 1.000000)
					( Origin gFrontEnd )
				)
				( attribute "XY" "(50,3025)"
					( Origin gFrontEnd )
				)
				( attribute "CHIPS_PART_NAME" "CAP_A"
					( Origin gPackager )
				)
				( attribute "CDS_PART_NAME" "CAP_A_0603V-22.0UF,4V,20%,X6S,A"
					( Origin gPackager )
				)
				( objectStatus "C8B11" )
			)
			( gate "@baseboard_fab2_lib.baseboard_fab2(sch_1):page131_i16"
				( attribute "BOM_COST" "SB"
					( Origin gFrontEnd )
				)
				( attribute "CDS_LIB" "dev_discrete"
					( Origin gPackager )
				)
				( attribute "CDS_LOCATION" "C8B14"
					( Origin gPackager )
				)
				( attribute "CDS_SEC" "1"
					( Origin gPackager )
				)
				( attribute "LOCATION" "C8B14"
					( Origin gFrontEnd )
				)
				( attribute "MATERIAL" "X6S"
					( Origin gFrontEnd )
				)
				( attribute "PACK_TYPE" "0603V"
					( Origin gFrontEnd )
				)
				( attribute "PART_NUMBER" "E15431-004"
					( Origin gFrontEnd )
				)
				( attribute "PHYS_PAGE" "131"
					( Origin gFrontEnd )
				)
				( attribute "ROOM" "SB_DECOUPLING"
					( Origin gFrontEnd )
				)
				( attribute "ROT" "0"
					( Origin gFrontEnd )
				)
				( attribute "SEC" "1"
					( Origin gPackager )
				)
				( attribute "TOLERANCE" "20%"
					( Origin gFrontEnd )
				)
				( attribute "VALUE" "22.0UF"
					( Origin gFrontEnd )
				)
				( attribute "VER" "1"
					( Origin gFrontEnd )
				)
				( attribute "VOLTAGE" "4V"
					( Units "uVoltage" "V" 1.000000)
					( Origin gFrontEnd )
				)
				( attribute "XY" "(-400,3025)"
					( Origin gFrontEnd )
				)
				( attribute "CHIPS_PART_NAME" "CAP_A"
					( Origin gPackager )
				)
				( attribute "CDS_PART_NAME" "CAP_A_0603V-22.0UF,4V,20%,X6S,A"
					( Origin gPackager )
				)
				( objectStatus "C8B14" )
			)
			( gate "@baseboard_fab2_lib.baseboard_fab2(sch_1):page131_i18"
				( attribute "BOM_COST" "SB"
					( Origin gFrontEnd )
				)
				( attribute "CDS_LIB" "dev_discrete"
					( Origin gPackager )
				)
				( attribute "CDS_LOCATION" "C7B17"
					( Origin gPackager )
				)
				( attribute "CDS_SEC" "1"
					( Origin gPackager )
				)
				( attribute "LOCATION" "C7B17"
					( Origin gFrontEnd )
				)
				( attribute "MATERIAL" "X6S"
					( Origin gFrontEnd )
				)
				( attribute "PACK_TYPE" "0603V"
					( Origin gFrontEnd )
				)
				( attribute "PART_NUMBER" "E15431-004"
					( Origin gFrontEnd )
				)
				( attribute "PHYS_PAGE" "131"
					( Origin gFrontEnd )
				)
				( attribute "ROOM" "SB_DECOUPLING"
					( Origin gFrontEnd )
				)
				( attribute "ROT" "0"
					( Origin gFrontEnd )
				)
				( attribute "SEC" "1"
					( Origin gPackager )
				)
				( attribute "TOLERANCE" "20%"
					( Origin gFrontEnd )
				)
				( attribute "VALUE" "22.0UF"
					( Origin gFrontEnd )
				)
				( attribute "VER" "1"
					( Origin gFrontEnd )
				)
				( attribute "VOLTAGE" "4V"
					( Units "uVoltage" "V" 1.000000)
					( Origin gFrontEnd )
				)
				( attribute "XY" "(-875,4025)"
					( Origin gFrontEnd )
				)
				( attribute "CHIPS_PART_NAME" "CAP_A"
					( Origin gPackager )
				)
				( attribute "CDS_PART_NAME" "CAP_A_0603V-22.0UF,4V,20%,X6S,A"
					( Origin gPackager )
				)
				( objectStatus "C7B17" )
			)
			( gate "@baseboard_fab2_lib.baseboard_fab2(sch_1):page131_i20"
				( attribute "BOM_COST" "SB"
					( Origin gFrontEnd )
				)
				( attribute "CDS_LIB" "dev_discrete"
					( Origin gPackager )
				)
				( attribute "CDS_LOCATION" "C8B13"
					( Origin gPackager )
				)
				( attribute "CDS_SEC" "1"
					( Origin gPackager )
				)
				( attribute "LOCATION" "C8B13"
					( Origin gFrontEnd )
				)
				( attribute "MATERIAL" "X6S"
					( Origin gFrontEnd )
				)
				( attribute "PACK_TYPE" "0603V"
					( Origin gFrontEnd )
				)
				( attribute "PART_NUMBER" "E15431-004"
					( Origin gFrontEnd )
				)
				( attribute "PHYS_PAGE" "131"
					( Origin gFrontEnd )
				)
				( attribute "ROOM" "SB_DECOUPLING"
					( Origin gFrontEnd )
				)
				( attribute "ROT" "0"
					( Origin gFrontEnd )
				)
				( attribute "SEC" "1"
					( Origin gPackager )
				)
				( attribute "TOLERANCE" "20%"
					( Origin gFrontEnd )
				)
				( attribute "VALUE" "22.0UF"
					( Origin gFrontEnd )
				)
				( attribute "VER" "1"
					( Origin gFrontEnd )
				)
				( attribute "VOLTAGE" "4V"
					( Units "uVoltage" "V" 1.000000)
					( Origin gFrontEnd )
				)
				( attribute "XY" "(-850,3025)"
					( Origin gFrontEnd )
				)
				( attribute "CHIPS_PART_NAME" "CAP_A"
					( Origin gPackager )
				)
				( attribute "CDS_PART_NAME" "CAP_A_0603V-22.0UF,4V,20%,X6S,A"
					( Origin gPackager )
				)
				( objectStatus "C8B13" )
			)
			( gate "@baseboard_fab2_lib.baseboard_fab2(sch_1):page131_i22"
				( attribute "BOM_COST" "SB"
					( Origin gFrontEnd )
				)
				( attribute "CDS_LIB" "mstr_discrete"
					( Origin gPackager )
				)
				( attribute "CDS_LOCATION" "C8B16"
					( Origin gPackager )
				)
				( attribute "CDS_SEC" "1"
					( Origin gPackager )
				)
				( attribute "LOCATION" "C8B16"
					( Origin gFrontEnd )
				)
				( attribute "MATERIAL" "X6S"
					( Origin gFrontEnd )
				)
				( attribute "PACK_TYPE" "0805"
					( Origin gFrontEnd )
				)
				( attribute "PART_NUMBER" "C95333-006"
					( Origin gFrontEnd )
				)
				( attribute "PHYS_PAGE" "131"
					( Origin gFrontEnd )
				)
				( attribute "ROOM" "SB_DECOUPLING"
					( Origin gFrontEnd )
				)
				( attribute "ROT" "0"
					( Origin gFrontEnd )
				)
				( attribute "SEC" "1"
					( Origin gPackager )
				)
				( attribute "TOLERANCE" "20%"
					( Origin gFrontEnd )
				)
				( attribute "VALUE" "47UF"
					( Origin gFrontEnd )
				)
				( attribute "VER" "1"
					( Origin gFrontEnd )
				)
				( attribute "VOLTAGE" "4V"
					( Units "uVoltage" "V" 1.000000)
					( Origin gFrontEnd )
				)
				( attribute "XY" "(50,2025)"
					( Origin gFrontEnd )
				)
				( attribute "CHIPS_PART_NAME" "CAP"
					( Origin gPackager )
				)
				( attribute "CDS_PART_NAME" "CAP_0805-47UF,4V,20%,X6S,C9533A"
					( Origin gPackager )
				)
				( objectStatus "C8B16" )
			)
			( gate "@baseboard_fab2_lib.baseboard_fab2(sch_1):page131_i24"
				( attribute "BOM_COST" "SB"
					( Origin gFrontEnd )
				)
				( attribute "CDS_LIB" "mstr_discrete"
					( Origin gPackager )
				)
				( attribute "CDS_LOCATION" "C8B15"
					( Origin gPackager )
				)
				( attribute "CDS_SEC" "1"
					( Origin gPackager )
				)
				( attribute "LOCATION" "C8B15"
					( Origin gFrontEnd )
				)
				( attribute "MATERIAL" "X6S"
					( Origin gFrontEnd )
				)
				( attribute "PACK_TYPE" "0805"
					( Origin gFrontEnd )
				)
				( attribute "PART_NUMBER" "C95333-006"
					( Origin gFrontEnd )
				)
				( attribute "PHYS_PAGE" "131"
					( Origin gFrontEnd )
				)
				( attribute "ROOM" "SB_DECOUPLING"
					( Origin gFrontEnd )
				)
				( attribute "ROT" "0"
					( Origin gFrontEnd )
				)
				( attribute "SEC" "1"
					( Origin gPackager )
				)
				( attribute "TOLERANCE" "20%"
					( Origin gFrontEnd )
				)
				( attribute "VALUE" "47UF"
					( Origin gFrontEnd )
				)
				( attribute "VER" "1"
					( Origin gFrontEnd )
				)
				( attribute "VOLTAGE" "4V"
					( Units "uVoltage" "V" 1.000000)
					( Origin gFrontEnd )
				)
				( attribute "XY" "(-400,2025)"
					( Origin gFrontEnd )
				)
				( attribute "CHIPS_PART_NAME" "CAP"
					( Origin gPackager )
				)
				( attribute "CDS_PART_NAME" "CAP_0805-47UF,4V,20%,X6S,C9533A"
					( Origin gPackager )
				)
				( objectStatus "C8B15" )
			)
			( gate "@baseboard_fab2_lib.baseboard_fab2(sch_1):page131_i27"
				( attribute "BOM_COST" "SB"
					( Origin gFrontEnd )
				)
				( attribute "CDS_LIB" "dev_discrete"
					( Origin gPackager )
				)
				( attribute "CDS_LOCATION" "C2M22"
					( Origin gPackager )
				)
				( attribute "CDS_SEC" "1"
					( Origin gPackager )
				)
				( attribute "LOCATION" "C2M22"
					( Origin gFrontEnd )
				)
				( attribute "MATERIAL" "X6S"
					( Origin gFrontEnd )
				)
				( attribute "PACK_TYPE" "0402V"
					( Origin gFrontEnd )
				)
				( attribute "PART_NUMBER" "D97712-004"
					( Origin gFrontEnd )
				)
				( attribute "PHYS_PAGE" "131"
					( Origin gFrontEnd )
				)
				( attribute "ROOM" "SB_DECOUPLING"
					( Origin gFrontEnd )
				)
				( attribute "ROT" "0"
					( Origin gFrontEnd )
				)
				( attribute "SEC" "1"
					( Origin gPackager )
				)
				( attribute "TOLERANCE" "10%"
					( Origin gFrontEnd )
				)
				( attribute "VALUE" "1.0UF"
					( Origin gFrontEnd )
				)
				( attribute "VER" "1"
					( Origin gFrontEnd )
				)
				( attribute "VOLTAGE" "6.3V"
					( Units "uVoltage" "V" 1.000000)
					( Origin gFrontEnd )
				)
				( attribute "XY" "(-2375,4725)"
					( Origin gFrontEnd )
				)
				( attribute "CHIPS_PART_NAME" "CAP_A"
					( Origin gPackager )
				)
				( attribute "CDS_PART_NAME" "CAP_A_0402V-1.0UF,6.3V,10%,X6SA"
					( Origin gPackager )
				)
				( objectStatus "C2M22" )
			)
			( gate "@baseboard_fab2_lib.baseboard_fab2(sch_1):page131_i28"
				( attribute "BOM_COST" "SB"
					( Origin gFrontEnd )
				)
				( attribute "CDS_LIB" "dev_discrete"
					( Origin gPackager )
				)
				( attribute "CDS_LOCATION" "C2M21"
					( Origin gPackager )
				)
				( attribute "CDS_SEC" "1"
					( Origin gPackager )
				)
				( attribute "LOCATION" "C2M21"
					( Origin gFrontEnd )
				)
				( attribute "MATERIAL" "X6S"
					( Origin gFrontEnd )
				)
				( attribute "PACK_TYPE" "0402V"
					( Origin gFrontEnd )
				)
				( attribute "PART_NUMBER" "D97712-004"
					( Origin gFrontEnd )
				)
				( attribute "PHYS_PAGE" "131"
					( Origin gFrontEnd )
				)
				( attribute "ROOM" "SB_DECOUPLING"
					( Origin gFrontEnd )
				)
				( attribute "ROT" "0"
					( Origin gFrontEnd )
				)
				( attribute "SEC" "1"
					( Origin gPackager )
				)
				( attribute "TOLERANCE" "10%"
					( Origin gFrontEnd )
				)
				( attribute "VALUE" "1.0UF"
					( Origin gFrontEnd )
				)
				( attribute "VER" "1"
					( Origin gFrontEnd )
				)
				( attribute "VOLTAGE" "6.3V"
					( Units "uVoltage" "V" 1.000000)
					( Origin gFrontEnd )
				)
				( attribute "XY" "(-2800,4725)"
					( Origin gFrontEnd )
				)
				( attribute "CHIPS_PART_NAME" "CAP_A"
					( Origin gPackager )
				)
				( attribute "CDS_PART_NAME" "CAP_A_0402V-1.0UF,6.3V,10%,X6SA"
					( Origin gPackager )
				)
				( objectStatus "C2M21" )
			)
			( gate "@baseboard_fab2_lib.baseboard_fab2(sch_1):page131_i29"
				( attribute "BOM_COST" "SB"
					( Origin gFrontEnd )
				)
				( attribute "CDS_LIB" "dev_discrete"
					( Origin gPackager )
				)
				( attribute "CDS_LOCATION" "C2M18"
					( Origin gPackager )
				)
				( attribute "CDS_SEC" "1"
					( Origin gPackager )
				)
				( attribute "LOCATION" "C2M18"
					( Origin gFrontEnd )
				)
				( attribute "MATERIAL" "X6S"
					( Origin gFrontEnd )
				)
				( attribute "PACK_TYPE" "0402V"
					( Origin gFrontEnd )
				)
				( attribute "PART_NUMBER" "D97712-004"
					( Origin gFrontEnd )
				)
				( attribute "PHYS_PAGE" "131"
					( Origin gFrontEnd )
				)
				( attribute "ROOM" "SB_DECOUPLING"
					( Origin gFrontEnd )
				)
				( attribute "ROT" "0"
					( Origin gFrontEnd )
				)
				( attribute "SEC" "1"
					( Origin gPackager )
				)
				( attribute "TOLERANCE" "10%"
					( Origin gFrontEnd )
				)
				( attribute "VALUE" "1.0UF"
					( Origin gFrontEnd )
				)
				( attribute "VER" "1"
					( Origin gFrontEnd )
				)
				( attribute "VOLTAGE" "6.3V"
					( Units "uVoltage" "V" 1.000000)
					( Origin gFrontEnd )
				)
				( attribute "XY" "(-3175,4725)"
					( Origin gFrontEnd )
				)
				( attribute "CHIPS_PART_NAME" "CAP_A"
					( Origin gPackager )
				)
				( attribute "CDS_PART_NAME" "CAP_A_0402V-1.0UF,6.3V,10%,X6SA"
					( Origin gPackager )
				)
				( objectStatus "C2M18" )
			)
			( gate "@baseboard_fab2_lib.baseboard_fab2(sch_1):page131_i31"
				( attribute "BOM_COST" "SB"
					( Origin gFrontEnd )
				)
				( attribute "CDS_LIB" "dev_discrete"
					( Origin gPackager )
				)
				( attribute "CDS_LOCATION" "C2M19"
					( Origin gPackager )
				)
				( attribute "CDS_SEC" "1"
					( Origin gPackager )
				)
				( attribute "LOCATION" "C2M19"
					( Origin gFrontEnd )
				)
				( attribute "MATERIAL" "X6S"
					( Origin gFrontEnd )
				)
				( attribute "PACK_TYPE" "0402V"
					( Origin gFrontEnd )
				)
				( attribute "PART_NUMBER" "D97712-004"
					( Origin gFrontEnd )
				)
				( attribute "PHYS_PAGE" "131"
					( Origin gFrontEnd )
				)
				( attribute "ROOM" "SB_DECOUPLING"
					( Origin gFrontEnd )
				)
				( attribute "ROT" "0"
					( Origin gFrontEnd )
				)
				( attribute "SEC" "1"
					( Origin gPackager )
				)
				( attribute "TOLERANCE" "10%"
					( Origin gFrontEnd )
				)
				( attribute "VALUE" "1.0UF"
					( Origin gFrontEnd )
				)
				( attribute "VER" "1"
					( Origin gFrontEnd )
				)
				( attribute "VOLTAGE" "6.3V"
					( Units "uVoltage" "V" 1.000000)
					( Origin gFrontEnd )
				)
				( attribute "XY" "(-2850,3525)"
					( Origin gFrontEnd )
				)
				( attribute "CHIPS_PART_NAME" "CAP_A"
					( Origin gPackager )
				)
				( attribute "CDS_PART_NAME" "CAP_A_0402V-1.0UF,6.3V,10%,X6SA"
					( Origin gPackager )
				)
				( objectStatus "C2M19" )
			)
			( gate "@baseboard_fab2_lib.baseboard_fab2(sch_1):page131_i32"
				( attribute "BOM_COST" "SB"
					( Origin gFrontEnd )
				)
				( attribute "CDS_LIB" "dev_discrete"
					( Origin gPackager )
				)
				( attribute "CDS_LOCATION" "C3M38"
					( Origin gPackager )
				)
				( attribute "CDS_SEC" "1"
					( Origin gPackager )
				)
				( attribute "LOCATION" "C3M38"
					( Origin gFrontEnd )
				)
				( attribute "MATERIAL" "X6S"
					( Origin gFrontEnd )
				)
				( attribute "PACK_TYPE" "0402V"
					( Origin gFrontEnd )
				)
				( attribute "PART_NUMBER" "D97712-004"
					( Origin gFrontEnd )
				)
				( attribute "PHYS_PAGE" "131"
					( Origin gFrontEnd )
				)
				( attribute "ROOM" "SB_DECOUPLING"
					( Origin gFrontEnd )
				)
				( attribute "ROT" "0"
					( Origin gFrontEnd )
				)
				( attribute "SEC" "1"
					( Origin gPackager )
				)
				( attribute "TOLERANCE" "10%"
					( Origin gFrontEnd )
				)
				( attribute "VALUE" "1.0UF"
					( Origin gFrontEnd )
				)
				( attribute "VER" "1"
					( Origin gFrontEnd )
				)
				( attribute "VOLTAGE" "6.3V"
					( Units "uVoltage" "V" 1.000000)
					( Origin gFrontEnd )
				)
				( attribute "XY" "(-3225,3525)"
					( Origin gFrontEnd )
				)
				( attribute "CHIPS_PART_NAME" "CAP_A"
					( Origin gPackager )
				)
				( attribute "CDS_PART_NAME" "CAP_A_0402V-1.0UF,6.3V,10%,X6SA"
					( Origin gPackager )
				)
				( objectStatus "C3M38" )
			)
			( gate "@baseboard_fab2_lib.baseboard_fab2(sch_1):page131_i34"
				( attribute "BOM_COST" "SB"
					( Origin gFrontEnd )
				)
				( attribute "CDS_LIB" "mstr_discrete"
					( Origin gPackager )
				)
				( attribute "CDS_LOCATION" "C2M17"
					( Origin gPackager )
				)
				( attribute "CDS_SEC" "1"
					( Origin gPackager )
				)
				( attribute "LOCATION" "C2M17"
					( Origin gFrontEnd )
				)
				( attribute "MATERIAL" "X6S"
					( Origin gFrontEnd )
				)
				( attribute "PACK_TYPE" "0805"
					( Origin gFrontEnd )
				)
				( attribute "PART_NUMBER" "C95333-006"
					( Origin gFrontEnd )
				)
				( attribute "PHYS_PAGE" "131"
					( Origin gFrontEnd )
				)
				( attribute "ROOM" "SB_DECOUPLING"
					( Origin gFrontEnd )
				)
				( attribute "ROT" "0"
					( Origin gFrontEnd )
				)
				( attribute "SEC" "1"
					( Origin gPackager )
				)
				( attribute "TOLERANCE" "20%"
					( Origin gFrontEnd )
				)
				( attribute "VALUE" "47UF"
					( Origin gFrontEnd )
				)
				( attribute "VER" "1"
					( Origin gFrontEnd )
				)
				( attribute "VOLTAGE" "4V"
					( Units "uVoltage" "V" 1.000000)
					( Origin gFrontEnd )
				)
				( attribute "XY" "(-2400,2025)"
					( Origin gFrontEnd )
				)
				( attribute "CHIPS_PART_NAME" "CAP"
					( Origin gPackager )
				)
				( attribute "CDS_PART_NAME" "CAP_0805-47UF,4V,20%,X6S,C9533A"
					( Origin gPackager )
				)
				( objectStatus "C2M17" )
			)
			( gate "@baseboard_fab2_lib.baseboard_fab2(sch_1):page131_i35"
				( attribute "BOM_COST" "SB"
					( Origin gFrontEnd )
				)
				( attribute "CDS_LIB" "mstr_discrete"
					( Origin gPackager )
				)
				( attribute "CDS_LOCATION" "C2M11"
					( Origin gPackager )
				)
				( attribute "CDS_SEC" "1"
					( Origin gPackager )
				)
				( attribute "LOCATION" "C2M11"
					( Origin gFrontEnd )
				)
				( attribute "MATERIAL" "X6S"
					( Origin gFrontEnd )
				)
				( attribute "PACK_TYPE" "0805"
					( Origin gFrontEnd )
				)
				( attribute "PART_NUMBER" "C95333-006"
					( Origin gFrontEnd )
				)
				( attribute "PHYS_PAGE" "131"
					( Origin gFrontEnd )
				)
				( attribute "ROOM" "SB_DECOUPLING"
					( Origin gFrontEnd )
				)
				( attribute "ROT" "0"
					( Origin gFrontEnd )
				)
				( attribute "SEC" "1"
					( Origin gPackager )
				)
				( attribute "TOLERANCE" "20%"
					( Origin gFrontEnd )
				)
				( attribute "VALUE" "47UF"
					( Origin gFrontEnd )
				)
				( attribute "VER" "1"
					( Origin gFrontEnd )
				)
				( attribute "VOLTAGE" "4V"
					( Units "uVoltage" "V" 1.000000)
					( Origin gFrontEnd )
				)
				( attribute "XY" "(-2800,2025)"
					( Origin gFrontEnd )
				)
				( attribute "CHIPS_PART_NAME" "CAP"
					( Origin gPackager )
				)
				( attribute "CDS_PART_NAME" "CAP_0805-47UF,4V,20%,X6S,C9533A"
					( Origin gPackager )
				)
				( objectStatus "C2M11" )
			)
			( gate "@baseboard_fab2_lib.baseboard_fab2(sch_1):page131_i37"
				( attribute "BOM_COST" "SB"
					( Origin gFrontEnd )
				)
				( attribute "CDS_LIB" "mstr_discrete"
					( Origin gPackager )
				)
				( attribute "CDS_LOCATION" "C8A13"
					( Origin gPackager )
				)
				( attribute "CDS_SEC" "1"
					( Origin gPackager )
				)
				( attribute "LOCATION" "C8A13"
					( Origin gFrontEnd )
				)
				( attribute "MATERIAL" "X6S"
					( Origin gFrontEnd )
				)
				( attribute "PACK_TYPE" "0805"
					( Origin gFrontEnd )
				)
				( attribute "PART_NUMBER" "C95333-006"
					( Origin gFrontEnd )
				)
				( attribute "PHYS_PAGE" "131"
					( Origin gFrontEnd )
				)
				( attribute "ROOM" "SB_DECOUPLING"
					( Origin gFrontEnd )
				)
				( attribute "ROT" "0"
					( Origin gFrontEnd )
				)
				( attribute "SEC" "1"
					( Origin gPackager )
				)
				( attribute "TOLERANCE" "20%"
					( Origin gFrontEnd )
				)
				( attribute "VALUE" "47UF"
					( Origin gFrontEnd )
				)
				( attribute "VER" "1"
					( Origin gFrontEnd )
				)
				( attribute "VOLTAGE" "4V"
					( Units "uVoltage" "V" 1.000000)
					( Origin gFrontEnd )
				)
				( attribute "XY" "(-3250,2025)"
					( Origin gFrontEnd )
				)
				( attribute "CHIPS_PART_NAME" "CAP"
					( Origin gPackager )
				)
				( attribute "CDS_PART_NAME" "CAP_0805-47UF,4V,20%,X6S,C9533A"
					( Origin gPackager )
				)
				( objectStatus "C8A13" )
			)
			( gate "@baseboard_fab2_lib.baseboard_fab2(sch_1):page131_i39"
				( attribute "BOM_COST" "SB"
					( Origin gFrontEnd )
				)
				( attribute "CDS_LIB" "dev_discrete"
					( Origin gPackager )
				)
				( attribute "CDS_LOCATION" "C2M20"
					( Origin gPackager )
				)
				( attribute "CDS_SEC" "1"
					( Origin gPackager )
				)
				( attribute "LOCATION" "C2M20"
					( Origin gFrontEnd )
				)
				( attribute "MATERIAL" "X6S"
					( Origin gFrontEnd )
				)
				( attribute "PACK_TYPE" "0402V"
					( Origin gFrontEnd )
				)
				( attribute "PART_NUMBER" "D97712-004"
					( Origin gFrontEnd )
				)
				( attribute "PHYS_PAGE" "131"
					( Origin gFrontEnd )
				)
				( attribute "ROOM" "SB_DECOUPLING"
					( Origin gFrontEnd )
				)
				( attribute "ROT" "0"
					( Origin gFrontEnd )
				)
				( attribute "SEC" "1"
					( Origin gPackager )
				)
				( attribute "TOLERANCE" "10%"
					( Origin gFrontEnd )
				)
				( attribute "VALUE" "1.0UF"
					( Origin gFrontEnd )
				)
				( attribute "VER" "1"
					( Origin gFrontEnd )
				)
				( attribute "VOLTAGE" "6.3V"
					( Units "uVoltage" "V" 1.000000)
					( Origin gFrontEnd )
				)
				( attribute "XY" "(-3550,4725)"
					( Origin gFrontEnd )
				)
				( attribute "CHIPS_PART_NAME" "CAP_A"
					( Origin gPackager )
				)
				( attribute "CDS_PART_NAME" "CAP_A_0402V-1.0UF,6.3V,10%,X6SA"
					( Origin gPackager )
				)
				( objectStatus "C2M20" )
			)
			( gate "@baseboard_fab2_lib.baseboard_fab2(sch_1):page131_i40"
				( attribute "BOM_COST" "SB"
					( Origin gFrontEnd )
				)
				( attribute "CDS_LIB" "dev_discrete"
					( Origin gPackager )
				)
				( attribute "CDS_LOCATION" "C2N13"
					( Origin gPackager )
				)
				( attribute "CDS_SEC" "1"
					( Origin gPackager )
				)
				( attribute "LOCATION" "C2N13"
					( Origin gFrontEnd )
				)
				( attribute "MATERIAL" "X6S"
					( Origin gFrontEnd )
				)
				( attribute "PACK_TYPE" "0402V"
					( Origin gFrontEnd )
				)
				( attribute "PART_NUMBER" "D97712-004"
					( Origin gFrontEnd )
				)
				( attribute "PHYS_PAGE" "131"
					( Origin gFrontEnd )
				)
				( attribute "ROOM" "SB_DECOUPLING"
					( Origin gFrontEnd )
				)
				( attribute "ROT" "0"
					( Origin gFrontEnd )
				)
				( attribute "SEC" "1"
					( Origin gPackager )
				)
				( attribute "TOLERANCE" "10%"
					( Origin gFrontEnd )
				)
				( attribute "VALUE" "1.0UF"
					( Origin gFrontEnd )
				)
				( attribute "VER" "1"
					( Origin gFrontEnd )
				)
				( attribute "VOLTAGE" "6.3V"
					( Units "uVoltage" "V" 1.000000)
					( Origin gFrontEnd )
				)
				( attribute "XY" "(-3950,4725)"
					( Origin gFrontEnd )
				)
				( attribute "CHIPS_PART_NAME" "CAP_A"
					( Origin gPackager )
				)
				( attribute "CDS_PART_NAME" "CAP_A_0402V-1.0UF,6.3V,10%,X6SA"
					( Origin gPackager )
				)
				( objectStatus "C2N13" )
			)
			( gate "@baseboard_fab2_lib.baseboard_fab2(sch_1):page131_i41"
				( attribute "BOM_COST" "SB"
					( Origin gFrontEnd )
				)
				( attribute "CDS_LIB" "dev_discrete"
					( Origin gPackager )
				)
				( attribute "CDS_LOCATION" "C2N2"
					( Origin gPackager )
				)
				( attribute "CDS_SEC" "1"
					( Origin gPackager )
				)
				( attribute "LOCATION" "C2N2"
					( Origin gFrontEnd )
				)
				( attribute "MATERIAL" "X6S"
					( Origin gFrontEnd )
				)
				( attribute "PACK_TYPE" "0402V"
					( Origin gFrontEnd )
				)
				( attribute "PART_NUMBER" "D97712-004"
					( Origin gFrontEnd )
				)
				( attribute "PHYS_PAGE" "131"
					( Origin gFrontEnd )
				)
				( attribute "ROOM" "SB_DECOUPLING"
					( Origin gFrontEnd )
				)
				( attribute "ROT" "0"
					( Origin gFrontEnd )
				)
				( attribute "SEC" "1"
					( Origin gPackager )
				)
				( attribute "TOLERANCE" "10%"
					( Origin gFrontEnd )
				)
				( attribute "VALUE" "1.0UF"
					( Origin gFrontEnd )
				)
				( attribute "VER" "1"
					( Origin gFrontEnd )
				)
				( attribute "VOLTAGE" "6.3V"
					( Units "uVoltage" "V" 1.000000)
					( Origin gFrontEnd )
				)
				( attribute "XY" "(-4350,4725)"
					( Origin gFrontEnd )
				)
				( attribute "CHIPS_PART_NAME" "CAP_A"
					( Origin gPackager )
				)
				( attribute "CDS_PART_NAME" "CAP_A_0402V-1.0UF,6.3V,10%,X6SA"
					( Origin gPackager )
				)
				( objectStatus "C2N2" )
			)
			( gate "@baseboard_fab2_lib.baseboard_fab2(sch_1):page131_i42"
				( attribute "BOM_COST" "SB"
					( Origin gFrontEnd )
				)
				( attribute "CDS_LIB" "dev_discrete"
					( Origin gPackager )
				)
				( attribute "CDS_LOCATION" "C3M43"
					( Origin gPackager )
				)
				( attribute "CDS_SEC" "1"
					( Origin gPackager )
				)
				( attribute "LOCATION" "C3M43"
					( Origin gFrontEnd )
				)
				( attribute "MATERIAL" "X6S"
					( Origin gFrontEnd )
				)
				( attribute "PACK_TYPE" "0402V"
					( Origin gFrontEnd )
				)
				( attribute "PART_NUMBER" "D97712-004"
					( Origin gFrontEnd )
				)
				( attribute "PHYS_PAGE" "131"
					( Origin gFrontEnd )
				)
				( attribute "ROOM" "SB_DECOUPLING"
					( Origin gFrontEnd )
				)
				( attribute "ROT" "0"
					( Origin gFrontEnd )
				)
				( attribute "SEC" "1"
					( Origin gPackager )
				)
				( attribute "TOLERANCE" "10%"
					( Origin gFrontEnd )
				)
				( attribute "VALUE" "1.0UF"
					( Origin gFrontEnd )
				)
				( attribute "VER" "1"
					( Origin gFrontEnd )
				)
				( attribute "VOLTAGE" "6.3V"
					( Units "uVoltage" "V" 1.000000)
					( Origin gFrontEnd )
				)
				( attribute "XY" "(-3600,3525)"
					( Origin gFrontEnd )
				)
				( attribute "CHIPS_PART_NAME" "CAP_A"
					( Origin gPackager )
				)
				( attribute "CDS_PART_NAME" "CAP_A_0402V-1.0UF,6.3V,10%,X6SA"
					( Origin gPackager )
				)
				( objectStatus "C3M43" )
			)
			( gate "@baseboard_fab2_lib.baseboard_fab2(sch_1):page131_i43"
				( attribute "BOM_COST" "SB"
					( Origin gFrontEnd )
				)
				( attribute "CDS_LIB" "dev_discrete"
					( Origin gPackager )
				)
				( attribute "CDS_LOCATION" "C2N7"
					( Origin gPackager )
				)
				( attribute "CDS_SEC" "1"
					( Origin gPackager )
				)
				( attribute "LOCATION" "C2N7"
					( Origin gFrontEnd )
				)
				( attribute "MATERIAL" "X6S"
					( Origin gFrontEnd )
				)
				( attribute "PACK_TYPE" "0402V"
					( Origin gFrontEnd )
				)
				( attribute "PART_NUMBER" "D97712-004"
					( Origin gFrontEnd )
				)
				( attribute "PHYS_PAGE" "131"
					( Origin gFrontEnd )
				)
				( attribute "ROOM" "SB_DECOUPLING"
					( Origin gFrontEnd )
				)
				( attribute "ROT" "0"
					( Origin gFrontEnd )
				)
				( attribute "SEC" "1"
					( Origin gPackager )
				)
				( attribute "TOLERANCE" "10%"
					( Origin gFrontEnd )
				)
				( attribute "VALUE" "1.0UF"
					( Origin gFrontEnd )
				)
				( attribute "VER" "1"
					( Origin gFrontEnd )
				)
				( attribute "VOLTAGE" "6.3V"
					( Units "uVoltage" "V" 1.000000)
					( Origin gFrontEnd )
				)
				( attribute "XY" "(-4000,3525)"
					( Origin gFrontEnd )
				)
				( attribute "CHIPS_PART_NAME" "CAP_A"
					( Origin gPackager )
				)
				( attribute "CDS_PART_NAME" "CAP_A_0402V-1.0UF,6.3V,10%,X6SA"
					( Origin gPackager )
				)
				( objectStatus "C2N7" )
			)
			( gate "@baseboard_fab2_lib.baseboard_fab2(sch_1):page131_i44"
				( attribute "BOM_COST" "SB"
					( Origin gFrontEnd )
				)
				( attribute "CDS_LIB" "dev_discrete"
					( Origin gPackager )
				)
				( attribute "CDS_LOCATION" "C3M39"
					( Origin gPackager )
				)
				( attribute "CDS_SEC" "1"
					( Origin gPackager )
				)
				( attribute "LOCATION" "C3M39"
					( Origin gFrontEnd )
				)
				( attribute "MATERIAL" "X6S"
					( Origin gFrontEnd )
				)
				( attribute "PACK_TYPE" "0402V"
					( Origin gFrontEnd )
				)
				( attribute "PART_NUMBER" "D97712-004"
					( Origin gFrontEnd )
				)
				( attribute "PHYS_PAGE" "131"
					( Origin gFrontEnd )
				)
				( attribute "ROOM" "SB_DECOUPLING"
					( Origin gFrontEnd )
				)
				( attribute "ROT" "0"
					( Origin gFrontEnd )
				)
				( attribute "SEC" "1"
					( Origin gPackager )
				)
				( attribute "TOLERANCE" "10%"
					( Origin gFrontEnd )
				)
				( attribute "VALUE" "1.0UF"
					( Origin gFrontEnd )
				)
				( attribute "VER" "1"
					( Origin gFrontEnd )
				)
				( attribute "VOLTAGE" "6.3V"
					( Units "uVoltage" "V" 1.000000)
					( Origin gFrontEnd )
				)
				( attribute "XY" "(-4375,3525)"
					( Origin gFrontEnd )
				)
				( attribute "CHIPS_PART_NAME" "CAP_A"
					( Origin gPackager )
				)
				( attribute "CDS_PART_NAME" "CAP_A_0402V-1.0UF,6.3V,10%,X6SA"
					( Origin gPackager )
				)
				( objectStatus "C3M39" )
			)
			( gate "@baseboard_fab2_lib.baseboard_fab2(sch_1):page131_i45"
				( attribute "BOM_COST" "SB"
					( Origin gFrontEnd )
				)
				( attribute "CDS_LIB" "dev_discrete"
					( Origin gPackager )
				)
				( attribute "CDS_LOCATION" "C3M42"
					( Origin gPackager )
				)
				( attribute "CDS_SEC" "1"
					( Origin gPackager )
				)
				( attribute "LOCATION" "C3M42"
					( Origin gFrontEnd )
				)
				( attribute "MATERIAL" "X6S"
					( Origin gFrontEnd )
				)
				( attribute "PACK_TYPE" "0402V"
					( Origin gFrontEnd )
				)
				( attribute "PART_NUMBER" "D97712-004"
					( Origin gFrontEnd )
				)
				( attribute "PHYS_PAGE" "131"
					( Origin gFrontEnd )
				)
				( attribute "ROOM" "SB_DECOUPLING"
					( Origin gFrontEnd )
				)
				( attribute "ROT" "0"
					( Origin gFrontEnd )
				)
				( attribute "SEC" "1"
					( Origin gPackager )
				)
				( attribute "TOLERANCE" "10%"
					( Origin gFrontEnd )
				)
				( attribute "VALUE" "1.0UF"
					( Origin gFrontEnd )
				)
				( attribute "VER" "1"
					( Origin gFrontEnd )
				)
				( attribute "VOLTAGE" "6.3V"
					( Units "uVoltage" "V" 1.000000)
					( Origin gFrontEnd )
				)
				( attribute "XY" "(-4750,4725)"
					( Origin gFrontEnd )
				)
				( attribute "CHIPS_PART_NAME" "CAP_A"
					( Origin gPackager )
				)
				( attribute "CDS_PART_NAME" "CAP_A_0402V-1.0UF,6.3V,10%,X6SA"
					( Origin gPackager )
				)
				( objectStatus "C3M42" )
			)
			( gate "@baseboard_fab2_lib.baseboard_fab2(sch_1):page131_i47"
				( attribute "BOM_COST" "SB"
					( Origin gFrontEnd )
				)
				( attribute "CDS_LIB" "dev_discrete"
					( Origin gPackager )
				)
				( attribute "CDS_LOCATION" "C2N8"
					( Origin gPackager )
				)
				( attribute "CDS_SEC" "1"
					( Origin gPackager )
				)
				( attribute "LOCATION" "C2N8"
					( Origin gFrontEnd )
				)
				( attribute "MATERIAL" "X6S"
					( Origin gFrontEnd )
				)
				( attribute "PACK_TYPE" "0402V"
					( Origin gFrontEnd )
				)
				( attribute "PART_NUMBER" "D97712-004"
					( Origin gFrontEnd )
				)
				( attribute "PHYS_PAGE" "131"
					( Origin gFrontEnd )
				)
				( attribute "ROOM" "SB_DECOUPLING"
					( Origin gFrontEnd )
				)
				( attribute "ROT" "0"
					( Origin gFrontEnd )
				)
				( attribute "SEC" "1"
					( Origin gPackager )
				)
				( attribute "TOLERANCE" "10%"
					( Origin gFrontEnd )
				)
				( attribute "VALUE" "1.0UF"
					( Origin gFrontEnd )
				)
				( attribute "VER" "1"
					( Origin gFrontEnd )
				)
				( attribute "VOLTAGE" "6.3V"
					( Units "uVoltage" "V" 1.000000)
					( Origin gFrontEnd )
				)
				( attribute "XY" "(-4775,3525)"
					( Origin gFrontEnd )
				)
				( attribute "CHIPS_PART_NAME" "CAP_A"
					( Origin gPackager )
				)
				( attribute "CDS_PART_NAME" "CAP_A_0402V-1.0UF,6.3V,10%,X6SA"
					( Origin gPackager )
				)
				( objectStatus "C2N8" )
			)
			( gate "@baseboard_fab2_lib.baseboard_fab2(sch_1):page131_i48"
				( attribute "BOM_COST" "SB"
					( Origin gFrontEnd )
				)
				( attribute "CDS_LIB" "dev_discrete"
					( Origin gPackager )
				)
				( attribute "CDS_LOCATION" "C2M13"
					( Origin gPackager )
				)
				( attribute "CDS_SEC" "1"
					( Origin gPackager )
				)
				( attribute "LOCATION" "C2M13"
					( Origin gFrontEnd )
				)
				( attribute "MATERIAL" "X6S"
					( Origin gFrontEnd )
				)
				( attribute "PACK_TYPE" "0603V"
					( Origin gFrontEnd )
				)
				( attribute "PART_NUMBER" "E15431-004"
					( Origin gFrontEnd )
				)
				( attribute "PHYS_PAGE" "131"
					( Origin gFrontEnd )
				)
				( attribute "ROOM" "SB_DECOUPLING"
					( Origin gFrontEnd )
				)
				( attribute "ROT" "0"
					( Origin gFrontEnd )
				)
				( attribute "SEC" "1"
					( Origin gPackager )
				)
				( attribute "TOLERANCE" "20%"
					( Origin gFrontEnd )
				)
				( attribute "VALUE" "22.0UF"
					( Origin gFrontEnd )
				)
				( attribute "VER" "1"
					( Origin gFrontEnd )
				)
				( attribute "VOLTAGE" "4V"
					( Units "uVoltage" "V" 1.000000)
					( Origin gFrontEnd )
				)
				( attribute "XY" "(-4250,2100)"
					( Origin gFrontEnd )
				)
				( attribute "CHIPS_PART_NAME" "CAP_A"
					( Origin gPackager )
				)
				( attribute "CDS_PART_NAME" "CAP_A_0603V-22.0UF,4V,20%,X6S,A"
					( Origin gPackager )
				)
				( objectStatus "C2M13" )
			)
			( gate "@baseboard_fab2_lib.baseboard_fab2(sch_1):page131_i50"
				( attribute "BOM_COST" "SB"
					( Origin gFrontEnd )
				)
				( attribute "CDS_LIB" "dev_discrete"
					( Origin gPackager )
				)
				( attribute "CDS_LOCATION" "C2N10"
					( Origin gPackager )
				)
				( attribute "CDS_SEC" "1"
					( Origin gPackager )
				)
				( attribute "LOCATION" "C2N10"
					( Origin gFrontEnd )
				)
				( attribute "MATERIAL" "X6S"
					( Origin gFrontEnd )
				)
				( attribute "PACK_TYPE" "0603V"
					( Origin gFrontEnd )
				)
				( attribute "PART_NUMBER" "E15431-004"
					( Origin gFrontEnd )
				)
				( attribute "PHYS_PAGE" "131"
					( Origin gFrontEnd )
				)
				( attribute "ROOM" "SB_DECOUPLING"
					( Origin gFrontEnd )
				)
				( attribute "ROT" "0"
					( Origin gFrontEnd )
				)
				( attribute "SEC" "1"
					( Origin gPackager )
				)
				( attribute "TOLERANCE" "20%"
					( Origin gFrontEnd )
				)
				( attribute "VALUE" "22.0UF"
					( Origin gFrontEnd )
				)
				( attribute "VER" "1"
					( Origin gFrontEnd )
				)
				( attribute "VOLTAGE" "4V"
					( Units "uVoltage" "V" 1.000000)
					( Origin gFrontEnd )
				)
				( attribute "XY" "(-4650,2100)"
					( Origin gFrontEnd )
				)
				( attribute "CHIPS_PART_NAME" "CAP_A"
					( Origin gPackager )
				)
				( attribute "CDS_PART_NAME" "CAP_A_0603V-22.0UF,4V,20%,X6S,A"
					( Origin gPackager )
				)
				( objectStatus "C2N10" )
			)
			( gate "@baseboard_fab2_lib.baseboard_fab2(sch_1):page131_i52"
				( attribute "BOM_COST" "SB"
					( Origin gFrontEnd )
				)
				( attribute "CDS_LIB" "dev_discrete"
					( Origin gPackager )
				)
				( attribute "CDS_LOCATION" "C2M12"
					( Origin gPackager )
				)
				( attribute "CDS_SEC" "1"
					( Origin gPackager )
				)
				( attribute "LOCATION" "C2M12"
					( Origin gFrontEnd )
				)
				( attribute "MATERIAL" "X6S"
					( Origin gFrontEnd )
				)
				( attribute "PACK_TYPE" "0603V"
					( Origin gFrontEnd )
				)
				( attribute "PART_NUMBER" "E15431-004"
					( Origin gFrontEnd )
				)
				( attribute "PHYS_PAGE" "131"
					( Origin gFrontEnd )
				)
				( attribute "ROOM" "SB_DECOUPLING"
					( Origin gFrontEnd )
				)
				( attribute "ROT" "0"
					( Origin gFrontEnd )
				)
				( attribute "SEC" "1"
					( Origin gPackager )
				)
				( attribute "TOLERANCE" "20%"
					( Origin gFrontEnd )
				)
				( attribute "VALUE" "22.0UF"
					( Origin gFrontEnd )
				)
				( attribute "VER" "1"
					( Origin gFrontEnd )
				)
				( attribute "VOLTAGE" "4V"
					( Units "uVoltage" "V" 1.000000)
					( Origin gFrontEnd )
				)
				( attribute "XY" "(-5075,2100)"
					( Origin gFrontEnd )
				)
				( attribute "CHIPS_PART_NAME" "CAP_A"
					( Origin gPackager )
				)
				( attribute "CDS_PART_NAME" "CAP_A_0603V-22.0UF,4V,20%,X6S,A"
					( Origin gPackager )
				)
				( objectStatus "C2M12" )
			)
			( gate "@baseboard_fab2_lib.baseboard_fab2(sch_1):page132_i1"
				( attribute "BOM_COST" "SB"
					( Origin gFrontEnd )
				)
				( attribute "CDS_LIB" "dev_discrete"
					( Origin gPackager )
				)
				( attribute "CDS_LOCATION" "C3L25"
					( Origin gPackager )
				)
				( attribute "CDS_SEC" "1"
					( Origin gPackager )
				)
				( attribute "LOCATION" "C3L25"
					( Origin gFrontEnd )
				)
				( attribute "MATERIAL" "X6S"
					( Origin gFrontEnd )
				)
				( attribute "PACK_TYPE" "0603V"
					( Origin gFrontEnd )
				)
				( attribute "PART_NUMBER" "E15431-004"
					( Origin gFrontEnd )
				)
				( attribute "PHYS_PAGE" "132"
					( Origin gFrontEnd )
				)
				( attribute "ROOM" "SB_DECOUPLING"
					( Origin gFrontEnd )
				)
				( attribute "ROT" "0"
					( Origin gFrontEnd )
				)
				( attribute "SEC" "1"
					( Origin gPackager )
				)
				( attribute "TOLERANCE" "20%"
					( Origin gFrontEnd )
				)
				( attribute "VALUE" "22.0UF"
					( Origin gFrontEnd )
				)
				( attribute "VER" "1"
					( Origin gFrontEnd )
				)
				( attribute "VOLTAGE" "4V"
					( Units "uVoltage" "V" 1.000000)
					( Origin gFrontEnd )
				)
				( attribute "XY" "(2575,4475)"
					( Origin gFrontEnd )
				)
				( attribute "CHIPS_PART_NAME" "CAP_A"
					( Origin gPackager )
				)
				( attribute "CDS_PART_NAME" "CAP_A_0603V-22.0UF,4V,20%,X6S,A"
					( Origin gPackager )
				)
				( objectStatus "C3L25" )
			)
			( gate "@baseboard_fab2_lib.baseboard_fab2(sch_1):page132_i2"
				( attribute "BOM_COST" "SB"
					( Origin gFrontEnd )
				)
				( attribute "CDS_LIB" "dev_discrete"
					( Origin gPackager )
				)
				( attribute "CDS_LOCATION" "C3M7"
					( Origin gPackager )
				)
				( attribute "CDS_SEC" "1"
					( Origin gPackager )
				)
				( attribute "LOCATION" "C3M7"
					( Origin gFrontEnd )
				)
				( attribute "MATERIAL" "X6S"
					( Origin gFrontEnd )
				)
				( attribute "PACK_TYPE" "0603V"
					( Origin gFrontEnd )
				)
				( attribute "PART_NUMBER" "E15431-004"
					( Origin gFrontEnd )
				)
				( attribute "PHYS_PAGE" "132"
					( Origin gFrontEnd )
				)
				( attribute "ROOM" "SB_DECOUPLING"
					( Origin gFrontEnd )
				)
				( attribute "ROT" "0"
					( Origin gFrontEnd )
				)
				( attribute "SEC" "1"
					( Origin gPackager )
				)
				( attribute "TOLERANCE" "20%"
					( Origin gFrontEnd )
				)
				( attribute "VALUE" "22.0UF"
					( Origin gFrontEnd )
				)
				( attribute "VER" "1"
					( Origin gFrontEnd )
				)
				( attribute "VOLTAGE" "4V"
					( Units "uVoltage" "V" 1.000000)
					( Origin gFrontEnd )
				)
				( attribute "XY" "(2200,4475)"
					( Origin gFrontEnd )
				)
				( attribute "CHIPS_PART_NAME" "CAP_A"
					( Origin gPackager )
				)
				( attribute "CDS_PART_NAME" "CAP_A_0603V-22.0UF,4V,20%,X6S,A"
					( Origin gPackager )
				)
				( objectStatus "C3M7" )
			)
			( gate "@baseboard_fab2_lib.baseboard_fab2(sch_1):page132_i3"
				( attribute "BOM_COST" "SB"
					( Origin gFrontEnd )
				)
				( attribute "CDS_LIB" "dev_discrete"
					( Origin gPackager )
				)
				( attribute "CDS_LOCATION" "C3L26"
					( Origin gPackager )
				)
				( attribute "CDS_SEC" "1"
					( Origin gPackager )
				)
				( attribute "LOCATION" "C3L26"
					( Origin gFrontEnd )
				)
				( attribute "MATERIAL" "X6S"
					( Origin gFrontEnd )
				)
				( attribute "PACK_TYPE" "0603V"
					( Origin gFrontEnd )
				)
				( attribute "PART_NUMBER" "E15431-004"
					( Origin gFrontEnd )
				)
				( attribute "PHYS_PAGE" "132"
					( Origin gFrontEnd )
				)
				( attribute "ROOM" "SB_DECOUPLING"
					( Origin gFrontEnd )
				)
				( attribute "ROT" "0"
					( Origin gFrontEnd )
				)
				( attribute "SEC" "1"
					( Origin gPackager )
				)
				( attribute "TOLERANCE" "20%"
					( Origin gFrontEnd )
				)
				( attribute "VALUE" "22.0UF"
					( Origin gFrontEnd )
				)
				( attribute "VER" "1"
					( Origin gFrontEnd )
				)
				( attribute "VOLTAGE" "4V"
					( Units "uVoltage" "V" 1.000000)
					( Origin gFrontEnd )
				)
				( attribute "XY" "(1825,4475)"
					( Origin gFrontEnd )
				)
				( attribute "CHIPS_PART_NAME" "CAP_A"
					( Origin gPackager )
				)
				( attribute "CDS_PART_NAME" "CAP_A_0603V-22.0UF,4V,20%,X6S,A"
					( Origin gPackager )
				)
				( objectStatus "C3L26" )
			)
			( gate "@baseboard_fab2_lib.baseboard_fab2(sch_1):page132_i4"
				( attribute "BOM_COST" "SB"
					( Origin gFrontEnd )
				)
				( attribute "CDS_LIB" "dev_discrete"
					( Origin gPackager )
				)
				( attribute "CDS_LOCATION" "C3L27"
					( Origin gPackager )
				)
				( attribute "CDS_SEC" "1"
					( Origin gPackager )
				)
				( attribute "LOCATION" "C3L27"
					( Origin gFrontEnd )
				)
				( attribute "MATERIAL" "X6S"
					( Origin gFrontEnd )
				)
				( attribute "PACK_TYPE" "0603V"
					( Origin gFrontEnd )
				)
				( attribute "PART_NUMBER" "E15431-004"
					( Origin gFrontEnd )
				)
				( attribute "PHYS_PAGE" "132"
					( Origin gFrontEnd )
				)
				( attribute "ROOM" "SB_DECOUPLING"
					( Origin gFrontEnd )
				)
				( attribute "ROT" "0"
					( Origin gFrontEnd )
				)
				( attribute "SEC" "1"
					( Origin gPackager )
				)
				( attribute "TOLERANCE" "20%"
					( Origin gFrontEnd )
				)
				( attribute "VALUE" "22.0UF"
					( Origin gFrontEnd )
				)
				( attribute "VER" "1"
					( Origin gFrontEnd )
				)
				( attribute "VOLTAGE" "4V"
					( Units "uVoltage" "V" 1.000000)
					( Origin gFrontEnd )
				)
				( attribute "XY" "(1450,4475)"
					( Origin gFrontEnd )
				)
				( attribute "CHIPS_PART_NAME" "CAP_A"
					( Origin gPackager )
				)
				( attribute "CDS_PART_NAME" "CAP_A_0603V-22.0UF,4V,20%,X6S,A"
					( Origin gPackager )
				)
				( objectStatus "C3L27" )
			)
			( gate "@baseboard_fab2_lib.baseboard_fab2(sch_1):page132_i6"
				( attribute "BOM_COST" "SB"
					( Origin gFrontEnd )
				)
				( attribute "CDS_LIB" "dev_discrete"
					( Origin gPackager )
				)
				( attribute "CDS_LOCATION" "C3M6"
					( Origin gPackager )
				)
				( attribute "CDS_SEC" "1"
					( Origin gPackager )
				)
				( attribute "LOCATION" "C3M6"
					( Origin gFrontEnd )
				)
				( attribute "MATERIAL" "X6S"
					( Origin gFrontEnd )
				)
				( attribute "PACK_TYPE" "0603V"
					( Origin gFrontEnd )
				)
				( attribute "PART_NUMBER" "E15431-004"
					( Origin gFrontEnd )
				)
				( attribute "PHYS_PAGE" "132"
					( Origin gFrontEnd )
				)
				( attribute "ROOM" "SB_DECOUPLING"
					( Origin gFrontEnd )
				)
				( attribute "ROT" "0"
					( Origin gFrontEnd )
				)
				( attribute "SEC" "1"
					( Origin gPackager )
				)
				( attribute "TOLERANCE" "20%"
					( Origin gFrontEnd )
				)
				( attribute "VALUE" "22.0UF"
					( Origin gFrontEnd )
				)
				( attribute "VER" "1"
					( Origin gFrontEnd )
				)
				( attribute "VOLTAGE" "4V"
					( Units "uVoltage" "V" 1.000000)
					( Origin gFrontEnd )
				)
				( attribute "XY" "(1075,4475)"
					( Origin gFrontEnd )
				)
				( attribute "CHIPS_PART_NAME" "CAP_A"
					( Origin gPackager )
				)
				( attribute "CDS_PART_NAME" "CAP_A_0603V-22.0UF,4V,20%,X6S,A"
					( Origin gPackager )
				)
				( objectStatus "C3M6" )
			)
			( gate "@baseboard_fab2_lib.baseboard_fab2(sch_1):page132_i7"
				( attribute "BOM_COST" "SB"
					( Origin gFrontEnd )
				)
				( attribute "CDS_LIB" "dev_discrete"
					( Origin gPackager )
				)
				( attribute "CDS_LOCATION" "C7C9"
					( Origin gPackager )
				)
				( attribute "CDS_SEC" "1"
					( Origin gPackager )
				)
				( attribute "LOCATION" "C7C9"
					( Origin gFrontEnd )
				)
				( attribute "MATERIAL" "X6S"
					( Origin gFrontEnd )
				)
				( attribute "PACK_TYPE" "0603V"
					( Origin gFrontEnd )
				)
				( attribute "PART_NUMBER" "E15431-004"
					( Origin gFrontEnd )
				)
				( attribute "PHYS_PAGE" "132"
					( Origin gFrontEnd )
				)
				( attribute "ROOM" "SB_DECOUPLING"
					( Origin gFrontEnd )
				)
				( attribute "ROT" "0"
					( Origin gFrontEnd )
				)
				( attribute "SEC" "1"
					( Origin gPackager )
				)
				( attribute "TOLERANCE" "20%"
					( Origin gFrontEnd )
				)
				( attribute "VALUE" "22.0UF"
					( Origin gFrontEnd )
				)
				( attribute "VER" "1"
					( Origin gFrontEnd )
				)
				( attribute "VOLTAGE" "4V"
					( Units "uVoltage" "V" 1.000000)
					( Origin gFrontEnd )
				)
				( attribute "XY" "(2550,3500)"
					( Origin gFrontEnd )
				)
				( attribute "CHIPS_PART_NAME" "CAP_A"
					( Origin gPackager )
				)
				( attribute "CDS_PART_NAME" "CAP_A_0603V-22.0UF,4V,20%,X6S,A"
					( Origin gPackager )
				)
				( objectStatus "C7C9" )
			)
			( gate "@baseboard_fab2_lib.baseboard_fab2(sch_1):page132_i8"
				( attribute "BOM_COST" "SB"
					( Origin gFrontEnd )
				)
				( attribute "CDS_LIB" "dev_discrete"
					( Origin gPackager )
				)
				( attribute "CDS_LOCATION" "C3N27"
					( Origin gPackager )
				)
				( attribute "CDS_SEC" "1"
					( Origin gPackager )
				)
				( attribute "LOCATION" "C3N27"
					( Origin gFrontEnd )
				)
				( attribute "MATERIAL" "X6S"
					( Origin gFrontEnd )
				)
				( attribute "PACK_TYPE" "0603V"
					( Origin gFrontEnd )
				)
				( attribute "PART_NUMBER" "E15431-004"
					( Origin gFrontEnd )
				)
				( attribute "PHYS_PAGE" "132"
					( Origin gFrontEnd )
				)
				( attribute "ROOM" "SB_DECOUPLING"
					( Origin gFrontEnd )
				)
				( attribute "ROT" "0"
					( Origin gFrontEnd )
				)
				( attribute "SEC" "1"
					( Origin gPackager )
				)
				( attribute "TOLERANCE" "20%"
					( Origin gFrontEnd )
				)
				( attribute "VALUE" "22.0UF"
					( Origin gFrontEnd )
				)
				( attribute "VER" "1"
					( Origin gFrontEnd )
				)
				( attribute "VOLTAGE" "4V"
					( Units "uVoltage" "V" 1.000000)
					( Origin gFrontEnd )
				)
				( attribute "XY" "(2600,2525)"
					( Origin gFrontEnd )
				)
				( attribute "CHIPS_PART_NAME" "CAP_A"
					( Origin gPackager )
				)
				( attribute "CDS_PART_NAME" "CAP_A_0603V-22.0UF,4V,20%,X6S,A"
					( Origin gPackager )
				)
				( objectStatus "C3N27" )
			)
			( gate "@baseboard_fab2_lib.baseboard_fab2(sch_1):page132_i9"
				( attribute "BOM_COST" "SB"
					( Origin gFrontEnd )
				)
				( attribute "CDS_LIB" "dev_discrete"
					( Origin gPackager )
				)
				( attribute "CDS_LOCATION" "C3N30"
					( Origin gPackager )
				)
				( attribute "CDS_SEC" "1"
					( Origin gPackager )
				)
				( attribute "LOCATION" "C3N30"
					( Origin gFrontEnd )
				)
				( attribute "MATERIAL" "X6S"
					( Origin gFrontEnd )
				)
				( attribute "PACK_TYPE" "0603V"
					( Origin gFrontEnd )
				)
				( attribute "PART_NUMBER" "E15431-004"
					( Origin gFrontEnd )
				)
				( attribute "PHYS_PAGE" "132"
					( Origin gFrontEnd )
				)
				( attribute "ROOM" "SB_DECOUPLING"
					( Origin gFrontEnd )
				)
				( attribute "ROT" "0"
					( Origin gFrontEnd )
				)
				( attribute "SEC" "1"
					( Origin gPackager )
				)
				( attribute "TOLERANCE" "20%"
					( Origin gFrontEnd )
				)
				( attribute "VALUE" "22.0UF"
					( Origin gFrontEnd )
				)
				( attribute "VER" "1"
					( Origin gFrontEnd )
				)
				( attribute "VOLTAGE" "4V"
					( Units "uVoltage" "V" 1.000000)
					( Origin gFrontEnd )
				)
				( attribute "XY" "(2225,2525)"
					( Origin gFrontEnd )
				)
				( attribute "CHIPS_PART_NAME" "CAP_A"
					( Origin gPackager )
				)
				( attribute "CDS_PART_NAME" "CAP_A_0603V-22.0UF,4V,20%,X6S,A"
					( Origin gPackager )
				)
				( objectStatus "C3N30" )
			)
			( gate "@baseboard_fab2_lib.baseboard_fab2(sch_1):page132_i11"
				( attribute "BOM_COST" "SB"
					( Origin gFrontEnd )
				)
				( attribute "CDS_LIB" "dev_discrete"
					( Origin gPackager )
				)
				( attribute "CDS_LOCATION" "C7A36"
					( Origin gPackager )
				)
				( attribute "CDS_SEC" "1"
					( Origin gPackager )
				)
				( attribute "LOCATION" "C7A36"
					( Origin gFrontEnd )
				)
				( attribute "MATERIAL" "X6S"
					( Origin gFrontEnd )
				)
				( attribute "PACK_TYPE" "0603V"
					( Origin gFrontEnd )
				)
				( attribute "PART_NUMBER" "E15431-004"
					( Origin gFrontEnd )
				)
				( attribute "PHYS_PAGE" "132"
					( Origin gFrontEnd )
				)
				( attribute "ROOM" "SB_DECOUPLING"
					( Origin gFrontEnd )
				)
				( attribute "ROT" "0"
					( Origin gFrontEnd )
				)
				( attribute "SEC" "1"
					( Origin gPackager )
				)
				( attribute "TOLERANCE" "20%"
					( Origin gFrontEnd )
				)
				( attribute "VALUE" "22.0UF"
					( Origin gFrontEnd )
				)
				( attribute "VER" "1"
					( Origin gFrontEnd )
				)
				( attribute "VOLTAGE" "4V"
					( Units "uVoltage" "V" 1.000000)
					( Origin gFrontEnd )
				)
				( attribute "XY" "(2200,3500)"
					( Origin gFrontEnd )
				)
				( attribute "CHIPS_PART_NAME" "CAP_A"
					( Origin gPackager )
				)
				( attribute "CDS_PART_NAME" "CAP_A_0603V-22.0UF,4V,20%,X6S,A"
					( Origin gPackager )
				)
				( objectStatus "C7A36" )
			)
			( gate "@baseboard_fab2_lib.baseboard_fab2(sch_1):page132_i12"
				( attribute "BOM_COST" "SB"
					( Origin gFrontEnd )
				)
				( attribute "CDS_LIB" "dev_discrete"
					( Origin gPackager )
				)
				( attribute "CDS_LOCATION" "C3N12"
					( Origin gPackager )
				)
				( attribute "CDS_SEC" "1"
					( Origin gPackager )
				)
				( attribute "LOCATION" "C3N12"
					( Origin gFrontEnd )
				)
				( attribute "MATERIAL" "X6S"
					( Origin gFrontEnd )
				)
				( attribute "PACK_TYPE" "0603V"
					( Origin gFrontEnd )
				)
				( attribute "PART_NUMBER" "E15431-004"
					( Origin gFrontEnd )
				)
				( attribute "PHYS_PAGE" "132"
					( Origin gFrontEnd )
				)
				( attribute "ROOM" "SB_DECOUPLING"
					( Origin gFrontEnd )
				)
				( attribute "ROT" "0"
					( Origin gFrontEnd )
				)
				( attribute "SEC" "1"
					( Origin gPackager )
				)
				( attribute "TOLERANCE" "20%"
					( Origin gFrontEnd )
				)
				( attribute "VALUE" "22.0UF"
					( Origin gFrontEnd )
				)
				( attribute "VER" "1"
					( Origin gFrontEnd )
				)
				( attribute "VOLTAGE" "4V"
					( Units "uVoltage" "V" 1.000000)
					( Origin gFrontEnd )
				)
				( attribute "XY" "(1825,3500)"
					( Origin gFrontEnd )
				)
				( attribute "CHIPS_PART_NAME" "CAP_A"
					( Origin gPackager )
				)
				( attribute "CDS_PART_NAME" "CAP_A_0603V-22.0UF,4V,20%,X6S,A"
					( Origin gPackager )
				)
				( objectStatus "C3N12" )
			)
			( gate "@baseboard_fab2_lib.baseboard_fab2(sch_1):page132_i13"
				( attribute "BOM_COST" "SB"
					( Origin gFrontEnd )
				)
				( attribute "CDS_LIB" "dev_discrete"
					( Origin gPackager )
				)
				( attribute "CDS_LOCATION" "C3N10"
					( Origin gPackager )
				)
				( attribute "CDS_SEC" "1"
					( Origin gPackager )
				)
				( attribute "LOCATION" "C3N10"
					( Origin gFrontEnd )
				)
				( attribute "MATERIAL" "X6S"
					( Origin gFrontEnd )
				)
				( attribute "PACK_TYPE" "0603V"
					( Origin gFrontEnd )
				)
				( attribute "PART_NUMBER" "E15431-004"
					( Origin gFrontEnd )
				)
				( attribute "PHYS_PAGE" "132"
					( Origin gFrontEnd )
				)
				( attribute "ROOM" "SB_DECOUPLING"
					( Origin gFrontEnd )
				)
				( attribute "ROT" "0"
					( Origin gFrontEnd )
				)
				( attribute "SEC" "1"
					( Origin gPackager )
				)
				( attribute "TOLERANCE" "20%"
					( Origin gFrontEnd )
				)
				( attribute "VALUE" "22.0UF"
					( Origin gFrontEnd )
				)
				( attribute "VER" "1"
					( Origin gFrontEnd )
				)
				( attribute "VOLTAGE" "4V"
					( Units "uVoltage" "V" 1.000000)
					( Origin gFrontEnd )
				)
				( attribute "XY" "(1450,3500)"
					( Origin gFrontEnd )
				)
				( attribute "CHIPS_PART_NAME" "CAP_A"
					( Origin gPackager )
				)
				( attribute "CDS_PART_NAME" "CAP_A_0603V-22.0UF,4V,20%,X6S,A"
					( Origin gPackager )
				)
				( objectStatus "C3N10" )
			)
			( gate "@baseboard_fab2_lib.baseboard_fab2(sch_1):page132_i16"
				( attribute "BOM_COST" "SB"
					( Origin gFrontEnd )
				)
				( attribute "CDS_LIB" "dev_discrete"
					( Origin gPackager )
				)
				( attribute "CDS_LOCATION" "C3N24"
					( Origin gPackager )
				)
				( attribute "CDS_SEC" "1"
					( Origin gPackager )
				)
				( attribute "LOCATION" "C3N24"
					( Origin gFrontEnd )
				)
				( attribute "MATERIAL" "X6S"
					( Origin gFrontEnd )
				)
				( attribute "PACK_TYPE" "0603V"
					( Origin gFrontEnd )
				)
				( attribute "PART_NUMBER" "E15431-004"
					( Origin gFrontEnd )
				)
				( attribute "PHYS_PAGE" "132"
					( Origin gFrontEnd )
				)
				( attribute "ROOM" "SB_DECOUPLING"
					( Origin gFrontEnd )
				)
				( attribute "ROT" "0"
					( Origin gFrontEnd )
				)
				( attribute "SEC" "1"
					( Origin gPackager )
				)
				( attribute "TOLERANCE" "20%"
					( Origin gFrontEnd )
				)
				( attribute "VALUE" "22.0UF"
					( Origin gFrontEnd )
				)
				( attribute "VER" "1"
					( Origin gFrontEnd )
				)
				( attribute "VOLTAGE" "4V"
					( Units "uVoltage" "V" 1.000000)
					( Origin gFrontEnd )
				)
				( attribute "XY" "(1850,2525)"
					( Origin gFrontEnd )
				)
				( attribute "CHIPS_PART_NAME" "CAP_A"
					( Origin gPackager )
				)
				( attribute "CDS_PART_NAME" "CAP_A_0603V-22.0UF,4V,20%,X6S,A"
					( Origin gPackager )
				)
				( objectStatus "C3N24" )
			)
			( gate "@baseboard_fab2_lib.baseboard_fab2(sch_1):page132_i17"
				( attribute "BOM_COST" "SB"
					( Origin gFrontEnd )
				)
				( attribute "CDS_LIB" "dev_discrete"
					( Origin gPackager )
				)
				( attribute "CDS_LOCATION" "C3N28"
					( Origin gPackager )
				)
				( attribute "CDS_SEC" "1"
					( Origin gPackager )
				)
				( attribute "LOCATION" "C3N28"
					( Origin gFrontEnd )
				)
				( attribute "MATERIAL" "X6S"
					( Origin gFrontEnd )
				)
				( attribute "PACK_TYPE" "0603V"
					( Origin gFrontEnd )
				)
				( attribute "PART_NUMBER" "E15431-004"
					( Origin gFrontEnd )
				)
				( attribute "PHYS_PAGE" "132"
					( Origin gFrontEnd )
				)
				( attribute "ROOM" "SB_DECOUPLING"
					( Origin gFrontEnd )
				)
				( attribute "ROT" "0"
					( Origin gFrontEnd )
				)
				( attribute "SEC" "1"
					( Origin gPackager )
				)
				( attribute "TOLERANCE" "20%"
					( Origin gFrontEnd )
				)
				( attribute "VALUE" "22.0UF"
					( Origin gFrontEnd )
				)
				( attribute "VER" "1"
					( Origin gFrontEnd )
				)
				( attribute "VOLTAGE" "4V"
					( Units "uVoltage" "V" 1.000000)
					( Origin gFrontEnd )
				)
				( attribute "XY" "(1475,2525)"
					( Origin gFrontEnd )
				)
				( attribute "CHIPS_PART_NAME" "CAP_A"
					( Origin gPackager )
				)
				( attribute "CDS_PART_NAME" "CAP_A_0603V-22.0UF,4V,20%,X6S,A"
					( Origin gPackager )
				)
				( objectStatus "C3N28" )
			)
			( gate "@baseboard_fab2_lib.baseboard_fab2(sch_1):page132_i19"
				( attribute "BOM_COST" "SB"
					( Origin gFrontEnd )
				)
				( attribute "CDS_LIB" "dev_discrete"
					( Origin gPackager )
				)
				( attribute "CDS_LOCATION" "C3N11"
					( Origin gPackager )
				)
				( attribute "CDS_SEC" "1"
					( Origin gPackager )
				)
				( attribute "LOCATION" "C3N11"
					( Origin gFrontEnd )
				)
				( attribute "MATERIAL" "X6S"
					( Origin gFrontEnd )
				)
				( attribute "PACK_TYPE" "0603V"
					( Origin gFrontEnd )
				)
				( attribute "PART_NUMBER" "E15431-004"
					( Origin gFrontEnd )
				)
				( attribute "PHYS_PAGE" "132"
					( Origin gFrontEnd )
				)
				( attribute "ROOM" "SB_DECOUPLING"
					( Origin gFrontEnd )
				)
				( attribute "ROT" "0"
					( Origin gFrontEnd )
				)
				( attribute "SEC" "1"
					( Origin gPackager )
				)
				( attribute "TOLERANCE" "20%"
					( Origin gFrontEnd )
				)
				( attribute "VALUE" "22.0UF"
					( Origin gFrontEnd )
				)
				( attribute "VER" "1"
					( Origin gFrontEnd )
				)
				( attribute "VOLTAGE" "4V"
					( Units "uVoltage" "V" 1.000000)
					( Origin gFrontEnd )
				)
				( attribute "XY" "(1075,3500)"
					( Origin gFrontEnd )
				)
				( attribute "CHIPS_PART_NAME" "CAP_A"
					( Origin gPackager )
				)
				( attribute "CDS_PART_NAME" "CAP_A_0603V-22.0UF,4V,20%,X6S,A"
					( Origin gPackager )
				)
				( objectStatus "C3N11" )
			)
			( gate "@baseboard_fab2_lib.baseboard_fab2(sch_1):page132_i20"
				( attribute "BOM_COST" "SB"
					( Origin gFrontEnd )
				)
				( attribute "CDS_LIB" "dev_discrete"
					( Origin gPackager )
				)
				( attribute "CDS_LOCATION" "C3N31"
					( Origin gPackager )
				)
				( attribute "CDS_SEC" "1"
					( Origin gPackager )
				)
				( attribute "LOCATION" "C3N31"
					( Origin gFrontEnd )
				)
				( attribute "MATERIAL" "X6S"
					( Origin gFrontEnd )
				)
				( attribute "PACK_TYPE" "0603V"
					( Origin gFrontEnd )
				)
				( attribute "PART_NUMBER" "E15431-004"
					( Origin gFrontEnd )
				)
				( attribute "PHYS_PAGE" "132"
					( Origin gFrontEnd )
				)
				( attribute "ROOM" "SB_DECOUPLING"
					( Origin gFrontEnd )
				)
				( attribute "ROT" "0"
					( Origin gFrontEnd )
				)
				( attribute "SEC" "1"
					( Origin gPackager )
				)
				( attribute "TOLERANCE" "20%"
					( Origin gFrontEnd )
				)
				( attribute "VALUE" "22.0UF"
					( Origin gFrontEnd )
				)
				( attribute "VER" "1"
					( Origin gFrontEnd )
				)
				( attribute "VOLTAGE" "4V"
					( Units "uVoltage" "V" 1.000000)
					( Origin gFrontEnd )
				)
				( attribute "XY" "(1100,2525)"
					( Origin gFrontEnd )
				)
				( attribute "CHIPS_PART_NAME" "CAP_A"
					( Origin gPackager )
				)
				( attribute "CDS_PART_NAME" "CAP_A_0603V-22.0UF,4V,20%,X6S,A"
					( Origin gPackager )
				)
				( objectStatus "C3N31" )
			)
			( gate "@baseboard_fab2_lib.baseboard_fab2(sch_1):page132_i23"
				( attribute "BOM_COST" "SB"
					( Origin gFrontEnd )
				)
				( attribute "CDS_LIB" "mstr_discrete"
					( Origin gPackager )
				)
				( attribute "CDS_LOCATION" "C7A33"
					( Origin gPackager )
				)
				( attribute "CDS_SEC" "1"
					( Origin gPackager )
				)
				( attribute "LOCATION" "C7A33"
					( Origin gFrontEnd )
				)
				( attribute "MATERIAL" "X6S"
					( Origin gFrontEnd )
				)
				( attribute "PACK_TYPE" "0805"
					( Origin gFrontEnd )
				)
				( attribute "PART_NUMBER" "C95333-006"
					( Origin gFrontEnd )
				)
				( attribute "PHYS_PAGE" "132"
					( Origin gFrontEnd )
				)
				( attribute "ROOM" "SB_DECOUPLING"
					( Origin gFrontEnd )
				)
				( attribute "ROT" "0"
					( Origin gFrontEnd )
				)
				( attribute "SEC" "1"
					( Origin gPackager )
				)
				( attribute "TOLERANCE" "20%"
					( Origin gFrontEnd )
				)
				( attribute "VALUE" "47UF"
					( Origin gFrontEnd )
				)
				( attribute "VER" "1"
					( Origin gFrontEnd )
				)
				( attribute "VOLTAGE" "4V"
					( Units "uVoltage" "V" 1.000000)
					( Origin gFrontEnd )
				)
				( attribute "XY" "(2150,1575)"
					( Origin gFrontEnd )
				)
				( attribute "CHIPS_PART_NAME" "CAP"
					( Origin gPackager )
				)
				( attribute "CDS_PART_NAME" "CAP_0805-47UF,4V,20%,X6S,C9533A"
					( Origin gPackager )
				)
				( objectStatus "C7A33" )
			)
			( gate "@baseboard_fab2_lib.baseboard_fab2(sch_1):page132_i24"
				( attribute "BOM_COST" "SB"
					( Origin gFrontEnd )
				)
				( attribute "CDS_LIB" "mstr_discrete"
					( Origin gPackager )
				)
				( attribute "CDS_LOCATION" "C7B4"
					( Origin gPackager )
				)
				( attribute "CDS_SEC" "1"
					( Origin gPackager )
				)
				( attribute "LOCATION" "C7B4"
					( Origin gFrontEnd )
				)
				( attribute "MATERIAL" "X6S"
					( Origin gFrontEnd )
				)
				( attribute "PACK_TYPE" "0805"
					( Origin gFrontEnd )
				)
				( attribute "PART_NUMBER" "C95333-006"
					( Origin gFrontEnd )
				)
				( attribute "PHYS_PAGE" "132"
					( Origin gFrontEnd )
				)
				( attribute "ROOM" "SB_DECOUPLING"
					( Origin gFrontEnd )
				)
				( attribute "ROT" "0"
					( Origin gFrontEnd )
				)
				( attribute "SEC" "1"
					( Origin gPackager )
				)
				( attribute "TOLERANCE" "20%"
					( Origin gFrontEnd )
				)
				( attribute "VALUE" "47UF"
					( Origin gFrontEnd )
				)
				( attribute "VER" "1"
					( Origin gFrontEnd )
				)
				( attribute "VOLTAGE" "4V"
					( Units "uVoltage" "V" 1.000000)
					( Origin gFrontEnd )
				)
				( attribute "XY" "(1700,1575)"
					( Origin gFrontEnd )
				)
				( attribute "CHIPS_PART_NAME" "CAP"
					( Origin gPackager )
				)
				( attribute "CDS_PART_NAME" "CAP_0805-47UF,4V,20%,X6S,C9533A"
					( Origin gPackager )
				)
				( objectStatus "C7B4" )
			)
			( gate "@baseboard_fab2_lib.baseboard_fab2(sch_1):page132_i26"
				( attribute "CDS_LIB" "dev_discrete"
					( Origin gPackager )
				)
				( attribute "CDS_LOCATION" "C2N9"
					( Origin gPackager )
				)
				( attribute "CDS_SEC" "1"
					( Origin gPackager )
				)
				( attribute "LOCATION" "C2N9"
					( Origin gFrontEnd )
				)
				( attribute "MATERIAL" "X6S"
					( Origin gFrontEnd )
				)
				( attribute "PACK_TYPE" "0402V"
					( Origin gFrontEnd )
				)
				( attribute "PART_NUMBER" "D97712-004"
					( Origin gFrontEnd )
				)
				( attribute "PHYS_PAGE" "132"
					( Origin gFrontEnd )
				)
				( attribute "ROOM" "SB_DECOUPLING"
					( Origin gFrontEnd )
				)
				( attribute "ROT" "0"
					( Origin gFrontEnd )
				)
				( attribute "SEC" "1"
					( Origin gPackager )
				)
				( attribute "TOLERANCE" "10%"
					( Origin gFrontEnd )
				)
				( attribute "VALUE" "1.0UF"
					( Origin gFrontEnd )
				)
				( attribute "VER" "1"
					( Origin gFrontEnd )
				)
				( attribute "VOLTAGE" "6.3V"
					( Units "uVoltage" "V" 1.000000)
					( Origin gFrontEnd )
				)
				( attribute "XY" "(-325,4050)"
					( Origin gFrontEnd )
				)
				( attribute "CHIPS_PART_NAME" "CAP_A"
					( Origin gPackager )
				)
				( attribute "CDS_PART_NAME" "CAP_A_0402V-1.0UF,6.3V,10%,X6SA"
					( Origin gPackager )
				)
				( objectStatus "C2N9" )
			)
			( gate "@baseboard_fab2_lib.baseboard_fab2(sch_1):page132_i27"
				( attribute "BOM_COST" "SB"
					( Origin gFrontEnd )
				)
				( attribute "CDS_LIB" "dev_discrete"
					( Origin gPackager )
				)
				( attribute "CDS_LOCATION" "C2N3"
					( Origin gPackager )
				)
				( attribute "CDS_SEC" "1"
					( Origin gPackager )
				)
				( attribute "LOCATION" "C2N3"
					( Origin gFrontEnd )
				)
				( attribute "MATERIAL" "X6S"
					( Origin gFrontEnd )
				)
				( attribute "PACK_TYPE" "0402V"
					( Origin gFrontEnd )
				)
				( attribute "PART_NUMBER" "D97712-004"
					( Origin gFrontEnd )
				)
				( attribute "PHYS_PAGE" "132"
					( Origin gFrontEnd )
				)
				( attribute "ROOM" "SB_DECOUPLING"
					( Origin gFrontEnd )
				)
				( attribute "ROT" "0"
					( Origin gFrontEnd )
				)
				( attribute "SEC" "1"
					( Origin gPackager )
				)
				( attribute "TOLERANCE" "10%"
					( Origin gFrontEnd )
				)
				( attribute "VALUE" "1.0UF"
					( Origin gFrontEnd )
				)
				( attribute "VER" "1"
					( Origin gFrontEnd )
				)
				( attribute "VOLTAGE" "6.3V"
					( Units "uVoltage" "V" 1.000000)
					( Origin gFrontEnd )
				)
				( attribute "XY" "(-725,4050)"
					( Origin gFrontEnd )
				)
				( attribute "CHIPS_PART_NAME" "CAP_A"
					( Origin gPackager )
				)
				( attribute "CDS_PART_NAME" "CAP_A_0402V-1.0UF,6.3V,10%,X6SA"
					( Origin gPackager )
				)
				( objectStatus "C2N3" )
			)
			( gate "@baseboard_fab2_lib.baseboard_fab2(sch_1):page132_i28"
				( attribute "CDS_LIB" "dev_discrete"
					( Origin gPackager )
				)
				( attribute "CDS_LOCATION" "C2N4"
					( Origin gPackager )
				)
				( attribute "CDS_SEC" "1"
					( Origin gPackager )
				)
				( attribute "LOCATION" "C2N4"
					( Origin gFrontEnd )
				)
				( attribute "MATERIAL" "X6S"
					( Origin gFrontEnd )
				)
				( attribute "PACK_TYPE" "0402V"
					( Origin gFrontEnd )
				)
				( attribute "PART_NUMBER" "D97712-004"
					( Origin gFrontEnd )
				)
				( attribute "PHYS_PAGE" "132"
					( Origin gFrontEnd )
				)
				( attribute "ROOM" "SB_DECOUPLING"
					( Origin gFrontEnd )
				)
				( attribute "ROT" "0"
					( Origin gFrontEnd )
				)
				( attribute "SEC" "1"
					( Origin gPackager )
				)
				( attribute "TOLERANCE" "10%"
					( Origin gFrontEnd )
				)
				( attribute "VALUE" "1.0UF"
					( Origin gFrontEnd )
				)
				( attribute "VER" "1"
					( Origin gFrontEnd )
				)
				( attribute "VOLTAGE" "6.3V"
					( Units "uVoltage" "V" 1.000000)
					( Origin gFrontEnd )
				)
				( attribute "XY" "(-300,3025)"
					( Origin gFrontEnd )
				)
				( attribute "CHIPS_PART_NAME" "CAP_A"
					( Origin gPackager )
				)
				( attribute "CDS_PART_NAME" "CAP_A_0402V-1.0UF,6.3V,10%,X6SA"
					( Origin gPackager )
				)
				( objectStatus "C2N4" )
			)
			( gate "@baseboard_fab2_lib.baseboard_fab2(sch_1):page132_i29"
				( attribute "BOM_COST" "SB"
					( Origin gFrontEnd )
				)
				( attribute "CDS_LIB" "dev_discrete"
					( Origin gPackager )
				)
				( attribute "CDS_LOCATION" "C2N12"
					( Origin gPackager )
				)
				( attribute "CDS_SEC" "1"
					( Origin gPackager )
				)
				( attribute "LOCATION" "C2N12"
					( Origin gFrontEnd )
				)
				( attribute "MATERIAL" "X6S"
					( Origin gFrontEnd )
				)
				( attribute "PACK_TYPE" "0402V"
					( Origin gFrontEnd )
				)
				( attribute "PART_NUMBER" "D97712-004"
					( Origin gFrontEnd )
				)
				( attribute "PHYS_PAGE" "132"
					( Origin gFrontEnd )
				)
				( attribute "ROOM" "SB_DECOUPLING"
					( Origin gFrontEnd )
				)
				( attribute "ROT" "0"
					( Origin gFrontEnd )
				)
				( attribute "SEC" "1"
					( Origin gPackager )
				)
				( attribute "TOLERANCE" "10%"
					( Origin gFrontEnd )
				)
				( attribute "VALUE" "1.0UF"
					( Origin gFrontEnd )
				)
				( attribute "VER" "1"
					( Origin gFrontEnd )
				)
				( attribute "VOLTAGE" "6.3V"
					( Units "uVoltage" "V" 1.000000)
					( Origin gFrontEnd )
				)
				( attribute "XY" "(-700,3025)"
					( Origin gFrontEnd )
				)
				( attribute "CHIPS_PART_NAME" "CAP_A"
					( Origin gPackager )
				)
				( attribute "CDS_PART_NAME" "CAP_A_0402V-1.0UF,6.3V,10%,X6SA"
					( Origin gPackager )
				)
				( objectStatus "C2N12" )
			)
			( gate "@baseboard_fab2_lib.baseboard_fab2(sch_1):page132_i30"
				( attribute "BOM_COST" "SB"
					( Origin gFrontEnd )
				)
				( attribute "CDS_LIB" "dev_discrete"
					( Origin gPackager )
				)
				( attribute "CDS_LOCATION" "C2N11"
					( Origin gPackager )
				)
				( attribute "CDS_SEC" "1"
					( Origin gPackager )
				)
				( attribute "LOCATION" "C2N11"
					( Origin gFrontEnd )
				)
				( attribute "MATERIAL" "X6S"
					( Origin gFrontEnd )
				)
				( attribute "PACK_TYPE" "0402V"
					( Origin gFrontEnd )
				)
				( attribute "PART_NUMBER" "D97712-004"
					( Origin gFrontEnd )
				)
				( attribute "PHYS_PAGE" "132"
					( Origin gFrontEnd )
				)
				( attribute "ROOM" "SB_DECOUPLING"
					( Origin gFrontEnd )
				)
				( attribute "ROT" "0"
					( Origin gFrontEnd )
				)
				( attribute "SEC" "1"
					( Origin gPackager )
				)
				( attribute "TOLERANCE" "10%"
					( Origin gFrontEnd )
				)
				( attribute "VALUE" "1.0UF"
					( Origin gFrontEnd )
				)
				( attribute "VER" "1"
					( Origin gFrontEnd )
				)
				( attribute "VOLTAGE" "6.3V"
					( Units "uVoltage" "V" 1.000000)
					( Origin gFrontEnd )
				)
				( attribute "XY" "(-1100,4050)"
					( Origin gFrontEnd )
				)
				( attribute "CHIPS_PART_NAME" "CAP_A"
					( Origin gPackager )
				)
				( attribute "CDS_PART_NAME" "CAP_A_0402V-1.0UF,6.3V,10%,X6SA"
					( Origin gPackager )
				)
				( objectStatus "C2N11" )
			)
			( gate "@baseboard_fab2_lib.baseboard_fab2(sch_1):page132_i31"
				( attribute "BOM_COST" "SB"
					( Origin gFrontEnd )
				)
				( attribute "CDS_LIB" "dev_discrete"
					( Origin gPackager )
				)
				( attribute "CDS_LOCATION" "C3N19"
					( Origin gPackager )
				)
				( attribute "CDS_SEC" "1"
					( Origin gPackager )
				)
				( attribute "LOCATION" "C3N19"
					( Origin gFrontEnd )
				)
				( attribute "MATERIAL" "X6S"
					( Origin gFrontEnd )
				)
				( attribute "PACK_TYPE" "0402V"
					( Origin gFrontEnd )
				)
				( attribute "PART_NUMBER" "D97712-004"
					( Origin gFrontEnd )
				)
				( attribute "PHYS_PAGE" "132"
					( Origin gFrontEnd )
				)
				( attribute "ROOM" "SB_DECOUPLING"
					( Origin gFrontEnd )
				)
				( attribute "ROT" "0"
					( Origin gFrontEnd )
				)
				( attribute "SEC" "1"
					( Origin gPackager )
				)
				( attribute "TOLERANCE" "10%"
					( Origin gFrontEnd )
				)
				( attribute "VALUE" "1.0UF"
					( Origin gFrontEnd )
				)
				( attribute "VER" "1"
					( Origin gFrontEnd )
				)
				( attribute "VOLTAGE" "6.3V"
					( Units "uVoltage" "V" 1.000000)
					( Origin gFrontEnd )
				)
				( attribute "XY" "(-1475,4050)"
					( Origin gFrontEnd )
				)
				( attribute "CHIPS_PART_NAME" "CAP_A"
					( Origin gPackager )
				)
				( attribute "CDS_PART_NAME" "CAP_A_0402V-1.0UF,6.3V,10%,X6SA"
					( Origin gPackager )
				)
				( objectStatus "C3N19" )
			)
			( gate "@baseboard_fab2_lib.baseboard_fab2(sch_1):page132_i32"
				( attribute "BOM_COST" "SB"
					( Origin gFrontEnd )
				)
				( attribute "CDS_LIB" "dev_discrete"
					( Origin gPackager )
				)
				( attribute "CDS_LOCATION" "C3N3"
					( Origin gPackager )
				)
				( attribute "CDS_SEC" "1"
					( Origin gPackager )
				)
				( attribute "LOCATION" "C3N3"
					( Origin gFrontEnd )
				)
				( attribute "MATERIAL" "X6S"
					( Origin gFrontEnd )
				)
				( attribute "PACK_TYPE" "0402V"
					( Origin gFrontEnd )
				)
				( attribute "PART_NUMBER" "D97712-004"
					( Origin gFrontEnd )
				)
				( attribute "PHYS_PAGE" "132"
					( Origin gFrontEnd )
				)
				( attribute "ROOM" "SB_DECOUPLING"
					( Origin gFrontEnd )
				)
				( attribute "ROT" "0"
					( Origin gFrontEnd )
				)
				( attribute "SEC" "1"
					( Origin gPackager )
				)
				( attribute "TOLERANCE" "10%"
					( Origin gFrontEnd )
				)
				( attribute "VALUE" "1.0UF"
					( Origin gFrontEnd )
				)
				( attribute "VER" "1"
					( Origin gFrontEnd )
				)
				( attribute "VOLTAGE" "6.3V"
					( Units "uVoltage" "V" 1.000000)
					( Origin gFrontEnd )
				)
				( attribute "XY" "(-1850,4050)"
					( Origin gFrontEnd )
				)
				( attribute "CHIPS_PART_NAME" "CAP_A"
					( Origin gPackager )
				)
				( attribute "CDS_PART_NAME" "CAP_A_0402V-1.0UF,6.3V,10%,X6SA"
					( Origin gPackager )
				)
				( objectStatus "C3N3" )
			)
			( gate "@baseboard_fab2_lib.baseboard_fab2(sch_1):page132_i34"
				( attribute "BOM_COST" "SB"
					( Origin gFrontEnd )
				)
				( attribute "CDS_LIB" "dev_discrete"
					( Origin gPackager )
				)
				( attribute "CDS_LOCATION" "C3N1"
					( Origin gPackager )
				)
				( attribute "CDS_SEC" "1"
					( Origin gPackager )
				)
				( attribute "LOCATION" "C3N1"
					( Origin gFrontEnd )
				)
				( attribute "MATERIAL" "X6S"
					( Origin gFrontEnd )
				)
				( attribute "PACK_TYPE" "0402V"
					( Origin gFrontEnd )
				)
				( attribute "PART_NUMBER" "D97712-004"
					( Origin gFrontEnd )
				)
				( attribute "PHYS_PAGE" "132"
					( Origin gFrontEnd )
				)
				( attribute "ROOM" "SB_DECOUPLING"
					( Origin gFrontEnd )
				)
				( attribute "ROT" "0"
					( Origin gFrontEnd )
				)
				( attribute "SEC" "1"
					( Origin gPackager )
				)
				( attribute "TOLERANCE" "10%"
					( Origin gFrontEnd )
				)
				( attribute "VALUE" "1.0UF"
					( Origin gFrontEnd )
				)
				( attribute "VER" "1"
					( Origin gFrontEnd )
				)
				( attribute "VOLTAGE" "6.3V"
					( Units "uVoltage" "V" 1.000000)
					( Origin gFrontEnd )
				)
				( attribute "XY" "(-1075,3025)"
					( Origin gFrontEnd )
				)
				( attribute "CHIPS_PART_NAME" "CAP_A"
					( Origin gPackager )
				)
				( attribute "CDS_PART_NAME" "CAP_A_0402V-1.0UF,6.3V,10%,X6SA"
					( Origin gPackager )
				)
				( objectStatus "C3N1" )
			)
			( gate "@baseboard_fab2_lib.baseboard_fab2(sch_1):page132_i35"
				( attribute "BOM_COST" "SB"
					( Origin gFrontEnd )
				)
				( attribute "CDS_LIB" "dev_discrete"
					( Origin gPackager )
				)
				( attribute "CDS_LOCATION" "C3N7"
					( Origin gPackager )
				)
				( attribute "CDS_SEC" "1"
					( Origin gPackager )
				)
				( attribute "LOCATION" "C3N7"
					( Origin gFrontEnd )
				)
				( attribute "MATERIAL" "X6S"
					( Origin gFrontEnd )
				)
				( attribute "PACK_TYPE" "0402V"
					( Origin gFrontEnd )
				)
				( attribute "PART_NUMBER" "D97712-004"
					( Origin gFrontEnd )
				)
				( attribute "PHYS_PAGE" "132"
					( Origin gFrontEnd )
				)
				( attribute "ROOM" "SB_DECOUPLING"
					( Origin gFrontEnd )
				)
				( attribute "ROT" "0"
					( Origin gFrontEnd )
				)
				( attribute "SEC" "1"
					( Origin gPackager )
				)
				( attribute "TOLERANCE" "10%"
					( Origin gFrontEnd )
				)
				( attribute "VALUE" "1.0UF"
					( Origin gFrontEnd )
				)
				( attribute "VER" "1"
					( Origin gFrontEnd )
				)
				( attribute "VOLTAGE" "6.3V"
					( Units "uVoltage" "V" 1.000000)
					( Origin gFrontEnd )
				)
				( attribute "XY" "(-1450,3025)"
					( Origin gFrontEnd )
				)
				( attribute "CHIPS_PART_NAME" "CAP_A"
					( Origin gPackager )
				)
				( attribute "CDS_PART_NAME" "CAP_A_0402V-1.0UF,6.3V,10%,X6SA"
					( Origin gPackager )
				)
				( objectStatus "C3N7" )
			)
			( gate "@baseboard_fab2_lib.baseboard_fab2(sch_1):page132_i36"
				( attribute "BOM_COST" "SB"
					( Origin gFrontEnd )
				)
				( attribute "CDS_LIB" "dev_discrete"
					( Origin gPackager )
				)
				( attribute "CDS_LOCATION" "C3N16"
					( Origin gPackager )
				)
				( attribute "CDS_SEC" "1"
					( Origin gPackager )
				)
				( attribute "LOCATION" "C3N16"
					( Origin gFrontEnd )
				)
				( attribute "MATERIAL" "X6S"
					( Origin gFrontEnd )
				)
				( attribute "PACK_TYPE" "0402V"
					( Origin gFrontEnd )
				)
				( attribute "PART_NUMBER" "D97712-004"
					( Origin gFrontEnd )
				)
				( attribute "PHYS_PAGE" "132"
					( Origin gFrontEnd )
				)
				( attribute "ROOM" "SB_DECOUPLING"
					( Origin gFrontEnd )
				)
				( attribute "ROT" "0"
					( Origin gFrontEnd )
				)
				( attribute "SEC" "1"
					( Origin gPackager )
				)
				( attribute "TOLERANCE" "10%"
					( Origin gFrontEnd )
				)
				( attribute "VALUE" "1.0UF"
					( Origin gFrontEnd )
				)
				( attribute "VER" "1"
					( Origin gFrontEnd )
				)
				( attribute "VOLTAGE" "6.3V"
					( Units "uVoltage" "V" 1.000000)
					( Origin gFrontEnd )
				)
				( attribute "XY" "(-1825,3025)"
					( Origin gFrontEnd )
				)
				( attribute "CHIPS_PART_NAME" "CAP_A"
					( Origin gPackager )
				)
				( attribute "CDS_PART_NAME" "CAP_A_0402V-1.0UF,6.3V,10%,X6SA"
					( Origin gPackager )
				)
				( objectStatus "C3N16" )
			)
			( gate "@baseboard_fab2_lib.baseboard_fab2(sch_1):page132_i38"
				( attribute "BOM_COST" "SB"
					( Origin gFrontEnd )
				)
				( attribute "CDS_LIB" "mstr_discrete"
					( Origin gPackager )
				)
				( attribute "CDS_LOCATION" "C7A32"
					( Origin gPackager )
				)
				( attribute "CDS_SEC" "1"
					( Origin gPackager )
				)
				( attribute "LOCATION" "C7A32"
					( Origin gFrontEnd )
				)
				( attribute "MATERIAL" "X6S"
					( Origin gFrontEnd )
				)
				( attribute "PACK_TYPE" "0805"
					( Origin gFrontEnd )
				)
				( attribute "PART_NUMBER" "C95333-006"
					( Origin gFrontEnd )
				)
				( attribute "PHYS_PAGE" "132"
					( Origin gFrontEnd )
				)
				( attribute "ROOM" "SB_DECOUPLING"
					( Origin gFrontEnd )
				)
				( attribute "ROT" "0"
					( Origin gFrontEnd )
				)
				( attribute "SEC" "1"
					( Origin gPackager )
				)
				( attribute "TOLERANCE" "20%"
					( Origin gFrontEnd )
				)
				( attribute "VALUE" "47UF"
					( Origin gFrontEnd )
				)
				( attribute "VER" "1"
					( Origin gFrontEnd )
				)
				( attribute "VOLTAGE" "4V"
					( Units "uVoltage" "V" 1.000000)
					( Origin gFrontEnd )
				)
				( attribute "XY" "(-650,1900)"
					( Origin gFrontEnd )
				)
				( attribute "CHIPS_PART_NAME" "CAP"
					( Origin gPackager )
				)
				( attribute "CDS_PART_NAME" "CAP_0805-47UF,4V,20%,X6S,C9533A"
					( Origin gPackager )
				)
				( objectStatus "C7A32" )
			)
			( gate "@baseboard_fab2_lib.baseboard_fab2(sch_1):page132_i40"
				( attribute "BOM_COST" "SB"
					( Origin gFrontEnd )
				)
				( attribute "CDS_LIB" "mstr_discrete"
					( Origin gPackager )
				)
				( attribute "CDS_LOCATION" "C7A31"
					( Origin gPackager )
				)
				( attribute "CDS_SEC" "1"
					( Origin gPackager )
				)
				( attribute "LOCATION" "C7A31"
					( Origin gFrontEnd )
				)
				( attribute "MATERIAL" "X6S"
					( Origin gFrontEnd )
				)
				( attribute "PACK_TYPE" "0805"
					( Origin gFrontEnd )
				)
				( attribute "PART_NUMBER" "C95333-006"
					( Origin gFrontEnd )
				)
				( attribute "PHYS_PAGE" "132"
					( Origin gFrontEnd )
				)
				( attribute "ROOM" "SB_DECOUPLING"
					( Origin gFrontEnd )
				)
				( attribute "ROT" "0"
					( Origin gFrontEnd )
				)
				( attribute "SEC" "1"
					( Origin gPackager )
				)
				( attribute "TOLERANCE" "20%"
					( Origin gFrontEnd )
				)
				( attribute "VALUE" "47UF"
					( Origin gFrontEnd )
				)
				( attribute "VER" "1"
					( Origin gFrontEnd )
				)
				( attribute "VOLTAGE" "4V"
					( Units "uVoltage" "V" 1.000000)
					( Origin gFrontEnd )
				)
				( attribute "XY" "(-1100,1900)"
					( Origin gFrontEnd )
				)
				( attribute "CHIPS_PART_NAME" "CAP"
					( Origin gPackager )
				)
				( attribute "CDS_PART_NAME" "CAP_0805-47UF,4V,20%,X6S,C9533A"
					( Origin gPackager )
				)
				( objectStatus "C7A31" )
			)
			( gate "@baseboard_fab2_lib.baseboard_fab2(sch_1):page132_i42"
				( attribute "BOM_COST" "SB"
					( Origin gFrontEnd )
				)
				( attribute "CDS_LIB" "dev_discrete"
					( Origin gPackager )
				)
				( attribute "CDS_LOCATION" "C3N18"
					( Origin gPackager )
				)
				( attribute "CDS_SEC" "1"
					( Origin gPackager )
				)
				( attribute "LOCATION" "C3N18"
					( Origin gFrontEnd )
				)
				( attribute "MATERIAL" "X6S"
					( Origin gFrontEnd )
				)
				( attribute "PACK_TYPE" "0402V"
					( Origin gFrontEnd )
				)
				( attribute "PART_NUMBER" "D97712-004"
					( Origin gFrontEnd )
				)
				( attribute "PHYS_PAGE" "132"
					( Origin gFrontEnd )
				)
				( attribute "ROOM" "SB_DECOUPLING"
					( Origin gFrontEnd )
				)
				( attribute "ROT" "0"
					( Origin gFrontEnd )
				)
				( attribute "SEC" "1"
					( Origin gPackager )
				)
				( attribute "TOLERANCE" "10%"
					( Origin gFrontEnd )
				)
				( attribute "VALUE" "1.0UF"
					( Origin gFrontEnd )
				)
				( attribute "VER" "1"
					( Origin gFrontEnd )
				)
				( attribute "VOLTAGE" "6.3V"
					( Units "uVoltage" "V" 1.000000)
					( Origin gFrontEnd )
				)
				( attribute "XY" "(-2225,4050)"
					( Origin gFrontEnd )
				)
				( attribute "CHIPS_PART_NAME" "CAP_A"
					( Origin gPackager )
				)
				( attribute "CDS_PART_NAME" "CAP_A_0402V-1.0UF,6.3V,10%,X6SA"
					( Origin gPackager )
				)
				( objectStatus "C3N18" )
			)
			( gate "@baseboard_fab2_lib.baseboard_fab2(sch_1):page132_i43"
				( attribute "BOM_COST" "SB"
					( Origin gFrontEnd )
				)
				( attribute "CDS_LIB" "dev_discrete"
					( Origin gPackager )
				)
				( attribute "CDS_LOCATION" "C3N2"
					( Origin gPackager )
				)
				( attribute "CDS_SEC" "1"
					( Origin gPackager )
				)
				( attribute "LOCATION" "C3N2"
					( Origin gFrontEnd )
				)
				( attribute "MATERIAL" "X6S"
					( Origin gFrontEnd )
				)
				( attribute "PACK_TYPE" "0402V"
					( Origin gFrontEnd )
				)
				( attribute "PART_NUMBER" "D97712-004"
					( Origin gFrontEnd )
				)
				( attribute "PHYS_PAGE" "132"
					( Origin gFrontEnd )
				)
				( attribute "ROOM" "SB_DECOUPLING"
					( Origin gFrontEnd )
				)
				( attribute "ROT" "0"
					( Origin gFrontEnd )
				)
				( attribute "SEC" "1"
					( Origin gPackager )
				)
				( attribute "TOLERANCE" "10%"
					( Origin gFrontEnd )
				)
				( attribute "VALUE" "1.0UF"
					( Origin gFrontEnd )
				)
				( attribute "VER" "1"
					( Origin gFrontEnd )
				)
				( attribute "VOLTAGE" "6.3V"
					( Units "uVoltage" "V" 1.000000)
					( Origin gFrontEnd )
				)
				( attribute "XY" "(-2625,4050)"
					( Origin gFrontEnd )
				)
				( attribute "CHIPS_PART_NAME" "CAP_A"
					( Origin gPackager )
				)
				( attribute "CDS_PART_NAME" "CAP_A_0402V-1.0UF,6.3V,10%,X6SA"
					( Origin gPackager )
				)
				( objectStatus "C3N2" )
			)
			( gate "@baseboard_fab2_lib.baseboard_fab2(sch_1):page132_i44"
				( attribute "BOM_COST" "SB"
					( Origin gFrontEnd )
				)
				( attribute "CDS_LIB" "dev_discrete"
					( Origin gPackager )
				)
				( attribute "CDS_LOCATION" "C3N6"
					( Origin gPackager )
				)
				( attribute "CDS_SEC" "1"
					( Origin gPackager )
				)
				( attribute "LOCATION" "C3N6"
					( Origin gFrontEnd )
				)
				( attribute "MATERIAL" "X6S"
					( Origin gFrontEnd )
				)
				( attribute "PACK_TYPE" "0402V"
					( Origin gFrontEnd )
				)
				( attribute "PART_NUMBER" "D97712-004"
					( Origin gFrontEnd )
				)
				( attribute "PHYS_PAGE" "132"
					( Origin gFrontEnd )
				)
				( attribute "ROOM" "SB_DECOUPLING"
					( Origin gFrontEnd )
				)
				( attribute "ROT" "0"
					( Origin gFrontEnd )
				)
				( attribute "SEC" "1"
					( Origin gPackager )
				)
				( attribute "TOLERANCE" "10%"
					( Origin gFrontEnd )
				)
				( attribute "VALUE" "1.0UF"
					( Origin gFrontEnd )
				)
				( attribute "VER" "1"
					( Origin gFrontEnd )
				)
				( attribute "VOLTAGE" "6.3V"
					( Units "uVoltage" "V" 1.000000)
					( Origin gFrontEnd )
				)
				( attribute "XY" "(-2200,3025)"
					( Origin gFrontEnd )
				)
				( attribute "CHIPS_PART_NAME" "CAP_A"
					( Origin gPackager )
				)
				( attribute "CDS_PART_NAME" "CAP_A_0402V-1.0UF,6.3V,10%,X6SA"
					( Origin gPackager )
				)
				( objectStatus "C3N6" )
			)
			( gate "@baseboard_fab2_lib.baseboard_fab2(sch_1):page132_i45"
				( attribute "BOM_COST" "SB"
					( Origin gFrontEnd )
				)
				( attribute "CDS_LIB" "dev_discrete"
					( Origin gPackager )
				)
				( attribute "CDS_LOCATION" "C3N17"
					( Origin gPackager )
				)
				( attribute "CDS_SEC" "1"
					( Origin gPackager )
				)
				( attribute "LOCATION" "C3N17"
					( Origin gFrontEnd )
				)
				( attribute "MATERIAL" "X6S"
					( Origin gFrontEnd )
				)
				( attribute "PACK_TYPE" "0402V"
					( Origin gFrontEnd )
				)
				( attribute "PART_NUMBER" "D97712-004"
					( Origin gFrontEnd )
				)
				( attribute "PHYS_PAGE" "132"
					( Origin gFrontEnd )
				)
				( attribute "ROOM" "SB_DECOUPLING"
					( Origin gFrontEnd )
				)
				( attribute "ROT" "0"
					( Origin gFrontEnd )
				)
				( attribute "SEC" "1"
					( Origin gPackager )
				)
				( attribute "TOLERANCE" "10%"
					( Origin gFrontEnd )
				)
				( attribute "VALUE" "1.0UF"
					( Origin gFrontEnd )
				)
				( attribute "VER" "1"
					( Origin gFrontEnd )
				)
				( attribute "VOLTAGE" "6.3V"
					( Units "uVoltage" "V" 1.000000)
					( Origin gFrontEnd )
				)
				( attribute "XY" "(-2600,3025)"
					( Origin gFrontEnd )
				)
				( attribute "CHIPS_PART_NAME" "CAP_A"
					( Origin gPackager )
				)
				( attribute "CDS_PART_NAME" "CAP_A_0402V-1.0UF,6.3V,10%,X6SA"
					( Origin gPackager )
				)
				( objectStatus "C3N17" )
			)
			( gate "@baseboard_fab2_lib.baseboard_fab2(sch_1):page132_i46"
				( attribute "BOM_COST" "SB"
					( Origin gFrontEnd )
				)
				( attribute "CDS_LIB" "dev_discrete"
					( Origin gPackager )
				)
				( attribute "CDS_LOCATION" "C3N4"
					( Origin gPackager )
				)
				( attribute "CDS_SEC" "1"
					( Origin gPackager )
				)
				( attribute "LOCATION" "C3N4"
					( Origin gFrontEnd )
				)
				( attribute "MATERIAL" "X6S"
					( Origin gFrontEnd )
				)
				( attribute "PACK_TYPE" "0402V"
					( Origin gFrontEnd )
				)
				( attribute "PART_NUMBER" "D97712-004"
					( Origin gFrontEnd )
				)
				( attribute "PHYS_PAGE" "132"
					( Origin gFrontEnd )
				)
				( attribute "ROOM" "SB_DECOUPLING"
					( Origin gFrontEnd )
				)
				( attribute "ROT" "0"
					( Origin gFrontEnd )
				)
				( attribute "SEC" "1"
					( Origin gPackager )
				)
				( attribute "TOLERANCE" "10%"
					( Origin gFrontEnd )
				)
				( attribute "VALUE" "1.0UF"
					( Origin gFrontEnd )
				)
				( attribute "VER" "1"
					( Origin gFrontEnd )
				)
				( attribute "VOLTAGE" "6.3V"
					( Units "uVoltage" "V" 1.000000)
					( Origin gFrontEnd )
				)
				( attribute "XY" "(-3000,4050)"
					( Origin gFrontEnd )
				)
				( attribute "CHIPS_PART_NAME" "CAP_A"
					( Origin gPackager )
				)
				( attribute "CDS_PART_NAME" "CAP_A_0402V-1.0UF,6.3V,10%,X6SA"
					( Origin gPackager )
				)
				( objectStatus "C3N4" )
			)
			( gate "@baseboard_fab2_lib.baseboard_fab2(sch_1):page132_i48"
				( attribute "BOM_COST" "SB"
					( Origin gFrontEnd )
				)
				( attribute "CDS_LIB" "dev_discrete"
					( Origin gPackager )
				)
				( attribute "CDS_LOCATION" "C3N5"
					( Origin gPackager )
				)
				( attribute "CDS_SEC" "1"
					( Origin gPackager )
				)
				( attribute "LOCATION" "C3N5"
					( Origin gFrontEnd )
				)
				( attribute "MATERIAL" "X6S"
					( Origin gFrontEnd )
				)
				( attribute "PACK_TYPE" "0402V"
					( Origin gFrontEnd )
				)
				( attribute "PART_NUMBER" "D97712-004"
					( Origin gFrontEnd )
				)
				( attribute "PHYS_PAGE" "132"
					( Origin gFrontEnd )
				)
				( attribute "ROOM" "SB_DECOUPLING"
					( Origin gFrontEnd )
				)
				( attribute "ROT" "0"
					( Origin gFrontEnd )
				)
				( attribute "SEC" "1"
					( Origin gPackager )
				)
				( attribute "TOLERANCE" "10%"
					( Origin gFrontEnd )
				)
				( attribute "VALUE" "1.0UF"
					( Origin gFrontEnd )
				)
				( attribute "VER" "1"
					( Origin gFrontEnd )
				)
				( attribute "VOLTAGE" "6.3V"
					( Units "uVoltage" "V" 1.000000)
					( Origin gFrontEnd )
				)
				( attribute "XY" "(-3400,4050)"
					( Origin gFrontEnd )
				)
				( attribute "CHIPS_PART_NAME" "CAP_A"
					( Origin gPackager )
				)
				( attribute "CDS_PART_NAME" "CAP_A_0402V-1.0UF,6.3V,10%,X6SA"
					( Origin gPackager )
				)
				( objectStatus "C3N5" )
			)
			( gate "@baseboard_fab2_lib.baseboard_fab2(sch_1):page132_i49"
				( attribute "BOM_COST" "SB"
					( Origin gFrontEnd )
				)
				( attribute "CDS_LIB" "dev_discrete"
					( Origin gPackager )
				)
				( attribute "CDS_LOCATION" "C3N15"
					( Origin gPackager )
				)
				( attribute "CDS_SEC" "1"
					( Origin gPackager )
				)
				( attribute "LOCATION" "C3N15"
					( Origin gFrontEnd )
				)
				( attribute "MATERIAL" "X6S"
					( Origin gFrontEnd )
				)
				( attribute "PACK_TYPE" "0402V"
					( Origin gFrontEnd )
				)
				( attribute "PART_NUMBER" "D97712-004"
					( Origin gFrontEnd )
				)
				( attribute "PHYS_PAGE" "132"
					( Origin gFrontEnd )
				)
				( attribute "ROOM" "SB_DECOUPLING"
					( Origin gFrontEnd )
				)
				( attribute "ROT" "0"
					( Origin gFrontEnd )
				)
				( attribute "SEC" "1"
					( Origin gPackager )
				)
				( attribute "TOLERANCE" "10%"
					( Origin gFrontEnd )
				)
				( attribute "VALUE" "1.0UF"
					( Origin gFrontEnd )
				)
				( attribute "VER" "1"
					( Origin gFrontEnd )
				)
				( attribute "VOLTAGE" "6.3V"
					( Units "uVoltage" "V" 1.000000)
					( Origin gFrontEnd )
				)
				( attribute "XY" "(-2975,3025)"
					( Origin gFrontEnd )
				)
				( attribute "CHIPS_PART_NAME" "CAP_A"
					( Origin gPackager )
				)
				( attribute "CDS_PART_NAME" "CAP_A_0402V-1.0UF,6.3V,10%,X6SA"
					( Origin gPackager )
				)
				( objectStatus "C3N15" )
			)
			( gate "@baseboard_fab2_lib.baseboard_fab2(sch_1):page132_i51"
				( attribute "BOM_COST" "SB"
					( Origin gFrontEnd )
				)
				( attribute "CDS_LIB" "dev_discrete"
					( Origin gPackager )
				)
				( attribute "CDS_LOCATION" "C3N20"
					( Origin gPackager )
				)
				( attribute "CDS_SEC" "1"
					( Origin gPackager )
				)
				( attribute "LOCATION" "C3N20"
					( Origin gFrontEnd )
				)
				( attribute "MATERIAL" "X6S"
					( Origin gFrontEnd )
				)
				( attribute "PACK_TYPE" "0402V"
					( Origin gFrontEnd )
				)
				( attribute "PART_NUMBER" "D97712-004"
					( Origin gFrontEnd )
				)
				( attribute "PHYS_PAGE" "132"
					( Origin gFrontEnd )
				)
				( attribute "ROOM" "SB_DECOUPLING"
					( Origin gFrontEnd )
				)
				( attribute "ROT" "0"
					( Origin gFrontEnd )
				)
				( attribute "SEC" "1"
					( Origin gPackager )
				)
				( attribute "TOLERANCE" "10%"
					( Origin gFrontEnd )
				)
				( attribute "VALUE" "1.0UF"
					( Origin gFrontEnd )
				)
				( attribute "VER" "1"
					( Origin gFrontEnd )
				)
				( attribute "VOLTAGE" "6.3V"
					( Units "uVoltage" "V" 1.000000)
					( Origin gFrontEnd )
				)
				( attribute "XY" "(-3375,3025)"
					( Origin gFrontEnd )
				)
				( attribute "CHIPS_PART_NAME" "CAP_A"
					( Origin gPackager )
				)
				( attribute "CDS_PART_NAME" "CAP_A_0402V-1.0UF,6.3V,10%,X6SA"
					( Origin gPackager )
				)
				( objectStatus "C3N20" )
			)
			( gate "@baseboard_fab2_lib.baseboard_fab2(sch_1):page132_i52"
				( attribute "BOM_COST" "SB"
					( Origin gFrontEnd )
				)
				( attribute "CDS_LIB" "dev_discrete"
					( Origin gPackager )
				)
				( attribute "CDS_LOCATION" "C3L23"
					( Origin gPackager )
				)
				( attribute "CDS_SEC" "1"
					( Origin gPackager )
				)
				( attribute "LOCATION" "C3L23"
					( Origin gFrontEnd )
				)
				( attribute "MATERIAL" "X6S"
					( Origin gFrontEnd )
				)
				( attribute "PACK_TYPE" "0603V"
					( Origin gFrontEnd )
				)
				( attribute "PART_NUMBER" "E15431-004"
					( Origin gFrontEnd )
				)
				( attribute "PHYS_PAGE" "132"
					( Origin gFrontEnd )
				)
				( attribute "ROOM" "SB_DECOUPLING"
					( Origin gFrontEnd )
				)
				( attribute "ROT" "0"
					( Origin gFrontEnd )
				)
				( attribute "SEC" "1"
					( Origin gPackager )
				)
				( attribute "TOLERANCE" "20%"
					( Origin gFrontEnd )
				)
				( attribute "VALUE" "22.0UF"
					( Origin gFrontEnd )
				)
				( attribute "VER" "1"
					( Origin gFrontEnd )
				)
				( attribute "VOLTAGE" "4V"
					( Units "uVoltage" "V" 1.000000)
					( Origin gFrontEnd )
				)
				( attribute "XY" "(-2550,1925)"
					( Origin gFrontEnd )
				)
				( attribute "CHIPS_PART_NAME" "CAP_A"
					( Origin gPackager )
				)
				( attribute "CDS_PART_NAME" "CAP_A_0603V-22.0UF,4V,20%,X6S,A"
					( Origin gPackager )
				)
				( objectStatus "C3L23" )
			)
			( gate "@baseboard_fab2_lib.baseboard_fab2(sch_1):page132_i54"
				( attribute "BOM_COST" "SB"
					( Origin gFrontEnd )
				)
				( attribute "CDS_LIB" "dev_discrete"
					( Origin gPackager )
				)
				( attribute "CDS_LOCATION" "C3L22"
					( Origin gPackager )
				)
				( attribute "CDS_SEC" "1"
					( Origin gPackager )
				)
				( attribute "LOCATION" "C3L22"
					( Origin gFrontEnd )
				)
				( attribute "MATERIAL" "X6S"
					( Origin gFrontEnd )
				)
				( attribute "PACK_TYPE" "0603V"
					( Origin gFrontEnd )
				)
				( attribute "PART_NUMBER" "E15431-004"
					( Origin gFrontEnd )
				)
				( attribute "PHYS_PAGE" "132"
					( Origin gFrontEnd )
				)
				( attribute "ROOM" "SB_DECOUPLING"
					( Origin gFrontEnd )
				)
				( attribute "ROT" "0"
					( Origin gFrontEnd )
				)
				( attribute "SEC" "1"
					( Origin gPackager )
				)
				( attribute "TOLERANCE" "20%"
					( Origin gFrontEnd )
				)
				( attribute "VALUE" "22.0UF"
					( Origin gFrontEnd )
				)
				( attribute "VER" "1"
					( Origin gFrontEnd )
				)
				( attribute "VOLTAGE" "4V"
					( Units "uVoltage" "V" 1.000000)
					( Origin gFrontEnd )
				)
				( attribute "XY" "(-2950,1925)"
					( Origin gFrontEnd )
				)
				( attribute "CHIPS_PART_NAME" "CAP_A"
					( Origin gPackager )
				)
				( attribute "CDS_PART_NAME" "CAP_A_0603V-22.0UF,4V,20%,X6S,A"
					( Origin gPackager )
				)
				( objectStatus "C3L22" )
			)
			( gate "@baseboard_fab2_lib.baseboard_fab2(sch_1):page132_i56"
				( attribute "BOM_COST" "SB"
					( Origin gFrontEnd )
				)
				( attribute "CDS_LIB" "dev_discrete"
					( Origin gPackager )
				)
				( attribute "CDS_LOCATION" "C3L24"
					( Origin gPackager )
				)
				( attribute "CDS_SEC" "1"
					( Origin gPackager )
				)
				( attribute "LOCATION" "C3L24"
					( Origin gFrontEnd )
				)
				( attribute "MATERIAL" "X6S"
					( Origin gFrontEnd )
				)
				( attribute "PACK_TYPE" "0603V"
					( Origin gFrontEnd )
				)
				( attribute "PART_NUMBER" "E15431-004"
					( Origin gFrontEnd )
				)
				( attribute "PHYS_PAGE" "132"
					( Origin gFrontEnd )
				)
				( attribute "ROOM" "SB_DECOUPLING"
					( Origin gFrontEnd )
				)
				( attribute "ROT" "0"
					( Origin gFrontEnd )
				)
				( attribute "SEC" "1"
					( Origin gPackager )
				)
				( attribute "TOLERANCE" "20%"
					( Origin gFrontEnd )
				)
				( attribute "VALUE" "22.0UF"
					( Origin gFrontEnd )
				)
				( attribute "VER" "1"
					( Origin gFrontEnd )
				)
				( attribute "VOLTAGE" "4V"
					( Units "uVoltage" "V" 1.000000)
					( Origin gFrontEnd )
				)
				( attribute "XY" "(-3425,1925)"
					( Origin gFrontEnd )
				)
				( attribute "CHIPS_PART_NAME" "CAP_A"
					( Origin gPackager )
				)
				( attribute "CDS_PART_NAME" "CAP_A_0603V-22.0UF,4V,20%,X6S,A"
					( Origin gPackager )
				)
				( objectStatus "C3L24" )
			)
			( gate "@baseboard_fab2_lib.baseboard_fab2(sch_1):page133_i120"
				( attribute "BOM_COST" "SB"
					( Origin gFrontEnd )
				)
				( attribute "CDS_LIB" "mstr_discrete"
					( Origin gPackager )
				)
				( attribute "CDS_LOCATION" "R3N3"
					( Origin gPackager )
				)
				( attribute "CDS_SEC" "1"
					( Origin gPackager )
				)
				( attribute "LOCATION" "R3N3"
					( Origin gFrontEnd )
				)
				( attribute "MATERIAL" "CHIP"
					( Origin gFrontEnd )
				)
				( attribute "PACK_TYPE" "0402"
					( Origin gFrontEnd )
				)
				( attribute "PART_NUMBER" "G21796-001"
					( Origin gFrontEnd )
				)
				( attribute "PHYS_PAGE" "133"
					( Origin gFrontEnd )
				)
				( attribute "ROOM" "SB"
					( Origin gFrontEnd )
				)
				( attribute "ROT" "0"
					( Origin gFrontEnd )
				)
				( attribute "SEC" "1"
					( Origin gPackager )
				)
				( attribute "TOLERANCE" "1%"
					( Origin gFrontEnd )
				)
				( attribute "VALUE" "2.0K"
					( Origin gFrontEnd )
				)
				( attribute "VER" "1"
					( Origin gFrontEnd )
				)
				( attribute "WATTAGE" "1/16W"
					( Origin gFrontEnd )
				)
				( attribute "XY" "(-2500,3850)"
					( Origin gFrontEnd )
				)
				( attribute "CHIPS_PART_NAME" "RES"
					( Origin gPackager )
				)
				( attribute "CDS_PART_NAME" "RES_0402-2.0K,1%,1/16W,CHIP,G2A"
					( Origin gPackager )
				)
				( objectStatus "R3N3" )
			)
			( gate "@baseboard_fab2_lib.baseboard_fab2(sch_1):page133_i122"
				( attribute "BOM_COST" "SB"
					( Origin gFrontEnd )
				)
				( attribute "CDS_LIB" "mstr_discrete"
					( Origin gPackager )
				)
				( attribute "CDS_LOCATION" "R2N12"
					( Origin gPackager )
				)
				( attribute "CDS_SEC" "1"
					( Origin gPackager )
				)
				( attribute "LOCATION" "R2N12"
					( Origin gFrontEnd )
				)
				( attribute "MATERIAL" "EMPTY"
					( Origin gFrontEnd )
				)
				( attribute "PACK_TYPE" "0402"
					( Origin gFrontEnd )
				)
				( attribute "PART_NUMBER" "G21796-016"
					( Origin gFrontEnd )
				)
				( attribute "PHYS_PAGE" "133"
					( Origin gFrontEnd )
				)
				( attribute "ROOM" "SB"
					( Origin gFrontEnd )
				)
				( attribute "ROT" "0"
					( Origin gFrontEnd )
				)
				( attribute "SEC" "1"
					( Origin gPackager )
				)
				( attribute "TOLERANCE" "1%"
					( Origin gFrontEnd )
				)
				( attribute "VALUE" "10.0K"
					( Origin gFrontEnd )
				)
				( attribute "VER" "1"
					( Origin gFrontEnd )
				)
				( attribute "WATTAGE" "1/16W"
					( Origin gFrontEnd )
				)
				( attribute "XY" "(-2500,4075)"
					( Origin gFrontEnd )
				)
				( attribute "CHIPS_PART_NAME" "RES"
					( Origin gPackager )
				)
				( attribute "CDS_PART_NAME" "RES_0402-10.0K,1%,1/16W,EMPTY,A"
					( Origin gPackager )
				)
				( objectStatus "R2N12" )
			)
			( gate "@baseboard_fab2_lib.baseboard_fab2(sch_1):page133_i200"
				( attribute "CDS_LIB" "mstr_discrete"
					( Origin gPackager )
				)
				( attribute "CDS_LOCATION" "R7D8"
					( Origin gPackager )
				)
				( attribute "CDS_SEC" "1"
					( Origin gPackager )
				)
				( attribute "LOCATION" "R7D8"
					( Origin gFrontEnd )
				)
				( attribute "MATERIAL" "CHIP"
					( Origin gFrontEnd )
				)
				( attribute "PACK_TYPE" "0402"
					( Origin gFrontEnd )
				)
				( attribute "PART_NUMBER" "G21796-016"
					( Origin gFrontEnd )
				)
				( attribute "PHYS_PAGE" "133"
					( Origin gFrontEnd )
				)
				( attribute "ROOM" "SB"
					( Origin gFrontEnd )
				)
				( attribute "ROT" "0"
					( Origin gFrontEnd )
				)
				( attribute "SEC" "1"
					( Origin gFrontEnd )
				)
				( attribute "SEC_TYPE" "0402"
					( Origin gFrontEnd )
				)
				( attribute "TOLERANCE" "1%"
					( Origin gFrontEnd )
				)
				( attribute "VALUE" "10.0K"
					( Origin gFrontEnd )
				)
				( attribute "VER" "1"
					( Origin gFrontEnd )
				)
				( attribute "WATTAGE" "1/16W"
					( Origin gFrontEnd )
				)
				( attribute "XY" "(-4700,4500)"
					( Origin gFrontEnd )
				)
				( attribute "CHIPS_PART_NAME" "RES"
					( Origin gPackager )
				)
				( attribute "CDS_PART_NAME" "RES_0402-10.0K,1%,1/16W,CHIP,GA"
					( Origin gPackager )
				)
				( objectStatus "R7D8" )
			)
			( gate "@baseboard_fab2_lib.baseboard_fab2(sch_1):page133_i202"
				( attribute "CDS_LIB" "mstr_discrete"
					( Origin gPackager )
				)
				( attribute "CDS_LOCATION" "R7D10"
					( Origin gPackager )
				)
				( attribute "CDS_SEC" "1"
					( Origin gPackager )
				)
				( attribute "LOCATION" "R7D10"
					( Origin gFrontEnd )
				)
				( attribute "MATERIAL" "CHIP"
					( Origin gFrontEnd )
				)
				( attribute "PACK_TYPE" "0402"
					( Origin gFrontEnd )
				)
				( attribute "PART_NUMBER" "G21796-016"
					( Origin gFrontEnd )
				)
				( attribute "PHYS_PAGE" "133"
					( Origin gFrontEnd )
				)
				( attribute "ROOM" "SB"
					( Origin gFrontEnd )
				)
				( attribute "ROT" "0"
					( Origin gFrontEnd )
				)
				( attribute "SEC" "1"
					( Origin gFrontEnd )
				)
				( attribute "SEC_TYPE" "0402"
					( Origin gFrontEnd )
				)
				( attribute "TOLERANCE" "1%"
					( Origin gFrontEnd )
				)
				( attribute "VALUE" "10.0K"
					( Origin gFrontEnd )
				)
				( attribute "VER" "1"
					( Origin gFrontEnd )
				)
				( attribute "WATTAGE" "1/16W"
					( Origin gFrontEnd )
				)
				( attribute "XY" "(-4700,4325)"
					( Origin gFrontEnd )
				)
				( attribute "CHIPS_PART_NAME" "RES"
					( Origin gPackager )
				)
				( attribute "CDS_PART_NAME" "RES_0402-10.0K,1%,1/16W,CHIP,GA"
					( Origin gPackager )
				)
				( objectStatus "R7D10" )
			)
			( gate "@baseboard_fab2_lib.baseboard_fab2(sch_1):page133_i237"
				( attribute "CDS_LIB" "mstr_discrete"
					( Origin gPackager )
				)
				( attribute "CDS_LOCATION" "R7D12"
					( Origin gPackager )
				)
				( attribute "CDS_SEC" "1"
					( Origin gPackager )
				)
				( attribute "LOCATION" "R7D12"
					( Origin gFrontEnd )
				)
				( attribute "MATERIAL" "CHIP"
					( Origin gFrontEnd )
				)
				( attribute "PACK_TYPE" "0402"
					( Origin gFrontEnd )
				)
				( attribute "PART_NUMBER" "G21796-016"
					( Origin gFrontEnd )
				)
				( attribute "PHYS_PAGE" "133"
					( Origin gFrontEnd )
				)
				( attribute "ROOM" "SB"
					( Origin gFrontEnd )
				)
				( attribute "ROT" "0"
					( Origin gFrontEnd )
				)
				( attribute "SEC" "1"
					( Origin gFrontEnd )
				)
				( attribute "SEC_TYPE" "0402"
					( Origin gFrontEnd )
				)
				( attribute "TOLERANCE" "1%"
					( Origin gFrontEnd )
				)
				( attribute "VALUE" "10.0K"
					( Origin gFrontEnd )
				)
				( attribute "VER" "1"
					( Origin gFrontEnd )
				)
				( attribute "WATTAGE" "1/16W"
					( Origin gFrontEnd )
				)
				( attribute "XY" "(-4700,3925)"
					( Origin gFrontEnd )
				)
				( attribute "CHIPS_PART_NAME" "RES"
					( Origin gPackager )
				)
				( attribute "CDS_PART_NAME" "RES_0402-10.0K,1%,1/16W,CHIP,GA"
					( Origin gPackager )
				)
				( objectStatus "R7D12" )
			)
			( gate "@baseboard_fab2_lib.baseboard_fab2(sch_1):page133_i243"
				( attribute "CDS_LIB" "mstr_discrete"
					( Origin gPackager )
				)
				( attribute "CDS_LOCATION" "R7D3"
					( Origin gPackager )
				)
				( attribute "CDS_SEC" "1"
					( Origin gPackager )
				)
				( attribute "LOCATION" "R7D3"
					( Origin gFrontEnd )
				)
				( attribute "MATERIAL" "CHIP"
					( Origin gFrontEnd )
				)
				( attribute "PACK_TYPE" "0402"
					( Origin gFrontEnd )
				)
				( attribute "PART_NUMBER" "G21796-072"
					( Origin gFrontEnd )
				)
				( attribute "PHYS_PAGE" "133"
					( Origin gFrontEnd )
				)
				( attribute "ROOM" "SB"
					( Origin gFrontEnd )
				)
				( attribute "ROT" "0"
					( Origin gFrontEnd )
				)
				( attribute "SEC" "1"
					( Origin gFrontEnd )
				)
				( attribute "SEC_TYPE" "0402"
					( Origin gFrontEnd )
				)
				( attribute "TOLERANCE" "1%"
					( Origin gFrontEnd )
				)
				( attribute "VALUE" "4.75K"
					( Origin gFrontEnd )
				)
				( attribute "VER" "1"
					( Origin gFrontEnd )
				)
				( attribute "WATTAGE" "1/16W"
					( Origin gFrontEnd )
				)
				( attribute "XY" "(-4700,4900)"
					( Origin gFrontEnd )
				)
				( attribute "CHIPS_PART_NAME" "RES"
					( Origin gPackager )
				)
				( attribute "CDS_PART_NAME" "RES_0402-4.75K,1%,1/16W,CHIP,GA"
					( Origin gPackager )
				)
				( objectStatus "R7D3" )
			)
			( gate "@baseboard_fab2_lib.baseboard_fab2(sch_1):page133_i245"
				( attribute "CDS_LIB" "mstr_discrete"
					( Origin gPackager )
				)
				( attribute "CDS_LOCATION" "R7D4"
					( Origin gPackager )
				)
				( attribute "CDS_SEC" "1"
					( Origin gPackager )
				)
				( attribute "LOCATION" "R7D4"
					( Origin gFrontEnd )
				)
				( attribute "MATERIAL" "CHIP"
					( Origin gFrontEnd )
				)
				( attribute "PACK_TYPE" "0402"
					( Origin gFrontEnd )
				)
				( attribute "PART_NUMBER" "G21796-016"
					( Origin gFrontEnd )
				)
				( attribute "PHYS_PAGE" "133"
					( Origin gFrontEnd )
				)
				( attribute "ROOM" "SB"
					( Origin gFrontEnd )
				)
				( attribute "ROT" "0"
					( Origin gFrontEnd )
				)
				( attribute "SEC" "1"
					( Origin gFrontEnd )
				)
				( attribute "SEC_TYPE" "0402"
					( Origin gFrontEnd )
				)
				( attribute "TOLERANCE" "1%"
					( Origin gFrontEnd )
				)
				( attribute "VALUE" "10.0K"
					( Origin gFrontEnd )
				)
				( attribute "VER" "1"
					( Origin gFrontEnd )
				)
				( attribute "WATTAGE" "1/16W"
					( Origin gFrontEnd )
				)
				( attribute "XY" "(-4700,4125)"
					( Origin gFrontEnd )
				)
				( attribute "CHIPS_PART_NAME" "RES"
					( Origin gPackager )
				)
				( attribute "CDS_PART_NAME" "RES_0402-10.0K,1%,1/16W,CHIP,GA"
					( Origin gPackager )
				)
				( objectStatus "R7D4" )
			)
			( gate "@baseboard_fab2_lib.baseboard_fab2(sch_1):page133_i247"
				( attribute "BOM_COST" "SB"
					( Origin gFrontEnd )
				)
				( attribute "CDS_LIB" "mstr_discrete"
					( Origin gPackager )
				)
				( attribute "CDS_LOCATION" "R2N16"
					( Origin gPackager )
				)
				( attribute "CDS_SEC" "1"
					( Origin gPackager )
				)
				( attribute "LOCATION" "R2N16"
					( Origin gFrontEnd )
				)
				( attribute "MATERIAL" "CHIP"
					( Origin gFrontEnd )
				)
				( attribute "PACK_TYPE" "0402"
					( Origin gFrontEnd )
				)
				( attribute "PART_NUMBER" "G21796-016"
					( Origin gFrontEnd )
				)
				( attribute "PHYS_PAGE" "133"
					( Origin gFrontEnd )
				)
				( attribute "ROOM" "SB"
					( Origin gFrontEnd )
				)
				( attribute "ROT" "0"
					( Origin gFrontEnd )
				)
				( attribute "SEC" "1"
					( Origin gPackager )
				)
				( attribute "TOLERANCE" "1%"
					( Origin gFrontEnd )
				)
				( attribute "VALUE" "10.0K"
					( Origin gFrontEnd )
				)
				( attribute "VER" "1"
					( Origin gFrontEnd )
				)
				( attribute "WATTAGE" "1/16W"
					( Origin gFrontEnd )
				)
				( attribute "XY" "(-4650,2725)"
					( Origin gFrontEnd )
				)
				( attribute "CHIPS_PART_NAME" "RES"
					( Origin gPackager )
				)
				( attribute "CDS_PART_NAME" "RES_0402-10.0K,1%,1/16W,CHIP,GA"
					( Origin gPackager )
				)
				( objectStatus "R2N16" )
			)
			( gate "@baseboard_fab2_lib.baseboard_fab2(sch_1):page133_i258"
				( attribute "BOM_COST" "SB"
					( Origin gFrontEnd )
				)
				( attribute "CDS_LIB" "mstr_discrete"
					( Origin gPackager )
				)
				( attribute "CDS_LOCATION" "R2R5"
					( Origin gPackager )
				)
				( attribute "CDS_SEC" "1"
					( Origin gPackager )
				)
				( attribute "LOCATION" "R2R5"
					( Origin gFrontEnd )
				)
				( attribute "MATERIAL" "CHIP"
					( Origin gFrontEnd )
				)
				( attribute "PACK_TYPE" "0402"
					( Origin gFrontEnd )
				)
				( attribute "PART_NUMBER" "G21796-026"
					( Origin gFrontEnd )
				)
				( attribute "PHYS_PAGE" "133"
					( Origin gFrontEnd )
				)
				( attribute "ROOM" "SB"
					( Origin gFrontEnd )
				)
				( attribute "ROT" "0"
					( Origin gFrontEnd )
				)
				( attribute "SEC" "1"
					( Origin gFrontEnd )
				)
				( attribute "SEC_TYPE" "0402"
					( Origin gFrontEnd )
				)
				( attribute "TOLERANCE" "1%"
					( Origin gFrontEnd )
				)
				( attribute "VALUE" "1.00K"
					( Origin gFrontEnd )
				)
				( attribute "VER" "1"
					( Origin gFrontEnd )
				)
				( attribute "WATTAGE" "1/16W"
					( Origin gFrontEnd )
				)
				( attribute "XY" "(-2600,5125)"
					( Origin gFrontEnd )
				)
				( attribute "CHIPS_PART_NAME" "RES"
					( Origin gPackager )
				)
				( attribute "CDS_PART_NAME" "RES_0402-1.00K,1%,1/16W,CHIP,GA"
					( Origin gPackager )
				)
				( objectStatus "R2R5" )
			)
			( gate "@baseboard_fab2_lib.baseboard_fab2(sch_1):page133_i267"
				( attribute "CDS_LIB" "mstr_discrete"
					( Origin gPackager )
				)
				( attribute "CDS_LOCATION" "R2N9"
					( Origin gPackager )
				)
				( attribute "CDS_SEC" "1"
					( Origin gPackager )
				)
				( attribute "LOCATION" "R2N9"
					( Origin gFrontEnd )
				)
				( attribute "MATERIAL" "CHIP"
					( Origin gFrontEnd )
				)
				( attribute "PACK_TYPE" "0402"
					( Origin gFrontEnd )
				)
				( attribute "PART_NUMBER" "G21796-016"
					( Origin gFrontEnd )
				)
				( attribute "PHYS_PAGE" "133"
					( Origin gFrontEnd )
				)
				( attribute "ROOM" "SB"
					( Origin gFrontEnd )
				)
				( attribute "ROT" "0"
					( Origin gFrontEnd )
				)
				( attribute "SEC" "1"
					( Origin gFrontEnd )
				)
				( attribute "SEC_TYPE" "0402"
					( Origin gFrontEnd )
				)
				( attribute "TOLERANCE" "1%"
					( Origin gFrontEnd )
				)
				( attribute "VALUE" "10.0K"
					( Origin gFrontEnd )
				)
				( attribute "VER" "1"
					( Origin gFrontEnd )
				)
				( attribute "WATTAGE" "1/16W"
					( Origin gFrontEnd )
				)
				( attribute "XY" "(-2475,1275)"
					( Origin gFrontEnd )
				)
				( attribute "CHIPS_PART_NAME" "RES"
					( Origin gPackager )
				)
				( attribute "CDS_PART_NAME" "RES_0402-10.0K,1%,1/16W,CHIP,GA"
					( Origin gPackager )
				)
				( objectStatus "R2N9" )
			)
			( gate "@baseboard_fab2_lib.baseboard_fab2(sch_1):page133_i280"
				( attribute "BOM_COST" "SB"
					( Origin gFrontEnd )
				)
				( attribute "CDS_LIB" "mstr_discrete"
					( Origin gPackager )
				)
				( attribute "CDS_LOCATION" "R8B23"
					( Origin gPackager )
				)
				( attribute "CDS_SEC" "1"
					( Origin gPackager )
				)
				( attribute "LOCATION" "R8B23"
					( Origin gFrontEnd )
				)
				( attribute "MATERIAL" "CHIP"
					( Origin gFrontEnd )
				)
				( attribute "PACK_TYPE" "0402"
					( Origin gFrontEnd )
				)
				( attribute "PART_NUMBER" "G21796-026"
					( Origin gFrontEnd )
				)
				( attribute "PHYS_PAGE" "133"
					( Origin gFrontEnd )
				)
				( attribute "ROOM" "SB"
					( Origin gFrontEnd )
				)
				( attribute "ROT" "0"
					( Origin gFrontEnd )
				)
				( attribute "SEC" "1"
					( Origin gFrontEnd )
				)
				( attribute "SEC_TYPE" "0402"
					( Origin gFrontEnd )
				)
				( attribute "TOLERANCE" "1%"
					( Origin gFrontEnd )
				)
				( attribute "VALUE" "1.00K"
					( Origin gFrontEnd )
				)
				( attribute "VER" "1"
					( Origin gFrontEnd )
				)
				( attribute "WATTAGE" "1/16W"
					( Origin gFrontEnd )
				)
				( attribute "XY" "(-2575,4675)"
					( Origin gFrontEnd )
				)
				( attribute "CHIPS_PART_NAME" "RES"
					( Origin gPackager )
				)
				( attribute "CDS_PART_NAME" "RES_0402-1.00K,1%,1/16W,CHIP,GA"
					( Origin gPackager )
				)
				( objectStatus "R8B23" )
			)
			( gate "@baseboard_fab2_lib.baseboard_fab2(sch_1):page133_i282"
				( attribute "BOM_COST" "SB"
					( Origin gFrontEnd )
				)
				( attribute "CDS_LIB" "mstr_discrete"
					( Origin gPackager )
				)
				( attribute "CDS_LOCATION" "R8B30"
					( Origin gPackager )
				)
				( attribute "CDS_SEC" "1"
					( Origin gPackager )
				)
				( attribute "LOCATION" "R8B30"
					( Origin gFrontEnd )
				)
				( attribute "MATERIAL" "CHIP"
					( Origin gFrontEnd )
				)
				( attribute "PACK_TYPE" "0402"
					( Origin gFrontEnd )
				)
				( attribute "PART_NUMBER" "G21796-026"
					( Origin gFrontEnd )
				)
				( attribute "PHYS_PAGE" "133"
					( Origin gFrontEnd )
				)
				( attribute "ROOM" "SB"
					( Origin gFrontEnd )
				)
				( attribute "ROT" "0"
					( Origin gFrontEnd )
				)
				( attribute "SEC" "1"
					( Origin gFrontEnd )
				)
				( attribute "SEC_TYPE" "0402"
					( Origin gFrontEnd )
				)
				( attribute "TOLERANCE" "1%"
					( Origin gFrontEnd )
				)
				( attribute "VALUE" "1.00K"
					( Origin gFrontEnd )
				)
				( attribute "VER" "1"
					( Origin gFrontEnd )
				)
				( attribute "WATTAGE" "1/16W"
					( Origin gFrontEnd )
				)
				( attribute "XY" "(-2575,4425)"
					( Origin gFrontEnd )
				)
				( attribute "CHIPS_PART_NAME" "RES"
					( Origin gPackager )
				)
				( attribute "CDS_PART_NAME" "RES_0402-1.00K,1%,1/16W,CHIP,GA"
					( Origin gPackager )
				)
				( objectStatus "R8B30" )
			)
			( gate "@baseboard_fab2_lib.baseboard_fab2(sch_1):page133_i284"
				( attribute "BOM_COST" "SB"
					( Origin gFrontEnd )
				)
				( attribute "CDS_LIB" "mstr_discrete"
					( Origin gPackager )
				)
				( attribute "CDS_LOCATION" "R2M4"
					( Origin gPackager )
				)
				( attribute "CDS_SEC" "1"
					( Origin gPackager )
				)
				( attribute "LOCATION" "R2M4"
					( Origin gFrontEnd )
				)
				( attribute "MATERIAL" "CHIP"
					( Origin gFrontEnd )
				)
				( attribute "PACK_TYPE" "0402"
					( Origin gFrontEnd )
				)
				( attribute "PART_NUMBER" "G21796-026"
					( Origin gFrontEnd )
				)
				( attribute "PHYS_PAGE" "133"
					( Origin gFrontEnd )
				)
				( attribute "ROOM" "SB"
					( Origin gFrontEnd )
				)
				( attribute "ROT" "0"
					( Origin gFrontEnd )
				)
				( attribute "SEC" "1"
					( Origin gFrontEnd )
				)
				( attribute "SEC_TYPE" "0402"
					( Origin gFrontEnd )
				)
				( attribute "TOLERANCE" "1%"
					( Origin gFrontEnd )
				)
				( attribute "VALUE" "1.00K"
					( Origin gFrontEnd )
				)
				( attribute "VER" "1"
					( Origin gFrontEnd )
				)
				( attribute "WATTAGE" "1/16W"
					( Origin gFrontEnd )
				)
				( attribute "XY" "(-2600,4900)"
					( Origin gFrontEnd )
				)
				( attribute "CHIPS_PART_NAME" "RES"
					( Origin gPackager )
				)
				( attribute "CDS_PART_NAME" "RES_0402-1.00K,1%,1/16W,CHIP,GA"
					( Origin gPackager )
				)
				( objectStatus "R2M4" )
			)
			( gate "@baseboard_fab2_lib.baseboard_fab2(sch_1):page133_i286"
				( attribute "BOM_COST" "SB_PU_PD"
					( Origin gFrontEnd )
				)
				( attribute "CDS_LIB" "mstr_discrete"
					( Origin gPackager )
				)
				( attribute "CDS_LOCATION" "R8C4"
					( Origin gPackager )
				)
				( attribute "CDS_SEC" "1"
					( Origin gPackager )
				)
				( attribute "LOCATION" "R8C4"
					( Origin gFrontEnd )
				)
				( attribute "MATERIAL" "CHIP"
					( Origin gFrontEnd )
				)
				( attribute "PACK_TYPE" "0402"
					( Origin gFrontEnd )
				)
				( attribute "PART_NUMBER" "G21796-026"
					( Origin gFrontEnd )
				)
				( attribute "PHYS_PAGE" "133"
					( Origin gFrontEnd )
				)
				( attribute "ROOM" "SB"
					( Origin gFrontEnd )
				)
				( attribute "ROT" "0"
					( Origin gFrontEnd )
				)
				( attribute "SEC" "1"
					( Origin gFrontEnd )
				)
				( attribute "SEC_TYPE" "0402"
					( Origin gFrontEnd )
				)
				( attribute "TOLERANCE" "1%"
					( Origin gFrontEnd )
				)
				( attribute "VALUE" "1.00K"
					( Origin gFrontEnd )
				)
				( attribute "VER" "1"
					( Origin gFrontEnd )
				)
				( attribute "WATTAGE" "1/16W"
					( Origin gFrontEnd )
				)
				( attribute "XY" "(-4800,950)"
					( Origin gFrontEnd )
				)
				( attribute "CHIPS_PART_NAME" "RES"
					( Origin gPackager )
				)
				( attribute "CDS_PART_NAME" "RES_0402-1.00K,1%,1/16W,CHIP,GA"
					( Origin gPackager )
				)
				( objectStatus "R8C4" )
			)
			( gate "@baseboard_fab2_lib.baseboard_fab2(sch_1):page133_i295"
				( attribute "CDS_LIB" "mstr_discrete"
					( Origin gPackager )
				)
				( attribute "CDS_LOCATION" "R7B6"
					( Origin gPackager )
				)
				( attribute "CDS_SEC" "1"
					( Origin gPackager )
				)
				( attribute "LOCATION" "R7B6"
					( Origin gFrontEnd )
				)
				( attribute "MATERIAL" "CHIP"
					( Origin gFrontEnd )
				)
				( attribute "PACK_TYPE" "0402"
					( Origin gFrontEnd )
				)
				( attribute "PART_NUMBER" "G21796-016"
					( Origin gFrontEnd )
				)
				( attribute "PHYS_PAGE" "133"
					( Origin gFrontEnd )
				)
				( attribute "ROOM" "SB_PU_PD"
					( Origin gFrontEnd )
				)
				( attribute "ROT" "0"
					( Origin gFrontEnd )
				)
				( attribute "SEC" "1"
					( Origin gFrontEnd )
				)
				( attribute "SEC_TYPE" "0402"
					( Origin gFrontEnd )
				)
				( attribute "TOLERANCE" "1%"
					( Origin gFrontEnd )
				)
				( attribute "VALUE" "10.0K"
					( Origin gFrontEnd )
				)
				( attribute "VER" "2"
					( Origin gFrontEnd )
				)
				( attribute "WATTAGE" "1/16W"
					( Origin gFrontEnd )
				)
				( attribute "XY" "(-175,1425)"
					( Origin gFrontEnd )
				)
				( attribute "CHIPS_PART_NAME" "RES"
					( Origin gPackager )
				)
				( attribute "CDS_PART_NAME" "RES_0402-10.0K,1%,1/16W,CHIP,GA"
					( Origin gPackager )
				)
				( objectStatus "R7B6" )
			)
			( gate "@baseboard_fab2_lib.baseboard_fab2(sch_1):page133_i296"
				( attribute "CDS_LIB" "mstr_discrete"
					( Origin gPackager )
				)
				( attribute "CDS_LOCATION" "R7C8"
					( Origin gPackager )
				)
				( attribute "CDS_SEC" "1"
					( Origin gPackager )
				)
				( attribute "LOCATION" "R7C8"
					( Origin gFrontEnd )
				)
				( attribute "MATERIAL" "CHIP"
					( Origin gFrontEnd )
				)
				( attribute "PACK_TYPE" "0402"
					( Origin gFrontEnd )
				)
				( attribute "PART_NUMBER" "G21796-016"
					( Origin gFrontEnd )
				)
				( attribute "PHYS_PAGE" "133"
					( Origin gFrontEnd )
				)
				( attribute "ROOM" "SB_PU_PD"
					( Origin gFrontEnd )
				)
				( attribute "ROT" "0"
					( Origin gFrontEnd )
				)
				( attribute "SEC" "1"
					( Origin gFrontEnd )
				)
				( attribute "SEC_TYPE" "0402"
					( Origin gFrontEnd )
				)
				( attribute "TOLERANCE" "1%"
					( Origin gFrontEnd )
				)
				( attribute "VALUE" "10.0K"
					( Origin gFrontEnd )
				)
				( attribute "VER" "2"
					( Origin gFrontEnd )
				)
				( attribute "WATTAGE" "1/16W"
					( Origin gFrontEnd )
				)
				( attribute "XY" "(-425,1425)"
					( Origin gFrontEnd )
				)
				( attribute "CHIPS_PART_NAME" "RES"
					( Origin gPackager )
				)
				( attribute "CDS_PART_NAME" "RES_0402-10.0K,1%,1/16W,CHIP,GA"
					( Origin gPackager )
				)
				( objectStatus "R7C8" )
			)
			( gate "@baseboard_fab2_lib.baseboard_fab2(sch_1):page133_i297"
				( attribute "CDS_LIB" "mstr_discrete"
					( Origin gPackager )
				)
				( attribute "CDS_LOCATION" "R7C5"
					( Origin gPackager )
				)
				( attribute "CDS_SEC" "1"
					( Origin gPackager )
				)
				( attribute "LOCATION" "R7C5"
					( Origin gFrontEnd )
				)
				( attribute "MATERIAL" "CHIP"
					( Origin gFrontEnd )
				)
				( attribute "PACK_TYPE" "0402"
					( Origin gFrontEnd )
				)
				( attribute "PART_NUMBER" "G21796-016"
					( Origin gFrontEnd )
				)
				( attribute "PHYS_PAGE" "133"
					( Origin gFrontEnd )
				)
				( attribute "ROOM" "SB_PU_PD"
					( Origin gFrontEnd )
				)
				( attribute "ROT" "0"
					( Origin gFrontEnd )
				)
				( attribute "SEC" "1"
					( Origin gFrontEnd )
				)
				( attribute "SEC_TYPE" "0402"
					( Origin gFrontEnd )
				)
				( attribute "TOLERANCE" "1%"
					( Origin gFrontEnd )
				)
				( attribute "VALUE" "10.0K"
					( Origin gFrontEnd )
				)
				( attribute "VER" "2"
					( Origin gFrontEnd )
				)
				( attribute "WATTAGE" "1/16W"
					( Origin gFrontEnd )
				)
				( attribute "XY" "(-650,1425)"
					( Origin gFrontEnd )
				)
				( attribute "CHIPS_PART_NAME" "RES"
					( Origin gPackager )
				)
				( attribute "CDS_PART_NAME" "RES_0402-10.0K,1%,1/16W,CHIP,GA"
					( Origin gPackager )
				)
				( objectStatus "R7C5" )
			)
			( gate "@baseboard_fab2_lib.baseboard_fab2(sch_1):page133_i301"
				( attribute "BOM_COST" "SB"
					( Origin gFrontEnd )
				)
				( attribute "CDS_LIB" "mstr_discrete"
					( Origin gPackager )
				)
				( attribute "CDS_LOCATION" "R8D14"
					( Origin gPackager )
				)
				( attribute "CDS_SEC" "1"
					( Origin gPackager )
				)
				( attribute "LOCATION" "R8D14"
					( Origin gFrontEnd )
				)
				( attribute "MATERIAL" "CHIP"
					( Origin gFrontEnd )
				)
				( attribute "PACK_TYPE" "0402"
					( Origin gFrontEnd )
				)
				( attribute "PART_NUMBER" "G21796-072"
					( Origin gFrontEnd )
				)
				( attribute "PHYS_PAGE" "133"
					( Origin gFrontEnd )
				)
				( attribute "ROOM" "SB"
					( Origin gFrontEnd )
				)
				( attribute "ROT" "0"
					( Origin gFrontEnd )
				)
				( attribute "SEC" "1"
					( Origin gFrontEnd )
				)
				( attribute "SEC_TYPE" "0402"
					( Origin gFrontEnd )
				)
				( attribute "TOLERANCE" "1%"
					( Origin gFrontEnd )
				)
				( attribute "VALUE" "4.75K"
					( Origin gFrontEnd )
				)
				( attribute "VER" "1"
					( Origin gFrontEnd )
				)
				( attribute "WATTAGE" "1/16W"
					( Origin gFrontEnd )
				)
				( attribute "XY" "(-2475,1800)"
					( Origin gFrontEnd )
				)
				( attribute "CHIPS_PART_NAME" "RES"
					( Origin gPackager )
				)
				( attribute "CDS_PART_NAME" "RES_0402-4.75K,1%,1/16W,CHIP,GA"
					( Origin gPackager )
				)
				( objectStatus "R8D14" )
			)
			( gate "@baseboard_fab2_lib.baseboard_fab2(sch_1):page133_i303"
				( attribute "CDS_LIB" "mstr_discrete"
					( Origin gPackager )
				)
				( attribute "CDS_LOCATION" "R8C6"
					( Origin gPackager )
				)
				( attribute "CDS_SEC" "1"
					( Origin gPackager )
				)
				( attribute "LOCATION" "R8C6"
					( Origin gFrontEnd )
				)
				( attribute "MATERIAL" "CHIP"
					( Origin gFrontEnd )
				)
				( attribute "PACK_TYPE" "0402"
					( Origin gFrontEnd )
				)
				( attribute "PART_NUMBER" "G21796-072"
					( Origin gFrontEnd )
				)
				( attribute "PHYS_PAGE" "133"
					( Origin gFrontEnd )
				)
				( attribute "ROOM" "SB_PU_PD"
					( Origin gFrontEnd )
				)
				( attribute "ROT" "0"
					( Origin gFrontEnd )
				)
				( attribute "SEC" "1"
					( Origin gFrontEnd )
				)
				( attribute "SEC_TYPE" "0402"
					( Origin gFrontEnd )
				)
				( attribute "TOLERANCE" "1%"
					( Origin gFrontEnd )
				)
				( attribute "VALUE" "4.75K"
					( Origin gFrontEnd )
				)
				( attribute "VER" "1"
					( Origin gFrontEnd )
				)
				( attribute "WATTAGE" "1/16W"
					( Origin gFrontEnd )
				)
				( attribute "XY" "(-4675,2400)"
					( Origin gFrontEnd )
				)
				( attribute "CHIPS_PART_NAME" "RES"
					( Origin gPackager )
				)
				( attribute "CDS_PART_NAME" "RES_0402-4.75K,1%,1/16W,CHIP,GA"
					( Origin gPackager )
				)
				( objectStatus "R8C6" )
			)
			( gate "@baseboard_fab2_lib.baseboard_fab2(sch_1):page133_i304"
				( attribute "CDS_LIB" "mstr_discrete"
					( Origin gPackager )
				)
				( attribute "CDS_LOCATION" "R8C2"
					( Origin gPackager )
				)
				( attribute "CDS_SEC" "1"
					( Origin gPackager )
				)
				( attribute "LOCATION" "R8C2"
					( Origin gFrontEnd )
				)
				( attribute "MATERIAL" "CHIP"
					( Origin gFrontEnd )
				)
				( attribute "PACK_TYPE" "0402"
					( Origin gFrontEnd )
				)
				( attribute "PART_NUMBER" "G21796-072"
					( Origin gFrontEnd )
				)
				( attribute "PHYS_PAGE" "133"
					( Origin gFrontEnd )
				)
				( attribute "ROOM" "SB_PU_PD"
					( Origin gFrontEnd )
				)
				( attribute "ROT" "0"
					( Origin gFrontEnd )
				)
				( attribute "SEC" "1"
					( Origin gFrontEnd )
				)
				( attribute "SEC_TYPE" "0402"
					( Origin gFrontEnd )
				)
				( attribute "TOLERANCE" "1%"
					( Origin gFrontEnd )
				)
				( attribute "VALUE" "4.75K"
					( Origin gFrontEnd )
				)
				( attribute "VER" "1"
					( Origin gFrontEnd )
				)
				( attribute "WATTAGE" "1/16W"
					( Origin gFrontEnd )
				)
				( attribute "XY" "(-4800,1825)"
					( Origin gFrontEnd )
				)
				( attribute "CHIPS_PART_NAME" "RES"
					( Origin gPackager )
				)
				( attribute "CDS_PART_NAME" "RES_0402-4.75K,1%,1/16W,CHIP,GA"
					( Origin gPackager )
				)
				( objectStatus "R8C2" )
			)
			( gate "@baseboard_fab2_lib.baseboard_fab2(sch_1):page133_i306"
				( attribute "CDS_LIB" "mstr_discrete"
					( Origin gPackager )
				)
				( attribute "CDS_LOCATION" "R7D6"
					( Origin gPackager )
				)
				( attribute "CDS_SEC" "1"
					( Origin gPackager )
				)
				( attribute "LOCATION" "R7D6"
					( Origin gFrontEnd )
				)
				( attribute "MATERIAL" "CHIP"
					( Origin gFrontEnd )
				)
				( attribute "PACK_TYPE" "0402"
					( Origin gFrontEnd )
				)
				( attribute "PART_NUMBER" "G21796-072"
					( Origin gFrontEnd )
				)
				( attribute "PHYS_PAGE" "133"
					( Origin gFrontEnd )
				)
				( attribute "ROOM" "SB_PU_PD"
					( Origin gFrontEnd )
				)
				( attribute "ROT" "0"
					( Origin gFrontEnd )
				)
				( attribute "SEC" "1"
					( Origin gFrontEnd )
				)
				( attribute "SEC_TYPE" "0402"
					( Origin gFrontEnd )
				)
				( attribute "TOLERANCE" "1%"
					( Origin gFrontEnd )
				)
				( attribute "VALUE" "4.75K"
					( Origin gFrontEnd )
				)
				( attribute "VER" "1"
					( Origin gFrontEnd )
				)
				( attribute "WATTAGE" "1/16W"
					( Origin gFrontEnd )
				)
				( attribute "XY" "(-4700,3700)"
					( Origin gFrontEnd )
				)
				( attribute "CHIPS_PART_NAME" "RES"
					( Origin gPackager )
				)
				( attribute "CDS_PART_NAME" "RES_0402-4.75K,1%,1/16W,CHIP,GA"
					( Origin gPackager )
				)
				( objectStatus "R7D6" )
			)
			( gate "@baseboard_fab2_lib.baseboard_fab2(sch_1):page133_i307"
				( attribute "CDS_LIB" "mstr_discrete"
					( Origin gPackager )
				)
				( attribute "CDS_LOCATION" "R8B31"
					( Origin gPackager )
				)
				( attribute "CDS_SEC" "1"
					( Origin gPackager )
				)
				( attribute "LOCATION" "R8B31"
					( Origin gFrontEnd )
				)
				( attribute "MATERIAL" "CHIP"
					( Origin gFrontEnd )
				)
				( attribute "PACK_TYPE" "0402"
					( Origin gFrontEnd )
				)
				( attribute "PART_NUMBER" "G21796-072"
					( Origin gFrontEnd )
				)
				( attribute "PHYS_PAGE" "133"
					( Origin gFrontEnd )
				)
				( attribute "ROOM" "SB_PU_PD"
					( Origin gFrontEnd )
				)
				( attribute "ROT" "0"
					( Origin gFrontEnd )
				)
				( attribute "SEC" "1"
					( Origin gFrontEnd )
				)
				( attribute "SEC_TYPE" "0402"
					( Origin gFrontEnd )
				)
				( attribute "TOLERANCE" "1%"
					( Origin gFrontEnd )
				)
				( attribute "VALUE" "4.75K"
					( Origin gFrontEnd )
				)
				( attribute "VER" "1"
					( Origin gFrontEnd )
				)
				( attribute "WATTAGE" "1/16W"
					( Origin gFrontEnd )
				)
				( attribute "XY" "(-4800,1650)"
					( Origin gFrontEnd )
				)
				( attribute "CHIPS_PART_NAME" "RES"
					( Origin gPackager )
				)
				( attribute "CDS_PART_NAME" "RES_0402-4.75K,1%,1/16W,CHIP,GA"
					( Origin gPackager )
				)
				( objectStatus "R8B31" )
			)
			( gate "@baseboard_fab2_lib.baseboard_fab2(sch_1):page133_i309"
				( attribute "CDS_LIB" "mstr_discrete"
					( Origin gPackager )
				)
				( attribute "CDS_LOCATION" "R2N7"
					( Origin gPackager )
				)
				( attribute "CDS_SEC" "1"
					( Origin gPackager )
				)
				( attribute "LOCATION" "R2N7"
					( Origin gFrontEnd )
				)
				( attribute "MATERIAL" "CHIP"
					( Origin gFrontEnd )
				)
				( attribute "PACK_TYPE" "0402"
					( Origin gFrontEnd )
				)
				( attribute "PART_NUMBER" "G21796-072"
					( Origin gFrontEnd )
				)
				( attribute "PHYS_PAGE" "133"
					( Origin gFrontEnd )
				)
				( attribute "ROOM" "SB_PU_PD"
					( Origin gFrontEnd )
				)
				( attribute "ROT" "0"
					( Origin gFrontEnd )
				)
				( attribute "SEC" "1"
					( Origin gFrontEnd )
				)
				( attribute "SEC_TYPE" "0402"
					( Origin gFrontEnd )
				)
				( attribute "TOLERANCE" "1%"
					( Origin gFrontEnd )
				)
				( attribute "VALUE" "4.75K"
					( Origin gFrontEnd )
				)
				( attribute "VER" "1"
					( Origin gFrontEnd )
				)
				( attribute "WATTAGE" "1/16W"
					( Origin gFrontEnd )
				)
				( attribute "XY" "(-2475,1025)"
					( Origin gFrontEnd )
				)
				( attribute "CHIPS_PART_NAME" "RES"
					( Origin gPackager )
				)
				( attribute "CDS_PART_NAME" "RES_0402-4.75K,1%,1/16W,CHIP,GA"
					( Origin gPackager )
				)
				( objectStatus "R2N7" )
			)
			( gate "@baseboard_fab2_lib.baseboard_fab2(sch_1):page133_i322"
				( attribute "BOM_COST" "SB"
					( Origin gFrontEnd )
				)
				( attribute "CDS_LIB" "mstr_discrete"
					( Origin gPackager )
				)
				( attribute "CDS_LOCATION" "R3P8"
					( Origin gPackager )
				)
				( attribute "CDS_SEC" "1"
					( Origin gPackager )
				)
				( attribute "LOCATION" "R3P8"
					( Origin gFrontEnd )
				)
				( attribute "MATERIAL" "CHIP"
					( Origin gFrontEnd )
				)
				( attribute "PACK_TYPE" "0402"
					( Origin gFrontEnd )
				)
				( attribute "PART_NUMBER" "G21796-026"
					( Origin gFrontEnd )
				)
				( attribute "PHYS_PAGE" "133"
					( Origin gFrontEnd )
				)
				( attribute "ROOM" "SB"
					( Origin gFrontEnd )
				)
				( attribute "ROT" "0"
					( Origin gFrontEnd )
				)
				( attribute "SEC" "1"
					( Origin gFrontEnd )
				)
				( attribute "SEC_TYPE" "0402"
					( Origin gFrontEnd )
				)
				( attribute "TOLERANCE" "1%"
					( Origin gFrontEnd )
				)
				( attribute "VALUE" "1.00K"
					( Origin gFrontEnd )
				)
				( attribute "VER" "1"
					( Origin gFrontEnd )
				)
				( attribute "WATTAGE" "1/16W"
					( Origin gFrontEnd )
				)
				( attribute "XY" "(-375,3925)"
					( Origin gFrontEnd )
				)
				( attribute "CHIPS_PART_NAME" "RES"
					( Origin gPackager )
				)
				( attribute "CDS_PART_NAME" "RES_0402-1.00K,1%,1/16W,CHIP,GA"
					( Origin gPackager )
				)
				( objectStatus "R3P8" )
			)
			( gate "@baseboard_fab2_lib.baseboard_fab2(sch_1):page133_i326"
				( attribute "CDS_LIB" "mstr_discrete"
					( Origin gPackager )
				)
				( attribute "CDS_LOCATION" "R8C1"
					( Origin gPackager )
				)
				( attribute "CDS_SEC" "1"
					( Origin gPackager )
				)
				( attribute "LOCATION" "R8C1"
					( Origin gFrontEnd )
				)
				( attribute "MATERIAL" "CHIP"
					( Origin gFrontEnd )
				)
				( attribute "PACK_TYPE" "0402"
					( Origin gFrontEnd )
				)
				( attribute "PART_NUMBER" "G21796-072"
					( Origin gFrontEnd )
				)
				( attribute "PHYS_PAGE" "133"
					( Origin gFrontEnd )
				)
				( attribute "ROOM" "SB_PU_PD"
					( Origin gFrontEnd )
				)
				( attribute "ROT" "0"
					( Origin gFrontEnd )
				)
				( attribute "SEC" "1"
					( Origin gFrontEnd )
				)
				( attribute "SEC_TYPE" "0402"
					( Origin gFrontEnd )
				)
				( attribute "TOLERANCE" "1%"
					( Origin gFrontEnd )
				)
				( attribute "VALUE" "4.75K"
					( Origin gFrontEnd )
				)
				( attribute "VER" "1"
					( Origin gFrontEnd )
				)
				( attribute "WATTAGE" "1/16W"
					( Origin gFrontEnd )
				)
				( attribute "XY" "(-4800,1300)"
					( Origin gFrontEnd )
				)
				( attribute "CHIPS_PART_NAME" "RES"
					( Origin gPackager )
				)
				( attribute "CDS_PART_NAME" "RES_0402-4.75K,1%,1/16W,CHIP,GA"
					( Origin gPackager )
				)
				( objectStatus "R8C1" )
			)
			( gate "@baseboard_fab2_lib.baseboard_fab2(sch_1):page133_i327"
				( attribute "BOM_COST" "SB"
					( Origin gFrontEnd )
				)
				( attribute "CDS_LIB" "mstr_discrete"
					( Origin gPackager )
				)
				( attribute "CDS_LOCATION" "R8C7"
					( Origin gPackager )
				)
				( attribute "CDS_SEC" "1"
					( Origin gPackager )
				)
				( attribute "LOCATION" "R8C7"
					( Origin gFrontEnd )
				)
				( attribute "MATERIAL" "CHIP"
					( Origin gFrontEnd )
				)
				( attribute "PACK_TYPE" "0402"
					( Origin gFrontEnd )
				)
				( attribute "PART_NUMBER" "G21796-072"
					( Origin gFrontEnd )
				)
				( attribute "PHYS_PAGE" "133"
					( Origin gFrontEnd )
				)
				( attribute "ROOM" "SB_PU_PD"
					( Origin gFrontEnd )
				)
				( attribute "ROT" "0"
					( Origin gFrontEnd )
				)
				( attribute "SEC" "1"
					( Origin gFrontEnd )
				)
				( attribute "SEC_TYPE" "0402"
					( Origin gFrontEnd )
				)
				( attribute "TOLERANCE" "1%"
					( Origin gFrontEnd )
				)
				( attribute "VALUE" "4.75K"
					( Origin gFrontEnd )
				)
				( attribute "VER" "1"
					( Origin gFrontEnd )
				)
				( attribute "WATTAGE" "1/16W"
					( Origin gFrontEnd )
				)
				( attribute "XY" "(-4800,1125)"
					( Origin gFrontEnd )
				)
				( attribute "CHIPS_PART_NAME" "RES"
					( Origin gPackager )
				)
				( attribute "CDS_PART_NAME" "RES_0402-4.75K,1%,1/16W,CHIP,GA"
					( Origin gPackager )
				)
				( objectStatus "R8C7" )
			)
			( gate "@baseboard_fab2_lib.baseboard_fab2(sch_1):page133_i331"
				( attribute "BOM_COST" "SB_PU_PD"
					( Origin gFrontEnd )
				)
				( attribute "CDS_LIB" "mstr_discrete"
					( Origin gPackager )
				)
				( attribute "CDS_LOCATION" "R7D7"
					( Origin gPackager )
				)
				( attribute "CDS_SEC" "1"
					( Origin gPackager )
				)
				( attribute "LOCATION" "R7D7"
					( Origin gFrontEnd )
				)
				( attribute "MATERIAL" "CHIP"
					( Origin gFrontEnd )
				)
				( attribute "PACK_TYPE" "0402"
					( Origin gFrontEnd )
				)
				( attribute "PART_NUMBER" "G21796-026"
					( Origin gFrontEnd )
				)
				( attribute "PHYS_PAGE" "133"
					( Origin gFrontEnd )
				)
				( attribute "ROOM" "SB"
					( Origin gFrontEnd )
				)
				( attribute "ROT" "0"
					( Origin gFrontEnd )
				)
				( attribute "SEC" "1"
					( Origin gFrontEnd )
				)
				( attribute "SEC_TYPE" "0402"
					( Origin gFrontEnd )
				)
				( attribute "TOLERANCE" "1%"
					( Origin gFrontEnd )
				)
				( attribute "VALUE" "1.00K"
					( Origin gFrontEnd )
				)
				( attribute "VER" "1"
					( Origin gFrontEnd )
				)
				( attribute "WATTAGE" "1/16W"
					( Origin gFrontEnd )
				)
				( attribute "XY" "(-4700,4700)"
					( Origin gFrontEnd )
				)
				( attribute "CHIPS_PART_NAME" "RES"
					( Origin gPackager )
				)
				( attribute "CDS_PART_NAME" "RES_0402-1.00K,1%,1/16W,CHIP,GA"
					( Origin gPackager )
				)
				( objectStatus "R7D7" )
			)
			( gate "@baseboard_fab2_lib.baseboard_fab2(sch_1):page133_i332"
				( attribute "BOM_COST" "SB_PU_PD"
					( Origin gFrontEnd )
				)
				( attribute "CDS_LIB" "mstr_discrete"
					( Origin gPackager )
				)
				( attribute "CDS_LOCATION" "R7D2"
					( Origin gPackager )
				)
				( attribute "CDS_SEC" "1"
					( Origin gPackager )
				)
				( attribute "LOCATION" "R7D2"
					( Origin gFrontEnd )
				)
				( attribute "MATERIAL" "CHIP"
					( Origin gFrontEnd )
				)
				( attribute "PACK_TYPE" "0402"
					( Origin gFrontEnd )
				)
				( attribute "PART_NUMBER" "G21796-026"
					( Origin gFrontEnd )
				)
				( attribute "PHYS_PAGE" "133"
					( Origin gFrontEnd )
				)
				( attribute "ROOM" "SB"
					( Origin gFrontEnd )
				)
				( attribute "ROT" "0"
					( Origin gFrontEnd )
				)
				( attribute "SEC" "1"
					( Origin gFrontEnd )
				)
				( attribute "SEC_TYPE" "0402"
					( Origin gFrontEnd )
				)
				( attribute "TOLERANCE" "1%"
					( Origin gFrontEnd )
				)
				( attribute "VALUE" "1.00K"
					( Origin gFrontEnd )
				)
				( attribute "VER" "1"
					( Origin gFrontEnd )
				)
				( attribute "WATTAGE" "1/16W"
					( Origin gFrontEnd )
				)
				( attribute "XY" "(-4700,5100)"
					( Origin gFrontEnd )
				)
				( attribute "CHIPS_PART_NAME" "RES"
					( Origin gPackager )
				)
				( attribute "CDS_PART_NAME" "RES_0402-1.00K,1%,1/16W,CHIP,GA"
					( Origin gPackager )
				)
				( objectStatus "R7D2" )
			)
			( gate "@baseboard_fab2_lib.baseboard_fab2(sch_1):page133_i333"
				( attribute "CDS_LIB" "mstr_discrete"
					( Origin gPackager )
				)
				( attribute "CDS_LOCATION" "R8C25"
					( Origin gPackager )
				)
				( attribute "CDS_SEC" "1"
					( Origin gPackager )
				)
				( attribute "LOCATION" "R8C25"
					( Origin gFrontEnd )
				)
				( attribute "MATERIAL" "CHIP"
					( Origin gFrontEnd )
				)
				( attribute "PACK_TYPE" "0402"
					( Origin gFrontEnd )
				)
				( attribute "PART_NUMBER" "G21796-072"
					( Origin gFrontEnd )
				)
				( attribute "PHYS_PAGE" "133"
					( Origin gFrontEnd )
				)
				( attribute "ROOM" "SB_PU_PD"
					( Origin gFrontEnd )
				)
				( attribute "ROT" "0"
					( Origin gFrontEnd )
				)
				( attribute "SEC" "1"
					( Origin gFrontEnd )
				)
				( attribute "SEC_TYPE" "0402"
					( Origin gFrontEnd )
				)
				( attribute "TOLERANCE" "1%"
					( Origin gFrontEnd )
				)
				( attribute "VALUE" "4.75K"
					( Origin gFrontEnd )
				)
				( attribute "VER" "1"
					( Origin gFrontEnd )
				)
				( attribute "WATTAGE" "1/16W"
					( Origin gFrontEnd )
				)
				( attribute "XY" "(-2500,3150)"
					( Origin gFrontEnd )
				)
				( attribute "CHIPS_PART_NAME" "RES"
					( Origin gPackager )
				)
				( attribute "CDS_PART_NAME" "RES_0402-4.75K,1%,1/16W,CHIP,GA"
					( Origin gPackager )
				)
				( objectStatus "R8C25" )
			)
			( gate "@baseboard_fab2_lib.baseboard_fab2(sch_1):page133_i341"
				( attribute "BOM_COST" "SB"
					( Origin gFrontEnd )
				)
				( attribute "CDS_LIB" "mstr_discrete"
					( Origin gPackager )
				)
				( attribute "CDS_LOCATION" "R2N32"
					( Origin gPackager )
				)
				( attribute "CDS_SEC" "1"
					( Origin gPackager )
				)
				( attribute "LOCATION" "R2N32"
					( Origin gFrontEnd )
				)
				( attribute "MATERIAL" "CHIP"
					( Origin gFrontEnd )
				)
				( attribute "PACK_TYPE" "0402"
					( Origin gFrontEnd )
				)
				( attribute "PART_NUMBER" "G21796-072"
					( Origin gFrontEnd )
				)
				( attribute "PHYS_PAGE" "133"
					( Origin gFrontEnd )
				)
				( attribute "ROOM" "SB"
					( Origin gFrontEnd )
				)
				( attribute "ROT" "0"
					( Origin gFrontEnd )
				)
				( attribute "SEC" "1"
					( Origin gFrontEnd )
				)
				( attribute "SEC_TYPE" "0402"
					( Origin gFrontEnd )
				)
				( attribute "TOLERANCE" "1%"
					( Origin gFrontEnd )
				)
				( attribute "VALUE" "4.75K"
					( Origin gFrontEnd )
				)
				( attribute "VER" "1"
					( Origin gFrontEnd )
				)
				( attribute "WATTAGE" "1/16W"
					( Origin gFrontEnd )
				)
				( attribute "XY" "(-2475,2700)"
					( Origin gFrontEnd )
				)
				( attribute "CHIPS_PART_NAME" "RES"
					( Origin gPackager )
				)
				( attribute "CDS_PART_NAME" "RES_0402-4.75K,1%,1/16W,CHIP,GA"
					( Origin gPackager )
				)
				( objectStatus "R2N32" )
			)
			( gate "@baseboard_fab2_lib.baseboard_fab2(sch_1):page133_i349"
				( attribute "BOM_COST" "SB"
					( Origin gFrontEnd )
				)
				( attribute "CDS_LIB" "mstr_discrete"
					( Origin gPackager )
				)
				( attribute "CDS_LOCATION" "R2M8"
					( Origin gPackager )
				)
				( attribute "CDS_SEC" "1"
					( Origin gPackager )
				)
				( attribute "LOCATION" "R2M8"
					( Origin gFrontEnd )
				)
				( attribute "MATERIAL" "CHIP"
					( Origin gFrontEnd )
				)
				( attribute "PACK_TYPE" "0402"
					( Origin gFrontEnd )
				)
				( attribute "PART_NUMBER" "G21796-003"
					( Origin gFrontEnd )
				)
				( attribute "PHYS_PAGE" "133"
					( Origin gFrontEnd )
				)
				( attribute "ROOM" "SB"
					( Origin gFrontEnd )
				)
				( attribute "ROT" "0"
					( Origin gFrontEnd )
				)
				( attribute "SEC" "1"
					( Origin gFrontEnd )
				)
				( attribute "SEC_TYPE" "0402"
					( Origin gFrontEnd )
				)
				( attribute "TOLERANCE" "1%"
					( Origin gFrontEnd )
				)
				( attribute "VALUE" "1.5K"
					( Origin gFrontEnd )
				)
				( attribute "VER" "1"
					( Origin gFrontEnd )
				)
				( attribute "WATTAGE" "1/16W"
					( Origin gFrontEnd )
				)
				( attribute "XY" "(-375,2725)"
					( Origin gFrontEnd )
				)
				( attribute "CHIPS_PART_NAME" "RES"
					( Origin gPackager )
				)
				( attribute "CDS_PART_NAME" "RES_0402-1.5K,1%,1/16W,CHIP,G2A"
					( Origin gPackager )
				)
				( objectStatus "R2M8" )
			)
			( gate "@baseboard_fab2_lib.baseboard_fab2(sch_1):page133_i352"
				( attribute "BOM_COST" "SB"
					( Origin gFrontEnd )
				)
				( attribute "CDS_LIB" "mstr_discrete"
					( Origin gPackager )
				)
				( attribute "CDS_LOCATION" "R2N29"
					( Origin gPackager )
				)
				( attribute "CDS_SEC" "1"
					( Origin gPackager )
				)
				( attribute "LOCATION" "R2N29"
					( Origin gFrontEnd )
				)
				( attribute "MATERIAL" "CHIP"
					( Origin gFrontEnd )
				)
				( attribute "PACK_TYPE" "0402"
					( Origin gFrontEnd )
				)
				( attribute "PART_NUMBER" "G21796-003"
					( Origin gFrontEnd )
				)
				( attribute "PHYS_PAGE" "133"
					( Origin gFrontEnd )
				)
				( attribute "ROOM" "SB"
					( Origin gFrontEnd )
				)
				( attribute "ROT" "0"
					( Origin gFrontEnd )
				)
				( attribute "SEC" "1"
					( Origin gFrontEnd )
				)
				( attribute "SEC_TYPE" "0402"
					( Origin gFrontEnd )
				)
				( attribute "TOLERANCE" "1%"
					( Origin gFrontEnd )
				)
				( attribute "VALUE" "1.5K"
					( Origin gFrontEnd )
				)
				( attribute "VER" "1"
					( Origin gFrontEnd )
				)
				( attribute "WATTAGE" "1/16W"
					( Origin gFrontEnd )
				)
				( attribute "XY" "(-375,2475)"
					( Origin gFrontEnd )
				)
				( attribute "CHIPS_PART_NAME" "RES"
					( Origin gPackager )
				)
				( attribute "CDS_PART_NAME" "RES_0402-1.5K,1%,1/16W,CHIP,G2A"
					( Origin gPackager )
				)
				( objectStatus "R2N29" )
			)
			( gate "@baseboard_fab2_lib.baseboard_fab2(sch_1):page42_i220"
				( attribute "BOM_COST" "MEM_VRD_PVDDQ_CD"
					( Origin gFrontEnd )
				)
				( attribute "CDS_LIB" "mstr_discrete"
					( Origin gPackager )
				)
				( attribute "CDS_LOCATION" "C5P29"
					( Origin gPackager )
				)
				( attribute "CDS_SEC" "1"
					( Origin gPackager )
				)
				( attribute "LOCATION" "C5P29"
					( Origin gFrontEnd )
				)
				( attribute "MATERIAL" "X5R"
					( Origin gFrontEnd )
				)
				( attribute "NEW_MATERIAL" "X6S"
					( Origin gFrontEnd )
				)
				( attribute "PACK_TYPE" "0805"
					( Origin gFrontEnd )
				)
				( attribute "PART_NUMBER" "602433-112"
					( Origin gFrontEnd )
				)
				( attribute "PHYS_PAGE" "42"
					( Origin gFrontEnd )
				)
				( attribute "ROOM" "VDDQ_ABC_PWR_VR"
					( Origin gFrontEnd )
				)
				( attribute "ROT" "0"
					( Origin gFrontEnd )
				)
				( attribute "SEC" "1"
					( Origin gFrontEnd )
				)
				( attribute "SEC_TYPE" "0805"
					( Origin gFrontEnd )
				)
				( attribute "TOLERANCE" "20%"
					( Origin gFrontEnd )
				)
				( attribute "VALUE" "100UF"
					( Origin gFrontEnd )
				)
				( attribute "VER" "1"
					( Origin gFrontEnd )
				)
				( attribute "VOLTAGE" "4V"
					( Units "uVoltage" "V" 1.000000)
					( Origin gFrontEnd )
				)
				( attribute "XY" "(-4750,2225)"
					( Origin gFrontEnd )
				)
				( attribute "CHIPS_PART_NAME" "CAP"
					( Origin gPackager )
				)
				( attribute "CDS_PART_NAME" "CAP_0805-100UF,4V,20%,X5R,6024A"
					( Origin gPackager )
				)
				( attribute "NEW_PN" "078.1071T.M002"
					( Origin gFrontEnd )
				)
				( attribute "GROUP" "PWR_MCP_CAP"
					( Origin gFrontEnd )
				)
				( objectStatus "C5P29" )
			)
			( gate "@baseboard_fab2_lib.baseboard_fab2(sch_1):page133_i356"
				( attribute "CDS_LIB" "mstr_discrete"
					( Origin gPackager )
				)
				( attribute "CDS_LOCATION" "R7D44"
					( Origin gPackager )
				)
				( attribute "CDS_SEC" "1"
					( Origin gPackager )
				)
				( attribute "LOCATION" "R7D44"
					( Origin gFrontEnd )
				)
				( attribute "MATERIAL" "CHIP"
					( Origin gFrontEnd )
				)
				( attribute "PACK_TYPE" "0402"
					( Origin gFrontEnd )
				)
				( attribute "PART_NUMBER" "G21796-072"
					( Origin gFrontEnd )
				)
				( attribute "PHYS_PAGE" "133"
					( Origin gFrontEnd )
				)
				( attribute "ROOM" "SB_PU_PD"
					( Origin gFrontEnd )
				)
				( attribute "ROT" "0"
					( Origin gFrontEnd )
				)
				( attribute "SEC" "1"
					( Origin gFrontEnd )
				)
				( attribute "SEC_TYPE" "0402"
					( Origin gFrontEnd )
				)
				( attribute "TOLERANCE" "1%"
					( Origin gFrontEnd )
				)
				( attribute "VALUE" "4.75K"
					( Origin gFrontEnd )
				)
				( attribute "VER" "1"
					( Origin gFrontEnd )
				)
				( attribute "WATTAGE" "1/16W"
					( Origin gFrontEnd )
				)
				( attribute "XY" "(-375,3725)"
					( Origin gFrontEnd )
				)
				( attribute "CHIPS_PART_NAME" "RES"
					( Origin gPackager )
				)
				( attribute "CDS_PART_NAME" "RES_0402-4.75K,1%,1/16W,CHIP,GA"
					( Origin gPackager )
				)
				( objectStatus "R7D44" )
			)
			( gate "@baseboard_fab2_lib.baseboard_fab2(sch_1):page133_i360"
				( attribute "BOM_COST" "SB"
					( Origin gFrontEnd )
				)
				( attribute "CDS_LIB" "mstr_discrete"
					( Origin gPackager )
				)
				( attribute "CDS_LOCATION" "R2P22"
					( Origin gPackager )
				)
				( attribute "CDS_SEC" "1"
					( Origin gPackager )
				)
				( attribute "LOCATION" "R2P22"
					( Origin gFrontEnd )
				)
				( attribute "MATERIAL" "CHIP"
					( Origin gFrontEnd )
				)
				( attribute "PACK_TYPE" "0402"
					( Origin gFrontEnd )
				)
				( attribute "PART_NUMBER" "G21796-016"
					( Origin gFrontEnd )
				)
				( attribute "PHYS_PAGE" "133"
					( Origin gFrontEnd )
				)
				( attribute "ROOM" "SB"
					( Origin gFrontEnd )
				)
				( attribute "ROT" "0"
					( Origin gFrontEnd )
				)
				( attribute "SEC" "1"
					( Origin gFrontEnd )
				)
				( attribute "SEC_TYPE" "0402"
					( Origin gFrontEnd )
				)
				( attribute "TOLERANCE" "1%"
					( Origin gFrontEnd )
				)
				( attribute "VALUE" "10.0K"
					( Origin gFrontEnd )
				)
				( attribute "VER" "1"
					( Origin gFrontEnd )
				)
				( attribute "WATTAGE" "1/16W"
					( Origin gFrontEnd )
				)
				( attribute "XY" "(-4800,1500)"
					( Origin gFrontEnd )
				)
				( attribute "CHIPS_PART_NAME" "RES"
					( Origin gPackager )
				)
				( attribute "CDS_PART_NAME" "RES_0402-10.0K,1%,1/16W,CHIP,GA"
					( Origin gPackager )
				)
				( objectStatus "R2P22" )
			)
			( gate "@baseboard_fab2_lib.baseboard_fab2(sch_1):page133_i362"
				( attribute "BOM_COST" "SB"
					( Origin gFrontEnd )
				)
				( attribute "CDS_LIB" "mstr_discrete"
					( Origin gPackager )
				)
				( attribute "CDS_LOCATION" "R8D44"
					( Origin gPackager )
				)
				( attribute "CDS_SEC" "1"
					( Origin gPackager )
				)
				( attribute "LOCATION" "R8D44"
					( Origin gFrontEnd )
				)
				( attribute "MATERIAL" "CHIP"
					( Origin gFrontEnd )
				)
				( attribute "PACK_TYPE" "0402"
					( Origin gFrontEnd )
				)
				( attribute "PART_NUMBER" "G21796-016"
					( Origin gFrontEnd )
				)
				( attribute "PHYS_PAGE" "133"
					( Origin gFrontEnd )
				)
				( attribute "ROOM" "SB"
					( Origin gFrontEnd )
				)
				( attribute "ROT" "0"
					( Origin gFrontEnd )
				)
				( attribute "SEC" "1"
					( Origin gFrontEnd )
				)
				( attribute "SEC_TYPE" "0402"
					( Origin gFrontEnd )
				)
				( attribute "TOLERANCE" "1%"
					( Origin gFrontEnd )
				)
				( attribute "VALUE" "10.0K"
					( Origin gFrontEnd )
				)
				( attribute "VER" "1"
					( Origin gFrontEnd )
				)
				( attribute "WATTAGE" "1/16W"
					( Origin gFrontEnd )
				)
				( attribute "XY" "(-2475,2450)"
					( Origin gFrontEnd )
				)
				( attribute "CHIPS_PART_NAME" "RES"
					( Origin gPackager )
				)
				( attribute "CDS_PART_NAME" "RES_0402-10.0K,1%,1/16W,CHIP,GA"
					( Origin gPackager )
				)
				( objectStatus "R8D44" )
			)
			( gate "@baseboard_fab2_lib.baseboard_fab2(sch_1):page134_i3"
				( attribute "BOM_COST" "SB"
					( Origin gFrontEnd )
				)
				( attribute "CDS_LIB" "mstr_discrete"
					( Origin gPackager )
				)
				( attribute "CDS_LOCATION" "R2P17"
					( Origin gPackager )
				)
				( attribute "CDS_SEC" "1"
					( Origin gPackager )
				)
				( attribute "LOCATION" "R2P17"
					( Origin gFrontEnd )
				)
				( attribute "MATERIAL" "CHIP"
					( Origin gFrontEnd )
				)
				( attribute "PACK_TYPE" "0402"
					( Origin gFrontEnd )
				)
				( attribute "PART_NUMBER" "G21796-072"
					( Origin gFrontEnd )
				)
				( attribute "PHYS_PAGE" "134"
					( Origin gFrontEnd )
				)
				( attribute "ROOM" "THERMTRIP_PCH"
					( Origin gFrontEnd )
				)
				( attribute "ROT" "0"
					( Origin gFrontEnd )
				)
				( attribute "SEC" "1"
					( Origin gFrontEnd )
				)
				( attribute "SEC_TYPE" "0402"
					( Origin gFrontEnd )
				)
				( attribute "TOLERANCE" "1%"
					( Origin gFrontEnd )
				)
				( attribute "VALUE" "4.75K"
					( Origin gFrontEnd )
				)
				( attribute "VER" "2"
					( Origin gFrontEnd )
				)
				( attribute "WATTAGE" "1/16W"
					( Origin gFrontEnd )
				)
				( attribute "XY" "(700,4925)"
					( Origin gFrontEnd )
				)
				( attribute "CHIPS_PART_NAME" "RES"
					( Origin gPackager )
				)
				( attribute "CDS_PART_NAME" "RES_0402-4.75K,1%,1/16W,CHIP,GA"
					( Origin gPackager )
				)
				( objectStatus "R2P17" )
			)
			( gate "@baseboard_fab2_lib.baseboard_fab2(sch_1):page95_i123"
				( attribute "CDS_LIB" "mstr_discrete"
					( Origin gPackager )
				)
				( attribute "LOCATION" "Q7E8"
					( Origin gFrontEnd )
				)
				( attribute "MATERIAL" "FET"
					( Origin gFrontEnd )
				)
				( attribute "PACK_TYPE" "SOT23LF"
					( Origin gFrontEnd )
				)
				( attribute "PART_NUMBER" "C79254-001"
					( Origin gFrontEnd )
				)
				( attribute "PHYS_PAGE" "95"
					( Origin gFrontEnd )
				)
				( attribute "ROOM" "HOT_SWAP"
					( Origin gFrontEnd )
				)
				( attribute "ROT" "0"
					( Origin gFrontEnd )
				)
				( attribute "VALUE" "2N7002"
					( Origin gFrontEnd )
				)
				( attribute "VER" "8"
					( Origin gFrontEnd )
				)
				( attribute "XY" "(-3100,4550)"
					( Origin gFrontEnd )
				)
				( attribute "CHIPS_PART_NAME" "FET_N"
					( Origin gPackager )
				)
				( attribute "CDS_PART_NAME" "FET_N_SOT23LF-2N7002,FET,C7925A"
					( Origin gPackager )
				)
				( attribute "CDS_LOCATION" "Q7E8"
					( Origin gPackager )
				)
				( attribute "CDS_SEC" "1"
					( Origin gPackager )
				)
				( attribute "SEC" "1"
					( Origin gPackager )
				)
				( objectStatus "Q7E8" )
			)
			( gate "@baseboard_fab2_lib.baseboard_fab2(sch_1):page134_i9"
				( attribute "BOM_COST" "SB"
					( Origin gFrontEnd )
				)
				( attribute "CDS_LIB" "mstr_discrete"
					( Origin gPackager )
				)
				( attribute "CDS_LOCATION" "R7C21"
					( Origin gPackager )
				)
				( attribute "CDS_SEC" "1"
					( Origin gPackager )
				)
				( attribute "LOCATION" "R7C21"
					( Origin gFrontEnd )
				)
				( attribute "MATERIAL" "CHIP"
					( Origin gFrontEnd )
				)
				( attribute "PACK_TYPE" "0402"
					( Origin gFrontEnd )
				)
				( attribute "PART_NUMBER" "G21796-016"
					( Origin gFrontEnd )
				)
				( attribute "PHYS_PAGE" "134"
					( Origin gFrontEnd )
				)
				( attribute "ROOM" "THERMTRIP_PCH"
					( Origin gFrontEnd )
				)
				( attribute "ROT" "0"
					( Origin gFrontEnd )
				)
				( attribute "SEC" "1"
					( Origin gFrontEnd )
				)
				( attribute "SEC_TYPE" "0402"
					( Origin gFrontEnd )
				)
				( attribute "TOLERANCE" "1%"
					( Origin gFrontEnd )
				)
				( attribute "VALUE" "10.0K"
					( Origin gFrontEnd )
				)
				( attribute "VER" "2"
					( Origin gFrontEnd )
				)
				( attribute "WATTAGE" "1/16W"
					( Origin gFrontEnd )
				)
				( attribute "XY" "(-2875,4875)"
					( Origin gFrontEnd )
				)
				( attribute "CHIPS_PART_NAME" "RES"
					( Origin gPackager )
				)
				( attribute "CDS_PART_NAME" "RES_0402-10.0K,1%,1/16W,CHIP,GA"
					( Origin gPackager )
				)
				( objectStatus "R7C21" )
			)
			( gate "@baseboard_fab2_lib.baseboard_fab2(sch_1):page95_i122"
				( attribute "CDS_LIB" "mstr_discrete"
					( Origin gPackager )
				)
				( attribute "LOCATION" "Q7E4"
					( Origin gFrontEnd )
				)
				( attribute "MATERIAL" "FET"
					( Origin gFrontEnd )
				)
				( attribute "PACK_TYPE" "SOT23LF"
					( Origin gFrontEnd )
				)
				( attribute "PART_NUMBER" "C79254-001"
					( Origin gFrontEnd )
				)
				( attribute "PHYS_PAGE" "95"
					( Origin gFrontEnd )
				)
				( attribute "ROOM" "HOT_SWAP"
					( Origin gFrontEnd )
				)
				( attribute "ROT" "0"
					( Origin gFrontEnd )
				)
				( attribute "VALUE" "2N7002"
					( Origin gFrontEnd )
				)
				( attribute "VER" "8"
					( Origin gFrontEnd )
				)
				( attribute "XY" "(2150,1350)"
					( Origin gFrontEnd )
				)
				( attribute "CHIPS_PART_NAME" "FET_N"
					( Origin gPackager )
				)
				( attribute "CDS_PART_NAME" "FET_N_SOT23LF-2N7002,FET,C7925A"
					( Origin gPackager )
				)
				( attribute "CDS_LOCATION" "Q7E4"
					( Origin gPackager )
				)
				( attribute "CDS_SEC" "1"
					( Origin gPackager )
				)
				( attribute "SEC" "1"
					( Origin gPackager )
				)
				( objectStatus "Q7E4" )
			)
			( gate "@baseboard_fab2_lib.baseboard_fab2(sch_1):page134_i11"
				( attribute "CDS_LIB" "mstr_discrete"
					( Origin gPackager )
				)
				( attribute "CDS_LOCATION" "R7D18"
					( Origin gPackager )
				)
				( attribute "CDS_SEC" "1"
					( Origin gPackager )
				)
				( attribute "LOCATION" "R7D18"
					( Origin gFrontEnd )
				)
				( attribute "MATERIAL" "CHIP"
					( Origin gFrontEnd )
				)
				( attribute "PACK_TYPE" "0402"
					( Origin gFrontEnd )
				)
				( attribute "PART_NUMBER" "G21796-026"
					( Origin gFrontEnd )
				)
				( attribute "PHYS_PAGE" "134"
					( Origin gFrontEnd )
				)
				( attribute "ROOM" "PROC_SIDEBAND"
					( Origin gFrontEnd )
				)
				( attribute "ROT" "0"
					( Origin gFrontEnd )
				)
				( attribute "SEC" "1"
					( Origin gFrontEnd )
				)
				( attribute "SEC_TYPE" "0402"
					( Origin gFrontEnd )
				)
				( attribute "TOLERANCE" "1%"
					( Origin gFrontEnd )
				)
				( attribute "VALUE" "1.00K"
					( Origin gFrontEnd )
				)
				( attribute "VER" "1"
					( Origin gFrontEnd )
				)
				( attribute "WATTAGE" "1/16W"
					( Origin gFrontEnd )
				)
				( attribute "XY" "(-3950,4300)"
					( Origin gFrontEnd )
				)
				( attribute "CHIPS_PART_NAME" "RES"
					( Origin gPackager )
				)
				( attribute "CDS_PART_NAME" "RES_0402-1.00K,1%,1/16W,CHIP,GA"
					( Origin gPackager )
				)
				( objectStatus "R7D18" )
			)
			( gate "@baseboard_fab2_lib.baseboard_fab2(sch_1):page135_i107"
				( attribute "BOM_COST" "CPLD"
					( Origin gFrontEnd )
				)
				( attribute "CDS_LIB" "mstr_discrete"
					( Origin gPackager )
				)
				( attribute "CDS_LOCATION" "R2P19"
					( Origin gPackager )
				)
				( attribute "CDS_SEC" "1"
					( Origin gPackager )
				)
				( attribute "LOCATION" "R2P19"
					( Origin gFrontEnd )
				)
				( attribute "MATERIAL" "CHIP"
					( Origin gFrontEnd )
				)
				( attribute "PACK_TYPE" "0402"
					( Origin gFrontEnd )
				)
				( attribute "PART_NUMBER" "G21796-016"
					( Origin gFrontEnd )
				)
				( attribute "PHYS_PAGE" "135"
					( Origin gFrontEnd )
				)
				( attribute "ROOM" "CPLD"
					( Origin gFrontEnd )
				)
				( attribute "ROT" "0"
					( Origin gFrontEnd )
				)
				( attribute "SEC" "1"
					( Origin gFrontEnd )
				)
				( attribute "SEC_TYPE" "0402"
					( Origin gFrontEnd )
				)
				( attribute "TOLERANCE" "1%"
					( Origin gFrontEnd )
				)
				( attribute "VALUE" "10.0K"
					( Origin gFrontEnd )
				)
				( attribute "VER" "2"
					( Origin gFrontEnd )
				)
				( attribute "WATTAGE" "1/16W"
					( Origin gFrontEnd )
				)
				( attribute "XY" "(200,2225)"
					( Origin gFrontEnd )
				)
				( attribute "CHIPS_PART_NAME" "RES"
					( Origin gPackager )
				)
				( attribute "CDS_PART_NAME" "RES_0402-10.0K,1%,1/16W,CHIP,GA"
					( Origin gPackager )
				)
				( objectStatus "R2P19" )
			)
			( gate "@baseboard_fab2_lib.baseboard_fab2(sch_1):page135_i112"
				( attribute "CDS_LIB" "mstr_discrete"
					( Origin gPackager )
				)
				( attribute "CDS_LOCATION" "R2N23"
					( Origin gPackager )
				)
				( attribute "CDS_SEC" "1"
					( Origin gPackager )
				)
				( attribute "LOCATION" "R2N23"
					( Origin gFrontEnd )
				)
				( attribute "MATERIAL" "CHIP"
					( Origin gFrontEnd )
				)
				( attribute "PACK_TYPE" "0402"
					( Origin gFrontEnd )
				)
				( attribute "PART_NUMBER" "G21796-016"
					( Origin gFrontEnd )
				)
				( attribute "PHYS_PAGE" "135"
					( Origin gFrontEnd )
				)
				( attribute "ROOM" "SB"
					( Origin gFrontEnd )
				)
				( attribute "ROT" "0"
					( Origin gFrontEnd )
				)
				( attribute "SEC" "1"
					( Origin gPackager )
				)
				( attribute "TOLERANCE" "1%"
					( Origin gFrontEnd )
				)
				( attribute "VALUE" "10.0K"
					( Origin gFrontEnd )
				)
				( attribute "VER" "2"
					( Origin gFrontEnd )
				)
				( attribute "WATTAGE" "1/16W"
					( Origin gFrontEnd )
				)
				( attribute "XY" "(-2150,4775)"
					( Origin gFrontEnd )
				)
				( attribute "CHIPS_PART_NAME" "RES"
					( Origin gPackager )
				)
				( attribute "CDS_PART_NAME" "RES_0402-10.0K,1%,1/16W,CHIP,GA"
					( Origin gPackager )
				)
				( objectStatus "R2N23" )
			)
			( gate "@baseboard_fab2_lib.baseboard_fab2(sch_1):page135_i113"
				( attribute "CDS_LIB" "mstr_discrete"
					( Origin gPackager )
				)
				( attribute "CDS_LOCATION" "R2N24"
					( Origin gPackager )
				)
				( attribute "CDS_SEC" "1"
					( Origin gPackager )
				)
				( attribute "LOCATION" "R2N24"
					( Origin gFrontEnd )
				)
				( attribute "MATERIAL" "EMPTY"
					( Origin gFrontEnd )
				)
				( attribute "PACK_TYPE" "0402"
					( Origin gFrontEnd )
				)
				( attribute "PART_NUMBER" "G21796-026"
					( Origin gFrontEnd )
				)
				( attribute "PHYS_PAGE" "135"
					( Origin gFrontEnd )
				)
				( attribute "ROOM" "SB"
					( Origin gFrontEnd )
				)
				( attribute "ROT" "0"
					( Origin gFrontEnd )
				)
				( attribute "SEC" "1"
					( Origin gFrontEnd )
				)
				( attribute "SEC_TYPE" "0402"
					( Origin gFrontEnd )
				)
				( attribute "TOLERANCE" "1%"
					( Origin gFrontEnd )
				)
				( attribute "VALUE" "1.00K"
					( Origin gFrontEnd )
				)
				( attribute "VER" "2"
					( Origin gFrontEnd )
				)
				( attribute "WATTAGE" "1/16W"
					( Origin gFrontEnd )
				)
				( attribute "XY" "(-2150,4325)"
					( Origin gFrontEnd )
				)
				( attribute "CHIPS_PART_NAME" "RES"
					( Origin gPackager )
				)
				( attribute "CDS_PART_NAME" "RES_0402-1.00K,1%,1/16W,EMPTY,A"
					( Origin gPackager )
				)
				( objectStatus "R2N24" )
			)
			( gate "@baseboard_fab2_lib.baseboard_fab2(sch_1):page135_i117"
				( attribute "BOM_COST" "SB"
					( Origin gFrontEnd )
				)
				( attribute "CDS_LIB" "mstr_discrete"
					( Origin gPackager )
				)
				( attribute "CDS_LOCATION" "R9A12"
					( Origin gPackager )
				)
				( attribute "CDS_SEC" "1"
					( Origin gPackager )
				)
				( attribute "LOCATION" "R9A12"
					( Origin gFrontEnd )
				)
				( attribute "MATERIAL" "CHIP"
					( Origin gFrontEnd )
				)
				( attribute "PACK_TYPE" "0402"
					( Origin gFrontEnd )
				)
				( attribute "PART_NUMBER" "G21796-112"
					( Origin gFrontEnd )
				)
				( attribute "PHYS_PAGE" "135"
					( Origin gFrontEnd )
				)
				( attribute "ROOM" "SB"
					( Origin gFrontEnd )
				)
				( attribute "ROT" "1"
					( Origin gFrontEnd )
				)
				( attribute "SEC" "1"
					( Origin gPackager )
				)
				( attribute "TOLERANCE" "1%"
					( Origin gFrontEnd )
				)
				( attribute "VALUE" "2.21K"
					( Origin gFrontEnd )
				)
				( attribute "VER" "1"
					( Origin gFrontEnd )
				)
				( attribute "WATTAGE" "1/16W"
					( Origin gFrontEnd )
				)
				( attribute "XY" "(-3875,4900)"
					( Origin gFrontEnd )
				)
				( attribute "CHIPS_PART_NAME" "RES"
					( Origin gPackager )
				)
				( attribute "CDS_PART_NAME" "RES_0402-2.21K,1%,1/16W,CHIP,GA"
					( Origin gPackager )
				)
				( objectStatus "R9A12" )
			)
			( gate "@baseboard_fab2_lib.baseboard_fab2(sch_1):page135_i118"
				( attribute "BOM_COST" "SB"
					( Origin gFrontEnd )
				)
				( attribute "CDS_LIB" "mstr_discrete"
					( Origin gPackager )
				)
				( attribute "CDS_LOCATION" "R9A13"
					( Origin gPackager )
				)
				( attribute "CDS_SEC" "1"
					( Origin gPackager )
				)
				( attribute "LOCATION" "R9A13"
					( Origin gFrontEnd )
				)
				( attribute "MATERIAL" "CHIP"
					( Origin gFrontEnd )
				)
				( attribute "PACK_TYPE" "0402"
					( Origin gFrontEnd )
				)
				( attribute "PART_NUMBER" "G21796-074"
					( Origin gFrontEnd )
				)
				( attribute "PHYS_PAGE" "135"
					( Origin gFrontEnd )
				)
				( attribute "ROOM" "SB"
					( Origin gFrontEnd )
				)
				( attribute "ROT" "0"
					( Origin gFrontEnd )
				)
				( attribute "SEC" "1"
					( Origin gPackager )
				)
				( attribute "TOLERANCE" "1%"
					( Origin gFrontEnd )
				)
				( attribute "VALUE" "33.2"
					( Origin gFrontEnd )
				)
				( attribute "VER" "1"
					( Origin gFrontEnd )
				)
				( attribute "WATTAGE" "1/16W"
					( Origin gFrontEnd )
				)
				( attribute "XY" "(-3650,4500)"
					( Origin gFrontEnd )
				)
				( attribute "CHIPS_PART_NAME" "RES"
					( Origin gPackager )
				)
				( attribute "CDS_PART_NAME" "RES_0402-33.2,1%,1/16W,CHIP,G2A"
					( Origin gPackager )
				)
				( objectStatus "R9A13" )
			)
			( gate "@baseboard_fab2_lib.baseboard_fab2(sch_1):page135_i120"
				( attribute "BOM_COST" "SB"
					( Origin gFrontEnd )
				)
				( attribute "CDS_LIB" "mstr_discrete"
					( Origin gPackager )
				)
				( attribute "CDS_LOCATION" "R8D21"
					( Origin gPackager )
				)
				( attribute "CDS_SEC" "1"
					( Origin gPackager )
				)
				( attribute "LOCATION" "R8D21"
					( Origin gFrontEnd )
				)
				( attribute "MATERIAL" "CHIP"
					( Origin gFrontEnd )
				)
				( attribute "PACK_TYPE" "0402"
					( Origin gFrontEnd )
				)
				( attribute "PART_NUMBER" "G21796-026"
					( Origin gFrontEnd )
				)
				( attribute "PHYS_PAGE" "135"
					( Origin gFrontEnd )
				)
				( attribute "ROOM" "SB"
					( Origin gFrontEnd )
				)
				( attribute "ROT" "0"
					( Origin gFrontEnd )
				)
				( attribute "SEC" "1"
					( Origin gFrontEnd )
				)
				( attribute "SEC_TYPE" "0402"
					( Origin gFrontEnd )
				)
				( attribute "TOLERANCE" "1%"
					( Origin gFrontEnd )
				)
				( attribute "VALUE" "1.00K"
					( Origin gFrontEnd )
				)
				( attribute "VER" "2"
					( Origin gFrontEnd )
				)
				( attribute "WATTAGE" "1/16W"
					( Origin gFrontEnd )
				)
				( attribute "XY" "(-225,2250)"
					( Origin gFrontEnd )
				)
				( attribute "CHIPS_PART_NAME" "RES"
					( Origin gPackager )
				)
				( attribute "CDS_PART_NAME" "RES_0402-1.00K,1%,1/16W,CHIP,GA"
					( Origin gPackager )
				)
				( objectStatus "R8D21" )
			)
			( gate "@baseboard_fab2_lib.baseboard_fab2(sch_1):page135_i121"
				( attribute "BOM_COST" "DEBUG"
					( Origin gFrontEnd )
				)
				( attribute "CDS_LIB" "mstr_discrete"
					( Origin gPackager )
				)
				( attribute "CDS_LOCATION" "R7D30"
					( Origin gPackager )
				)
				( attribute "CDS_SEC" "1"
					( Origin gPackager )
				)
				( attribute "LOCATION" "R7D30"
					( Origin gFrontEnd )
				)
				( attribute "MATERIAL" "CHIP"
					( Origin gFrontEnd )
				)
				( attribute "PACK_TYPE" "0402"
					( Origin gFrontEnd )
				)
				( attribute "PART_NUMBER" "G21796-072"
					( Origin gFrontEnd )
				)
				( attribute "PHYS_PAGE" "135"
					( Origin gFrontEnd )
				)
				( attribute "ROOM" "UART_MUX"
					( Origin gFrontEnd )
				)
				( attribute "ROT" "0"
					( Origin gFrontEnd )
				)
				( attribute "SEC" "1"
					( Origin gFrontEnd )
				)
				( attribute "SEC_TYPE" "0402"
					( Origin gFrontEnd )
				)
				( attribute "TOLERANCE" "1%"
					( Origin gFrontEnd )
				)
				( attribute "VALUE" "4.75K"
					( Origin gFrontEnd )
				)
				( attribute "VER" "2"
					( Origin gFrontEnd )
				)
				( attribute "WATTAGE" "1/16W"
					( Origin gFrontEnd )
				)
				( attribute "XY" "(-1525,2250)"
					( Origin gFrontEnd )
				)
				( attribute "CHIPS_PART_NAME" "RES"
					( Origin gPackager )
				)
				( attribute "CDS_PART_NAME" "RES_0402-4.75K,1%,1/16W,CHIP,GA"
					( Origin gPackager )
				)
				( objectStatus "R7D30" )
			)
			( gate "@baseboard_fab2_lib.baseboard_fab2(sch_1):page135_i124"
				( attribute "BOM_COST" "SB"
					( Origin gFrontEnd )
				)
				( attribute "CDS_LIB" "mstr_conn"
					( Origin gPackager )
				)
				( attribute "CDS_LOCATION" "J8G2"
					( Origin gPackager )
				)
				( attribute "CDS_SEC" "1"
					( Origin gPackager )
				)
				( attribute "LOCATION" "J8G2"
					( Origin gFrontEnd )
				)
				( attribute "MATERIAL" "CONN"
					( Origin gFrontEnd )
				)
				( attribute "PACK_TYPE" "PIP"
					( Origin gFrontEnd )
				)
				( attribute "PART_NUMBER" "C73564-003"
					( Origin gFrontEnd )
				)
				( attribute "PHYS_PAGE" "135"
					( Origin gFrontEnd )
				)
				( attribute "ROOM" "SB"
					( Origin gFrontEnd )
				)
				( attribute "ROT" "0"
					( Origin gFrontEnd )
				)
				( attribute "SEC" "1"
					( Origin gFrontEnd )
				)
				( attribute "SEC_TYPE" "PIP"
					( Origin gFrontEnd )
				)
				( attribute "VER" "1"
					( Origin gFrontEnd )
				)
				( attribute "XY" "(-775,1900)"
					( Origin gFrontEnd )
				)
				( attribute "CHIPS_PART_NAME" "CONN12_C73564003"
					( Origin gPackager )
				)
				( attribute "CDS_PART_NAME" "CONN12_C73564003_PIP-CONN,C735A"
					( Origin gPackager )
				)
				( objectStatus "J8G2" )
			)
			( gate "@baseboard_fab2_lib.baseboard_fab2(sch_1):page135_i129"
				( attribute "BOM_COST" "SB"
					( Origin gFrontEnd )
				)
				( attribute "CDS_LIB" "mstr_discrete"
					( Origin gPackager )
				)
				( attribute "CDS_LOCATION" "R9A16"
					( Origin gPackager )
				)
				( attribute "CDS_SEC" "1"
					( Origin gPackager )
				)
				( attribute "LOCATION" "R9A16"
					( Origin gFrontEnd )
				)
				( attribute "MATERIAL" "CHIP"
					( Origin gFrontEnd )
				)
				( attribute "PACK_TYPE" "0402"
					( Origin gFrontEnd )
				)
				( attribute "PART_NUMBER" "G21796-112"
					( Origin gFrontEnd )
				)
				( attribute "PHYS_PAGE" "135"
					( Origin gFrontEnd )
				)
				( attribute "ROOM" "SB"
					( Origin gFrontEnd )
				)
				( attribute "ROT" "1"
					( Origin gFrontEnd )
				)
				( attribute "SEC" "1"
					( Origin gPackager )
				)
				( attribute "TOLERANCE" "1%"
					( Origin gFrontEnd )
				)
				( attribute "VALUE" "2.21K"
					( Origin gFrontEnd )
				)
				( attribute "VER" "1"
					( Origin gFrontEnd )
				)
				( attribute "WATTAGE" "1/16W"
					( Origin gFrontEnd )
				)
				( attribute "XY" "(-4275,4900)"
					( Origin gFrontEnd )
				)
				( attribute "CHIPS_PART_NAME" "RES"
					( Origin gPackager )
				)
				( attribute "CDS_PART_NAME" "RES_0402-2.21K,1%,1/16W,CHIP,GA"
					( Origin gPackager )
				)
				( objectStatus "R9A16" )
			)
			( gate "@baseboard_fab2_lib.baseboard_fab2(sch_1):page135_i131"
				( attribute "BOM_COST" "SB"
					( Origin gFrontEnd )
				)
				( attribute "CDS_LIB" "mstr_conn"
					( Origin gPackager )
				)
				( attribute "CDS_LOCATION" "J9A1"
					( Origin gPackager )
				)
				( attribute "CDS_SEC" "1"
					( Origin gPackager )
				)
				( attribute "LOCATION" "J9A1"
					( Origin gFrontEnd )
				)
				( attribute "MATERIAL" "CONN"
					( Origin gFrontEnd )
				)
				( attribute "PACK_TYPE" "PIP"
					( Origin gFrontEnd )
				)
				( attribute "PART_NUMBER" "D42317-002"
					( Origin gFrontEnd )
				)
				( attribute "PHYS_PAGE" "135"
					( Origin gFrontEnd )
				)
				( attribute "ROOM" "SB"
					( Origin gFrontEnd )
				)
				( attribute "ROT" "2"
					( Origin gFrontEnd )
				)
				( attribute "SEC" "1"
					( Origin gPackager )
				)
				( attribute "VER" "1"
					( Origin gFrontEnd )
				)
				( attribute "XY" "(-5075,4600)"
					( Origin gFrontEnd )
				)
				( attribute "CHIPS_PART_NAME" "CONN4_D42317002"
					( Origin gPackager )
				)
				( attribute "CDS_PART_NAME" "CONN4_D42317002_PIP-CONN,D4231A"
					( Origin gPackager )
				)
				( attribute "POP" "NOPOP"
					( Origin gFrontEnd )
				)
				( objectStatus "J9A1" )
			)
			( gate "@baseboard_fab2_lib.baseboard_fab2(sch_1):page136_i101"
				( attribute "CDS_LIB" "mstr_discrete"
					( Origin gPackager )
				)
				( attribute "CDS_LOCATION" "R7G26"
					( Origin gPackager )
				)
				( attribute "CDS_SEC" "1"
					( Origin gPackager )
				)
				( attribute "LOCATION" "R7G26"
					( Origin gFrontEnd )
				)
				( attribute "MATERIAL" "CHIP"
					( Origin gFrontEnd )
				)
				( attribute "PACK_TYPE" "0402"
					( Origin gFrontEnd )
				)
				( attribute "PART_NUMBER" "G21796-016"
					( Origin gFrontEnd )
				)
				( attribute "PHYS_PAGE" "136"
					( Origin gFrontEnd )
				)
				( attribute "ROOM" "SB"
					( Origin gFrontEnd )
				)
				( attribute "ROT" "0"
					( Origin gFrontEnd )
				)
				( attribute "SEC" "1"
					( Origin gFrontEnd )
				)
				( attribute "SEC_TYPE" "0402"
					( Origin gFrontEnd )
				)
				( attribute "TOLERANCE" "1%"
					( Origin gFrontEnd )
				)
				( attribute "VALUE" "10.0K"
					( Origin gFrontEnd )
				)
				( attribute "VER" "2"
					( Origin gFrontEnd )
				)
				( attribute "WATTAGE" "1/16W"
					( Origin gFrontEnd )
				)
				( attribute "XY" "(-2250,4800)"
					( Origin gFrontEnd )
				)
				( attribute "CHIPS_PART_NAME" "RES"
					( Origin gPackager )
				)
				( attribute "CDS_PART_NAME" "RES_0402-10.0K,1%,1/16W,CHIP,GA"
					( Origin gPackager )
				)
				( objectStatus "R7G26" )
			)
			( gate "@baseboard_fab2_lib.baseboard_fab2(sch_1):page136_i102"
				( attribute "BOM_COST" "SB"
					( Origin gFrontEnd )
				)
				( attribute "CDS_LIB" "mstr_discrete"
					( Origin gPackager )
				)
				( attribute "CDS_LOCATION" "R7G28"
					( Origin gPackager )
				)
				( attribute "CDS_SEC" "1"
					( Origin gPackager )
				)
				( attribute "LOCATION" "R7G28"
					( Origin gFrontEnd )
				)
				( attribute "MATERIAL" "CHIP"
					( Origin gFrontEnd )
				)
				( attribute "PACK_TYPE" "0402"
					( Origin gFrontEnd )
				)
				( attribute "PART_NUMBER" "G21796-026"
					( Origin gFrontEnd )
				)
				( attribute "PHYS_PAGE" "136"
					( Origin gFrontEnd )
				)
				( attribute "ROOM" "SB"
					( Origin gFrontEnd )
				)
				( attribute "ROT" "0"
					( Origin gFrontEnd )
				)
				( attribute "SEC" "1"
					( Origin gFrontEnd )
				)
				( attribute "SEC_TYPE" "0402"
					( Origin gFrontEnd )
				)
				( attribute "TOLERANCE" "1%"
					( Origin gFrontEnd )
				)
				( attribute "VALUE" "1.00K"
					( Origin gFrontEnd )
				)
				( attribute "VER" "2"
					( Origin gFrontEnd )
				)
				( attribute "WATTAGE" "1/16W"
					( Origin gFrontEnd )
				)
				( attribute "XY" "(-2450,3825)"
					( Origin gFrontEnd )
				)
				( attribute "CHIPS_PART_NAME" "RES"
					( Origin gPackager )
				)
				( attribute "CDS_PART_NAME" "RES_0402-1.00K,1%,1/16W,CHIP,GA"
					( Origin gPackager )
				)
				( objectStatus "R7G28" )
			)
			( gate "@baseboard_fab2_lib.baseboard_fab2(sch_1):page136_i126"
				( attribute "BOM_COST" "SB"
					( Origin gFrontEnd )
				)
				( attribute "CDS_LIB" "mstr_discrete"
					( Origin gPackager )
				)
				( attribute "CDS_LOCATION" "R8E20"
					( Origin gPackager )
				)
				( attribute "CDS_SEC" "1"
					( Origin gPackager )
				)
				( attribute "LOCATION" "R8E20"
					( Origin gFrontEnd )
				)
				( attribute "MATERIAL" "CHIP"
					( Origin gFrontEnd )
				)
				( attribute "PACK_TYPE" "0402"
					( Origin gFrontEnd )
				)
				( attribute "PART_NUMBER" "G21796-074"
					( Origin gFrontEnd )
				)
				( attribute "PHYS_PAGE" "136"
					( Origin gFrontEnd )
				)
				( attribute "ROOM" "SB"
					( Origin gFrontEnd )
				)
				( attribute "ROT" "0"
					( Origin gFrontEnd )
				)
				( attribute "SEC" "1"
					( Origin gFrontEnd )
				)
				( attribute "SEC_TYPE" "0402"
					( Origin gFrontEnd )
				)
				( attribute "TOLERANCE" "1%"
					( Origin gFrontEnd )
				)
				( attribute "VALUE" "33.2"
					( Origin gFrontEnd )
				)
				( attribute "VER" "1"
					( Origin gFrontEnd )
				)
				( attribute "WATTAGE" "1/16W"
					( Origin gFrontEnd )
				)
				( attribute "XY" "(1000,2300)"
					( Origin gFrontEnd )
				)
				( attribute "CHIPS_PART_NAME" "RES"
					( Origin gPackager )
				)
				( attribute "CDS_PART_NAME" "RES_0402-33.2,1%,1/16W,CHIP,G2A"
					( Origin gPackager )
				)
				( objectStatus "R8E20" )
			)
			( gate "@baseboard_fab2_lib.baseboard_fab2(sch_1):page136_i128"
				( attribute "BOM_COST" "SB"
					( Origin gFrontEnd )
				)
				( attribute "CDS_LIB" "dev_discrete"
					( Origin gPackager )
				)
				( attribute "CDS_LOCATION" "C8E8"
					( Origin gPackager )
				)
				( attribute "CDS_SEC" "1"
					( Origin gPackager )
				)
				( attribute "LOCATION" "C8E8"
					( Origin gFrontEnd )
				)
				( attribute "MATERIAL" "X7R"
					( Origin gFrontEnd )
				)
				( attribute "PACK_TYPE" "0402V"
					( Origin gFrontEnd )
				)
				( attribute "PART_NUMBER" "A36096-030"
					( Origin gFrontEnd )
				)
				( attribute "PHYS_PAGE" "136"
					( Origin gFrontEnd )
				)
				( attribute "ROOM" "SB"
					( Origin gFrontEnd )
				)
				( attribute "ROT" "0"
					( Origin gFrontEnd )
				)
				( attribute "SEC" "1"
					( Origin gFrontEnd )
				)
				( attribute "SEC_TYPE" "0402V"
					( Origin gFrontEnd )
				)
				( attribute "TOLERANCE" "10%"
					( Origin gFrontEnd )
				)
				( attribute "VALUE" "0.1UF"
					( Origin gFrontEnd )
				)
				( attribute "VER" "1"
					( Origin gFrontEnd )
				)
				( attribute "VOLTAGE" "16V"
					( Units "uVoltage" "V" 1.000000)
					( Origin gFrontEnd )
				)
				( attribute "XY" "(575,1575)"
					( Origin gFrontEnd )
				)
				( attribute "CHIPS_PART_NAME" "CAP_A"
					( Origin gPackager )
				)
				( attribute "CDS_PART_NAME" "CAP_A_0402V-0.1UF,16V,10%,X7R,A"
					( Origin gPackager )
				)
				( objectStatus "C8E8" )
			)
			( gate "@baseboard_fab2_lib.baseboard_fab2(sch_1):page136_i130"
				( attribute "BOM_COST" "SB"
					( Origin gFrontEnd )
				)
				( attribute "CDS_LIB" "mstr_ttl"
					( Origin gPackager )
				)
				( attribute "CDS_LOCATION" "U8E3"
					( Origin gPackager )
				)
				( attribute "CDS_SEC" "1"
					( Origin gPackager )
				)
				( attribute "LOCATION" "U8E3"
					( Origin gFrontEnd )
				)
				( attribute "MATERIAL" "IC"
					( Origin gFrontEnd )
				)
				( attribute "PACK_TYPE" "SOT"
					( Origin gFrontEnd )
				)
				( attribute "PART_NUMBER" "A79322-001"
					( Origin gFrontEnd )
				)
				( attribute "PHYS_PAGE" "136"
					( Origin gFrontEnd )
				)
				( attribute "ROOM" "SB"
					( Origin gFrontEnd )
				)
				( attribute "ROT" "0"
					( Origin gFrontEnd )
				)
				( attribute "SEC" "1"
					( Origin gFrontEnd )
				)
				( attribute "SEC_TYPE" "SOT"
					( Origin gFrontEnd )
				)
				( attribute "VALUE" "74HC1G126"
					( Origin gFrontEnd )
				)
				( attribute "VER" "1"
					( Origin gFrontEnd )
				)
				( attribute "XY" "(0,2300)"
					( Origin gFrontEnd )
				)
				( attribute "CHIPS_PART_NAME" "TTL1G126_A"
					( Origin gPackager )
				)
				( attribute "CDS_PART_NAME" "TTL1G126_A_SOT-74HC1G126,IC,A7B"
					( Origin gPackager )
				)
				( objectStatus "U8E3" )
			)
			( gate "@baseboard_fab2_lib.baseboard_fab2(sch_1):page136_i133"
				( attribute "CDS_LIB" "mstr_discrete"
					( Origin gPackager )
				)
				( attribute "CDS_LOCATION" "R8E14"
					( Origin gPackager )
				)
				( attribute "CDS_SEC" "1"
					( Origin gPackager )
				)
				( attribute "LOCATION" "R8E14"
					( Origin gFrontEnd )
				)
				( attribute "MATERIAL" "CHIP"
					( Origin gFrontEnd )
				)
				( attribute "PACK_TYPE" "0402"
					( Origin gFrontEnd )
				)
				( attribute "PART_NUMBER" "G21796-072"
					( Origin gFrontEnd )
				)
				( attribute "PHYS_PAGE" "136"
					( Origin gFrontEnd )
				)
				( attribute "ROOM" "SB"
					( Origin gFrontEnd )
				)
				( attribute "ROT" "0"
					( Origin gFrontEnd )
				)
				( attribute "SEC" "1"
					( Origin gFrontEnd )
				)
				( attribute "SEC_TYPE" "0402"
					( Origin gFrontEnd )
				)
				( attribute "TOLERANCE" "1%"
					( Origin gFrontEnd )
				)
				( attribute "VALUE" "4.75K"
					( Origin gFrontEnd )
				)
				( attribute "VER" "2"
					( Origin gFrontEnd )
				)
				( attribute "WATTAGE" "1/16W"
					( Origin gFrontEnd )
				)
				( attribute "XY" "(-550,1900)"
					( Origin gFrontEnd )
				)
				( attribute "CHIPS_PART_NAME" "RES"
					( Origin gPackager )
				)
				( attribute "CDS_PART_NAME" "RES_0402-4.75K,1%,1/16W,CHIP,GA"
					( Origin gPackager )
				)
				( objectStatus "R8E14" )
			)
			( gate "@baseboard_fab2_lib.baseboard_fab2(sch_1):page136_i134"
				( attribute "CDS_LIB" "mstr_discrete"
					( Origin gPackager )
				)
				( attribute "CDS_LOCATION" "Q8E1"
					( Origin gPackager )
				)
				( attribute "CDS_SEC" "1"
					( Origin gPackager )
				)
				( attribute "LOCATION" "Q8E1"
					( Origin gFrontEnd )
				)
				( attribute "MATERIAL" "FET"
					( Origin gFrontEnd )
				)
				( attribute "PACK_TYPE" "SOT23LF"
					( Origin gFrontEnd )
				)
				( attribute "PART_NUMBER" "C79254-001"
					( Origin gFrontEnd )
				)
				( attribute "PHYS_PAGE" "136"
					( Origin gFrontEnd )
				)
				( attribute "ROOM" "SB"
					( Origin gFrontEnd )
				)
				( attribute "ROT" "0"
					( Origin gFrontEnd )
				)
				( attribute "SEC" "1"
					( Origin gFrontEnd )
				)
				( attribute "SEC_TYPE" "SOT23LF"
					( Origin gFrontEnd )
				)
				( attribute "VALUE" "2N7002"
					( Origin gFrontEnd )
				)
				( attribute "VER" "8"
					( Origin gFrontEnd )
				)
				( attribute "XY" "(-550,1375)"
					( Origin gFrontEnd )
				)
				( attribute "CHIPS_PART_NAME" "FET_N"
					( Origin gPackager )
				)
				( attribute "CDS_PART_NAME" "FET_N_SOT23LF-2N7002,FET,C7925A"
					( Origin gPackager )
				)
				( objectStatus "Q8E1" )
			)
			( gate "@baseboard_fab2_lib.baseboard_fab2(sch_1):page136_i139"
				( attribute "BOM_COST" "SB"
					( Origin gFrontEnd )
				)
				( attribute "CDS_LIB" "mstr_discrete"
					( Origin gPackager )
				)
				( attribute "CDS_LOCATION" "R7G31"
					( Origin gPackager )
				)
				( attribute "CDS_SEC" "1"
					( Origin gPackager )
				)
				( attribute "LOCATION" "R7G31"
					( Origin gFrontEnd )
				)
				( attribute "MATERIAL" "CHIP"
					( Origin gFrontEnd )
				)
				( attribute "PACK_TYPE" "0402"
					( Origin gFrontEnd )
				)
				( attribute "PART_NUMBER" "G21796-026"
					( Origin gFrontEnd )
				)
				( attribute "PHYS_PAGE" "136"
					( Origin gFrontEnd )
				)
				( attribute "ROOM" "SB"
					( Origin gFrontEnd )
				)
				( attribute "ROT" "0"
					( Origin gFrontEnd )
				)
				( attribute "SEC" "1"
					( Origin gFrontEnd )
				)
				( attribute "SEC_TYPE" "0402"
					( Origin gFrontEnd )
				)
				( attribute "TOLERANCE" "1%"
					( Origin gFrontEnd )
				)
				( attribute "VALUE" "1.00K"
					( Origin gFrontEnd )
				)
				( attribute "VER" "2"
					( Origin gFrontEnd )
				)
				( attribute "WATTAGE" "1/16W"
					( Origin gFrontEnd )
				)
				( attribute "XY" "(-400,4800)"
					( Origin gFrontEnd )
				)
				( attribute "CHIPS_PART_NAME" "RES"
					( Origin gPackager )
				)
				( attribute "CDS_PART_NAME" "RES_0402-1.00K,1%,1/16W,CHIP,GA"
					( Origin gPackager )
				)
				( objectStatus "R7G31" )
			)
			( gate "@baseboard_fab2_lib.baseboard_fab2(sch_1):page136_i140"
				( attribute "BOM_COST" "SB"
					( Origin gFrontEnd )
				)
				( attribute "CDS_LIB" "mstr_discrete"
					( Origin gPackager )
				)
				( attribute "CDS_LOCATION" "R8E16"
					( Origin gPackager )
				)
				( attribute "CDS_SEC" "1"
					( Origin gPackager )
				)
				( attribute "LOCATION" "R8E16"
					( Origin gFrontEnd )
				)
				( attribute "MATERIAL" "CHIP"
					( Origin gFrontEnd )
				)
				( attribute "PACK_TYPE" "0402"
					( Origin gFrontEnd )
				)
				( attribute "PART_NUMBER" "G21796-040"
					( Origin gFrontEnd )
				)
				( attribute "PHYS_PAGE" "136"
					( Origin gFrontEnd )
				)
				( attribute "ROOM" "SB"
					( Origin gFrontEnd )
				)
				( attribute "ROT" "0"
					( Origin gFrontEnd )
				)
				( attribute "SEC" "1"
					( Origin gFrontEnd )
				)
				( attribute "SEC_TYPE" "0402"
					( Origin gFrontEnd )
				)
				( attribute "TOLERANCE" "1%"
					( Origin gFrontEnd )
				)
				( attribute "VALUE" "20.0K"
					( Origin gFrontEnd )
				)
				( attribute "VER" "2"
					( Origin gFrontEnd )
				)
				( attribute "WATTAGE" "1/16W"
					( Origin gFrontEnd )
				)
				( attribute "XY" "(0,3900)"
					( Origin gFrontEnd )
				)
				( attribute "CHIPS_PART_NAME" "RES"
					( Origin gPackager )
				)
				( attribute "CDS_PART_NAME" "RES_0402-20.0K,1%,1/16W,CHIP,GA"
					( Origin gPackager )
				)
				( objectStatus "R8E16" )
			)
			( gate "@baseboard_fab2_lib.baseboard_fab2(sch_1):page136_i147"
				( attribute "BOM_COST" "SB"
					( Origin gFrontEnd )
				)
				( attribute "CDS_LIB" "mstr_discrete"
					( Origin gPackager )
				)
				( attribute "CDS_LOCATION" "R2N28"
					( Origin gPackager )
				)
				( attribute "CDS_SEC" "1"
					( Origin gPackager )
				)
				( attribute "LOCATION" "R2N28"
					( Origin gFrontEnd )
				)
				( attribute "MATERIAL" "CHIP"
					( Origin gFrontEnd )
				)
				( attribute "PACK_TYPE" "0402"
					( Origin gFrontEnd )
				)
				( attribute "PART_NUMBER" "G21796-016"
					( Origin gFrontEnd )
				)
				( attribute "PHYS_PAGE" "136"
					( Origin gFrontEnd )
				)
				( attribute "ROOM" "SB"
					( Origin gFrontEnd )
				)
				( attribute "ROT" "2"
					( Origin gFrontEnd )
				)
				( attribute "SEC" "1"
					( Origin gFrontEnd )
				)
				( attribute "SEC_TYPE" "0402"
					( Origin gFrontEnd )
				)
				( attribute "TOLERANCE" "1%"
					( Origin gFrontEnd )
				)
				( attribute "VALUE" "10.0K"
					( Origin gFrontEnd )
				)
				( attribute "VER" "2"
					( Origin gFrontEnd )
				)
				( attribute "WATTAGE" "1/16W"
					( Origin gFrontEnd )
				)
				( attribute "XY" "(-2500,4800)"
					( Origin gFrontEnd )
				)
				( attribute "CHIPS_PART_NAME" "RES"
					( Origin gPackager )
				)
				( attribute "CDS_PART_NAME" "RES_0402-10.0K,1%,1/16W,CHIP,GA"
					( Origin gPackager )
				)
				( objectStatus "R2N28" )
			)
			( gate "@baseboard_fab2_lib.baseboard_fab2(sch_1):page136_i148"
				( attribute "BOM_COST" "SB"
					( Origin gFrontEnd )
				)
				( attribute "CDS_LIB" "mstr_discrete"
					( Origin gPackager )
				)
				( attribute "CDS_LOCATION" "R7G29"
					( Origin gPackager )
				)
				( attribute "CDS_SEC" "1"
					( Origin gPackager )
				)
				( attribute "LOCATION" "R7G29"
					( Origin gFrontEnd )
				)
				( attribute "MATERIAL" "CHIP"
					( Origin gFrontEnd )
				)
				( attribute "PACK_TYPE" "0402"
					( Origin gFrontEnd )
				)
				( attribute "PART_NUMBER" "G21796-026"
					( Origin gFrontEnd )
				)
				( attribute "PHYS_PAGE" "136"
					( Origin gFrontEnd )
				)
				( attribute "ROOM" "SB"
					( Origin gFrontEnd )
				)
				( attribute "ROT" "0"
					( Origin gFrontEnd )
				)
				( attribute "SEC" "1"
					( Origin gFrontEnd )
				)
				( attribute "SEC_TYPE" "0402"
					( Origin gFrontEnd )
				)
				( attribute "TOLERANCE" "1%"
					( Origin gFrontEnd )
				)
				( attribute "VALUE" "1.00K"
					( Origin gFrontEnd )
				)
				( attribute "VER" "2"
					( Origin gFrontEnd )
				)
				( attribute "WATTAGE" "1/16W"
					( Origin gFrontEnd )
				)
				( attribute "XY" "(-3100,3850)"
					( Origin gFrontEnd )
				)
				( attribute "CHIPS_PART_NAME" "RES"
					( Origin gPackager )
				)
				( attribute "CDS_PART_NAME" "RES_0402-1.00K,1%,1/16W,CHIP,GA"
					( Origin gPackager )
				)
				( objectStatus "R7G29" )
			)
			( gate "@baseboard_fab2_lib.baseboard_fab2(sch_1):page136_i155"
				( attribute "BOM_COST" "SB"
					( Origin gFrontEnd )
				)
				( attribute "CDS_LIB" "mstr_discrete"
					( Origin gPackager )
				)
				( attribute "CDS_LOCATION" "R7G27"
					( Origin gPackager )
				)
				( attribute "CDS_SEC" "1"
					( Origin gPackager )
				)
				( attribute "LOCATION" "R7G27"
					( Origin gFrontEnd )
				)
				( attribute "MATERIAL" "CHIP"
					( Origin gFrontEnd )
				)
				( attribute "PACK_TYPE" "0402"
					( Origin gFrontEnd )
				)
				( attribute "PART_NUMBER" "G21796-026"
					( Origin gFrontEnd )
				)
				( attribute "PHYS_PAGE" "136"
					( Origin gFrontEnd )
				)
				( attribute "ROOM" "SB"
					( Origin gFrontEnd )
				)
				( attribute "ROT" "2"
					( Origin gFrontEnd )
				)
				( attribute "SEC" "1"
					( Origin gFrontEnd )
				)
				( attribute "SEC_TYPE" "0402"
					( Origin gFrontEnd )
				)
				( attribute "TOLERANCE" "1%"
					( Origin gFrontEnd )
				)
				( attribute "VALUE" "1.00K"
					( Origin gFrontEnd )
				)
				( attribute "VER" "2"
					( Origin gFrontEnd )
				)
				( attribute "WATTAGE" "1/16W"
					( Origin gFrontEnd )
				)
				( attribute "XY" "(-600,4800)"
					( Origin gFrontEnd )
				)
				( attribute "CHIPS_PART_NAME" "RES"
					( Origin gPackager )
				)
				( attribute "CDS_PART_NAME" "RES_0402-1.00K,1%,1/16W,CHIP,GA"
					( Origin gPackager )
				)
				( objectStatus "R7G27" )
			)
			( gate "@baseboard_fab2_lib.baseboard_fab2(sch_1):page136_i156"
				( attribute "BOM_COST" "SB"
					( Origin gFrontEnd )
				)
				( attribute "CDS_LIB" "mstr_discrete"
					( Origin gPackager )
				)
				( attribute "CDS_LOCATION" "R3T14"
					( Origin gPackager )
				)
				( attribute "CDS_SEC" "1"
					( Origin gPackager )
				)
				( attribute "LOCATION" "R3T14"
					( Origin gFrontEnd )
				)
				( attribute "MATERIAL" "CHIP"
					( Origin gFrontEnd )
				)
				( attribute "PACK_TYPE" "0402"
					( Origin gFrontEnd )
				)
				( attribute "PART_NUMBER" "G21796-016"
					( Origin gFrontEnd )
				)
				( attribute "PHYS_PAGE" "136"
					( Origin gFrontEnd )
				)
				( attribute "ROOM" "SB"
					( Origin gFrontEnd )
				)
				( attribute "ROT" "0"
					( Origin gFrontEnd )
				)
				( attribute "SEC" "1"
					( Origin gFrontEnd )
				)
				( attribute "SEC_TYPE" "0402"
					( Origin gFrontEnd )
				)
				( attribute "TOLERANCE" "1%"
					( Origin gFrontEnd )
				)
				( attribute "VALUE" "10.0K"
					( Origin gFrontEnd )
				)
				( attribute "VER" "2"
					( Origin gFrontEnd )
				)
				( attribute "WATTAGE" "1/16W"
					( Origin gFrontEnd )
				)
				( attribute "XY" "(-300,3900)"
					( Origin gFrontEnd )
				)
				( attribute "CHIPS_PART_NAME" "RES"
					( Origin gPackager )
				)
				( attribute "CDS_PART_NAME" "RES_0402-10.0K,1%,1/16W,CHIP,GA"
					( Origin gPackager )
				)
				( objectStatus "R3T14" )
			)
			( gate "@baseboard_fab2_lib.baseboard_fab2(sch_1):page136_i174"
				( attribute "BOM_COST" "SB"
					( Origin gFrontEnd )
				)
				( attribute "CDS_LIB" "mstr_conn"
					( Origin gPackager )
				)
				( attribute "CDS_LOCATION" "J7G3"
					( Origin gPackager )
				)
				( attribute "CDS_SEC" "1"
					( Origin gPackager )
				)
				( attribute "LOCATION" "J7G3"
					( Origin gFrontEnd )
				)
				( attribute "MATERIAL" "CONN"
					( Origin gFrontEnd )
				)
				( attribute "PACK_TYPE" "PIP"
					( Origin gFrontEnd )
				)
				( attribute "PART_NUMBER" "C73564-003"
					( Origin gFrontEnd )
				)
				( attribute "PHYS_PAGE" "136"
					( Origin gFrontEnd )
				)
				( attribute "ROOM" "SB"
					( Origin gFrontEnd )
				)
				( attribute "ROT" "0"
					( Origin gFrontEnd )
				)
				( attribute "SEC" "1"
					( Origin gFrontEnd )
				)
				( attribute "SEC_TYPE" "PIP"
					( Origin gFrontEnd )
				)
				( attribute "VER" "1"
					( Origin gFrontEnd )
				)
				( attribute "XY" "(-1650,4250)"
					( Origin gFrontEnd )
				)
				( attribute "CHIPS_PART_NAME" "CONN12_C73564003"
					( Origin gPackager )
				)
				( attribute "CDS_PART_NAME" "CONN12_C73564003_PIP-CONN,C735A"
					( Origin gPackager )
				)
				( objectStatus "J7G3" )
			)
			( gate "@baseboard_fab2_lib.baseboard_fab2(sch_1):page137_i11"
				( attribute "BOM_COST" "SB"
					( Origin gFrontEnd )
				)
				( attribute "CDS_LIB" "mstr_discrete"
					( Origin gPackager )
				)
				( attribute "CDS_LOCATION" "R7C11"
					( Origin gPackager )
				)
				( attribute "CDS_SEC" "1"
					( Origin gPackager )
				)
				( attribute "LOCATION" "R7C11"
					( Origin gFrontEnd )
				)
				( attribute "MATERIAL" "EMPTY"
					( Origin gFrontEnd )
				)
				( attribute "PACK_TYPE" "0402"
					( Origin gFrontEnd )
				)
				( attribute "PART_NUMBER" "G21796-021"
					( Origin gFrontEnd )
				)
				( attribute "PHYS_PAGE" "137"
					( Origin gFrontEnd )
				)
				( attribute "ROOM" "SB"
					( Origin gFrontEnd )
				)
				( attribute "ROT" "1"
					( Origin gFrontEnd )
				)
				( attribute "SEC" "1"
					( Origin gPackager )
				)
				( attribute "TOLERANCE" "1%"
					( Origin gFrontEnd )
				)
				( attribute "VALUE" "1.0M"
					( Origin gFrontEnd )
				)
				( attribute "VER" "1"
					( Origin gFrontEnd )
				)
				( attribute "WATTAGE" "1/16W"
					( Origin gFrontEnd )
				)
				( attribute "XY" "(325,3450)"
					( Origin gFrontEnd )
				)
				( attribute "CHIPS_PART_NAME" "RES"
					( Origin gPackager )
				)
				( attribute "CDS_PART_NAME" "RES_0402-1.0M,1%,1/16W,EMPTY,GA"
					( Origin gPackager )
				)
				( objectStatus "R7C11" )
			)
			( gate "@baseboard_fab2_lib.baseboard_fab2(sch_1):page137_i13"
				( attribute "BOM_COST" "SB"
					( Origin gFrontEnd )
				)
				( attribute "CDS_LIB" "mstr_discrete"
					( Origin gPackager )
				)
				( attribute "CDS_LOCATION" "R7C10"
					( Origin gPackager )
				)
				( attribute "CDS_SEC" "1"
					( Origin gPackager )
				)
				( attribute "LOCATION" "R7C10"
					( Origin gFrontEnd )
				)
				( attribute "MATERIAL" "CHIP"
					( Origin gFrontEnd )
				)
				( attribute "NO_XNET_CONNECTION" "1"
					( Origin gFrontEnd )
				)
				( attribute "PACK_TYPE" "0402"
					( Origin gFrontEnd )
				)
				( attribute "PART_NUMBER" "G21796-040"
					( Origin gFrontEnd )
				)
				( attribute "PHYS_PAGE" "137"
					( Origin gFrontEnd )
				)
				( attribute "ROOM" "SB"
					( Origin gFrontEnd )
				)
				( attribute "ROT" "0"
					( Origin gFrontEnd )
				)
				( attribute "SEC" "1"
					( Origin gFrontEnd )
				)
				( attribute "SEC_TYPE" "0402"
					( Origin gFrontEnd )
				)
				( attribute "TOLERANCE" "1%"
					( Origin gFrontEnd )
				)
				( attribute "VALUE" "20.0K"
					( Origin gFrontEnd )
				)
				( attribute "VER" "2"
					( Origin gFrontEnd )
				)
				( attribute "WATTAGE" "1/16W"
					( Origin gFrontEnd )
				)
				( attribute "XY" "(-200,4025)"
					( Origin gFrontEnd )
				)
				( attribute "CHIPS_PART_NAME" "RES"
					( Origin gPackager )
				)
				( attribute "CDS_PART_NAME" "RES_0402-20.0K,1%,1/16W,CHIP,GA"
					( Origin gPackager )
				)
				( objectStatus "R7C10" )
			)
			( gate "@baseboard_fab2_lib.baseboard_fab2(sch_1):page137_i14"
				( attribute "BOM_COST" "SB"
					( Origin gFrontEnd )
				)
				( attribute "CDS_LIB" "dev_discrete"
					( Origin gPackager )
				)
				( attribute "CDS_LOCATION" "C7C19"
					( Origin gPackager )
				)
				( attribute "CDS_SEC" "1"
					( Origin gPackager )
				)
				( attribute "LOCATION" "C7C19"
					( Origin gFrontEnd )
				)
				( attribute "MATERIAL" "X6S"
					( Origin gFrontEnd )
				)
				( attribute "PACK_TYPE" "0402V"
					( Origin gFrontEnd )
				)
				( attribute "PART_NUMBER" "D97712-004"
					( Origin gFrontEnd )
				)
				( attribute "PHYS_PAGE" "137"
					( Origin gFrontEnd )
				)
				( attribute "ROOM" "SB"
					( Origin gFrontEnd )
				)
				( attribute "ROT" "0"
					( Origin gFrontEnd )
				)
				( attribute "SEC" "1"
					( Origin gFrontEnd )
				)
				( attribute "SEC_TYPE" "0402V"
					( Origin gFrontEnd )
				)
				( attribute "TOLERANCE" "10%"
					( Origin gFrontEnd )
				)
				( attribute "VALUE" "1.0UF"
					( Origin gFrontEnd )
				)
				( attribute "VER" "1"
					( Origin gFrontEnd )
				)
				( attribute "VOLTAGE" "6.3V"
					( Units "uVoltage" "V" 1.000000)
					( Origin gFrontEnd )
				)
				( attribute "XY" "(-125,3450)"
					( Origin gFrontEnd )
				)
				( attribute "CHIPS_PART_NAME" "CAP_A"
					( Origin gPackager )
				)
				( attribute "CDS_PART_NAME" "CAP_A_0402V-1.0UF,6.3V,10%,X6SA"
					( Origin gPackager )
				)
				( objectStatus "C7C19" )
			)
			( gate "@baseboard_fab2_lib.baseboard_fab2(sch_1):page137_i15"
				( attribute "BOM_COST" "SB"
					( Origin gFrontEnd )
				)
				( attribute "CDS_LIB" "mstr_discrete"
					( Origin gPackager )
				)
				( attribute "CDS_LOCATION" "R1U63"
					( Origin gPackager )
				)
				( attribute "CDS_SEC" "1"
					( Origin gPackager )
				)
				( attribute "LOCATION" "R1U63"
					( Origin gFrontEnd )
				)
				( attribute "MATERIAL" "CHIP"
					( Origin gFrontEnd )
				)
				( attribute "PACK_TYPE" "0402"
					( Origin gFrontEnd )
				)
				( attribute "PART_NUMBER" "G21796-026"
					( Origin gFrontEnd )
				)
				( attribute "PHYS_PAGE" "137"
					( Origin gFrontEnd )
				)
				( attribute "ROOM" "SB"
					( Origin gFrontEnd )
				)
				( attribute "ROT" "2"
					( Origin gFrontEnd )
				)
				( attribute "SEC" "1"
					( Origin gFrontEnd )
				)
				( attribute "SEC_TYPE" "0402"
					( Origin gFrontEnd )
				)
				( attribute "TOLERANCE" "1%"
					( Origin gFrontEnd )
				)
				( attribute "VALUE" "1.00K"
					( Origin gFrontEnd )
				)
				( attribute "VER" "2"
					( Origin gFrontEnd )
				)
				( attribute "WATTAGE" "1/16W"
					( Origin gFrontEnd )
				)
				( attribute "XY" "(-275,3450)"
					( Origin gFrontEnd )
				)
				( attribute "CHIPS_PART_NAME" "RES"
					( Origin gPackager )
				)
				( attribute "CDS_PART_NAME" "RES_0402-1.00K,1%,1/16W,CHIP,GA"
					( Origin gPackager )
				)
				( objectStatus "R1U63" )
			)
			( gate "@baseboard_fab2_lib.baseboard_fab2(sch_1):page137_i19"
				( attribute "BOM_COST" "SB"
					( Origin gFrontEnd )
				)
				( attribute "CDS_LIB" "mstr_discrete"
					( Origin gPackager )
				)
				( attribute "CDS_LOCATION" "R3N4"
					( Origin gPackager )
				)
				( attribute "CDS_SEC" "1"
					( Origin gPackager )
				)
				( attribute "LOCATION" "R3N4"
					( Origin gFrontEnd )
				)
				( attribute "MATERIAL" "CHIP"
					( Origin gFrontEnd )
				)
				( attribute "NO_XNET_CONNECTION" "1"
					( Origin gFrontEnd )
				)
				( attribute "PACK_TYPE" "0402"
					( Origin gFrontEnd )
				)
				( attribute "PART_NUMBER" "G21796-040"
					( Origin gFrontEnd )
				)
				( attribute "PHYS_PAGE" "137"
					( Origin gFrontEnd )
				)
				( attribute "ROOM" "SB"
					( Origin gFrontEnd )
				)
				( attribute "ROT" "0"
					( Origin gFrontEnd )
				)
				( attribute "SEC" "1"
					( Origin gPackager )
				)
				( attribute "TOLERANCE" "1%"
					( Origin gFrontEnd )
				)
				( attribute "VALUE" "20.0K"
					( Origin gFrontEnd )
				)
				( attribute "VER" "2"
					( Origin gFrontEnd )
				)
				( attribute "WATTAGE" "1/16W"
					( Origin gFrontEnd )
				)
				( attribute "XY" "(-300,1900)"
					( Origin gFrontEnd )
				)
				( attribute "CHIPS_PART_NAME" "RES"
					( Origin gPackager )
				)
				( attribute "CDS_PART_NAME" "RES_0402-20.0K,1%,1/16W,CHIP,GA"
					( Origin gPackager )
				)
				( objectStatus "R3N4" )
			)
			( gate "@baseboard_fab2_lib.baseboard_fab2(sch_1):page137_i20"
				( attribute "BOM_COST" "SB"
					( Origin gFrontEnd )
				)
				( attribute "CDS_LIB" "dev_discrete"
					( Origin gPackager )
				)
				( attribute "CDS_LOCATION" "C3N32"
					( Origin gPackager )
				)
				( attribute "CDS_SEC" "1"
					( Origin gPackager )
				)
				( attribute "LOCATION" "C3N32"
					( Origin gFrontEnd )
				)
				( attribute "MATERIAL" "X6S"
					( Origin gFrontEnd )
				)
				( attribute "PACK_TYPE" "0402V"
					( Origin gFrontEnd )
				)
				( attribute "PART_NUMBER" "D97712-004"
					( Origin gFrontEnd )
				)
				( attribute "PHYS_PAGE" "137"
					( Origin gFrontEnd )
				)
				( attribute "ROOM" "SB"
					( Origin gFrontEnd )
				)
				( attribute "ROT" "0"
					( Origin gFrontEnd )
				)
				( attribute "SEC" "1"
					( Origin gFrontEnd )
				)
				( attribute "SEC_TYPE" "0402V"
					( Origin gFrontEnd )
				)
				( attribute "TOLERANCE" "10%"
					( Origin gFrontEnd )
				)
				( attribute "VALUE" "1.0UF"
					( Origin gFrontEnd )
				)
				( attribute "VER" "1"
					( Origin gFrontEnd )
				)
				( attribute "VOLTAGE" "6.3V"
					( Units "uVoltage" "V" 1.000000)
					( Origin gFrontEnd )
				)
				( attribute "XY" "(-300,1450)"
					( Origin gFrontEnd )
				)
				( attribute "CHIPS_PART_NAME" "CAP_A"
					( Origin gPackager )
				)
				( attribute "CDS_PART_NAME" "CAP_A_0402V-1.0UF,6.3V,10%,X6SA"
					( Origin gPackager )
				)
				( objectStatus "C3N32" )
			)
			( gate "@baseboard_fab2_lib.baseboard_fab2(sch_1):page137_i67"
				( attribute "BOM_COST" "SB"
					( Origin gFrontEnd )
				)
				( attribute "CDS_LIB" "mstr_discrete"
					( Origin gPackager )
				)
				( attribute "CDS_LOCATION" "R7C13"
					( Origin gPackager )
				)
				( attribute "CDS_SEC" "1"
					( Origin gPackager )
				)
				( attribute "LOCATION" "R7C13"
					( Origin gFrontEnd )
				)
				( attribute "MATERIAL" "CHIP"
					( Origin gFrontEnd )
				)
				( attribute "PACK_TYPE" "0402"
					( Origin gFrontEnd )
				)
				( attribute "PART_NUMBER" "G21796-016"
					( Origin gFrontEnd )
				)
				( attribute "PHYS_PAGE" "137"
					( Origin gFrontEnd )
				)
				( attribute "ROOM" "SB"
					( Origin gFrontEnd )
				)
				( attribute "ROT" "0"
					( Origin gFrontEnd )
				)
				( attribute "SEC" "1"
					( Origin gFrontEnd )
				)
				( attribute "SEC_TYPE" "0402"
					( Origin gFrontEnd )
				)
				( attribute "TOLERANCE" "1%"
					( Origin gFrontEnd )
				)
				( attribute "VALUE" "10.0K"
					( Origin gFrontEnd )
				)
				( attribute "VER" "2"
					( Origin gFrontEnd )
				)
				( attribute "WATTAGE" "1/16W"
					( Origin gFrontEnd )
				)
				( attribute "XY" "(-2650,4225)"
					( Origin gFrontEnd )
				)
				( attribute "CHIPS_PART_NAME" "RES"
					( Origin gPackager )
				)
				( attribute "CDS_PART_NAME" "RES_0402-10.0K,1%,1/16W,CHIP,GA"
					( Origin gPackager )
				)
				( objectStatus "R7C13" )
			)
			( gate "@baseboard_fab2_lib.baseboard_fab2(sch_1):page137_i69"
				( attribute "BOM_COST" "SB"
					( Origin gFrontEnd )
				)
				( attribute "CDS_LIB" "mstr_discrete"
					( Origin gPackager )
				)
				( attribute "CDS_LOCATION" "R1U64"
					( Origin gPackager )
				)
				( attribute "CDS_SEC" "1"
					( Origin gPackager )
				)
				( attribute "LOCATION" "R1U64"
					( Origin gFrontEnd )
				)
				( attribute "MATERIAL" "CHIP"
					( Origin gFrontEnd )
				)
				( attribute "PACK_TYPE" "0402"
					( Origin gFrontEnd )
				)
				( attribute "PART_NUMBER" "G21796-026"
					( Origin gFrontEnd )
				)
				( attribute "PHYS_PAGE" "137"
					( Origin gFrontEnd )
				)
				( attribute "ROOM" "SB"
					( Origin gFrontEnd )
				)
				( attribute "ROT" "0"
					( Origin gFrontEnd )
				)
				( attribute "SEC" "1"
					( Origin gFrontEnd )
				)
				( attribute "SEC_TYPE" "0402"
					( Origin gFrontEnd )
				)
				( attribute "TOLERANCE" "1%"
					( Origin gFrontEnd )
				)
				( attribute "VALUE" "1.00K"
					( Origin gFrontEnd )
				)
				( attribute "VER" "2"
					( Origin gFrontEnd )
				)
				( attribute "WATTAGE" "1/16W"
					( Origin gFrontEnd )
				)
				( attribute "XY" "(-3150,3275)"
					( Origin gFrontEnd )
				)
				( attribute "CHIPS_PART_NAME" "RES"
					( Origin gPackager )
				)
				( attribute "CDS_PART_NAME" "RES_0402-1.00K,1%,1/16W,CHIP,GA"
					( Origin gPackager )
				)
				( objectStatus "R1U64" )
			)
			( gate "@baseboard_fab2_lib.baseboard_fab2(sch_1):page137_i128"
				( attribute "BOM_COST" "SB"
					( Origin gFrontEnd )
				)
				( attribute "CDS_LIB" "mstr_conn"
					( Origin gPackager )
				)
				( attribute "LOCATION" "J9G1"
					( Origin gFrontEnd )
				)
				( attribute "MATERIAL" "CONN"
					( Origin gFrontEnd )
				)
				( attribute "PACK_TYPE" "PIP"
					( Origin gFrontEnd )
				)
				( attribute "PART_NUMBER" "C73564-003"
					( Origin gFrontEnd )
				)
				( attribute "PHYS_PAGE" "137"
					( Origin gFrontEnd )
				)
				( attribute "ROOM" "SB"
					( Origin gFrontEnd )
				)
				( attribute "ROT" "0"
					( Origin gFrontEnd )
				)
				( attribute "SEC" "1"
					( Origin gFrontEnd )
				)
				( attribute "SEC_TYPE" "PIP"
					( Origin gFrontEnd )
				)
				( attribute "VER" "1"
					( Origin gFrontEnd )
				)
				( attribute "XY" "(-2175,3675)"
					( Origin gFrontEnd )
				)
				( attribute "CHIPS_PART_NAME" "CONN12_C73564003"
					( Origin gPackager )
				)
				( attribute "CDS_PART_NAME" "CONN12_C73564003_PIP-CONN,C735A"
					( Origin gPackager )
				)
				( attribute "CDS_LOCATION" "J9G1"
					( Origin gPackager )
				)
				( attribute "CDS_SEC" "1"
					( Origin gPackager )
				)
				( objectStatus "J9G1" )
			)
			( gate "@baseboard_fab2_lib.baseboard_fab2(sch_1):page138_i83"
				( attribute "BOM_COST" "SM_CONTROLLER"
					( Origin gFrontEnd )
				)
				( attribute "CDS_LIB" "mstr_discrete"
					( Origin gPackager )
				)
				( attribute "CDS_LOCATION" "R2T53"
					( Origin gPackager )
				)
				( attribute "CDS_SEC" "1"
					( Origin gPackager )
				)
				( attribute "LOCATION" "R2T53"
					( Origin gFrontEnd )
				)
				( attribute "MATERIAL" "CHIP"
					( Origin gFrontEnd )
				)
				( attribute "PACK_TYPE" "0402"
					( Origin gFrontEnd )
				)
				( attribute "PART_NUMBER" "G21796-235"
					( Origin gFrontEnd )
				)
				( attribute "PHYS_PAGE" "138"
					( Origin gFrontEnd )
				)
				( attribute "ROOM" "SMBUS"
					( Origin gFrontEnd )
				)
				( attribute "ROT" "0"
					( Origin gFrontEnd )
				)
				( attribute "SEC" "1"
					( Origin gFrontEnd )
				)
				( attribute "SEC_TYPE" "0402"
					( Origin gFrontEnd )
				)
				( attribute "TOLERANCE" "1.0%"
					( Origin gFrontEnd )
				)
				( attribute "VALUE" "665"
					( Origin gFrontEnd )
				)
				( attribute "VER" "2"
					( Origin gFrontEnd )
				)
				( attribute "WATTAGE" "1/16W"
					( Origin gFrontEnd )
				)
				( attribute "XY" "(500,4450)"
					( Origin gFrontEnd )
				)
				( attribute "CHIPS_PART_NAME" "RES"
					( Origin gPackager )
				)
				( attribute "CDS_PART_NAME" "RES_0402-665,1.0%,1/16W,CHIP,GA"
					( Origin gPackager )
				)
				( objectStatus "R2T53" )
			)
			( gate "@baseboard_fab2_lib.baseboard_fab2(sch_1):page138_i84"
				( attribute "BOM_COST" "SM_CONTROLLER"
					( Origin gFrontEnd )
				)
				( attribute "CDS_LIB" "mstr_discrete"
					( Origin gPackager )
				)
				( attribute "CDS_LOCATION" "R2T54"
					( Origin gPackager )
				)
				( attribute "CDS_SEC" "1"
					( Origin gPackager )
				)
				( attribute "LOCATION" "R2T54"
					( Origin gFrontEnd )
				)
				( attribute "MATERIAL" "CHIP"
					( Origin gFrontEnd )
				)
				( attribute "PACK_TYPE" "0402"
					( Origin gFrontEnd )
				)
				( attribute "PART_NUMBER" "G21796-235"
					( Origin gFrontEnd )
				)
				( attribute "PHYS_PAGE" "138"
					( Origin gFrontEnd )
				)
				( attribute "ROOM" "SMBUS"
					( Origin gFrontEnd )
				)
				( attribute "ROT" "0"
					( Origin gFrontEnd )
				)
				( attribute "SEC" "1"
					( Origin gFrontEnd )
				)
				( attribute "SEC_TYPE" "0402"
					( Origin gFrontEnd )
				)
				( attribute "TOLERANCE" "1.0%"
					( Origin gFrontEnd )
				)
				( attribute "VALUE" "665"
					( Origin gFrontEnd )
				)
				( attribute "VER" "2"
					( Origin gFrontEnd )
				)
				( attribute "WATTAGE" "1/16W"
					( Origin gFrontEnd )
				)
				( attribute "XY" "(850,4400)"
					( Origin gFrontEnd )
				)
				( attribute "CHIPS_PART_NAME" "RES"
					( Origin gPackager )
				)
				( attribute "CDS_PART_NAME" "RES_0402-665,1.0%,1/16W,CHIP,GA"
					( Origin gPackager )
				)
				( objectStatus "R2T54" )
			)
			( gate "@baseboard_fab2_lib.baseboard_fab2(sch_1):page138_i87"
				( attribute "BOM_COST" "SM_CONTROLLER"
					( Origin gFrontEnd )
				)
				( attribute "CDS_LIB" "mstr_discrete"
					( Origin gPackager )
				)
				( attribute "CDS_LOCATION" "R8D17"
					( Origin gPackager )
				)
				( attribute "LOCATION" "R8D17"
					( Origin gFrontEnd )
				)
				( attribute "MATERIAL" "CHIP"
					( Origin gFrontEnd )
				)
				( attribute "PACK_TYPE" "0402"
					( Origin gFrontEnd )
				)
				( attribute "PART_NUMBER" "G21796-095"
					( Origin gFrontEnd )
				)
				( attribute "PHYS_PAGE" "138"
					( Origin gFrontEnd )
				)
				( attribute "ROOM" "SMBUS"
					( Origin gFrontEnd )
				)
				( attribute "ROT" "0"
					( Origin gFrontEnd )
				)
				( attribute "SEC" "1"
					( Origin gFrontEnd )
				)
				( attribute "TOLERANCE" "1%"
					( Origin gFrontEnd )
				)
				( attribute "VALUE" "1.37K"
					( Origin gFrontEnd )
				)
				( attribute "VER" "2"
					( Origin gFrontEnd )
				)
				( attribute "WATTAGE" "1/16W"
					( Origin gFrontEnd )
				)
				( attribute "XY" "(500,2575)"
					( Origin gFrontEnd )
				)
				( attribute "CHIPS_PART_NAME" "RES"
					( Origin gPackager )
				)
				( attribute "CDS_PART_NAME" "RES_0402-1.37K,1%,1/16W,CHIP,GA"
					( Origin gPackager )
				)
				( attribute "SEC_TYPE" "0402"
					( Origin gFrontEnd )
				)
				( attribute "CDS_SEC" "1"
					( Origin gPackager )
				)
				( objectStatus "R8D17" )
			)
			( gate "@baseboard_fab2_lib.baseboard_fab2(sch_1):page138_i88"
				( attribute "BOM_COST" "SM_CONTROLLER"
					( Origin gFrontEnd )
				)
				( attribute "CDS_LIB" "mstr_discrete"
					( Origin gPackager )
				)
				( attribute "CDS_LOCATION" "R8D15"
					( Origin gPackager )
				)
				( attribute "LOCATION" "R8D15"
					( Origin gFrontEnd )
				)
				( attribute "MATERIAL" "CHIP"
					( Origin gFrontEnd )
				)
				( attribute "PACK_TYPE" "0402"
					( Origin gFrontEnd )
				)
				( attribute "PART_NUMBER" "G21796-095"
					( Origin gFrontEnd )
				)
				( attribute "PHYS_PAGE" "138"
					( Origin gFrontEnd )
				)
				( attribute "ROOM" "SMBUS"
					( Origin gFrontEnd )
				)
				( attribute "ROT" "0"
					( Origin gFrontEnd )
				)
				( attribute "SEC" "1"
					( Origin gFrontEnd )
				)
				( attribute "TOLERANCE" "1%"
					( Origin gFrontEnd )
				)
				( attribute "VALUE" "1.37K"
					( Origin gFrontEnd )
				)
				( attribute "VER" "2"
					( Origin gFrontEnd )
				)
				( attribute "WATTAGE" "1/16W"
					( Origin gFrontEnd )
				)
				( attribute "XY" "(875,2525)"
					( Origin gFrontEnd )
				)
				( attribute "CHIPS_PART_NAME" "RES"
					( Origin gPackager )
				)
				( attribute "CDS_PART_NAME" "RES_0402-1.37K,1%,1/16W,CHIP,GA"
					( Origin gPackager )
				)
				( attribute "SEC_TYPE" "0402"
					( Origin gFrontEnd )
				)
				( attribute "CDS_SEC" "1"
					( Origin gPackager )
				)
				( objectStatus "R8D15" )
			)
			( gate "@baseboard_fab2_lib.baseboard_fab2(sch_1):page138_i89"
				( attribute "BOM_COST" "SM_CONTROLLER"
					( Origin gFrontEnd )
				)
				( attribute "CDS_LIB" "mstr_discrete"
					( Origin gPackager )
				)
				( attribute "CDS_LOCATION" "R2N8"
					( Origin gPackager )
				)
				( attribute "CDS_SEC" "1"
					( Origin gPackager )
				)
				( attribute "LOCATION" "R2N8"
					( Origin gFrontEnd )
				)
				( attribute "MATERIAL" "CHIP"
					( Origin gFrontEnd )
				)
				( attribute "PACK_TYPE" "0402"
					( Origin gFrontEnd )
				)
				( attribute "PART_NUMBER" "G21796-235"
					( Origin gFrontEnd )
				)
				( attribute "PHYS_PAGE" "138"
					( Origin gFrontEnd )
				)
				( attribute "ROOM" "SMBUS"
					( Origin gFrontEnd )
				)
				( attribute "ROT" "0"
					( Origin gFrontEnd )
				)
				( attribute "SEC" "1"
					( Origin gFrontEnd )
				)
				( attribute "SEC_TYPE" "0402"
					( Origin gFrontEnd )
				)
				( attribute "TOLERANCE" "1.0%"
					( Origin gFrontEnd )
				)
				( attribute "VALUE" "665"
					( Origin gFrontEnd )
				)
				( attribute "VER" "2"
					( Origin gFrontEnd )
				)
				( attribute "WATTAGE" "1/16W"
					( Origin gFrontEnd )
				)
				( attribute "XY" "(-3175,4950)"
					( Origin gFrontEnd )
				)
				( attribute "CHIPS_PART_NAME" "RES"
					( Origin gPackager )
				)
				( attribute "CDS_PART_NAME" "RES_0402-665,1.0%,1/16W,CHIP,GA"
					( Origin gPackager )
				)
				( objectStatus "R2N8" )
			)
			( gate "@baseboard_fab2_lib.baseboard_fab2(sch_1):page138_i90"
				( attribute "BOM_COST" "SM_CONTROLLER"
					( Origin gFrontEnd )
				)
				( attribute "CDS_LIB" "mstr_discrete"
					( Origin gPackager )
				)
				( attribute "CDS_LOCATION" "R2N5"
					( Origin gPackager )
				)
				( attribute "CDS_SEC" "1"
					( Origin gPackager )
				)
				( attribute "LOCATION" "R2N5"
					( Origin gFrontEnd )
				)
				( attribute "MATERIAL" "CHIP"
					( Origin gFrontEnd )
				)
				( attribute "PACK_TYPE" "0402"
					( Origin gFrontEnd )
				)
				( attribute "PART_NUMBER" "G21796-235"
					( Origin gFrontEnd )
				)
				( attribute "PHYS_PAGE" "138"
					( Origin gFrontEnd )
				)
				( attribute "ROOM" "SMBUS"
					( Origin gFrontEnd )
				)
				( attribute "ROT" "0"
					( Origin gFrontEnd )
				)
				( attribute "SEC" "1"
					( Origin gFrontEnd )
				)
				( attribute "SEC_TYPE" "0402"
					( Origin gFrontEnd )
				)
				( attribute "TOLERANCE" "1.0%"
					( Origin gFrontEnd )
				)
				( attribute "VALUE" "665"
					( Origin gFrontEnd )
				)
				( attribute "VER" "2"
					( Origin gFrontEnd )
				)
				( attribute "WATTAGE" "1/16W"
					( Origin gFrontEnd )
				)
				( attribute "XY" "(-2775,4900)"
					( Origin gFrontEnd )
				)
				( attribute "CHIPS_PART_NAME" "RES"
					( Origin gPackager )
				)
				( attribute "CDS_PART_NAME" "RES_0402-665,1.0%,1/16W,CHIP,GA"
					( Origin gPackager )
				)
				( objectStatus "R2N5" )
			)
			( gate "@baseboard_fab2_lib.baseboard_fab2(sch_1):page138_i97"
				( attribute "BOM_COST" "SM_CONTROLLER"
					( Origin gFrontEnd )
				)
				( attribute "CDS_LIB" "mstr_discrete"
					( Origin gPackager )
				)
				( attribute "CDS_LOCATION" "R2U11"
					( Origin gPackager )
				)
				( attribute "CDS_SEC" "1"
					( Origin gPackager )
				)
				( attribute "LOCATION" "R2U11"
					( Origin gFrontEnd )
				)
				( attribute "MATERIAL" "CHIP"
					( Origin gFrontEnd )
				)
				( attribute "PACK_TYPE" "0402"
					( Origin gFrontEnd )
				)
				( attribute "PART_NUMBER" "G21796-235"
					( Origin gFrontEnd )
				)
				( attribute "PHYS_PAGE" "138"
					( Origin gFrontEnd )
				)
				( attribute "ROOM" "SMBUS"
					( Origin gFrontEnd )
				)
				( attribute "ROT" "0"
					( Origin gFrontEnd )
				)
				( attribute "SEC" "1"
					( Origin gFrontEnd )
				)
				( attribute "SEC_TYPE" "0402"
					( Origin gFrontEnd )
				)
				( attribute "TOLERANCE" "1.0%"
					( Origin gFrontEnd )
				)
				( attribute "VALUE" "665"
					( Origin gFrontEnd )
				)
				( attribute "VER" "2"
					( Origin gFrontEnd )
				)
				( attribute "WATTAGE" "1/16W"
					( Origin gFrontEnd )
				)
				( attribute "XY" "(-3150,2100)"
					( Origin gFrontEnd )
				)
				( attribute "CHIPS_PART_NAME" "RES"
					( Origin gPackager )
				)
				( attribute "CDS_PART_NAME" "RES_0402-665,1.0%,1/16W,CHIP,GA"
					( Origin gPackager )
				)
				( objectStatus "R2U11" )
			)
			( gate "@baseboard_fab2_lib.baseboard_fab2(sch_1):page138_i98"
				( attribute "BOM_COST" "SM_CONTROLLER"
					( Origin gFrontEnd )
				)
				( attribute "CDS_LIB" "mstr_discrete"
					( Origin gPackager )
				)
				( attribute "CDS_LOCATION" "R2U3"
					( Origin gPackager )
				)
				( attribute "CDS_SEC" "1"
					( Origin gPackager )
				)
				( attribute "LOCATION" "R2U3"
					( Origin gFrontEnd )
				)
				( attribute "MATERIAL" "CHIP"
					( Origin gFrontEnd )
				)
				( attribute "PACK_TYPE" "0402"
					( Origin gFrontEnd )
				)
				( attribute "PART_NUMBER" "G21796-235"
					( Origin gFrontEnd )
				)
				( attribute "PHYS_PAGE" "138"
					( Origin gFrontEnd )
				)
				( attribute "ROOM" "SMBUS"
					( Origin gFrontEnd )
				)
				( attribute "ROT" "0"
					( Origin gFrontEnd )
				)
				( attribute "SEC" "1"
					( Origin gFrontEnd )
				)
				( attribute "SEC_TYPE" "0402"
					( Origin gFrontEnd )
				)
				( attribute "TOLERANCE" "1.0%"
					( Origin gFrontEnd )
				)
				( attribute "VALUE" "665"
					( Origin gFrontEnd )
				)
				( attribute "VER" "2"
					( Origin gFrontEnd )
				)
				( attribute "WATTAGE" "1/16W"
					( Origin gFrontEnd )
				)
				( attribute "XY" "(-2750,2025)"
					( Origin gFrontEnd )
				)
				( attribute "CHIPS_PART_NAME" "RES"
					( Origin gPackager )
				)
				( attribute "CDS_PART_NAME" "RES_0402-665,1.0%,1/16W,CHIP,GA"
					( Origin gPackager )
				)
				( objectStatus "R2U3" )
			)
			( gate "@baseboard_fab2_lib.baseboard_fab2(sch_1):page138_i158"
				( attribute "BOM_COST" "SM_CONTROLLER"
					( Origin gFrontEnd )
				)
				( attribute "CDS_LIB" "mstr_discrete"
					( Origin gPackager )
				)
				( attribute "CDS_LOCATION" "R2U8"
					( Origin gPackager )
				)
				( attribute "CDS_SEC" "1"
					( Origin gPackager )
				)
				( attribute "LOCATION" "R2U8"
					( Origin gFrontEnd )
				)
				( attribute "MATERIAL" "EMPTY"
					( Origin gFrontEnd )
				)
				( attribute "PACK_TYPE" "0402"
					( Origin gFrontEnd )
				)
				( attribute "PART_NUMBER" "G21796-173"
					( Origin gFrontEnd )
				)
				( attribute "PHYS_PAGE" "138"
					( Origin gFrontEnd )
				)
				( attribute "ROOM" "SMBUS"
					( Origin gFrontEnd )
				)
				( attribute "ROT" "0"
					( Origin gFrontEnd )
				)
				( attribute "SEC" "1"
					( Origin gPackager )
				)
				( attribute "SKU" "A"
					( Origin gFrontEnd )
				)
				( attribute "TOLERANCE" "1%"
					( Origin gFrontEnd )
				)
				( attribute "VALUE" "20.0"
					( Origin gFrontEnd )
				)
				( attribute "VER" "1"
					( Origin gFrontEnd )
				)
				( attribute "WATTAGE" "1/16W"
					( Origin gFrontEnd )
				)
				( attribute "XY" "(-3100,1325)"
					( Origin gFrontEnd )
				)
				( attribute "CHIPS_PART_NAME" "RES"
					( Origin gPackager )
				)
				( attribute "CDS_PART_NAME" "RES_0402-20.0,1%,1/16W,EMPTY,GA"
					( Origin gPackager )
				)
				( objectStatus "R2U8" )
			)
			( gate "@baseboard_fab2_lib.baseboard_fab2(sch_1):page138_i159"
				( attribute "BOM_COST" "SM_CONTROLLER"
					( Origin gFrontEnd )
				)
				( attribute "CDS_LIB" "mstr_discrete"
					( Origin gPackager )
				)
				( attribute "CDS_LOCATION" "R2U12"
					( Origin gPackager )
				)
				( attribute "CDS_SEC" "1"
					( Origin gPackager )
				)
				( attribute "LOCATION" "R2U12"
					( Origin gFrontEnd )
				)
				( attribute "MATERIAL" "EMPTY"
					( Origin gFrontEnd )
				)
				( attribute "PACK_TYPE" "0402"
					( Origin gFrontEnd )
				)
				( attribute "PART_NUMBER" "G21796-173"
					( Origin gFrontEnd )
				)
				( attribute "PHYS_PAGE" "138"
					( Origin gFrontEnd )
				)
				( attribute "ROOM" "SMBUS"
					( Origin gFrontEnd )
				)
				( attribute "ROT" "0"
					( Origin gFrontEnd )
				)
				( attribute "SEC" "1"
					( Origin gPackager )
				)
				( attribute "SKU" "A"
					( Origin gFrontEnd )
				)
				( attribute "TOLERANCE" "1%"
					( Origin gFrontEnd )
				)
				( attribute "VALUE" "20.0"
					( Origin gFrontEnd )
				)
				( attribute "VER" "1"
					( Origin gFrontEnd )
				)
				( attribute "WATTAGE" "1/16W"
					( Origin gFrontEnd )
				)
				( attribute "XY" "(-3100,1425)"
					( Origin gFrontEnd )
				)
				( attribute "CHIPS_PART_NAME" "RES"
					( Origin gPackager )
				)
				( attribute "CDS_PART_NAME" "RES_0402-20.0,1%,1/16W,EMPTY,GA"
					( Origin gPackager )
				)
				( objectStatus "R2U12" )
			)
			( gate "@baseboard_fab2_lib.baseboard_fab2(sch_1):page247_i105"
				( attribute "CDS_LIB" "dev_discrete"
					( Origin gPackager )
				)
				( attribute "CDS_LOCATION" "C6W4"
					( Origin gPackager )
				)
				( attribute "CDS_SEC" "1"
					( Origin gPackager )
				)
				( attribute "LOCATION" "C6W4"
					( Origin gFrontEnd )
				)
				( attribute "MATERIAL" "X7R"
					( Origin gFrontEnd )
				)
				( attribute "PACK_TYPE" "0402V"
					( Origin gFrontEnd )
				)
				( attribute "PART_NUMBER" "A36096-030"
					( Origin gFrontEnd )
				)
				( attribute "PHYS_PAGE" "247"
					( Origin gFrontEnd )
				)
				( attribute "ROOM" "SMB_PE_HP_CPU1"
					( Origin gFrontEnd )
				)
				( attribute "ROT" "0"
					( Origin gFrontEnd )
				)
				( attribute "SEC" "1"
					( Origin gFrontEnd )
				)
				( attribute "SEC_TYPE" "0402V"
					( Origin gFrontEnd )
				)
				( attribute "TOLERANCE" "10%"
					( Origin gFrontEnd )
				)
				( attribute "VALUE" "0.1UF"
					( Origin gFrontEnd )
				)
				( attribute "VER" "1"
					( Origin gFrontEnd )
				)
				( attribute "VOLTAGE" "16V"
					( Units "uVoltage" "V" 1.000000)
					( Origin gFrontEnd )
				)
				( attribute "XY" "(-7250,1250)"
					( Origin gFrontEnd )
				)
				( attribute "CHIPS_PART_NAME" "CAP_A"
					( Origin gPackager )
				)
				( attribute "CDS_PART_NAME" "CAP_A_0402V-0.1UF,16V,10%,X7R,A"
					( Origin gPackager )
				)
				( objectStatus "C6W4" )
			)
			( gate "@baseboard_fab2_lib.baseboard_fab2(sch_1):page138_i163"
				( attribute "BOM_COST" "SM_CONTROLLER"
					( Origin gFrontEnd )
				)
				( attribute "CDS_LIB" "mstr_discrete"
					( Origin gPackager )
				)
				( attribute "CDS_LOCATION" "R8D7"
					( Origin gPackager )
				)
				( attribute "CDS_SEC" "1"
					( Origin gPackager )
				)
				( attribute "LOCATION" "R8D7"
					( Origin gFrontEnd )
				)
				( attribute "MATERIAL" "CHIP"
					( Origin gFrontEnd )
				)
				( attribute "PACK_TYPE" "0402"
					( Origin gFrontEnd )
				)
				( attribute "PART_NUMBER" "G21796-173"
					( Origin gFrontEnd )
				)
				( attribute "PHYS_PAGE" "138"
					( Origin gFrontEnd )
				)
				( attribute "ROOM" "SMBUS"
					( Origin gFrontEnd )
				)
				( attribute "ROT" "0"
					( Origin gFrontEnd )
				)
				( attribute "SEC" "1"
					( Origin gFrontEnd )
				)
				( attribute "SEC_TYPE" "0402"
					( Origin gFrontEnd )
				)
				( attribute "TOLERANCE" "1%"
					( Origin gFrontEnd )
				)
				( attribute "VALUE" "20.0"
					( Origin gFrontEnd )
				)
				( attribute "VER" "1"
					( Origin gFrontEnd )
				)
				( attribute "WATTAGE" "1/16W"
					( Origin gFrontEnd )
				)
				( attribute "XY" "(100,2275)"
					( Origin gFrontEnd )
				)
				( attribute "CHIPS_PART_NAME" "RES"
					( Origin gPackager )
				)
				( attribute "CDS_PART_NAME" "RES_0402-20.0,1%,1/16W,CHIP,G2A"
					( Origin gPackager )
				)
				( objectStatus "R8D7" )
			)
			( gate "@baseboard_fab2_lib.baseboard_fab2(sch_1):page138_i164"
				( attribute "BOM_COST" "SM_CONTROLLER"
					( Origin gFrontEnd )
				)
				( attribute "CDS_LIB" "mstr_discrete"
					( Origin gPackager )
				)
				( attribute "CDS_LOCATION" "R8D4"
					( Origin gPackager )
				)
				( attribute "CDS_SEC" "1"
					( Origin gPackager )
				)
				( attribute "LOCATION" "R8D4"
					( Origin gFrontEnd )
				)
				( attribute "MATERIAL" "CHIP"
					( Origin gFrontEnd )
				)
				( attribute "PACK_TYPE" "0402"
					( Origin gFrontEnd )
				)
				( attribute "PART_NUMBER" "G21796-173"
					( Origin gFrontEnd )
				)
				( attribute "PHYS_PAGE" "138"
					( Origin gFrontEnd )
				)
				( attribute "ROOM" "SMBUS"
					( Origin gFrontEnd )
				)
				( attribute "ROT" "0"
					( Origin gFrontEnd )
				)
				( attribute "SEC" "1"
					( Origin gFrontEnd )
				)
				( attribute "SEC_TYPE" "0402"
					( Origin gFrontEnd )
				)
				( attribute "TOLERANCE" "1%"
					( Origin gFrontEnd )
				)
				( attribute "VALUE" "20.0"
					( Origin gFrontEnd )
				)
				( attribute "VER" "1"
					( Origin gFrontEnd )
				)
				( attribute "WATTAGE" "1/16W"
					( Origin gFrontEnd )
				)
				( attribute "XY" "(100,2125)"
					( Origin gFrontEnd )
				)
				( attribute "CHIPS_PART_NAME" "RES"
					( Origin gPackager )
				)
				( attribute "CDS_PART_NAME" "RES_0402-20.0,1%,1/16W,CHIP,G2A"
					( Origin gPackager )
				)
				( objectStatus "R8D4" )
			)
			( gate "@baseboard_fab2_lib.baseboard_fab2(sch_1):page138_i165"
				( attribute "BOM_COST" "SM_CONTROLLER"
					( Origin gFrontEnd )
				)
				( attribute "CDS_LIB" "mstr_discrete"
					( Origin gPackager )
				)
				( attribute "CDS_LOCATION" "R2U9"
					( Origin gPackager )
				)
				( attribute "CDS_SEC" "1"
					( Origin gPackager )
				)
				( attribute "LOCATION" "R2U9"
					( Origin gFrontEnd )
				)
				( attribute "MATERIAL" "CHIP"
					( Origin gFrontEnd )
				)
				( attribute "PACK_TYPE" "0402"
					( Origin gFrontEnd )
				)
				( attribute "PART_NUMBER" "G21796-173"
					( Origin gFrontEnd )
				)
				( attribute "PHYS_PAGE" "138"
					( Origin gFrontEnd )
				)
				( attribute "ROOM" "SMBUS"
					( Origin gFrontEnd )
				)
				( attribute "ROT" "0"
					( Origin gFrontEnd )
				)
				( attribute "SEC" "1"
					( Origin gFrontEnd )
				)
				( attribute "SEC_TYPE" "0402"
					( Origin gFrontEnd )
				)
				( attribute "TOLERANCE" "1%"
					( Origin gFrontEnd )
				)
				( attribute "VALUE" "20.0"
					( Origin gFrontEnd )
				)
				( attribute "VER" "1"
					( Origin gFrontEnd )
				)
				( attribute "WATTAGE" "1/16W"
					( Origin gFrontEnd )
				)
				( attribute "XY" "(-3950,1775)"
					( Origin gFrontEnd )
				)
				( attribute "CHIPS_PART_NAME" "RES"
					( Origin gPackager )
				)
				( attribute "CDS_PART_NAME" "RES_0402-20.0,1%,1/16W,CHIP,G2A"
					( Origin gPackager )
				)
				( objectStatus "R2U9" )
			)
			( gate "@baseboard_fab2_lib.baseboard_fab2(sch_1):page138_i166"
				( attribute "BOM_COST" "SM_CONTROLLER"
					( Origin gFrontEnd )
				)
				( attribute "CDS_LIB" "mstr_discrete"
					( Origin gPackager )
				)
				( attribute "CDS_LOCATION" "R2U6"
					( Origin gPackager )
				)
				( attribute "CDS_SEC" "1"
					( Origin gPackager )
				)
				( attribute "LOCATION" "R2U6"
					( Origin gFrontEnd )
				)
				( attribute "MATERIAL" "CHIP"
					( Origin gFrontEnd )
				)
				( attribute "PACK_TYPE" "0402"
					( Origin gFrontEnd )
				)
				( attribute "PART_NUMBER" "G21796-173"
					( Origin gFrontEnd )
				)
				( attribute "PHYS_PAGE" "138"
					( Origin gFrontEnd )
				)
				( attribute "ROOM" "SMBUS"
					( Origin gFrontEnd )
				)
				( attribute "ROT" "0"
					( Origin gFrontEnd )
				)
				( attribute "SEC" "1"
					( Origin gFrontEnd )
				)
				( attribute "SEC_TYPE" "0402"
					( Origin gFrontEnd )
				)
				( attribute "TOLERANCE" "1%"
					( Origin gFrontEnd )
				)
				( attribute "VALUE" "20.0"
					( Origin gFrontEnd )
				)
				( attribute "VER" "1"
					( Origin gFrontEnd )
				)
				( attribute "WATTAGE" "1/16W"
					( Origin gFrontEnd )
				)
				( attribute "XY" "(-3950,1625)"
					( Origin gFrontEnd )
				)
				( attribute "CHIPS_PART_NAME" "RES"
					( Origin gPackager )
				)
				( attribute "CDS_PART_NAME" "RES_0402-20.0,1%,1/16W,CHIP,G2A"
					( Origin gPackager )
				)
				( objectStatus "R2U6" )
			)
			( gate "@baseboard_fab2_lib.baseboard_fab2(sch_1):page138_i167"
				( attribute "BOM_COST" "SM_CONTROLLER"
					( Origin gFrontEnd )
				)
				( attribute "CDS_LIB" "mstr_discrete"
					( Origin gPackager )
				)
				( attribute "CDS_LOCATION" "R8C20"
					( Origin gPackager )
				)
				( attribute "CDS_SEC" "1"
					( Origin gPackager )
				)
				( attribute "LOCATION" "R8C20"
					( Origin gFrontEnd )
				)
				( attribute "MATERIAL" "CHIP"
					( Origin gFrontEnd )
				)
				( attribute "PACK_TYPE" "0402"
					( Origin gFrontEnd )
				)
				( attribute "PART_NUMBER" "G21796-173"
					( Origin gFrontEnd )
				)
				( attribute "PHYS_PAGE" "138"
					( Origin gFrontEnd )
				)
				( attribute "ROOM" "SMBUS"
					( Origin gFrontEnd )
				)
				( attribute "ROT" "0"
					( Origin gFrontEnd )
				)
				( attribute "SEC" "1"
					( Origin gFrontEnd )
				)
				( attribute "SEC_TYPE" "0402"
					( Origin gFrontEnd )
				)
				( attribute "TOLERANCE" "1%"
					( Origin gFrontEnd )
				)
				( attribute "VALUE" "20.0"
					( Origin gFrontEnd )
				)
				( attribute "VER" "1"
					( Origin gFrontEnd )
				)
				( attribute "WATTAGE" "1/16W"
					( Origin gFrontEnd )
				)
				( attribute "XY" "(-3775,3700)"
					( Origin gFrontEnd )
				)
				( attribute "CHIPS_PART_NAME" "RES"
					( Origin gPackager )
				)
				( attribute "CDS_PART_NAME" "RES_0402-20.0,1%,1/16W,CHIP,G2A"
					( Origin gPackager )
				)
				( objectStatus "R8C20" )
			)
			( gate "@baseboard_fab2_lib.baseboard_fab2(sch_1):page138_i168"
				( attribute "BOM_COST" "SM_CONTROLLER"
					( Origin gFrontEnd )
				)
				( attribute "CDS_LIB" "mstr_discrete"
					( Origin gPackager )
				)
				( attribute "CDS_LOCATION" "R8C14"
					( Origin gPackager )
				)
				( attribute "CDS_SEC" "1"
					( Origin gPackager )
				)
				( attribute "LOCATION" "R8C14"
					( Origin gFrontEnd )
				)
				( attribute "MATERIAL" "CHIP"
					( Origin gFrontEnd )
				)
				( attribute "PACK_TYPE" "0402"
					( Origin gFrontEnd )
				)
				( attribute "PART_NUMBER" "G21796-173"
					( Origin gFrontEnd )
				)
				( attribute "PHYS_PAGE" "138"
					( Origin gFrontEnd )
				)
				( attribute "ROOM" "SMBUS"
					( Origin gFrontEnd )
				)
				( attribute "ROT" "0"
					( Origin gFrontEnd )
				)
				( attribute "SEC" "1"
					( Origin gFrontEnd )
				)
				( attribute "SEC_TYPE" "0402"
					( Origin gFrontEnd )
				)
				( attribute "TOLERANCE" "1%"
					( Origin gFrontEnd )
				)
				( attribute "VALUE" "20.0"
					( Origin gFrontEnd )
				)
				( attribute "VER" "1"
					( Origin gFrontEnd )
				)
				( attribute "WATTAGE" "1/16W"
					( Origin gFrontEnd )
				)
				( attribute "XY" "(-3775,3550)"
					( Origin gFrontEnd )
				)
				( attribute "CHIPS_PART_NAME" "RES"
					( Origin gPackager )
				)
				( attribute "CDS_PART_NAME" "RES_0402-20.0,1%,1/16W,CHIP,G2A"
					( Origin gPackager )
				)
				( objectStatus "R8C14" )
			)
			( gate "@baseboard_fab2_lib.baseboard_fab2(sch_1):page138_i169"
				( attribute "BOM_COST" "SM_CONTROLLER"
					( Origin gFrontEnd )
				)
				( attribute "CDS_LIB" "mstr_discrete"
					( Origin gPackager )
				)
				( attribute "CDS_LOCATION" "R8C11"
					( Origin gPackager )
				)
				( attribute "CDS_SEC" "1"
					( Origin gPackager )
				)
				( attribute "LOCATION" "R8C11"
					( Origin gFrontEnd )
				)
				( attribute "MATERIAL" "CHIP"
					( Origin gFrontEnd )
				)
				( attribute "PACK_TYPE" "0402"
					( Origin gFrontEnd )
				)
				( attribute "PART_NUMBER" "G21796-173"
					( Origin gFrontEnd )
				)
				( attribute "PHYS_PAGE" "138"
					( Origin gFrontEnd )
				)
				( attribute "ROOM" "SMBUS"
					( Origin gFrontEnd )
				)
				( attribute "ROT" "0"
					( Origin gFrontEnd )
				)
				( attribute "SEC" "1"
					( Origin gFrontEnd )
				)
				( attribute "SEC_TYPE" "0402"
					( Origin gFrontEnd )
				)
				( attribute "TOLERANCE" "1%"
					( Origin gFrontEnd )
				)
				( attribute "VALUE" "20.0"
					( Origin gFrontEnd )
				)
				( attribute "VER" "1"
					( Origin gFrontEnd )
				)
				( attribute "WATTAGE" "1/16W"
					( Origin gFrontEnd )
				)
				( attribute "XY" "(-3975,4625)"
					( Origin gFrontEnd )
				)
				( attribute "CHIPS_PART_NAME" "RES"
					( Origin gPackager )
				)
				( attribute "CDS_PART_NAME" "RES_0402-20.0,1%,1/16W,CHIP,G2A"
					( Origin gPackager )
				)
				( objectStatus "R8C11" )
			)
			( gate "@baseboard_fab2_lib.baseboard_fab2(sch_1):page138_i170"
				( attribute "BOM_COST" "SM_CONTROLLER"
					( Origin gFrontEnd )
				)
				( attribute "CDS_LIB" "mstr_discrete"
					( Origin gPackager )
				)
				( attribute "CDS_LOCATION" "R8C12"
					( Origin gPackager )
				)
				( attribute "CDS_SEC" "1"
					( Origin gPackager )
				)
				( attribute "LOCATION" "R8C12"
					( Origin gFrontEnd )
				)
				( attribute "MATERIAL" "CHIP"
					( Origin gFrontEnd )
				)
				( attribute "PACK_TYPE" "0402"
					( Origin gFrontEnd )
				)
				( attribute "PART_NUMBER" "G21796-173"
					( Origin gFrontEnd )
				)
				( attribute "PHYS_PAGE" "138"
					( Origin gFrontEnd )
				)
				( attribute "ROOM" "SMBUS"
					( Origin gFrontEnd )
				)
				( attribute "ROT" "0"
					( Origin gFrontEnd )
				)
				( attribute "SEC" "1"
					( Origin gFrontEnd )
				)
				( attribute "SEC_TYPE" "0402"
					( Origin gFrontEnd )
				)
				( attribute "TOLERANCE" "1%"
					( Origin gFrontEnd )
				)
				( attribute "VALUE" "20.0"
					( Origin gFrontEnd )
				)
				( attribute "VER" "1"
					( Origin gFrontEnd )
				)
				( attribute "WATTAGE" "1/16W"
					( Origin gFrontEnd )
				)
				( attribute "XY" "(-3975,4475)"
					( Origin gFrontEnd )
				)
				( attribute "CHIPS_PART_NAME" "RES"
					( Origin gPackager )
				)
				( attribute "CDS_PART_NAME" "RES_0402-20.0,1%,1/16W,CHIP,G2A"
					( Origin gPackager )
				)
				( objectStatus "R8C12" )
			)
			( gate "@baseboard_fab2_lib.baseboard_fab2(sch_1):page138_i171"
				( attribute "BOM_COST" "SM_CONTROLLER"
					( Origin gFrontEnd )
				)
				( attribute "CDS_LIB" "mstr_discrete"
					( Origin gPackager )
				)
				( attribute "CDS_LOCATION" "R2N20"
					( Origin gPackager )
				)
				( attribute "CDS_SEC" "1"
					( Origin gPackager )
				)
				( attribute "LOCATION" "R2N20"
					( Origin gFrontEnd )
				)
				( attribute "MATERIAL" "CHIP"
					( Origin gFrontEnd )
				)
				( attribute "PACK_TYPE" "0402"
					( Origin gFrontEnd )
				)
				( attribute "PART_NUMBER" "G21497-005"
					( Origin gFrontEnd )
				)
				( attribute "PHYS_PAGE" "138"
					( Origin gFrontEnd )
				)
				( attribute "ROOM" "SMBUS"
					( Origin gFrontEnd )
				)
				( attribute "ROT" "0"
					( Origin gFrontEnd )
				)
				( attribute "SEC" "1"
					( Origin gFrontEnd )
				)
				( attribute "SEC_TYPE" "0402"
					( Origin gFrontEnd )
				)
				( attribute "TOLERANCE" "5%"
					( Origin gFrontEnd )
				)
				( attribute "VALUE" "0.0"
					( Origin gFrontEnd )
				)
				( attribute "VER" "1"
					( Origin gFrontEnd )
				)
				( attribute "WATTAGE" "1/16W"
					( Origin gFrontEnd )
				)
				( attribute "XY" "(-3975,2150)"
					( Origin gFrontEnd )
				)
				( attribute "CHIPS_PART_NAME" "RES"
					( Origin gPackager )
				)
				( attribute "CDS_PART_NAME" "RES_0402-0.0,5%,1/16W,CHIP,G21A"
					( Origin gPackager )
				)
				( objectStatus "R2N20" )
			)
			( gate "@baseboard_fab2_lib.baseboard_fab2(sch_1):page138_i175"
				( attribute "BOM_COST" "SM_CONTROLLER"
					( Origin gFrontEnd )
				)
				( attribute "CDS_LIB" "mstr_discrete"
					( Origin gPackager )
				)
				( attribute "CDS_LOCATION" "R2N21"
					( Origin gPackager )
				)
				( attribute "CDS_SEC" "1"
					( Origin gPackager )
				)
				( attribute "LOCATION" "R2N21"
					( Origin gFrontEnd )
				)
				( attribute "MATERIAL" "CHIP"
					( Origin gFrontEnd )
				)
				( attribute "PACK_TYPE" "0402"
					( Origin gFrontEnd )
				)
				( attribute "PART_NUMBER" "G21497-005"
					( Origin gFrontEnd )
				)
				( attribute "PHYS_PAGE" "138"
					( Origin gFrontEnd )
				)
				( attribute "ROOM" "SMBUS"
					( Origin gFrontEnd )
				)
				( attribute "ROT" "0"
					( Origin gFrontEnd )
				)
				( attribute "SEC" "1"
					( Origin gFrontEnd )
				)
				( attribute "SEC_TYPE" "0402"
					( Origin gFrontEnd )
				)
				( attribute "TOLERANCE" "5%"
					( Origin gFrontEnd )
				)
				( attribute "VALUE" "0.0"
					( Origin gFrontEnd )
				)
				( attribute "VER" "1"
					( Origin gFrontEnd )
				)
				( attribute "WATTAGE" "1/16W"
					( Origin gFrontEnd )
				)
				( attribute "XY" "(-3975,2000)"
					( Origin gFrontEnd )
				)
				( attribute "CHIPS_PART_NAME" "RES"
					( Origin gPackager )
				)
				( attribute "CDS_PART_NAME" "RES_0402-0.0,5%,1/16W,CHIP,G21A"
					( Origin gPackager )
				)
				( objectStatus "R2N21" )
			)
			( gate "@baseboard_fab2_lib.baseboard_fab2(sch_1):page139_i72"
				( attribute "BOM_COST" "NT_GBE_BASE"
					( Origin gFrontEnd )
				)
				( attribute "CDS_LIB" "mstr_intel"
					( Origin gPackager )
				)
				( attribute "CDS_LOCATION" "EU9E1"
					( Origin gPackager )
				)
				( attribute "CDS_SEC" "1"
					( Origin gPackager )
				)
				( attribute "LOCATION" "EU9E1"
					( Origin gFrontEnd )
				)
				( attribute "MATERIAL" "IC"
					( Origin gFrontEnd )
				)
				( attribute "PACK_TYPE" "SM1"
					( Origin gFrontEnd )
				)
				( attribute "PART_NUMBER" "G47144-004"
					( Origin gFrontEnd )
				)
				( attribute "PHYS_PAGE" "139"
					( Origin gFrontEnd )
				)
				( attribute "ROOM" "NIC_SPRV"
					( Origin gFrontEnd )
				)
				( attribute "ROT" "0"
					( Origin gFrontEnd )
				)
				( attribute "SEC" "1"
					( Origin gFrontEnd )
				)
				( attribute "SEC_TYPE" "SM1"
					( Origin gFrontEnd )
				)
				( attribute "VER" "2"
					( Origin gFrontEnd )
				)
				( attribute "XY" "(-4200,3125)"
					( Origin gFrontEnd )
				)
				( attribute "CHIPS_PART_NAME" "SPRINGVILLE"
					( Origin gPackager )
				)
				( attribute "CDS_PART_NAME" "SPRINGVILLE_SM1-IC,G47144-004"
					( Origin gPackager )
				)
				( attribute "GROUP" "NI_I210&RJ45"
					( Origin gFrontEnd )
				)
				( objectStatus "EU9E1" )
			)
			( gate "@baseboard_fab2_lib.baseboard_fab2(sch_1):page139_i76"
				( attribute "BOM_COST" "NT_GBE_BASE"
					( Origin gFrontEnd )
				)
				( attribute "CDS_LIB" "mstr_discrete"
					( Origin gPackager )
				)
				( attribute "CDS_LOCATION" "C9E7"
					( Origin gPackager )
				)
				( attribute "CDS_SEC" "1"
					( Origin gPackager )
				)
				( attribute "LOCATION" "C9E7"
					( Origin gFrontEnd )
				)
				( attribute "MATERIAL" "X7R"
					( Origin gFrontEnd )
				)
				( attribute "PACK_TYPE" "0402LF"
					( Origin gFrontEnd )
				)
				( attribute "PART_NUMBER" "A36096-063"
					( Origin gFrontEnd )
				)
				( attribute "PHYS_PAGE" "139"
					( Origin gFrontEnd )
				)
				( attribute "ROOM" "NIC_SPRV"
					( Origin gFrontEnd )
				)
				( attribute "ROT" "0"
					( Origin gFrontEnd )
				)
				( attribute "SEC" "1"
					( Origin gFrontEnd )
				)
				( attribute "SEC_TYPE" "0402LF"
					( Origin gFrontEnd )
				)
				( attribute "TOLERANCE" "10%"
					( Origin gFrontEnd )
				)
				( attribute "VALUE" "0.039UF"
					( Origin gFrontEnd )
				)
				( attribute "VER" "1"
					( Origin gFrontEnd )
				)
				( attribute "VOLTAGE" "25V"
					( Units "uVoltage" "V" 1.000000)
					( Origin gFrontEnd )
				)
				( attribute "XY" "(-2725,3500)"
					( Origin gFrontEnd )
				)
				( attribute "CHIPS_PART_NAME" "CAP"
					( Origin gPackager )
				)
				( attribute "CDS_PART_NAME" "CAP_0402LF-0.039UF,25V,10%,X7RA"
					( Origin gPackager )
				)
				( attribute "GROUP" "NI_I210&RJ45"
					( Origin gFrontEnd )
				)
				( objectStatus "C9E7" )
			)
			( gate "@baseboard_fab2_lib.baseboard_fab2(sch_1):page139_i87"
				( attribute "BOM_COST" "NT_GBE_BASE"
					( Origin gFrontEnd )
				)
				( attribute "CDS_LIB" "dev_discrete"
					( Origin gPackager )
				)
				( attribute "CDS_LOCATION" "C9E5"
					( Origin gPackager )
				)
				( attribute "CDS_SEC" "1"
					( Origin gPackager )
				)
				( attribute "LOCATION" "C9E5"
					( Origin gFrontEnd )
				)
				( attribute "MATERIAL" "X7R"
					( Origin gFrontEnd )
				)
				( attribute "PACK_TYPE" "0402V"
					( Origin gFrontEnd )
				)
				( attribute "PART_NUMBER" "A36096-030"
					( Origin gFrontEnd )
				)
				( attribute "PHYS_PAGE" "139"
					( Origin gFrontEnd )
				)
				( attribute "ROOM" "NIC_SPRV"
					( Origin gFrontEnd )
				)
				( attribute "ROT" "0"
					( Origin gFrontEnd )
				)
				( attribute "SEC" "1"
					( Origin gFrontEnd )
				)
				( attribute "SEC_TYPE" "0402V"
					( Origin gFrontEnd )
				)
				( attribute "TOLERANCE" "10%"
					( Origin gFrontEnd )
				)
				( attribute "VALUE" "0.1UF"
					( Origin gFrontEnd )
				)
				( attribute "VER" "2"
					( Origin gFrontEnd )
				)
				( attribute "VOLTAGE" "16V"
					( Units "uVoltage" "V" 1.000000)
					( Origin gFrontEnd )
				)
				( attribute "XY" "(-1650,2075)"
					( Origin gFrontEnd )
				)
				( attribute "CHIPS_PART_NAME" "CAP_A"
					( Origin gPackager )
				)
				( attribute "CDS_PART_NAME" "CAP_A_0402V-0.1UF,16V,10%,X7R,A"
					( Origin gPackager )
				)
				( attribute "GROUP" "NI_I210&RJ45"
					( Origin gFrontEnd )
				)
				( objectStatus "C9E5" )
			)
			( gate "@baseboard_fab2_lib.baseboard_fab2(sch_1):page139_i88"
				( attribute "BOM_COST" "NT_GBE_BASE"
					( Origin gFrontEnd )
				)
				( attribute "CDS_LIB" "dev_discrete"
					( Origin gPackager )
				)
				( attribute "CDS_LOCATION" "C9E4"
					( Origin gPackager )
				)
				( attribute "CDS_SEC" "1"
					( Origin gPackager )
				)
				( attribute "LOCATION" "C9E4"
					( Origin gFrontEnd )
				)
				( attribute "MATERIAL" "X7R"
					( Origin gFrontEnd )
				)
				( attribute "PACK_TYPE" "0402V"
					( Origin gFrontEnd )
				)
				( attribute "PART_NUMBER" "A36096-030"
					( Origin gFrontEnd )
				)
				( attribute "PHYS_PAGE" "139"
					( Origin gFrontEnd )
				)
				( attribute "ROOM" "NIC_SPRV"
					( Origin gFrontEnd )
				)
				( attribute "ROT" "0"
					( Origin gFrontEnd )
				)
				( attribute "SEC" "1"
					( Origin gFrontEnd )
				)
				( attribute "SEC_TYPE" "0402V"
					( Origin gFrontEnd )
				)
				( attribute "TOLERANCE" "10%"
					( Origin gFrontEnd )
				)
				( attribute "VALUE" "0.1UF"
					( Origin gFrontEnd )
				)
				( attribute "VER" "2"
					( Origin gFrontEnd )
				)
				( attribute "VOLTAGE" "16V"
					( Units "uVoltage" "V" 1.000000)
					( Origin gFrontEnd )
				)
				( attribute "XY" "(-2400,2125)"
					( Origin gFrontEnd )
				)
				( attribute "CHIPS_PART_NAME" "CAP_A"
					( Origin gPackager )
				)
				( attribute "CDS_PART_NAME" "CAP_A_0402V-0.1UF,16V,10%,X7R,A"
					( Origin gPackager )
				)
				( attribute "GROUP" "NI_I210&RJ45"
					( Origin gFrontEnd )
				)
				( objectStatus "C9E4" )
			)
			( gate "@baseboard_fab2_lib.baseboard_fab2(sch_1):page139_i89"
				( attribute "BOM_COST" "NT_GBE_BASE"
					( Origin gFrontEnd )
				)
				( attribute "CDS_LIB" "dev_discrete"
					( Origin gPackager )
				)
				( attribute "CDS_LOCATION" "C2M23"
					( Origin gPackager )
				)
				( attribute "CDS_SEC" "1"
					( Origin gPackager )
				)
				( attribute "LOCATION" "C2M23"
					( Origin gFrontEnd )
				)
				( attribute "MATERIAL" "X7R"
					( Origin gFrontEnd )
				)
				( attribute "PACK_TYPE" "0402V"
					( Origin gFrontEnd )
				)
				( attribute "PART_NUMBER" "A36096-030"
					( Origin gFrontEnd )
				)
				( attribute "PHYS_PAGE" "139"
					( Origin gFrontEnd )
				)
				( attribute "ROOM" "NIC_SPRV"
					( Origin gFrontEnd )
				)
				( attribute "ROT" "0"
					( Origin gFrontEnd )
				)
				( attribute "SEC" "1"
					( Origin gFrontEnd )
				)
				( attribute "SEC_TYPE" "0402V"
					( Origin gFrontEnd )
				)
				( attribute "TOLERANCE" "10%"
					( Origin gFrontEnd )
				)
				( attribute "VALUE" "0.1UF"
					( Origin gFrontEnd )
				)
				( attribute "VER" "2"
					( Origin gFrontEnd )
				)
				( attribute "VOLTAGE" "16V"
					( Units "uVoltage" "V" 1.000000)
					( Origin gFrontEnd )
				)
				( attribute "XY" "(-5925,2125)"
					( Origin gFrontEnd )
				)
				( attribute "CHIPS_PART_NAME" "CAP_A"
					( Origin gPackager )
				)
				( attribute "CDS_PART_NAME" "CAP_A_0402V-0.1UF,16V,10%,X7R,A"
					( Origin gPackager )
				)
				( attribute "GROUP" "NI_I210&RJ45"
					( Origin gFrontEnd )
				)
				( objectStatus "C2M23" )
			)
			( gate "@baseboard_fab2_lib.baseboard_fab2(sch_1):page139_i90"
				( attribute "BOM_COST" "NT_GBE_BASE"
					( Origin gFrontEnd )
				)
				( attribute "CDS_LIB" "dev_discrete"
					( Origin gPackager )
				)
				( attribute "CDS_LOCATION" "C2M24"
					( Origin gPackager )
				)
				( attribute "CDS_SEC" "1"
					( Origin gPackager )
				)
				( attribute "LOCATION" "C2M24"
					( Origin gFrontEnd )
				)
				( attribute "MATERIAL" "X7R"
					( Origin gFrontEnd )
				)
				( attribute "PACK_TYPE" "0402V"
					( Origin gFrontEnd )
				)
				( attribute "PART_NUMBER" "A36096-030"
					( Origin gFrontEnd )
				)
				( attribute "PHYS_PAGE" "139"
					( Origin gFrontEnd )
				)
				( attribute "ROOM" "NIC_SPRV"
					( Origin gFrontEnd )
				)
				( attribute "ROT" "0"
					( Origin gFrontEnd )
				)
				( attribute "SEC" "1"
					( Origin gFrontEnd )
				)
				( attribute "SEC_TYPE" "0402V"
					( Origin gFrontEnd )
				)
				( attribute "TOLERANCE" "10%"
					( Origin gFrontEnd )
				)
				( attribute "VALUE" "0.1UF"
					( Origin gFrontEnd )
				)
				( attribute "VER" "2"
					( Origin gFrontEnd )
				)
				( attribute "VOLTAGE" "16V"
					( Units "uVoltage" "V" 1.000000)
					( Origin gFrontEnd )
				)
				( attribute "XY" "(-6150,2075)"
					( Origin gFrontEnd )
				)
				( attribute "CHIPS_PART_NAME" "CAP_A"
					( Origin gPackager )
				)
				( attribute "CDS_PART_NAME" "CAP_A_0402V-0.1UF,16V,10%,X7R,A"
					( Origin gPackager )
				)
				( attribute "GROUP" "NI_I210&RJ45"
					( Origin gFrontEnd )
				)
				( objectStatus "C2M24" )
			)
			( gate "@baseboard_fab2_lib.baseboard_fab2(sch_1):page139_i109"
				( attribute "BOM_COST" "NT_GBE_BASE"
					( Origin gFrontEnd )
				)
				( attribute "CDS_LIB" "mstr_discrete"
					( Origin gPackager )
				)
				( attribute "CDS_LOCATION" "Y9E1"
					( Origin gPackager )
				)
				( attribute "CDS_SEC" "1"
					( Origin gPackager )
				)
				( attribute "LOCATION" "Y9E1"
					( Origin gFrontEnd )
				)
				( attribute "MATERIAL" "IC"
					( Origin gFrontEnd )
				)
				( attribute "PACK_TYPE" "2013"
					( Origin gFrontEnd )
				)
				( attribute "PART_NUMBER" "D71700-057"
					( Origin gFrontEnd )
				)
				( attribute "PHYS_PAGE" "139"
					( Origin gFrontEnd )
				)
				( attribute "ROOM" "NIC_SPRV"
					( Origin gFrontEnd )
				)
				( attribute "ROT" "0"
					( Origin gFrontEnd )
				)
				( attribute "SEC" "1"
					( Origin gFrontEnd )
				)
				( attribute "SEC_TYPE" "2013"
					( Origin gFrontEnd )
				)
				( attribute "VALUE" "25.000MHZ"
					( Origin gFrontEnd )
				)
				( attribute "VER" "1"
					( Origin gFrontEnd )
				)
				( attribute "XY" "(-7525,1475)"
					( Origin gFrontEnd )
				)
				( attribute "CHIPS_PART_NAME" "CRYSTAL"
					( Origin gPackager )
				)
				( attribute "CDS_PART_NAME" "CRYSTAL_2013-25.000MHZ,IC,D717A"
					( Origin gPackager )
				)
				( attribute "GROUP" "NI_I210&RJ45"
					( Origin gFrontEnd )
				)
				( objectStatus "Y9E1" )
			)
			( gate "@baseboard_fab2_lib.baseboard_fab2(sch_1):page139_i110"
				( attribute "BOM_COST" "NT_GBE_BASE"
					( Origin gFrontEnd )
				)
				( attribute "CDS_LIB" "mstr_discrete"
					( Origin gPackager )
				)
				( attribute "CDS_LOCATION" "R9E20"
					( Origin gPackager )
				)
				( attribute "CDS_SEC" "1"
					( Origin gPackager )
				)
				( attribute "LOCATION" "R9E20"
					( Origin gFrontEnd )
				)
				( attribute "MATERIAL" "CHIP"
					( Origin gFrontEnd )
				)
				( attribute "PACK_TYPE" "0402"
					( Origin gFrontEnd )
				)
				( attribute "PART_NUMBER" "G21497-005"
					( Origin gFrontEnd )
				)
				( attribute "PHYS_PAGE" "139"
					( Origin gFrontEnd )
				)
				( attribute "ROOM" "NIC_SPRV"
					( Origin gFrontEnd )
				)
				( attribute "ROT" "0"
					( Origin gFrontEnd )
				)
				( attribute "SEC" "1"
					( Origin gFrontEnd )
				)
				( attribute "SEC_TYPE" "0402"
					( Origin gFrontEnd )
				)
				( attribute "TOLERANCE" "5%"
					( Origin gFrontEnd )
				)
				( attribute "VALUE" "0.0"
					( Origin gFrontEnd )
				)
				( attribute "VER" "1"
					( Origin gFrontEnd )
				)
				( attribute "WATTAGE" "1/16W"
					( Origin gFrontEnd )
				)
				( attribute "XY" "(-6800,1675)"
					( Origin gFrontEnd )
				)
				( attribute "CHIPS_PART_NAME" "RES"
					( Origin gPackager )
				)
				( attribute "CDS_PART_NAME" "RES_0402-0.0,5%,1/16W,CHIP,G21A"
					( Origin gPackager )
				)
				( attribute "GROUP" "NI_I210&RJ45"
					( Origin gFrontEnd )
				)
				( objectStatus "R9E20" )
			)
			( gate "@baseboard_fab2_lib.baseboard_fab2(sch_1):page185_i217"
				( attribute "BOM_COST" "PROC"
					( Origin gFrontEnd )
				)
				( attribute "CDS_LIB" "mstr_discrete"
					( Origin gPackager )
				)
				( attribute "LOCATION" "C32W5"
					( Origin gFrontEnd )
				)
				( attribute "MATERIAL" "X6S"
					( Origin gFrontEnd )
				)
				( attribute "PACK_TYPE" "0402"
					( Origin gFrontEnd )
				)
				( attribute "PART_NUMBER" "D97712-011"
					( Origin gFrontEnd )
				)
				( attribute "PHYS_PAGE" "185"
					( Origin gFrontEnd )
				)
				( attribute "ROOM" "PROC_SIDEBAND"
					( Origin gFrontEnd )
				)
				( attribute "ROT" "0"
					( Origin gFrontEnd )
				)
				( attribute "SEC" "1"
					( Origin gFrontEnd )
				)
				( attribute "SEC_TYPE" "0402"
					( Origin gFrontEnd )
				)
				( attribute "TOLERANCE" "10%"
					( Origin gFrontEnd )
				)
				( attribute "VALUE" "1.0UF"
					( Origin gFrontEnd )
				)
				( attribute "VER" "1"
					( Origin gFrontEnd )
				)
				( attribute "VOLTAGE" "16V"
					( Units "uVoltage" "V" 1.000000)
					( Origin gFrontEnd )
				)
				( attribute "XY" "(-7300,900)"
					( Origin gFrontEnd )
				)
				( attribute "CHIPS_PART_NAME" "CAP"
					( Origin gPackager )
				)
				( attribute "CDS_PART_NAME" "CAP_0402-1.0UF,16V,10%,X6S,D97A"
					( Origin gPackager )
				)
				( attribute "POP" "NOPOP"
					( Origin gFrontEnd )
				)
				( attribute "CDS_LOCATION" "C32W5"
					( Origin gPackager )
				)
				( attribute "CDS_SEC" "1"
					( Origin gPackager )
				)
				( objectStatus "C32W5" )
			)
			( gate "@baseboard_fab2_lib.baseboard_fab2(sch_1):page139_i128"
				( attribute "BOM_COST" "NT_GBE_BASE"
					( Origin gFrontEnd )
				)
				( attribute "CDS_LIB" "mstr_discrete"
					( Origin gPackager )
				)
				( attribute "CDS_LOCATION" "R9E9"
					( Origin gPackager )
				)
				( attribute "CDS_SEC" "1"
					( Origin gPackager )
				)
				( attribute "LOCATION" "R9E9"
					( Origin gFrontEnd )
				)
				( attribute "MATERIAL" "CHIP"
					( Origin gFrontEnd )
				)
				( attribute "PACK_TYPE" "0402"
					( Origin gFrontEnd )
				)
				( attribute "PART_NUMBER" "G21796-074"
					( Origin gFrontEnd )
				)
				( attribute "PHYS_PAGE" "139"
					( Origin gFrontEnd )
				)
				( attribute "ROOM" "NIC_SPRV"
					( Origin gFrontEnd )
				)
				( attribute "ROT" "0"
					( Origin gFrontEnd )
				)
				( attribute "SEC" "1"
					( Origin gFrontEnd )
				)
				( attribute "SEC_TYPE" "0402"
					( Origin gFrontEnd )
				)
				( attribute "TOLERANCE" "1%"
					( Origin gFrontEnd )
				)
				( attribute "VALUE" "33.2"
					( Origin gFrontEnd )
				)
				( attribute "VER" "1"
					( Origin gFrontEnd )
				)
				( attribute "WATTAGE" "1/16W"
					( Origin gFrontEnd )
				)
				( attribute "XY" "(-2400,2375)"
					( Origin gFrontEnd )
				)
				( attribute "CHIPS_PART_NAME" "RES"
					( Origin gPackager )
				)
				( attribute "CDS_PART_NAME" "RES_0402-33.2,1%,1/16W,CHIP,G2A"
					( Origin gPackager )
				)
				( attribute "GROUP" "NI_I210&RJ45"
					( Origin gFrontEnd )
				)
				( objectStatus "R9E9" )
			)
			( gate "@baseboard_fab2_lib.baseboard_fab2(sch_1):page139_i129"
				( attribute "BOM_COST" "NT_GBE_BASE"
					( Origin gFrontEnd )
				)
				( attribute "CDS_LIB" "mstr_discrete"
					( Origin gPackager )
				)
				( attribute "CDS_LOCATION" "R9E5"
					( Origin gPackager )
				)
				( attribute "CDS_SEC" "1"
					( Origin gPackager )
				)
				( attribute "LOCATION" "R9E5"
					( Origin gFrontEnd )
				)
				( attribute "MATERIAL" "CHIP"
					( Origin gFrontEnd )
				)
				( attribute "PACK_TYPE" "0402"
					( Origin gFrontEnd )
				)
				( attribute "PART_NUMBER" "G21796-074"
					( Origin gFrontEnd )
				)
				( attribute "PHYS_PAGE" "139"
					( Origin gFrontEnd )
				)
				( attribute "ROOM" "NIC_SPRV"
					( Origin gFrontEnd )
				)
				( attribute "ROT" "0"
					( Origin gFrontEnd )
				)
				( attribute "SEC" "1"
					( Origin gFrontEnd )
				)
				( attribute "SEC_TYPE" "0402"
					( Origin gFrontEnd )
				)
				( attribute "TOLERANCE" "1%"
					( Origin gFrontEnd )
				)
				( attribute "VALUE" "33.2"
					( Origin gFrontEnd )
				)
				( attribute "VER" "1"
					( Origin gFrontEnd )
				)
				( attribute "WATTAGE" "1/16W"
					( Origin gFrontEnd )
				)
				( attribute "XY" "(-1850,2325)"
					( Origin gFrontEnd )
				)
				( attribute "CHIPS_PART_NAME" "RES"
					( Origin gPackager )
				)
				( attribute "CDS_PART_NAME" "RES_0402-33.2,1%,1/16W,CHIP,G2A"
					( Origin gPackager )
				)
				( attribute "GROUP" "NI_I210&RJ45"
					( Origin gFrontEnd )
				)
				( objectStatus "R9E5" )
			)
			( gate "@baseboard_fab2_lib.baseboard_fab2(sch_1):page139_i130"
				( attribute "BOM_COST" "NT_GBE_BASE"
					( Origin gFrontEnd )
				)
				( attribute "CDS_LIB" "mstr_discrete"
					( Origin gPackager )
				)
				( attribute "CDS_LOCATION" "R9E8"
					( Origin gPackager )
				)
				( attribute "CDS_SEC" "1"
					( Origin gPackager )
				)
				( attribute "LOCATION" "R9E8"
					( Origin gFrontEnd )
				)
				( attribute "MATERIAL" "CHIP"
					( Origin gFrontEnd )
				)
				( attribute "PACK_TYPE" "0402"
					( Origin gFrontEnd )
				)
				( attribute "PART_NUMBER" "G21796-074"
					( Origin gFrontEnd )
				)
				( attribute "PHYS_PAGE" "139"
					( Origin gFrontEnd )
				)
				( attribute "ROOM" "NIC_SPRV"
					( Origin gFrontEnd )
				)
				( attribute "ROT" "0"
					( Origin gFrontEnd )
				)
				( attribute "SEC" "1"
					( Origin gFrontEnd )
				)
				( attribute "SEC_TYPE" "0402"
					( Origin gFrontEnd )
				)
				( attribute "TOLERANCE" "1%"
					( Origin gFrontEnd )
				)
				( attribute "VALUE" "33.2"
					( Origin gFrontEnd )
				)
				( attribute "VER" "1"
					( Origin gFrontEnd )
				)
				( attribute "WATTAGE" "1/16W"
					( Origin gFrontEnd )
				)
				( attribute "XY" "(-2400,2275)"
					( Origin gFrontEnd )
				)
				( attribute "CHIPS_PART_NAME" "RES"
					( Origin gPackager )
				)
				( attribute "CDS_PART_NAME" "RES_0402-33.2,1%,1/16W,CHIP,G2A"
					( Origin gPackager )
				)
				( attribute "GROUP" "NI_I210&RJ45"
					( Origin gFrontEnd )
				)
				( objectStatus "R9E8" )
			)
			( gate "@baseboard_fab2_lib.baseboard_fab2(sch_1):page139_i134"
				( attribute "BOM_COST" "NT_GBE_BASE"
					( Origin gFrontEnd )
				)
				( attribute "CDS_LIB" "mstr_discrete"
					( Origin gPackager )
				)
				( attribute "CDS_LOCATION" "C1T4"
					( Origin gPackager )
				)
				( attribute "CDS_SEC" "1"
					( Origin gPackager )
				)
				( attribute "LOCATION" "C1T4"
					( Origin gFrontEnd )
				)
				( attribute "MATERIAL" "X6S"
					( Origin gFrontEnd )
				)
				( attribute "PACK_TYPE" "0603"
					( Origin gFrontEnd )
				)
				( attribute "PART_NUMBER" "E15431-002"
					( Origin gFrontEnd )
				)
				( attribute "PHYS_PAGE" "139"
					( Origin gFrontEnd )
				)
				( attribute "ROOM" "NIC_SPRV"
					( Origin gFrontEnd )
				)
				( attribute "ROT" "0"
					( Origin gFrontEnd )
				)
				( attribute "SEC" "1"
					( Origin gFrontEnd )
				)
				( attribute "SEC_TYPE" "0603"
					( Origin gFrontEnd )
				)
				( attribute "TOLERANCE" "20%"
					( Origin gFrontEnd )
				)
				( attribute "VALUE" "10UF"
					( Origin gFrontEnd )
				)
				( attribute "VER" "1"
					( Origin gFrontEnd )
				)
				( attribute "VOLTAGE" "6.3V"
					( Units "uVoltage" "V" 1.000000)
					( Origin gFrontEnd )
				)
				( attribute "XY" "(-5975,4275)"
					( Origin gFrontEnd )
				)
				( attribute "CHIPS_PART_NAME" "CAP"
					( Origin gPackager )
				)
				( attribute "CDS_PART_NAME" "CAP_0603-10UF,6.3V,20%,X6S,E15A"
					( Origin gPackager )
				)
				( attribute "GROUP" "NI_I210&RJ45"
					( Origin gFrontEnd )
				)
				( objectStatus "C1T4" )
			)
			( gate "@baseboard_fab2_lib.baseboard_fab2(sch_1):page139_i135"
				( attribute "BOM_COST" "NT_GBE_BASE"
					( Origin gFrontEnd )
				)
				( attribute "CDS_LIB" "mstr_discrete"
					( Origin gPackager )
				)
				( attribute "CDS_LOCATION" "C1R30"
					( Origin gPackager )
				)
				( attribute "CDS_SEC" "1"
					( Origin gPackager )
				)
				( attribute "LOCATION" "C1R30"
					( Origin gFrontEnd )
				)
				( attribute "MATERIAL" "X6S"
					( Origin gFrontEnd )
				)
				( attribute "PACK_TYPE" "0603"
					( Origin gFrontEnd )
				)
				( attribute "PART_NUMBER" "E15431-002"
					( Origin gFrontEnd )
				)
				( attribute "PHYS_PAGE" "139"
					( Origin gFrontEnd )
				)
				( attribute "ROOM" "NIC_SPRV"
					( Origin gFrontEnd )
				)
				( attribute "ROT" "0"
					( Origin gFrontEnd )
				)
				( attribute "SEC" "1"
					( Origin gFrontEnd )
				)
				( attribute "SEC_TYPE" "0603"
					( Origin gFrontEnd )
				)
				( attribute "TOLERANCE" "20%"
					( Origin gFrontEnd )
				)
				( attribute "VALUE" "10UF"
					( Origin gFrontEnd )
				)
				( attribute "VER" "1"
					( Origin gFrontEnd )
				)
				( attribute "VOLTAGE" "6.3V"
					( Units "uVoltage" "V" 1.000000)
					( Origin gFrontEnd )
				)
				( attribute "XY" "(-6375,3975)"
					( Origin gFrontEnd )
				)
				( attribute "CHIPS_PART_NAME" "CAP"
					( Origin gPackager )
				)
				( attribute "CDS_PART_NAME" "CAP_0603-10UF,6.3V,20%,X6S,E15A"
					( Origin gPackager )
				)
				( attribute "GROUP" "NI_I210&RJ45"
					( Origin gFrontEnd )
				)
				( objectStatus "C1R30" )
			)
			( gate "@baseboard_fab2_lib.baseboard_fab2(sch_1):page139_i136"
				( attribute "BOM_COST" "NT_GBE_BASE"
					( Origin gFrontEnd )
				)
				( attribute "CDS_LIB" "mstr_discrete"
					( Origin gPackager )
				)
				( attribute "CDS_LOCATION" "C1R22"
					( Origin gPackager )
				)
				( attribute "CDS_SEC" "1"
					( Origin gPackager )
				)
				( attribute "LOCATION" "C1R22"
					( Origin gFrontEnd )
				)
				( attribute "MATERIAL" "X6S"
					( Origin gFrontEnd )
				)
				( attribute "PACK_TYPE" "0603"
					( Origin gFrontEnd )
				)
				( attribute "PART_NUMBER" "E15431-002"
					( Origin gFrontEnd )
				)
				( attribute "PHYS_PAGE" "139"
					( Origin gFrontEnd )
				)
				( attribute "ROOM" "NIC_SPRV"
					( Origin gFrontEnd )
				)
				( attribute "ROT" "0"
					( Origin gFrontEnd )
				)
				( attribute "SEC" "1"
					( Origin gFrontEnd )
				)
				( attribute "SEC_TYPE" "0603"
					( Origin gFrontEnd )
				)
				( attribute "TOLERANCE" "20%"
					( Origin gFrontEnd )
				)
				( attribute "VALUE" "10UF"
					( Origin gFrontEnd )
				)
				( attribute "VER" "1"
					( Origin gFrontEnd )
				)
				( attribute "VOLTAGE" "6.3V"
					( Units "uVoltage" "V" 1.000000)
					( Origin gFrontEnd )
				)
				( attribute "XY" "(-6950,3750)"
					( Origin gFrontEnd )
				)
				( attribute "CHIPS_PART_NAME" "CAP"
					( Origin gPackager )
				)
				( attribute "CDS_PART_NAME" "CAP_0603-10UF,6.3V,20%,X6S,E15A"
					( Origin gPackager )
				)
				( attribute "GROUP" "NI_I210&RJ45"
					( Origin gFrontEnd )
				)
				( objectStatus "C1R22" )
			)
			( gate "@baseboard_fab2_lib.baseboard_fab2(sch_1):page139_i142"
				( attribute "BOM_COST" "NT_GBE_BASE"
					( Origin gFrontEnd )
				)
				( attribute "CDS_LIB" "mstr_discrete"
					( Origin gPackager )
				)
				( attribute "CDS_LOCATION" "C1R13"
					( Origin gPackager )
				)
				( attribute "CDS_SEC" "1"
					( Origin gPackager )
				)
				( attribute "LOCATION" "C1R13"
					( Origin gFrontEnd )
				)
				( attribute "MATERIAL" "X6S"
					( Origin gFrontEnd )
				)
				( attribute "PACK_TYPE" "0603"
					( Origin gFrontEnd )
				)
				( attribute "PART_NUMBER" "E15431-002"
					( Origin gFrontEnd )
				)
				( attribute "PHYS_PAGE" "139"
					( Origin gFrontEnd )
				)
				( attribute "ROOM" "NIC_SPRV"
					( Origin gFrontEnd )
				)
				( attribute "ROT" "0"
					( Origin gFrontEnd )
				)
				( attribute "SEC" "1"
					( Origin gPackager )
				)
				( attribute "TOLERANCE" "20%"
					( Origin gFrontEnd )
				)
				( attribute "VALUE" "10UF"
					( Origin gFrontEnd )
				)
				( attribute "VER" "1"
					( Origin gFrontEnd )
				)
				( attribute "VOLTAGE" "6.3V"
					( Units "uVoltage" "V" 1.000000)
					( Origin gFrontEnd )
				)
				( attribute "XY" "(-5450,850)"
					( Origin gFrontEnd )
				)
				( attribute "CHIPS_PART_NAME" "CAP"
					( Origin gPackager )
				)
				( attribute "CDS_PART_NAME" "CAP_0603-10UF,6.3V,20%,X6S,E15A"
					( Origin gPackager )
				)
				( attribute "GROUP" "NI_I210&RJ45"
					( Origin gFrontEnd )
				)
				( objectStatus "C1R13" )
			)
			( gate "@baseboard_fab2_lib.baseboard_fab2(sch_1):page139_i143"
				( attribute "BOM_COST" "NT_GBE_BASE"
					( Origin gFrontEnd )
				)
				( attribute "CDS_LIB" "dev_discrete"
					( Origin gPackager )
				)
				( attribute "CDS_LOCATION" "C1R20"
					( Origin gPackager )
				)
				( attribute "CDS_SEC" "1"
					( Origin gPackager )
				)
				( attribute "LOCATION" "C1R20"
					( Origin gFrontEnd )
				)
				( attribute "MATERIAL" "X7R"
					( Origin gFrontEnd )
				)
				( attribute "PACK_TYPE" "0402V"
					( Origin gFrontEnd )
				)
				( attribute "PART_NUMBER" "A36096-030"
					( Origin gFrontEnd )
				)
				( attribute "PHYS_PAGE" "139"
					( Origin gFrontEnd )
				)
				( attribute "ROOM" "NIC_SPRV"
					( Origin gFrontEnd )
				)
				( attribute "ROT" "0"
					( Origin gFrontEnd )
				)
				( attribute "SEC" "1"
					( Origin gPackager )
				)
				( attribute "TOLERANCE" "10%"
					( Origin gFrontEnd )
				)
				( attribute "VALUE" "0.1UF"
					( Origin gFrontEnd )
				)
				( attribute "VER" "1"
					( Origin gFrontEnd )
				)
				( attribute "VOLTAGE" "16V"
					( Units "uVoltage" "V" 1.000000)
					( Origin gFrontEnd )
				)
				( attribute "XY" "(-5200,850)"
					( Origin gFrontEnd )
				)
				( attribute "CHIPS_PART_NAME" "CAP_A"
					( Origin gPackager )
				)
				( attribute "CDS_PART_NAME" "CAP_A_0402V-0.1UF,16V,10%,X7R,A"
					( Origin gPackager )
				)
				( attribute "GROUP" "NI_I210&RJ45"
					( Origin gFrontEnd )
				)
				( objectStatus "C1R20" )
			)
			( gate "@baseboard_fab2_lib.baseboard_fab2(sch_1):page139_i144"
				( attribute "BOM_COST" "NT_GBE_BASE"
					( Origin gFrontEnd )
				)
				( attribute "CDS_LIB" "dev_discrete"
					( Origin gPackager )
				)
				( attribute "CDS_LOCATION" "C1T3"
					( Origin gPackager )
				)
				( attribute "CDS_SEC" "1"
					( Origin gPackager )
				)
				( attribute "LOCATION" "C1T3"
					( Origin gFrontEnd )
				)
				( attribute "MATERIAL" "X7R"
					( Origin gFrontEnd )
				)
				( attribute "PACK_TYPE" "0402V"
					( Origin gFrontEnd )
				)
				( attribute "PART_NUMBER" "A36096-030"
					( Origin gFrontEnd )
				)
				( attribute "PHYS_PAGE" "139"
					( Origin gFrontEnd )
				)
				( attribute "ROOM" "NIC_SPRV"
					( Origin gFrontEnd )
				)
				( attribute "ROT" "0"
					( Origin gFrontEnd )
				)
				( attribute "SEC" "1"
					( Origin gPackager )
				)
				( attribute "TOLERANCE" "10%"
					( Origin gFrontEnd )
				)
				( attribute "VALUE" "0.1UF"
					( Origin gFrontEnd )
				)
				( attribute "VER" "1"
					( Origin gFrontEnd )
				)
				( attribute "VOLTAGE" "16V"
					( Units "uVoltage" "V" 1.000000)
					( Origin gFrontEnd )
				)
				( attribute "XY" "(-4950,850)"
					( Origin gFrontEnd )
				)
				( attribute "CHIPS_PART_NAME" "CAP_A"
					( Origin gPackager )
				)
				( attribute "CDS_PART_NAME" "CAP_A_0402V-0.1UF,16V,10%,X7R,A"
					( Origin gPackager )
				)
				( attribute "GROUP" "NI_I210&RJ45"
					( Origin gFrontEnd )
				)
				( objectStatus "C1T3" )
			)
			( gate "@baseboard_fab2_lib.baseboard_fab2(sch_1):page139_i145"
				( attribute "BOM_COST" "NT_GBE_BASE"
					( Origin gFrontEnd )
				)
				( attribute "CDS_LIB" "dev_discrete"
					( Origin gPackager )
				)
				( attribute "CDS_LOCATION" "C1R14"
					( Origin gPackager )
				)
				( attribute "CDS_SEC" "1"
					( Origin gPackager )
				)
				( attribute "LOCATION" "C1R14"
					( Origin gFrontEnd )
				)
				( attribute "MATERIAL" "X7R"
					( Origin gFrontEnd )
				)
				( attribute "PACK_TYPE" "0402V"
					( Origin gFrontEnd )
				)
				( attribute "PART_NUMBER" "A36096-030"
					( Origin gFrontEnd )
				)
				( attribute "PHYS_PAGE" "139"
					( Origin gFrontEnd )
				)
				( attribute "ROOM" "NIC_SPRV"
					( Origin gFrontEnd )
				)
				( attribute "ROT" "0"
					( Origin gFrontEnd )
				)
				( attribute "SEC" "1"
					( Origin gPackager )
				)
				( attribute "TOLERANCE" "10%"
					( Origin gFrontEnd )
				)
				( attribute "VALUE" "0.1UF"
					( Origin gFrontEnd )
				)
				( attribute "VER" "1"
					( Origin gFrontEnd )
				)
				( attribute "VOLTAGE" "16V"
					( Units "uVoltage" "V" 1.000000)
					( Origin gFrontEnd )
				)
				( attribute "XY" "(-4700,850)"
					( Origin gFrontEnd )
				)
				( attribute "CHIPS_PART_NAME" "CAP_A"
					( Origin gPackager )
				)
				( attribute "CDS_PART_NAME" "CAP_A_0402V-0.1UF,16V,10%,X7R,A"
					( Origin gPackager )
				)
				( attribute "GROUP" "NI_I210&RJ45"
					( Origin gFrontEnd )
				)
				( objectStatus "C1R14" )
			)
			( gate "@baseboard_fab2_lib.baseboard_fab2(sch_1):page139_i146"
				( attribute "BOM_COST" "NT_GBE_BASE"
					( Origin gFrontEnd )
				)
				( attribute "CDS_LIB" "dev_discrete"
					( Origin gPackager )
				)
				( attribute "CDS_LOCATION" "C1R21"
					( Origin gPackager )
				)
				( attribute "CDS_SEC" "1"
					( Origin gPackager )
				)
				( attribute "LOCATION" "C1R21"
					( Origin gFrontEnd )
				)
				( attribute "MATERIAL" "X7R"
					( Origin gFrontEnd )
				)
				( attribute "PACK_TYPE" "0402V"
					( Origin gFrontEnd )
				)
				( attribute "PART_NUMBER" "A36096-030"
					( Origin gFrontEnd )
				)
				( attribute "PHYS_PAGE" "139"
					( Origin gFrontEnd )
				)
				( attribute "ROOM" "NIC_SPRV"
					( Origin gFrontEnd )
				)
				( attribute "ROT" "0"
					( Origin gFrontEnd )
				)
				( attribute "SEC" "1"
					( Origin gPackager )
				)
				( attribute "TOLERANCE" "10%"
					( Origin gFrontEnd )
				)
				( attribute "VALUE" "0.1UF"
					( Origin gFrontEnd )
				)
				( attribute "VER" "1"
					( Origin gFrontEnd )
				)
				( attribute "VOLTAGE" "16V"
					( Units "uVoltage" "V" 1.000000)
					( Origin gFrontEnd )
				)
				( attribute "XY" "(-4450,850)"
					( Origin gFrontEnd )
				)
				( attribute "CHIPS_PART_NAME" "CAP_A"
					( Origin gPackager )
				)
				( attribute "CDS_PART_NAME" "CAP_A_0402V-0.1UF,16V,10%,X7R,A"
					( Origin gPackager )
				)
				( attribute "GROUP" "NI_I210&RJ45"
					( Origin gFrontEnd )
				)
				( objectStatus "C1R21" )
			)
			( gate "@baseboard_fab2_lib.baseboard_fab2(sch_1):page139_i149"
				( attribute "BOM_COST" "NT_GBE_BASE"
					( Origin gFrontEnd )
				)
				( attribute "CDS_LIB" "dev_discrete"
					( Origin gPackager )
				)
				( attribute "CDS_LOCATION" "C1R26"
					( Origin gPackager )
				)
				( attribute "CDS_SEC" "1"
					( Origin gPackager )
				)
				( attribute "LOCATION" "C1R26"
					( Origin gFrontEnd )
				)
				( attribute "MATERIAL" "X7R"
					( Origin gFrontEnd )
				)
				( attribute "PACK_TYPE" "0402V"
					( Origin gFrontEnd )
				)
				( attribute "PART_NUMBER" "A36096-030"
					( Origin gFrontEnd )
				)
				( attribute "PHYS_PAGE" "139"
					( Origin gFrontEnd )
				)
				( attribute "ROOM" "NIC_SPRV"
					( Origin gFrontEnd )
				)
				( attribute "ROT" "0"
					( Origin gFrontEnd )
				)
				( attribute "SEC" "1"
					( Origin gPackager )
				)
				( attribute "TOLERANCE" "10%"
					( Origin gFrontEnd )
				)
				( attribute "VALUE" "0.1UF"
					( Origin gFrontEnd )
				)
				( attribute "VER" "1"
					( Origin gFrontEnd )
				)
				( attribute "VOLTAGE" "16V"
					( Units "uVoltage" "V" 1.000000)
					( Origin gFrontEnd )
				)
				( attribute "XY" "(-2325,875)"
					( Origin gFrontEnd )
				)
				( attribute "CHIPS_PART_NAME" "CAP_A"
					( Origin gPackager )
				)
				( attribute "CDS_PART_NAME" "CAP_A_0402V-0.1UF,16V,10%,X7R,A"
					( Origin gPackager )
				)
				( attribute "GROUP" "NI_I210&RJ45"
					( Origin gFrontEnd )
				)
				( objectStatus "C1R26" )
			)
			( gate "@baseboard_fab2_lib.baseboard_fab2(sch_1):page139_i150"
				( attribute "BOM_COST" "NT_GBE_BASE"
					( Origin gFrontEnd )
				)
				( attribute "CDS_LIB" "dev_discrete"
					( Origin gPackager )
				)
				( attribute "CDS_LOCATION" "C1R29"
					( Origin gPackager )
				)
				( attribute "CDS_SEC" "1"
					( Origin gPackager )
				)
				( attribute "LOCATION" "C1R29"
					( Origin gFrontEnd )
				)
				( attribute "MATERIAL" "X7R"
					( Origin gFrontEnd )
				)
				( attribute "PACK_TYPE" "0402V"
					( Origin gFrontEnd )
				)
				( attribute "PART_NUMBER" "A36096-030"
					( Origin gFrontEnd )
				)
				( attribute "PHYS_PAGE" "139"
					( Origin gFrontEnd )
				)
				( attribute "ROOM" "NIC_SPRV"
					( Origin gFrontEnd )
				)
				( attribute "ROT" "0"
					( Origin gFrontEnd )
				)
				( attribute "SEC" "1"
					( Origin gPackager )
				)
				( attribute "TOLERANCE" "10%"
					( Origin gFrontEnd )
				)
				( attribute "VALUE" "0.1UF"
					( Origin gFrontEnd )
				)
				( attribute "VER" "1"
					( Origin gFrontEnd )
				)
				( attribute "VOLTAGE" "16V"
					( Units "uVoltage" "V" 1.000000)
					( Origin gFrontEnd )
				)
				( attribute "XY" "(-2575,875)"
					( Origin gFrontEnd )
				)
				( attribute "CHIPS_PART_NAME" "CAP_A"
					( Origin gPackager )
				)
				( attribute "CDS_PART_NAME" "CAP_A_0402V-0.1UF,16V,10%,X7R,A"
					( Origin gPackager )
				)
				( attribute "GROUP" "NI_I210&RJ45"
					( Origin gFrontEnd )
				)
				( objectStatus "C1R29" )
			)
			( gate "@baseboard_fab2_lib.baseboard_fab2(sch_1):page139_i151"
				( attribute "BOM_COST" "NT_GBE_BASE"
					( Origin gFrontEnd )
				)
				( attribute "CDS_LIB" "dev_discrete"
					( Origin gPackager )
				)
				( attribute "CDS_LOCATION" "C1R19"
					( Origin gPackager )
				)
				( attribute "CDS_SEC" "1"
					( Origin gPackager )
				)
				( attribute "LOCATION" "C1R19"
					( Origin gFrontEnd )
				)
				( attribute "MATERIAL" "X7R"
					( Origin gFrontEnd )
				)
				( attribute "PACK_TYPE" "0402V"
					( Origin gFrontEnd )
				)
				( attribute "PART_NUMBER" "A36096-030"
					( Origin gFrontEnd )
				)
				( attribute "PHYS_PAGE" "139"
					( Origin gFrontEnd )
				)
				( attribute "ROOM" "NIC_SPRV"
					( Origin gFrontEnd )
				)
				( attribute "ROT" "0"
					( Origin gFrontEnd )
				)
				( attribute "SEC" "1"
					( Origin gPackager )
				)
				( attribute "TOLERANCE" "10%"
					( Origin gFrontEnd )
				)
				( attribute "VALUE" "0.1UF"
					( Origin gFrontEnd )
				)
				( attribute "VER" "1"
					( Origin gFrontEnd )
				)
				( attribute "VOLTAGE" "16V"
					( Units "uVoltage" "V" 1.000000)
					( Origin gFrontEnd )
				)
				( attribute "XY" "(-2825,875)"
					( Origin gFrontEnd )
				)
				( attribute "CHIPS_PART_NAME" "CAP_A"
					( Origin gPackager )
				)
				( attribute "CDS_PART_NAME" "CAP_A_0402V-0.1UF,16V,10%,X7R,A"
					( Origin gPackager )
				)
				( attribute "GROUP" "NI_I210&RJ45"
					( Origin gFrontEnd )
				)
				( objectStatus "C1R19" )
			)
			( gate "@baseboard_fab2_lib.baseboard_fab2(sch_1):page139_i152"
				( attribute "BOM_COST" "NT_GBE_BASE"
					( Origin gFrontEnd )
				)
				( attribute "CDS_LIB" "dev_discrete"
					( Origin gPackager )
				)
				( attribute "CDS_LOCATION" "C1R31"
					( Origin gPackager )
				)
				( attribute "CDS_SEC" "1"
					( Origin gPackager )
				)
				( attribute "LOCATION" "C1R31"
					( Origin gFrontEnd )
				)
				( attribute "MATERIAL" "X7R"
					( Origin gFrontEnd )
				)
				( attribute "PACK_TYPE" "0402V"
					( Origin gFrontEnd )
				)
				( attribute "PART_NUMBER" "A36096-030"
					( Origin gFrontEnd )
				)
				( attribute "PHYS_PAGE" "139"
					( Origin gFrontEnd )
				)
				( attribute "ROOM" "NIC_SPRV"
					( Origin gFrontEnd )
				)
				( attribute "ROT" "0"
					( Origin gFrontEnd )
				)
				( attribute "SEC" "1"
					( Origin gPackager )
				)
				( attribute "TOLERANCE" "10%"
					( Origin gFrontEnd )
				)
				( attribute "VALUE" "0.1UF"
					( Origin gFrontEnd )
				)
				( attribute "VER" "1"
					( Origin gFrontEnd )
				)
				( attribute "VOLTAGE" "16V"
					( Units "uVoltage" "V" 1.000000)
					( Origin gFrontEnd )
				)
				( attribute "XY" "(-3075,875)"
					( Origin gFrontEnd )
				)
				( attribute "CHIPS_PART_NAME" "CAP_A"
					( Origin gPackager )
				)
				( attribute "CDS_PART_NAME" "CAP_A_0402V-0.1UF,16V,10%,X7R,A"
					( Origin gPackager )
				)
				( attribute "GROUP" "NI_I210&RJ45"
					( Origin gFrontEnd )
				)
				( objectStatus "C1R31" )
			)
			( gate "@baseboard_fab2_lib.baseboard_fab2(sch_1):page139_i153"
				( attribute "BOM_COST" "NT_GBE_BASE"
					( Origin gFrontEnd )
				)
				( attribute "CDS_LIB" "mstr_discrete"
					( Origin gPackager )
				)
				( attribute "CDS_LOCATION" "C1R17"
					( Origin gPackager )
				)
				( attribute "CDS_SEC" "1"
					( Origin gPackager )
				)
				( attribute "LOCATION" "C1R17"
					( Origin gFrontEnd )
				)
				( attribute "MATERIAL" "X6S"
					( Origin gFrontEnd )
				)
				( attribute "PACK_TYPE" "0603"
					( Origin gFrontEnd )
				)
				( attribute "PART_NUMBER" "E15431-002"
					( Origin gFrontEnd )
				)
				( attribute "PHYS_PAGE" "139"
					( Origin gFrontEnd )
				)
				( attribute "ROOM" "NIC_SPRV"
					( Origin gFrontEnd )
				)
				( attribute "ROT" "0"
					( Origin gFrontEnd )
				)
				( attribute "SEC" "1"
					( Origin gPackager )
				)
				( attribute "TOLERANCE" "20%"
					( Origin gFrontEnd )
				)
				( attribute "VALUE" "10UF"
					( Origin gFrontEnd )
				)
				( attribute "VER" "1"
					( Origin gFrontEnd )
				)
				( attribute "VOLTAGE" "6.3V"
					( Units "uVoltage" "V" 1.000000)
					( Origin gFrontEnd )
				)
				( attribute "XY" "(-3325,875)"
					( Origin gFrontEnd )
				)
				( attribute "CHIPS_PART_NAME" "CAP"
					( Origin gPackager )
				)
				( attribute "CDS_PART_NAME" "CAP_0603-10UF,6.3V,20%,X6S,E15A"
					( Origin gPackager )
				)
				( attribute "GROUP" "NI_I210&RJ45"
					( Origin gFrontEnd )
				)
				( objectStatus "C1R17" )
			)
			( gate "@baseboard_fab2_lib.baseboard_fab2(sch_1):page139_i157"
				( attribute "BOM_COST" "NT_GBE_BASE"
					( Origin gFrontEnd )
				)
				( attribute "CDS_LIB" "dev_discrete"
					( Origin gPackager )
				)
				( attribute "CDS_LOCATION" "C1R18"
					( Origin gPackager )
				)
				( attribute "CDS_SEC" "1"
					( Origin gPackager )
				)
				( attribute "LOCATION" "C1R18"
					( Origin gFrontEnd )
				)
				( attribute "MATERIAL" "X7R"
					( Origin gFrontEnd )
				)
				( attribute "PACK_TYPE" "0402V"
					( Origin gFrontEnd )
				)
				( attribute "PART_NUMBER" "A36096-030"
					( Origin gFrontEnd )
				)
				( attribute "PHYS_PAGE" "139"
					( Origin gFrontEnd )
				)
				( attribute "ROOM" "NIC_SPRV"
					( Origin gFrontEnd )
				)
				( attribute "ROT" "0"
					( Origin gFrontEnd )
				)
				( attribute "SEC" "1"
					( Origin gPackager )
				)
				( attribute "TOLERANCE" "10%"
					( Origin gFrontEnd )
				)
				( attribute "VALUE" "0.1UF"
					( Origin gFrontEnd )
				)
				( attribute "VER" "1"
					( Origin gFrontEnd )
				)
				( attribute "VOLTAGE" "16V"
					( Units "uVoltage" "V" 1.000000)
					( Origin gFrontEnd )
				)
				( attribute "XY" "(-350,875)"
					( Origin gFrontEnd )
				)
				( attribute "CHIPS_PART_NAME" "CAP_A"
					( Origin gPackager )
				)
				( attribute "CDS_PART_NAME" "CAP_A_0402V-0.1UF,16V,10%,X7R,A"
					( Origin gPackager )
				)
				( attribute "GROUP" "NI_I210&RJ45"
					( Origin gFrontEnd )
				)
				( objectStatus "C1R18" )
			)
			( gate "@baseboard_fab2_lib.baseboard_fab2(sch_1):page139_i158"
				( attribute "BOM_COST" "NT_GBE_BASE"
					( Origin gFrontEnd )
				)
				( attribute "CDS_LIB" "dev_discrete"
					( Origin gPackager )
				)
				( attribute "CDS_LOCATION" "C1T5"
					( Origin gPackager )
				)
				( attribute "CDS_SEC" "1"
					( Origin gPackager )
				)
				( attribute "LOCATION" "C1T5"
					( Origin gFrontEnd )
				)
				( attribute "MATERIAL" "X7R"
					( Origin gFrontEnd )
				)
				( attribute "PACK_TYPE" "0402V"
					( Origin gFrontEnd )
				)
				( attribute "PART_NUMBER" "A36096-030"
					( Origin gFrontEnd )
				)
				( attribute "PHYS_PAGE" "139"
					( Origin gFrontEnd )
				)
				( attribute "ROOM" "NIC_SPRV"
					( Origin gFrontEnd )
				)
				( attribute "ROT" "0"
					( Origin gFrontEnd )
				)
				( attribute "SEC" "1"
					( Origin gPackager )
				)
				( attribute "TOLERANCE" "10%"
					( Origin gFrontEnd )
				)
				( attribute "VALUE" "0.1UF"
					( Origin gFrontEnd )
				)
				( attribute "VER" "1"
					( Origin gFrontEnd )
				)
				( attribute "VOLTAGE" "16V"
					( Units "uVoltage" "V" 1.000000)
					( Origin gFrontEnd )
				)
				( attribute "XY" "(-600,875)"
					( Origin gFrontEnd )
				)
				( attribute "CHIPS_PART_NAME" "CAP_A"
					( Origin gPackager )
				)
				( attribute "CDS_PART_NAME" "CAP_A_0402V-0.1UF,16V,10%,X7R,A"
					( Origin gPackager )
				)
				( attribute "GROUP" "NI_I210&RJ45"
					( Origin gFrontEnd )
				)
				( objectStatus "C1T5" )
			)
			( gate "@baseboard_fab2_lib.baseboard_fab2(sch_1):page139_i159"
				( attribute "BOM_COST" "NT_GBE_BASE"
					( Origin gFrontEnd )
				)
				( attribute "CDS_LIB" "dev_discrete"
					( Origin gPackager )
				)
				( attribute "CDS_LOCATION" "C1R24"
					( Origin gPackager )
				)
				( attribute "CDS_SEC" "1"
					( Origin gPackager )
				)
				( attribute "LOCATION" "C1R24"
					( Origin gFrontEnd )
				)
				( attribute "MATERIAL" "X7R"
					( Origin gFrontEnd )
				)
				( attribute "PACK_TYPE" "0402V"
					( Origin gFrontEnd )
				)
				( attribute "PART_NUMBER" "A36096-030"
					( Origin gFrontEnd )
				)
				( attribute "PHYS_PAGE" "139"
					( Origin gFrontEnd )
				)
				( attribute "ROOM" "NIC_SPRV"
					( Origin gFrontEnd )
				)
				( attribute "ROT" "0"
					( Origin gFrontEnd )
				)
				( attribute "SEC" "1"
					( Origin gPackager )
				)
				( attribute "TOLERANCE" "10%"
					( Origin gFrontEnd )
				)
				( attribute "VALUE" "0.1UF"
					( Origin gFrontEnd )
				)
				( attribute "VER" "1"
					( Origin gFrontEnd )
				)
				( attribute "VOLTAGE" "16V"
					( Units "uVoltage" "V" 1.000000)
					( Origin gFrontEnd )
				)
				( attribute "XY" "(-850,875)"
					( Origin gFrontEnd )
				)
				( attribute "CHIPS_PART_NAME" "CAP_A"
					( Origin gPackager )
				)
				( attribute "CDS_PART_NAME" "CAP_A_0402V-0.1UF,16V,10%,X7R,A"
					( Origin gPackager )
				)
				( attribute "GROUP" "NI_I210&RJ45"
					( Origin gFrontEnd )
				)
				( objectStatus "C1R24" )
			)
			( gate "@baseboard_fab2_lib.baseboard_fab2(sch_1):page139_i160"
				( attribute "BOM_COST" "NT_GBE_BASE"
					( Origin gFrontEnd )
				)
				( attribute "CDS_LIB" "dev_discrete"
					( Origin gPackager )
				)
				( attribute "CDS_LOCATION" "C1R15"
					( Origin gPackager )
				)
				( attribute "CDS_SEC" "1"
					( Origin gPackager )
				)
				( attribute "LOCATION" "C1R15"
					( Origin gFrontEnd )
				)
				( attribute "MATERIAL" "X7R"
					( Origin gFrontEnd )
				)
				( attribute "PACK_TYPE" "0402V"
					( Origin gFrontEnd )
				)
				( attribute "PART_NUMBER" "A36096-030"
					( Origin gFrontEnd )
				)
				( attribute "PHYS_PAGE" "139"
					( Origin gFrontEnd )
				)
				( attribute "ROOM" "NIC_SPRV"
					( Origin gFrontEnd )
				)
				( attribute "ROT" "0"
					( Origin gFrontEnd )
				)
				( attribute "SEC" "1"
					( Origin gPackager )
				)
				( attribute "TOLERANCE" "10%"
					( Origin gFrontEnd )
				)
				( attribute "VALUE" "0.1UF"
					( Origin gFrontEnd )
				)
				( attribute "VER" "1"
					( Origin gFrontEnd )
				)
				( attribute "VOLTAGE" "16V"
					( Units "uVoltage" "V" 1.000000)
					( Origin gFrontEnd )
				)
				( attribute "XY" "(-1100,875)"
					( Origin gFrontEnd )
				)
				( attribute "CHIPS_PART_NAME" "CAP_A"
					( Origin gPackager )
				)
				( attribute "CDS_PART_NAME" "CAP_A_0402V-0.1UF,16V,10%,X7R,A"
					( Origin gPackager )
				)
				( attribute "GROUP" "NI_I210&RJ45"
					( Origin gFrontEnd )
				)
				( objectStatus "C1R15" )
			)
			( gate "@baseboard_fab2_lib.baseboard_fab2(sch_1):page139_i161"
				( attribute "BOM_COST" "NT_GBE_BASE"
					( Origin gFrontEnd )
				)
				( attribute "CDS_LIB" "mstr_discrete"
					( Origin gPackager )
				)
				( attribute "CDS_LOCATION" "C1R16"
					( Origin gPackager )
				)
				( attribute "CDS_SEC" "1"
					( Origin gPackager )
				)
				( attribute "LOCATION" "C1R16"
					( Origin gFrontEnd )
				)
				( attribute "MATERIAL" "X6S"
					( Origin gFrontEnd )
				)
				( attribute "PACK_TYPE" "0603"
					( Origin gFrontEnd )
				)
				( attribute "PART_NUMBER" "E15431-002"
					( Origin gFrontEnd )
				)
				( attribute "PHYS_PAGE" "139"
					( Origin gFrontEnd )
				)
				( attribute "ROOM" "NIC_SPRV"
					( Origin gFrontEnd )
				)
				( attribute "ROT" "0"
					( Origin gFrontEnd )
				)
				( attribute "SEC" "1"
					( Origin gPackager )
				)
				( attribute "TOLERANCE" "20%"
					( Origin gFrontEnd )
				)
				( attribute "VALUE" "10UF"
					( Origin gFrontEnd )
				)
				( attribute "VER" "1"
					( Origin gFrontEnd )
				)
				( attribute "VOLTAGE" "6.3V"
					( Units "uVoltage" "V" 1.000000)
					( Origin gFrontEnd )
				)
				( attribute "XY" "(-1350,875)"
					( Origin gFrontEnd )
				)
				( attribute "CHIPS_PART_NAME" "CAP"
					( Origin gPackager )
				)
				( attribute "CDS_PART_NAME" "CAP_0603-10UF,6.3V,20%,X6S,E15A"
					( Origin gPackager )
				)
				( attribute "GROUP" "NI_I210&RJ45"
					( Origin gFrontEnd )
				)
				( objectStatus "C1R16" )
			)
			( gate "@baseboard_fab2_lib.baseboard_fab2(sch_1):page139_i163"
				( attribute "BOM_COST" "NT_GBE_BASE"
					( Origin gFrontEnd )
				)
				( attribute "CDS_LIB" "dev_discrete"
					( Origin gPackager )
				)
				( attribute "CDS_LOCATION" "C9E1"
					( Origin gPackager )
				)
				( attribute "CDS_SEC" "1"
					( Origin gPackager )
				)
				( attribute "LOCATION" "C9E1"
					( Origin gFrontEnd )
				)
				( attribute "MATERIAL" "EMPTY"
					( Origin gFrontEnd )
				)
				( attribute "PACK_TYPE" "0603V"
					( Origin gFrontEnd )
				)
				( attribute "PART_NUMBER" "E15431-004"
					( Origin gFrontEnd )
				)
				( attribute "PHYS_PAGE" "139"
					( Origin gFrontEnd )
				)
				( attribute "ROOM" "NIC_SPRV"
					( Origin gFrontEnd )
				)
				( attribute "ROT" "0"
					( Origin gFrontEnd )
				)
				( attribute "SEC" "1"
					( Origin gFrontEnd )
				)
				( attribute "SEC_TYPE" "0603V"
					( Origin gFrontEnd )
				)
				( attribute "TOLERANCE" "20%"
					( Origin gFrontEnd )
				)
				( attribute "VALUE" "22.0UF"
					( Origin gFrontEnd )
				)
				( attribute "VER" "1"
					( Origin gFrontEnd )
				)
				( attribute "VOLTAGE" "4V"
					( Units "uVoltage" "V" 1.000000)
					( Origin gFrontEnd )
				)
				( attribute "XY" "(-1600,875)"
					( Origin gFrontEnd )
				)
				( attribute "CHIPS_PART_NAME" "CAP_A"
					( Origin gPackager )
				)
				( attribute "CDS_PART_NAME" "CAP_A_0603V-22.0UF,4V,20%,EMPTA"
					( Origin gPackager )
				)
				( attribute "GROUP" "NI_I210&RJ45"
					( Origin gFrontEnd )
				)
				( objectStatus "C9E1" )
			)
			( gate "@baseboard_fab2_lib.baseboard_fab2(sch_1):page139_i173"
				( attribute "BOM_COST" "NT_GBE_BASE"
					( Origin gFrontEnd )
				)
				( attribute "CDS_LIB" "mstr_discrete"
					( Origin gPackager )
				)
				( attribute "CDS_LOCATION" "R9F5"
					( Origin gPackager )
				)
				( attribute "CDS_SEC" "1"
					( Origin gPackager )
				)
				( attribute "LOCATION" "R9F5"
					( Origin gFrontEnd )
				)
				( attribute "MATERIAL" "CHIP"
					( Origin gFrontEnd )
				)
				( attribute "PACK_TYPE" "0402"
					( Origin gFrontEnd )
				)
				( attribute "PART_NUMBER" "G21796-027"
					( Origin gFrontEnd )
				)
				( attribute "PHYS_PAGE" "139"
					( Origin gFrontEnd )
				)
				( attribute "ROOM" "NIC_SPRV"
					( Origin gFrontEnd )
				)
				( attribute "ROT" "0"
					( Origin gFrontEnd )
				)
				( attribute "SEC" "1"
					( Origin gPackager )
				)
				( attribute "TOLERANCE" "1%"
					( Origin gFrontEnd )
				)
				( attribute "VALUE" "3.32K"
					( Origin gFrontEnd )
				)
				( attribute "VER" "2"
					( Origin gFrontEnd )
				)
				( attribute "WATTAGE" "1/16W"
					( Origin gFrontEnd )
				)
				( attribute "XY" "(-900,3825)"
					( Origin gFrontEnd )
				)
				( attribute "CHIPS_PART_NAME" "RES"
					( Origin gPackager )
				)
				( attribute "CDS_PART_NAME" "RES_0402-3.32K,1%,1/16W,CHIP,GA"
					( Origin gPackager )
				)
				( attribute "GROUP" "NI_I210&RJ45"
					( Origin gFrontEnd )
				)
				( objectStatus "R9F5" )
			)
			( gate "@baseboard_fab2_lib.baseboard_fab2(sch_1):page139_i174"
				( attribute "BOM_COST" "NT_GBE_BASE"
					( Origin gFrontEnd )
				)
				( attribute "CDS_LIB" "mstr_discrete"
					( Origin gPackager )
				)
				( attribute "CDS_LOCATION" "R9E23"
					( Origin gPackager )
				)
				( attribute "CDS_SEC" "1"
					( Origin gPackager )
				)
				( attribute "LOCATION" "R9E23"
					( Origin gFrontEnd )
				)
				( attribute "MATERIAL" "CHIP"
					( Origin gFrontEnd )
				)
				( attribute "PACK_TYPE" "0402"
					( Origin gFrontEnd )
				)
				( attribute "PART_NUMBER" "G21796-013"
					( Origin gFrontEnd )
				)
				( attribute "PHYS_PAGE" "139"
					( Origin gFrontEnd )
				)
				( attribute "ROOM" "NIC_SPRV"
					( Origin gFrontEnd )
				)
				( attribute "ROT" "0"
					( Origin gFrontEnd )
				)
				( attribute "SEC" "1"
					( Origin gFrontEnd )
				)
				( attribute "SEC_TYPE" "0402"
					( Origin gFrontEnd )
				)
				( attribute "TOLERANCE" "1%"
					( Origin gFrontEnd )
				)
				( attribute "VALUE" "4.99K"
					( Origin gFrontEnd )
				)
				( attribute "VER" "2"
					( Origin gFrontEnd )
				)
				( attribute "WATTAGE" "1/16W"
					( Origin gFrontEnd )
				)
				( attribute "XY" "(-900,3225)"
					( Origin gFrontEnd )
				)
				( attribute "CHIPS_PART_NAME" "RES"
					( Origin gPackager )
				)
				( attribute "CDS_PART_NAME" "RES_0402-4.99K,1%,1/16W,CHIP,GA"
					( Origin gPackager )
				)
				( attribute "GROUP" "NI_I210&RJ45"
					( Origin gFrontEnd )
				)
				( objectStatus "R9E23" )
			)
			( gate "@baseboard_fab2_lib.baseboard_fab2(sch_1):page139_i177"
				( attribute "BOM_COST" "NT_GBE_BASE"
					( Origin gFrontEnd )
				)
				( attribute "CDS_LIB" "mstr_discrete"
					( Origin gPackager )
				)
				( attribute "CDS_LOCATION" "R9E2"
					( Origin gPackager )
				)
				( attribute "CDS_SEC" "1"
					( Origin gPackager )
				)
				( attribute "LOCATION" "R9E2"
					( Origin gFrontEnd )
				)
				( attribute "MATERIAL" "CHIP"
					( Origin gFrontEnd )
				)
				( attribute "PACK_TYPE" "0402"
					( Origin gFrontEnd )
				)
				( attribute "PART_NUMBER" "G21796-016"
					( Origin gFrontEnd )
				)
				( attribute "PHYS_PAGE" "139"
					( Origin gFrontEnd )
				)
				( attribute "ROOM" "NIC_SPRV"
					( Origin gFrontEnd )
				)
				( attribute "ROT" "0"
					( Origin gFrontEnd )
				)
				( attribute "SEC" "1"
					( Origin gFrontEnd )
				)
				( attribute "SEC_TYPE" "0402"
					( Origin gFrontEnd )
				)
				( attribute "TOLERANCE" "1%"
					( Origin gFrontEnd )
				)
				( attribute "VALUE" "10.0K"
					( Origin gFrontEnd )
				)
				( attribute "VER" "2"
					( Origin gFrontEnd )
				)
				( attribute "WATTAGE" "1/16W"
					( Origin gFrontEnd )
				)
				( attribute "XY" "(-7200,3125)"
					( Origin gFrontEnd )
				)
				( attribute "CHIPS_PART_NAME" "RES"
					( Origin gPackager )
				)
				( attribute "CDS_PART_NAME" "RES_0402-10.0K,1%,1/16W,CHIP,GA"
					( Origin gPackager )
				)
				( attribute "GROUP" "NI_I210&RJ45"
					( Origin gFrontEnd )
				)
				( objectStatus "R9E2" )
			)
			( gate "@baseboard_fab2_lib.baseboard_fab2(sch_1):page139_i178"
				( attribute "BOM_COST" "NT_GBE_BASE"
					( Origin gFrontEnd )
				)
				( attribute "CDS_LIB" "mstr_discrete"
					( Origin gPackager )
				)
				( attribute "CDS_LOCATION" "R9E3"
					( Origin gPackager )
				)
				( attribute "CDS_SEC" "1"
					( Origin gPackager )
				)
				( attribute "LOCATION" "R9E3"
					( Origin gFrontEnd )
				)
				( attribute "MATERIAL" "CHIP"
					( Origin gFrontEnd )
				)
				( attribute "PACK_TYPE" "0402"
					( Origin gFrontEnd )
				)
				( attribute "PART_NUMBER" "G21796-016"
					( Origin gFrontEnd )
				)
				( attribute "PHYS_PAGE" "139"
					( Origin gFrontEnd )
				)
				( attribute "ROOM" "NIC_SPRV"
					( Origin gFrontEnd )
				)
				( attribute "ROT" "0"
					( Origin gFrontEnd )
				)
				( attribute "SEC" "1"
					( Origin gFrontEnd )
				)
				( attribute "SEC_TYPE" "0402"
					( Origin gFrontEnd )
				)
				( attribute "TOLERANCE" "1%"
					( Origin gFrontEnd )
				)
				( attribute "VALUE" "10.0K"
					( Origin gFrontEnd )
				)
				( attribute "VER" "2"
					( Origin gFrontEnd )
				)
				( attribute "WATTAGE" "1/16W"
					( Origin gFrontEnd )
				)
				( attribute "XY" "(-7475,3125)"
					( Origin gFrontEnd )
				)
				( attribute "CHIPS_PART_NAME" "RES"
					( Origin gPackager )
				)
				( attribute "CDS_PART_NAME" "RES_0402-10.0K,1%,1/16W,CHIP,GA"
					( Origin gPackager )
				)
				( attribute "GROUP" "NI_I210&RJ45"
					( Origin gFrontEnd )
				)
				( objectStatus "R9E3" )
			)
			( gate "@baseboard_fab2_lib.baseboard_fab2(sch_1):page139_i179"
				( attribute "BOM_COST" "NT_GBE_BASE"
					( Origin gFrontEnd )
				)
				( attribute "CDS_LIB" "mstr_discrete"
					( Origin gPackager )
				)
				( attribute "CDS_LOCATION" "R9E1"
					( Origin gPackager )
				)
				( attribute "CDS_SEC" "1"
					( Origin gPackager )
				)
				( attribute "LOCATION" "R9E1"
					( Origin gFrontEnd )
				)
				( attribute "MATERIAL" "CHIP"
					( Origin gFrontEnd )
				)
				( attribute "PACK_TYPE" "0402"
					( Origin gFrontEnd )
				)
				( attribute "PART_NUMBER" "G21796-016"
					( Origin gFrontEnd )
				)
				( attribute "PHYS_PAGE" "139"
					( Origin gFrontEnd )
				)
				( attribute "ROOM" "NIC_SPRV"
					( Origin gFrontEnd )
				)
				( attribute "ROT" "0"
					( Origin gFrontEnd )
				)
				( attribute "SEC" "1"
					( Origin gFrontEnd )
				)
				( attribute "SEC_TYPE" "0402"
					( Origin gFrontEnd )
				)
				( attribute "TOLERANCE" "1%"
					( Origin gFrontEnd )
				)
				( attribute "VALUE" "10.0K"
					( Origin gFrontEnd )
				)
				( attribute "VER" "2"
					( Origin gFrontEnd )
				)
				( attribute "WATTAGE" "1/16W"
					( Origin gFrontEnd )
				)
				( attribute "XY" "(-7750,3125)"
					( Origin gFrontEnd )
				)
				( attribute "CHIPS_PART_NAME" "RES"
					( Origin gPackager )
				)
				( attribute "CDS_PART_NAME" "RES_0402-10.0K,1%,1/16W,CHIP,GA"
					( Origin gPackager )
				)
				( attribute "GROUP" "NI_I210&RJ45"
					( Origin gFrontEnd )
				)
				( objectStatus "R9E1" )
			)
			( gate "@baseboard_fab2_lib.baseboard_fab2(sch_1):page139_i181"
				( attribute "BOM_COST" "NT_GBE_BASE"
					( Origin gFrontEnd )
				)
				( attribute "CDS_LIB" "mstr_discrete"
					( Origin gPackager )
				)
				( attribute "CDS_LOCATION" "R9E22"
					( Origin gPackager )
				)
				( attribute "CDS_SEC" "1"
					( Origin gPackager )
				)
				( attribute "LOCATION" "R9E22"
					( Origin gFrontEnd )
				)
				( attribute "MATERIAL" "CHIP"
					( Origin gFrontEnd )
				)
				( attribute "PACK_TYPE" "0402"
					( Origin gFrontEnd )
				)
				( attribute "PART_NUMBER" "G21796-016"
					( Origin gFrontEnd )
				)
				( attribute "PHYS_PAGE" "139"
					( Origin gFrontEnd )
				)
				( attribute "ROOM" "NIC_SPRV"
					( Origin gFrontEnd )
				)
				( attribute "ROT" "0"
					( Origin gFrontEnd )
				)
				( attribute "SEC" "1"
					( Origin gFrontEnd )
				)
				( attribute "SEC_TYPE" "0402"
					( Origin gFrontEnd )
				)
				( attribute "TOLERANCE" "1%"
					( Origin gFrontEnd )
				)
				( attribute "VALUE" "10.0K"
					( Origin gFrontEnd )
				)
				( attribute "VER" "1"
					( Origin gFrontEnd )
				)
				( attribute "WATTAGE" "1/16W"
					( Origin gFrontEnd )
				)
				( attribute "XY" "(-1500,2825)"
					( Origin gFrontEnd )
				)
				( attribute "CHIPS_PART_NAME" "RES"
					( Origin gPackager )
				)
				( attribute "CDS_PART_NAME" "RES_0402-10.0K,1%,1/16W,CHIP,GA"
					( Origin gPackager )
				)
				( attribute "GROUP" "NI_I210&RJ45"
					( Origin gFrontEnd )
				)
				( objectStatus "R9E22" )
			)
			( gate "@baseboard_fab2_lib.baseboard_fab2(sch_1):page139_i193"
				( attribute "BOM_COST" "NT_GBE_BASE"
					( Origin gFrontEnd )
				)
				( attribute "CDS_LIB" "mstr_discrete"
					( Origin gPackager )
				)
				( attribute "CDS_LOCATION" "R9E7"
					( Origin gPackager )
				)
				( attribute "CDS_SEC" "1"
					( Origin gPackager )
				)
				( attribute "LOCATION" "R9E7"
					( Origin gFrontEnd )
				)
				( attribute "MATERIAL" "CHIP"
					( Origin gFrontEnd )
				)
				( attribute "PACK_TYPE" "0402"
					( Origin gFrontEnd )
				)
				( attribute "PART_NUMBER" "G21796-027"
					( Origin gFrontEnd )
				)
				( attribute "PHYS_PAGE" "139"
					( Origin gFrontEnd )
				)
				( attribute "ROOM" "NIC_SPRV"
					( Origin gFrontEnd )
				)
				( attribute "ROT" "0"
					( Origin gFrontEnd )
				)
				( attribute "SEC" "1"
					( Origin gPackager )
				)
				( attribute "TOLERANCE" "1%"
					( Origin gFrontEnd )
				)
				( attribute "VALUE" "3.32K"
					( Origin gFrontEnd )
				)
				( attribute "VER" "2"
					( Origin gFrontEnd )
				)
				( attribute "WATTAGE" "1/16W"
					( Origin gFrontEnd )
				)
				( attribute "XY" "(-1000,4475)"
					( Origin gFrontEnd )
				)
				( attribute "CHIPS_PART_NAME" "RES"
					( Origin gPackager )
				)
				( attribute "CDS_PART_NAME" "RES_0402-3.32K,1%,1/16W,CHIP,GA"
					( Origin gPackager )
				)
				( objectStatus "R9E7" )
			)
			( gate "@baseboard_fab2_lib.baseboard_fab2(sch_1):page139_i195"
				( attribute "BOM_COST" "NT_GBE_BASE"
					( Origin gFrontEnd )
				)
				( attribute "CDS_LIB" "mstr_discrete"
					( Origin gPackager )
				)
				( attribute "CDS_LOCATION" "R1R1"
					( Origin gPackager )
				)
				( attribute "CDS_SEC" "1"
					( Origin gPackager )
				)
				( attribute "LOCATION" "R1R1"
					( Origin gFrontEnd )
				)
				( attribute "MATERIAL" "CHIP"
					( Origin gFrontEnd )
				)
				( attribute "PACK_TYPE" "0402"
					( Origin gFrontEnd )
				)
				( attribute "PART_NUMBER" "G21497-005"
					( Origin gFrontEnd )
				)
				( attribute "PHYS_PAGE" "139"
					( Origin gFrontEnd )
				)
				( attribute "ROOM" "NIC_SPRV"
					( Origin gFrontEnd )
				)
				( attribute "ROT" "0"
					( Origin gFrontEnd )
				)
				( attribute "SEC" "1"
					( Origin gFrontEnd )
				)
				( attribute "SEC_TYPE" "0402"
					( Origin gFrontEnd )
				)
				( attribute "TOLERANCE" "5%"
					( Origin gFrontEnd )
				)
				( attribute "VALUE" "0.0"
					( Origin gFrontEnd )
				)
				( attribute "VER" "1"
					( Origin gFrontEnd )
				)
				( attribute "WATTAGE" "1/16W"
					( Origin gFrontEnd )
				)
				( attribute "XY" "(-7075,350)"
					( Origin gFrontEnd )
				)
				( attribute "CHIPS_PART_NAME" "RES"
					( Origin gPackager )
				)
				( attribute "CDS_PART_NAME" "RES_0402-0.0,5%,1/16W,CHIP,G21A"
					( Origin gPackager )
				)
				( objectStatus "R1R1" )
			)
			( gate "@baseboard_fab2_lib.baseboard_fab2(sch_1):page139_i200"
				( attribute "BOM_COST" "NT_GBE_BASE"
					( Origin gFrontEnd )
				)
				( attribute "CDS_LIB" "mstr_discrete"
					( Origin gPackager )
				)
				( attribute "CDS_LOCATION" "R9E4"
					( Origin gPackager )
				)
				( attribute "CDS_SEC" "1"
					( Origin gPackager )
				)
				( attribute "LOCATION" "R9E4"
					( Origin gFrontEnd )
				)
				( attribute "MATERIAL" "CHIP"
					( Origin gFrontEnd )
				)
				( attribute "PACK_TYPE" "0402"
					( Origin gFrontEnd )
				)
				( attribute "PART_NUMBER" "G21796-016"
					( Origin gFrontEnd )
				)
				( attribute "PHYS_PAGE" "139"
					( Origin gFrontEnd )
				)
				( attribute "ROOM" "NIC_SPRV"
					( Origin gFrontEnd )
				)
				( attribute "ROT" "0"
					( Origin gFrontEnd )
				)
				( attribute "SEC" "1"
					( Origin gFrontEnd )
				)
				( attribute "SEC_TYPE" "0402"
					( Origin gFrontEnd )
				)
				( attribute "TOLERANCE" "1%"
					( Origin gFrontEnd )
				)
				( attribute "VALUE" "10.0K"
					( Origin gFrontEnd )
				)
				( attribute "VER" "2"
					( Origin gFrontEnd )
				)
				( attribute "WATTAGE" "1/16W"
					( Origin gFrontEnd )
				)
				( attribute "XY" "(-6925,550)"
					( Origin gFrontEnd )
				)
				( attribute "CHIPS_PART_NAME" "RES"
					( Origin gPackager )
				)
				( attribute "CDS_PART_NAME" "RES_0402-10.0K,1%,1/16W,CHIP,GA"
					( Origin gPackager )
				)
				( objectStatus "R9E4" )
			)
			( gate "@baseboard_fab2_lib.baseboard_fab2(sch_1):page139_i201"
				( attribute "BOM_COST" "NT_GBE_BASE"
					( Origin gFrontEnd )
				)
				( attribute "CDS_LIB" "mstr_discrete"
					( Origin gPackager )
				)
				( attribute "CDS_LOCATION" "R9E18"
					( Origin gPackager )
				)
				( attribute "CDS_SEC" "1"
					( Origin gPackager )
				)
				( attribute "LOCATION" "R9E18"
					( Origin gFrontEnd )
				)
				( attribute "MATERIAL" "CHIP"
					( Origin gFrontEnd )
				)
				( attribute "PACK_TYPE" "0402"
					( Origin gFrontEnd )
				)
				( attribute "PART_NUMBER" "G21497-005"
					( Origin gFrontEnd )
				)
				( attribute "PHYS_PAGE" "139"
					( Origin gFrontEnd )
				)
				( attribute "ROOM" "NIC_SPRV"
					( Origin gFrontEnd )
				)
				( attribute "ROT" "0"
					( Origin gFrontEnd )
				)
				( attribute "SEC" "1"
					( Origin gFrontEnd )
				)
				( attribute "SEC_TYPE" "0402"
					( Origin gFrontEnd )
				)
				( attribute "TOLERANCE" "5%"
					( Origin gFrontEnd )
				)
				( attribute "VALUE" "0.0"
					( Origin gFrontEnd )
				)
				( attribute "VER" "1"
					( Origin gFrontEnd )
				)
				( attribute "WATTAGE" "1/16W"
					( Origin gFrontEnd )
				)
				( attribute "XY" "(-6800,1575)"
					( Origin gFrontEnd )
				)
				( attribute "CHIPS_PART_NAME" "RES"
					( Origin gPackager )
				)
				( attribute "CDS_PART_NAME" "RES_0402-0.0,5%,1/16W,CHIP,G21A"
					( Origin gPackager )
				)
				( attribute "GROUP" "NI_I210&RJ45"
					( Origin gFrontEnd )
				)
				( objectStatus "R9E18" )
			)
			( gate "@baseboard_fab2_lib.baseboard_fab2(sch_1):page139_i212"
				( attribute "BOM_COST" "NT_GBE_BASE"
					( Origin gFrontEnd )
				)
				( attribute "CDS_LIB" "mstr_discrete"
					( Origin gPackager )
				)
				( attribute "CDS_LOCATION" "R9E13"
					( Origin gPackager )
				)
				( attribute "CDS_SEC" "1"
					( Origin gPackager )
				)
				( attribute "LOCATION" "R9E13"
					( Origin gFrontEnd )
				)
				( attribute "MATERIAL" "CHIP"
					( Origin gFrontEnd )
				)
				( attribute "PACK_TYPE" "0402"
					( Origin gFrontEnd )
				)
				( attribute "PART_NUMBER" "G21796-016"
					( Origin gFrontEnd )
				)
				( attribute "PHYS_PAGE" "139"
					( Origin gFrontEnd )
				)
				( attribute "ROOM" "NIC_SPRV"
					( Origin gFrontEnd )
				)
				( attribute "ROT" "0"
					( Origin gFrontEnd )
				)
				( attribute "SEC" "1"
					( Origin gPackager )
				)
				( attribute "TOLERANCE" "1%"
					( Origin gFrontEnd )
				)
				( attribute "VALUE" "10.0K"
					( Origin gFrontEnd )
				)
				( attribute "VER" "2"
					( Origin gFrontEnd )
				)
				( attribute "WATTAGE" "1/16W"
					( Origin gFrontEnd )
				)
				( attribute "XY" "(-1900,1650)"
					( Origin gFrontEnd )
				)
				( attribute "CHIPS_PART_NAME" "RES"
					( Origin gPackager )
				)
				( attribute "CDS_PART_NAME" "RES_0402-10.0K,1%,1/16W,CHIP,GA"
					( Origin gPackager )
				)
				( objectStatus "R9E13" )
			)
			( gate "@baseboard_fab2_lib.baseboard_fab2(sch_1):page139_i213"
				( attribute "BOM_COST" "NT_GBE_BASE"
					( Origin gFrontEnd )
				)
				( attribute "CDS_LIB" "mstr_discrete"
					( Origin gPackager )
				)
				( attribute "CDS_LOCATION" "R1R12"
					( Origin gPackager )
				)
				( attribute "CDS_SEC" "1"
					( Origin gPackager )
				)
				( attribute "LOCATION" "R1R12"
					( Origin gFrontEnd )
				)
				( attribute "MATERIAL" "CHIP"
					( Origin gFrontEnd )
				)
				( attribute "PACK_TYPE" "0402"
					( Origin gFrontEnd )
				)
				( attribute "PART_NUMBER" "G21796-016"
					( Origin gFrontEnd )
				)
				( attribute "PHYS_PAGE" "139"
					( Origin gFrontEnd )
				)
				( attribute "ROOM" "NIC_SPRV"
					( Origin gFrontEnd )
				)
				( attribute "ROT" "0"
					( Origin gFrontEnd )
				)
				( attribute "SEC" "1"
					( Origin gPackager )
				)
				( attribute "TOLERANCE" "1%"
					( Origin gFrontEnd )
				)
				( attribute "VALUE" "10.0K"
					( Origin gFrontEnd )
				)
				( attribute "VER" "2"
					( Origin gFrontEnd )
				)
				( attribute "WATTAGE" "1/16W"
					( Origin gFrontEnd )
				)
				( attribute "XY" "(-3050,1500)"
					( Origin gFrontEnd )
				)
				( attribute "CHIPS_PART_NAME" "RES"
					( Origin gPackager )
				)
				( attribute "CDS_PART_NAME" "RES_0402-10.0K,1%,1/16W,CHIP,GA"
					( Origin gPackager )
				)
				( attribute "GROUP" "NI_I210&RJ45"
					( Origin gFrontEnd )
				)
				( objectStatus "R1R12" )
			)
			( gate "@baseboard_fab2_lib.baseboard_fab2(sch_1):page139_i214"
				( attribute "BOM_COST" "NT_GBE_BASE"
					( Origin gFrontEnd )
				)
				( attribute "CDS_LIB" "mstr_discrete"
					( Origin gPackager )
				)
				( attribute "CDS_LOCATION" "R1T1"
					( Origin gPackager )
				)
				( attribute "CDS_SEC" "1"
					( Origin gPackager )
				)
				( attribute "LOCATION" "R1T1"
					( Origin gFrontEnd )
				)
				( attribute "MATERIAL" "CHIP"
					( Origin gFrontEnd )
				)
				( attribute "PACK_TYPE" "0402"
					( Origin gFrontEnd )
				)
				( attribute "PART_NUMBER" "G21796-016"
					( Origin gFrontEnd )
				)
				( attribute "PHYS_PAGE" "139"
					( Origin gFrontEnd )
				)
				( attribute "ROOM" "NIC_SPRV"
					( Origin gFrontEnd )
				)
				( attribute "ROT" "0"
					( Origin gFrontEnd )
				)
				( attribute "SEC" "1"
					( Origin gPackager )
				)
				( attribute "TOLERANCE" "1%"
					( Origin gFrontEnd )
				)
				( attribute "VALUE" "10.0K"
					( Origin gFrontEnd )
				)
				( attribute "VER" "2"
					( Origin gFrontEnd )
				)
				( attribute "WATTAGE" "1/16W"
					( Origin gFrontEnd )
				)
				( attribute "XY" "(-1300,1550)"
					( Origin gFrontEnd )
				)
				( attribute "CHIPS_PART_NAME" "RES"
					( Origin gPackager )
				)
				( attribute "CDS_PART_NAME" "RES_0402-10.0K,1%,1/16W,CHIP,GA"
					( Origin gPackager )
				)
				( objectStatus "R1T1" )
			)
			( gate "@baseboard_fab2_lib.baseboard_fab2(sch_1):page139_i225"
				( attribute "CDS_LIB" "mstr_discrete"
					( Origin gPackager )
				)
				( attribute "CDS_LOCATION" "R9F1"
					( Origin gPackager )
				)
				( attribute "CDS_SEC" "1"
					( Origin gPackager )
				)
				( attribute "LOCATION" "R9F1"
					( Origin gFrontEnd )
				)
				( attribute "MATERIAL" "CHIP"
					( Origin gFrontEnd )
				)
				( attribute "PACK_TYPE" "0402"
					( Origin gFrontEnd )
				)
				( attribute "PART_NUMBER" "G21796-250"
					( Origin gFrontEnd )
				)
				( attribute "PHYS_PAGE" "139"
					( Origin gFrontEnd )
				)
				( attribute "ROT" "0"
					( Origin gFrontEnd )
				)
				( attribute "SEC" "1"
					( Origin gPackager )
				)
				( attribute "TOLERANCE" "1.0%"
					( Origin gFrontEnd )
				)
				( attribute "VALUE" "22.1"
					( Origin gFrontEnd )
				)
				( attribute "VER" "1"
					( Origin gFrontEnd )
				)
				( attribute "WATTAGE" "1/16W"
					( Origin gFrontEnd )
				)
				( attribute "XY" "(-2400,2675)"
					( Origin gFrontEnd )
				)
				( attribute "CHIPS_PART_NAME" "RES"
					( Origin gPackager )
				)
				( attribute "CDS_PART_NAME" "RES_0402-22.1,1.0%,1/16W,CHIP,A"
					( Origin gPackager )
				)
				( attribute "GROUP" "NI_I210&RJ45"
					( Origin gFrontEnd )
				)
				( objectStatus "R9F1" )
			)
			( gate "@baseboard_fab2_lib.baseboard_fab2(sch_1):page139_i228"
				( attribute "BOM_COST" "SM_CONTROLLER"
					( Origin gFrontEnd )
				)
				( attribute "CDS_LIB" "mstr_discrete"
					( Origin gPackager )
				)
				( attribute "CDS_LOCATION" "R9E19"
					( Origin gPackager )
				)
				( attribute "CDS_SEC" "1"
					( Origin gPackager )
				)
				( attribute "LOCATION" "R9E19"
					( Origin gFrontEnd )
				)
				( attribute "MATERIAL" "CHIP"
					( Origin gFrontEnd )
				)
				( attribute "PACK_TYPE" "0402"
					( Origin gFrontEnd )
				)
				( attribute "PART_NUMBER" "G21796-250"
					( Origin gFrontEnd )
				)
				( attribute "PHYS_PAGE" "139"
					( Origin gFrontEnd )
				)
				( attribute "ROOM" "BMC"
					( Origin gFrontEnd )
				)
				( attribute "ROT" "0"
					( Origin gFrontEnd )
				)
				( attribute "SEC" "1"
					( Origin gFrontEnd )
				)
				( attribute "SEC_TYPE" "0402"
					( Origin gFrontEnd )
				)
				( attribute "TOLERANCE" "1.0%"
					( Origin gFrontEnd )
				)
				( attribute "VALUE" "22.1"
					( Origin gFrontEnd )
				)
				( attribute "VER" "1"
					( Origin gFrontEnd )
				)
				( attribute "WATTAGE" "1/16W"
					( Origin gFrontEnd )
				)
				( attribute "XY" "(-2275,2525)"
					( Origin gFrontEnd )
				)
				( attribute "CHIPS_PART_NAME" "RES"
					( Origin gPackager )
				)
				( attribute "CDS_PART_NAME" "RES_0402-22.1,1.0%,1/16W,CHIP,A"
					( Origin gPackager )
				)
				( attribute "GROUP" "NI_I210&RJ45"
					( Origin gFrontEnd )
				)
				( objectStatus "R9E19" )
			)
			( gate "@baseboard_fab2_lib.baseboard_fab2(sch_1):page139_i229"
				( attribute "BOM_COST" "SM_CONTROLLER"
					( Origin gFrontEnd )
				)
				( attribute "CDS_LIB" "mstr_discrete"
					( Origin gPackager )
				)
				( attribute "CDS_LOCATION" "R9E17"
					( Origin gPackager )
				)
				( attribute "CDS_SEC" "1"
					( Origin gPackager )
				)
				( attribute "LOCATION" "R9E17"
					( Origin gFrontEnd )
				)
				( attribute "MATERIAL" "CHIP"
					( Origin gFrontEnd )
				)
				( attribute "PACK_TYPE" "0402"
					( Origin gFrontEnd )
				)
				( attribute "PART_NUMBER" "G21796-250"
					( Origin gFrontEnd )
				)
				( attribute "PHYS_PAGE" "139"
					( Origin gFrontEnd )
				)
				( attribute "ROOM" "BMC"
					( Origin gFrontEnd )
				)
				( attribute "ROT" "0"
					( Origin gFrontEnd )
				)
				( attribute "SEC" "1"
					( Origin gFrontEnd )
				)
				( attribute "SEC_TYPE" "0402"
					( Origin gFrontEnd )
				)
				( attribute "TOLERANCE" "1.0%"
					( Origin gFrontEnd )
				)
				( attribute "VALUE" "22.1"
					( Origin gFrontEnd )
				)
				( attribute "VER" "1"
					( Origin gFrontEnd )
				)
				( attribute "WATTAGE" "1/16W"
					( Origin gFrontEnd )
				)
				( attribute "XY" "(-1900,2450)"
					( Origin gFrontEnd )
				)
				( attribute "CHIPS_PART_NAME" "RES"
					( Origin gPackager )
				)
				( attribute "CDS_PART_NAME" "RES_0402-22.1,1.0%,1/16W,CHIP,A"
					( Origin gPackager )
				)
				( attribute "GROUP" "NI_I210&RJ45"
					( Origin gFrontEnd )
				)
				( objectStatus "R9E17" )
			)
			( gate "@baseboard_fab2_lib.baseboard_fab2(sch_1):page139_i235"
				( attribute "CDS_LIB" "mstr_discrete"
					( Origin gPackager )
				)
				( attribute "CDS_LOCATION" "R9E16"
					( Origin gPackager )
				)
				( attribute "CDS_SEC" "1"
					( Origin gPackager )
				)
				( attribute "LOCATION" "R9E16"
					( Origin gFrontEnd )
				)
				( attribute "MATERIAL" "CHIP"
					( Origin gFrontEnd )
				)
				( attribute "PACK_TYPE" "0402"
					( Origin gFrontEnd )
				)
				( attribute "PART_NUMBER" "G21796-074"
					( Origin gFrontEnd )
				)
				( attribute "PHYS_PAGE" "139"
					( Origin gFrontEnd )
				)
				( attribute "ROOM" "SB"
					( Origin gFrontEnd )
				)
				( attribute "ROT" "0"
					( Origin gFrontEnd )
				)
				( attribute "SEC" "1"
					( Origin gFrontEnd )
				)
				( attribute "SEC_TYPE" "0402"
					( Origin gFrontEnd )
				)
				( attribute "TOLERANCE" "1%"
					( Origin gFrontEnd )
				)
				( attribute "VALUE" "33.2"
					( Origin gFrontEnd )
				)
				( attribute "VER" "1"
					( Origin gFrontEnd )
				)
				( attribute "WATTAGE" "1/16W"
					( Origin gFrontEnd )
				)
				( attribute "XY" "(-2075,2725)"
					( Origin gFrontEnd )
				)
				( attribute "CHIPS_PART_NAME" "RES"
					( Origin gPackager )
				)
				( attribute "CDS_PART_NAME" "RES_0402-33.2,1%,1/16W,CHIP,G2A"
					( Origin gPackager )
				)
				( attribute "GROUP" "NI_I210&RJ45"
					( Origin gFrontEnd )
				)
				( objectStatus "R9E16" )
			)
			( gate "@baseboard_fab2_lib.baseboard_fab2(sch_1):page139_i237"
				( attribute "BOM_COST" "NT_GBE_BASE"
					( Origin gFrontEnd )
				)
				( attribute "CDS_LIB" "mstr_discrete"
					( Origin gPackager )
				)
				( attribute "CDS_LOCATION" "R1R15"
					( Origin gPackager )
				)
				( attribute "CDS_SEC" "1"
					( Origin gPackager )
				)
				( attribute "LOCATION" "R1R15"
					( Origin gFrontEnd )
				)
				( attribute "MATERIAL" "CHIP"
					( Origin gFrontEnd )
				)
				( attribute "PACK_TYPE" "0603"
					( Origin gFrontEnd )
				)
				( attribute "PART_NUMBER" "G22178-002"
					( Origin gFrontEnd )
				)
				( attribute "PHYS_PAGE" "139"
					( Origin gFrontEnd )
				)
				( attribute "ROOM" "NIC_SPRV"
					( Origin gFrontEnd )
				)
				( attribute "ROT" "0"
					( Origin gFrontEnd )
				)
				( attribute "SEC" "1"
					( Origin gFrontEnd )
				)
				( attribute "SEC_TYPE" "0603"
					( Origin gFrontEnd )
				)
				( attribute "TOLERANCE" "5.0%"
					( Origin gFrontEnd )
				)
				( attribute "VALUE" "0"
					( Origin gFrontEnd )
				)
				( attribute "VER" "1"
					( Origin gFrontEnd )
				)
				( attribute "WATTAGE" "1/10W"
					( Origin gFrontEnd )
				)
				( attribute "XY" "(-5600,4025)"
					( Origin gFrontEnd )
				)
				( attribute "CHIPS_PART_NAME" "RES"
					( Origin gPackager )
				)
				( attribute "CDS_PART_NAME" "RES_0603-0,5.0%,1/10W,CHIP,G22A"
					( Origin gPackager )
				)
				( attribute "GROUP" "NI_I210&RJ45"
					( Origin gFrontEnd )
				)
				( objectStatus "R1R15" )
			)
			( gate "@baseboard_fab2_lib.baseboard_fab2(sch_1):page139_i238"
				( attribute "BOM_COST" "NT_GBE_BASE"
					( Origin gFrontEnd )
				)
				( attribute "CDS_LIB" "mstr_discrete"
					( Origin gPackager )
				)
				( attribute "CDS_LOCATION" "R1T32"
					( Origin gPackager )
				)
				( attribute "CDS_SEC" "1"
					( Origin gPackager )
				)
				( attribute "LOCATION" "R1T32"
					( Origin gFrontEnd )
				)
				( attribute "MATERIAL" "CHIP"
					( Origin gFrontEnd )
				)
				( attribute "PACK_TYPE" "0603"
					( Origin gFrontEnd )
				)
				( attribute "PART_NUMBER" "G22178-002"
					( Origin gFrontEnd )
				)
				( attribute "PHYS_PAGE" "139"
					( Origin gFrontEnd )
				)
				( attribute "ROOM" "NIC_SPRV"
					( Origin gFrontEnd )
				)
				( attribute "ROT" "0"
					( Origin gFrontEnd )
				)
				( attribute "SEC" "1"
					( Origin gFrontEnd )
				)
				( attribute "SEC_TYPE" "0603"
					( Origin gFrontEnd )
				)
				( attribute "TOLERANCE" "5.0%"
					( Origin gFrontEnd )
				)
				( attribute "VALUE" "0"
					( Origin gFrontEnd )
				)
				( attribute "VER" "1"
					( Origin gFrontEnd )
				)
				( attribute "WATTAGE" "1/10W"
					( Origin gFrontEnd )
				)
				( attribute "XY" "(-5800,3875)"
					( Origin gFrontEnd )
				)
				( attribute "CHIPS_PART_NAME" "RES"
					( Origin gPackager )
				)
				( attribute "CDS_PART_NAME" "RES_0603-0,5.0%,1/10W,CHIP,G22A"
					( Origin gPackager )
				)
				( attribute "GROUP" "NI_I210&RJ45"
					( Origin gFrontEnd )
				)
				( objectStatus "R1T32" )
			)
			( gate "@baseboard_fab2_lib.baseboard_fab2(sch_1):page139_i239"
				( attribute "BOM_COST" "NT_GBE_BASE"
					( Origin gFrontEnd )
				)
				( attribute "CDS_LIB" "mstr_discrete"
					( Origin gPackager )
				)
				( attribute "CDS_LOCATION" "R1T34"
					( Origin gPackager )
				)
				( attribute "CDS_SEC" "1"
					( Origin gPackager )
				)
				( attribute "LOCATION" "R1T34"
					( Origin gFrontEnd )
				)
				( attribute "MATERIAL" "CHIP"
					( Origin gFrontEnd )
				)
				( attribute "PACK_TYPE" "0603"
					( Origin gFrontEnd )
				)
				( attribute "PART_NUMBER" "G22178-002"
					( Origin gFrontEnd )
				)
				( attribute "PHYS_PAGE" "139"
					( Origin gFrontEnd )
				)
				( attribute "ROOM" "NIC_SPRV"
					( Origin gFrontEnd )
				)
				( attribute "ROT" "0"
					( Origin gFrontEnd )
				)
				( attribute "SEC" "1"
					( Origin gFrontEnd )
				)
				( attribute "SEC_TYPE" "0603"
					( Origin gFrontEnd )
				)
				( attribute "TOLERANCE" "5.0%"
					( Origin gFrontEnd )
				)
				( attribute "VALUE" "0"
					( Origin gFrontEnd )
				)
				( attribute "VER" "1"
					( Origin gFrontEnd )
				)
				( attribute "WATTAGE" "1/10W"
					( Origin gFrontEnd )
				)
				( attribute "XY" "(-5600,3525)"
					( Origin gFrontEnd )
				)
				( attribute "CHIPS_PART_NAME" "RES"
					( Origin gPackager )
				)
				( attribute "CDS_PART_NAME" "RES_0603-0,5.0%,1/10W,CHIP,G22A"
					( Origin gPackager )
				)
				( attribute "GROUP" "NI_I210&RJ45"
					( Origin gFrontEnd )
				)
				( objectStatus "R1T34" )
			)
			( gate "@baseboard_fab2_lib.baseboard_fab2(sch_1):page139_i240"
				( attribute "BOM_COST" "NT_GBE_BASE"
					( Origin gFrontEnd )
				)
				( attribute "CDS_LIB" "mstr_discrete"
					( Origin gPackager )
				)
				( attribute "CDS_LOCATION" "R1T33"
					( Origin gPackager )
				)
				( attribute "LOCATION" "R1T33"
					( Origin gFrontEnd )
				)
				( attribute "MATERIAL" "EMPTY"
					( Origin gFrontEnd )
				)
				( attribute "PACK_TYPE" "0603"
					( Origin gFrontEnd )
				)
				( attribute "PART_NUMBER" "G22178-002"
					( Origin gFrontEnd )
				)
				( attribute "PHYS_PAGE" "139"
					( Origin gFrontEnd )
				)
				( attribute "ROOM" "NIC_SPRV"
					( Origin gFrontEnd )
				)
				( attribute "ROT" "0"
					( Origin gFrontEnd )
				)
				( attribute "SEC" "1"
					( Origin gFrontEnd )
				)
				( attribute "SEC_TYPE" "0603"
					( Origin gFrontEnd )
				)
				( attribute "TOLERANCE" "5.0%"
					( Origin gFrontEnd )
				)
				( attribute "VALUE" "0"
					( Origin gFrontEnd )
				)
				( attribute "VER" "1"
					( Origin gFrontEnd )
				)
				( attribute "WATTAGE" "1/10W"
					( Origin gFrontEnd )
				)
				( attribute "XY" "(-5800,3725)"
					( Origin gFrontEnd )
				)
				( attribute "CHIPS_PART_NAME" "RES"
					( Origin gPackager )
				)
				( attribute "CDS_PART_NAME" "RES_0603-0,5.0%,1/10W,EMPTY,G2A"
					( Origin gPackager )
				)
				( attribute "CDS_SEC" "1"
					( Origin gPackager )
				)
				( attribute "GROUP" "NI_I210&RJ45"
					( Origin gFrontEnd )
				)
				( objectStatus "R1T33" )
			)
			( gate "@baseboard_fab2_lib.baseboard_fab2(sch_1):page139_i241"
				( attribute "BOM_COST" "NT_GBE_BASE"
					( Origin gFrontEnd )
				)
				( attribute "CDS_LIB" "dev_discrete"
					( Origin gPackager )
				)
				( attribute "CDS_LOCATION" "C9E12"
					( Origin gPackager )
				)
				( attribute "CDS_SEC" "1"
					( Origin gPackager )
				)
				( attribute "LOCATION" "C9E12"
					( Origin gFrontEnd )
				)
				( attribute "MATERIAL" "EMPTY"
					( Origin gFrontEnd )
				)
				( attribute "PACK_TYPE" "0603V"
					( Origin gFrontEnd )
				)
				( attribute "PART_NUMBER" "E15431-004"
					( Origin gFrontEnd )
				)
				( attribute "PHYS_PAGE" "139"
					( Origin gFrontEnd )
				)
				( attribute "ROOM" "NIC_SPRV"
					( Origin gFrontEnd )
				)
				( attribute "ROT" "0"
					( Origin gFrontEnd )
				)
				( attribute "SEC" "1"
					( Origin gFrontEnd )
				)
				( attribute "SEC_TYPE" "0603V"
					( Origin gFrontEnd )
				)
				( attribute "TOLERANCE" "20%"
					( Origin gFrontEnd )
				)
				( attribute "VALUE" "22.0UF"
					( Origin gFrontEnd )
				)
				( attribute "VER" "1"
					( Origin gFrontEnd )
				)
				( attribute "VOLTAGE" "4V"
					( Units "uVoltage" "V" 1.000000)
					( Origin gFrontEnd )
				)
				( attribute "XY" "(-1925,875)"
					( Origin gFrontEnd )
				)
				( attribute "CHIPS_PART_NAME" "CAP_A"
					( Origin gPackager )
				)
				( attribute "CDS_PART_NAME" "CAP_A_0603V-22.0UF,4V,20%,EMPTA"
					( Origin gPackager )
				)
				( attribute "GROUP" "NI_I210&RJ45"
					( Origin gFrontEnd )
				)
				( objectStatus "C9E12" )
			)
			( gate "@baseboard_fab2_lib.baseboard_fab2(sch_1):page140_i1"
				( attribute "BOM_COST" "NT_GBE_BASE"
					( Origin gFrontEnd )
				)
				( attribute "CDS_LIB" "mstr_memory"
					( Origin gPackager )
				)
				( attribute "CDS_LOCATION" "U9E1"
					( Origin gPackager )
				)
				( attribute "CDS_SEC" "1"
					( Origin gPackager )
				)
				( attribute "LOCATION" "U9E1"
					( Origin gFrontEnd )
				)
				( attribute "MATERIAL" "IC"
					( Origin gFrontEnd )
				)
				( attribute "PACK_TYPE" "SM"
					( Origin gFrontEnd )
				)
				( attribute "PART_NUMBER" "H77797-001"
					( Origin gFrontEnd )
				)
				( attribute "PHYS_PAGE" "140"
					( Origin gFrontEnd )
				)
				( attribute "ROOM" "NIC_SPRV"
					( Origin gFrontEnd )
				)
				( attribute "ROT" "0"
					( Origin gFrontEnd )
				)
				( attribute "SEC" "1"
					( Origin gFrontEnd )
				)
				( attribute "SEC_TYPE" "SM"
					( Origin gFrontEnd )
				)
				( attribute "VER" "1"
					( Origin gFrontEnd )
				)
				( attribute "XY" "(-2350,2700)"
					( Origin gFrontEnd )
				)
				( attribute "CHIPS_PART_NAME" "M25PE16"
					( Origin gPackager )
				)
				( attribute "CDS_PART_NAME" "M25PE16_SM-IC,H77797-001"
					( Origin gPackager )
				)
				( attribute "GROUP" "NI_I210&RJ45"
					( Origin gFrontEnd )
				)
				( objectStatus "U9E1" )
			)
			( gate "@baseboard_fab2_lib.baseboard_fab2(sch_1):page140_i3"
				( attribute "BOM_COST" "NT_GBE_BASE"
					( Origin gFrontEnd )
				)
				( attribute "CDS_LIB" "dev_discrete"
					( Origin gPackager )
				)
				( attribute "CDS_LOCATION" "C1R25"
					( Origin gPackager )
				)
				( attribute "CDS_SEC" "1"
					( Origin gPackager )
				)
				( attribute "LOCATION" "C1R25"
					( Origin gFrontEnd )
				)
				( attribute "MATERIAL" "X7R"
					( Origin gFrontEnd )
				)
				( attribute "PACK_TYPE" "0402V"
					( Origin gFrontEnd )
				)
				( attribute "PART_NUMBER" "A36096-030"
					( Origin gFrontEnd )
				)
				( attribute "PHYS_PAGE" "140"
					( Origin gFrontEnd )
				)
				( attribute "ROOM" "NIC_SPRV"
					( Origin gFrontEnd )
				)
				( attribute "ROT" "0"
					( Origin gFrontEnd )
				)
				( attribute "SEC" "1"
					( Origin gFrontEnd )
				)
				( attribute "SEC_TYPE" "0402V"
					( Origin gFrontEnd )
				)
				( attribute "TOLERANCE" "10%"
					( Origin gFrontEnd )
				)
				( attribute "VALUE" "0.1UF"
					( Origin gFrontEnd )
				)
				( attribute "VER" "1"
					( Origin gFrontEnd )
				)
				( attribute "VOLTAGE" "16V"
					( Units "uVoltage" "V" 1.000000)
					( Origin gFrontEnd )
				)
				( attribute "XY" "(-2475,3375)"
					( Origin gFrontEnd )
				)
				( attribute "CHIPS_PART_NAME" "CAP_A"
					( Origin gPackager )
				)
				( attribute "CDS_PART_NAME" "CAP_A_0402V-0.1UF,16V,10%,X7R,A"
					( Origin gPackager )
				)
				( attribute "GROUP" "NI_I210&RJ45"
					( Origin gFrontEnd )
				)
				( objectStatus "C1R25" )
			)
			( gate "@baseboard_fab2_lib.baseboard_fab2(sch_1):page140_i10"
				( attribute "BOM_COST" "NT_GBE_BASE"
					( Origin gFrontEnd )
				)
				( attribute "CDS_LIB" "mstr_discrete"
					( Origin gPackager )
				)
				( attribute "CDS_LOCATION" "R1R9"
					( Origin gPackager )
				)
				( attribute "CDS_SEC" "1"
					( Origin gPackager )
				)
				( attribute "LOCATION" "R1R9"
					( Origin gFrontEnd )
				)
				( attribute "MATERIAL" "CHIP"
					( Origin gFrontEnd )
				)
				( attribute "PACK_TYPE" "0402"
					( Origin gFrontEnd )
				)
				( attribute "PART_NUMBER" "G21796-027"
					( Origin gFrontEnd )
				)
				( attribute "PHYS_PAGE" "140"
					( Origin gFrontEnd )
				)
				( attribute "ROOM" "NIC_SPRV"
					( Origin gFrontEnd )
				)
				( attribute "ROT" "0"
					( Origin gFrontEnd )
				)
				( attribute "SEC" "1"
					( Origin gFrontEnd )
				)
				( attribute "SEC_TYPE" "0402"
					( Origin gFrontEnd )
				)
				( attribute "TOLERANCE" "1%"
					( Origin gFrontEnd )
				)
				( attribute "VALUE" "3.32K"
					( Origin gFrontEnd )
				)
				( attribute "VER" "2"
					( Origin gFrontEnd )
				)
				( attribute "WATTAGE" "1/16W"
					( Origin gFrontEnd )
				)
				( attribute "XY" "(-3200,3300)"
					( Origin gFrontEnd )
				)
				( attribute "CHIPS_PART_NAME" "RES"
					( Origin gPackager )
				)
				( attribute "CDS_PART_NAME" "RES_0402-3.32K,1%,1/16W,CHIP,GA"
					( Origin gPackager )
				)
				( attribute "GROUP" "NI_I210&RJ45"
					( Origin gFrontEnd )
				)
				( objectStatus "R1R9" )
			)
			( gate "@baseboard_fab2_lib.baseboard_fab2(sch_1):page140_i11"
				( attribute "BOM_COST" "NT_GBE_BASE"
					( Origin gFrontEnd )
				)
				( attribute "CDS_LIB" "mstr_discrete"
					( Origin gPackager )
				)
				( attribute "CDS_LOCATION" "R1R3"
					( Origin gPackager )
				)
				( attribute "CDS_SEC" "1"
					( Origin gPackager )
				)
				( attribute "LOCATION" "R1R3"
					( Origin gFrontEnd )
				)
				( attribute "MATERIAL" "CHIP"
					( Origin gFrontEnd )
				)
				( attribute "PACK_TYPE" "0402"
					( Origin gFrontEnd )
				)
				( attribute "PART_NUMBER" "G21796-027"
					( Origin gFrontEnd )
				)
				( attribute "PHYS_PAGE" "140"
					( Origin gFrontEnd )
				)
				( attribute "ROOM" "NIC_SPRV"
					( Origin gFrontEnd )
				)
				( attribute "ROT" "0"
					( Origin gFrontEnd )
				)
				( attribute "SEC" "1"
					( Origin gFrontEnd )
				)
				( attribute "SEC_TYPE" "0402"
					( Origin gFrontEnd )
				)
				( attribute "TOLERANCE" "1%"
					( Origin gFrontEnd )
				)
				( attribute "VALUE" "3.32K"
					( Origin gFrontEnd )
				)
				( attribute "VER" "2"
					( Origin gFrontEnd )
				)
				( attribute "WATTAGE" "1/16W"
					( Origin gFrontEnd )
				)
				( attribute "XY" "(-3550,3300)"
					( Origin gFrontEnd )
				)
				( attribute "CHIPS_PART_NAME" "RES"
					( Origin gPackager )
				)
				( attribute "CDS_PART_NAME" "RES_0402-3.32K,1%,1/16W,CHIP,GA"
					( Origin gPackager )
				)
				( attribute "GROUP" "NI_I210&RJ45"
					( Origin gFrontEnd )
				)
				( objectStatus "R1R3" )
			)
			( gate "@baseboard_fab2_lib.baseboard_fab2(sch_1):page140_i12"
				( attribute "BOM_COST" "NT_GBE_BASE"
					( Origin gFrontEnd )
				)
				( attribute "CDS_LIB" "mstr_discrete"
					( Origin gPackager )
				)
				( attribute "CDS_LOCATION" "R1R7"
					( Origin gPackager )
				)
				( attribute "CDS_SEC" "1"
					( Origin gPackager )
				)
				( attribute "LOCATION" "R1R7"
					( Origin gFrontEnd )
				)
				( attribute "MATERIAL" "CHIP"
					( Origin gFrontEnd )
				)
				( attribute "PACK_TYPE" "0402"
					( Origin gFrontEnd )
				)
				( attribute "PART_NUMBER" "G21796-040"
					( Origin gFrontEnd )
				)
				( attribute "PHYS_PAGE" "140"
					( Origin gFrontEnd )
				)
				( attribute "ROOM" "NIC_SPRV"
					( Origin gFrontEnd )
				)
				( attribute "ROT" "0"
					( Origin gFrontEnd )
				)
				( attribute "SEC" "1"
					( Origin gFrontEnd )
				)
				( attribute "SEC_TYPE" "0402"
					( Origin gFrontEnd )
				)
				( attribute "TOLERANCE" "1%"
					( Origin gFrontEnd )
				)
				( attribute "VALUE" "20.0K"
					( Origin gFrontEnd )
				)
				( attribute "VER" "2"
					( Origin gFrontEnd )
				)
				( attribute "WATTAGE" "1/16W"
					( Origin gFrontEnd )
				)
				( attribute "XY" "(-3950,3300)"
					( Origin gFrontEnd )
				)
				( attribute "CHIPS_PART_NAME" "RES"
					( Origin gPackager )
				)
				( attribute "CDS_PART_NAME" "RES_0402-20.0K,1%,1/16W,CHIP,GA"
					( Origin gPackager )
				)
				( attribute "GROUP" "NI_I210&RJ45"
					( Origin gFrontEnd )
				)
				( objectStatus "R1R7" )
			)
			( gate "@baseboard_fab2_lib.baseboard_fab2(sch_1):page140_i14"
				( attribute "BOM_COST" "NT_GBE_BASE"
					( Origin gFrontEnd )
				)
				( attribute "CDS_LIB" "mstr_discrete"
					( Origin gPackager )
				)
				( attribute "CDS_LOCATION" "R1R6"
					( Origin gPackager )
				)
				( attribute "CDS_SEC" "1"
					( Origin gPackager )
				)
				( attribute "LOCATION" "R1R6"
					( Origin gFrontEnd )
				)
				( attribute "MATERIAL" "EMPTY"
					( Origin gFrontEnd )
				)
				( attribute "PACK_TYPE" "0402"
					( Origin gFrontEnd )
				)
				( attribute "PART_NUMBER" "G21796-027"
					( Origin gFrontEnd )
				)
				( attribute "PHYS_PAGE" "140"
					( Origin gFrontEnd )
				)
				( attribute "ROOM" "NIC_SPRV"
					( Origin gFrontEnd )
				)
				( attribute "ROT" "0"
					( Origin gFrontEnd )
				)
				( attribute "SEC" "1"
					( Origin gFrontEnd )
				)
				( attribute "SEC_TYPE" "0402"
					( Origin gFrontEnd )
				)
				( attribute "TOLERANCE" "1%"
					( Origin gFrontEnd )
				)
				( attribute "VALUE" "3.32K"
					( Origin gFrontEnd )
				)
				( attribute "VER" "2"
					( Origin gFrontEnd )
				)
				( attribute "WATTAGE" "1/16W"
					( Origin gFrontEnd )
				)
				( attribute "XY" "(-3825,2350)"
					( Origin gFrontEnd )
				)
				( attribute "CHIPS_PART_NAME" "RES"
					( Origin gPackager )
				)
				( attribute "CDS_PART_NAME" "RES_0402-3.32K,1%,1/16W,EMPTY,A"
					( Origin gPackager )
				)
				( attribute "GROUP" "NI_I210&RJ45"
					( Origin gFrontEnd )
				)
				( objectStatus "R1R6" )
			)
			( gate "@baseboard_fab2_lib.baseboard_fab2(sch_1):page140_i17"
				( attribute "BOM_COST" "NT_GBE_BASE"
					( Origin gFrontEnd )
				)
				( attribute "CDS_LIB" "mstr_discrete"
					( Origin gPackager )
				)
				( attribute "CDS_LOCATION" "R9E6"
					( Origin gPackager )
				)
				( attribute "CDS_SEC" "1"
					( Origin gPackager )
				)
				( attribute "LOCATION" "R9E6"
					( Origin gFrontEnd )
				)
				( attribute "MATERIAL" "CHIP"
					( Origin gFrontEnd )
				)
				( attribute "PACK_TYPE" "0402"
					( Origin gFrontEnd )
				)
				( attribute "PART_NUMBER" "G21796-074"
					( Origin gFrontEnd )
				)
				( attribute "PHYS_PAGE" "140"
					( Origin gFrontEnd )
				)
				( attribute "ROOM" "NIC_SPRV"
					( Origin gFrontEnd )
				)
				( attribute "ROT" "0"
					( Origin gFrontEnd )
				)
				( attribute "SEC" "1"
					( Origin gFrontEnd )
				)
				( attribute "SEC_TYPE" "0402"
					( Origin gFrontEnd )
				)
				( attribute "TOLERANCE" "1%"
					( Origin gFrontEnd )
				)
				( attribute "VALUE" "33.2"
					( Origin gFrontEnd )
				)
				( attribute "VER" "1"
					( Origin gFrontEnd )
				)
				( attribute "WATTAGE" "1/16W"
					( Origin gFrontEnd )
				)
				( attribute "XY" "(-1400,2750)"
					( Origin gFrontEnd )
				)
				( attribute "CHIPS_PART_NAME" "RES"
					( Origin gPackager )
				)
				( attribute "CDS_PART_NAME" "RES_0402-33.2,1%,1/16W,CHIP,G2A"
					( Origin gPackager )
				)
				( attribute "GROUP" "NI_I210&RJ45"
					( Origin gFrontEnd )
				)
				( objectStatus "R9E6" )
			)
			( gate "@baseboard_fab2_lib.baseboard_fab2(sch_1):page141_i46"
				( attribute "BOM_COST" "NT_GBE_BASE"
					( Origin gFrontEnd )
				)
				( attribute "CDS_LIB" "dev_discrete"
					( Origin gPackager )
				)
				( attribute "CDS_LOCATION" "C9G4"
					( Origin gPackager )
				)
				( attribute "CDS_SEC" "1"
					( Origin gPackager )
				)
				( attribute "LOCATION" "C9G4"
					( Origin gFrontEnd )
				)
				( attribute "MATERIAL" "X7R"
					( Origin gFrontEnd )
				)
				( attribute "PACK_TYPE" "0402V"
					( Origin gFrontEnd )
				)
				( attribute "PART_NUMBER" "A36096-030"
					( Origin gFrontEnd )
				)
				( attribute "PHYS_PAGE" "141"
					( Origin gFrontEnd )
				)
				( attribute "ROOM" "NIC_SPRV"
					( Origin gFrontEnd )
				)
				( attribute "ROT" "0"
					( Origin gFrontEnd )
				)
				( attribute "SEC" "1"
					( Origin gFrontEnd )
				)
				( attribute "SEC_TYPE" "0402V"
					( Origin gFrontEnd )
				)
				( attribute "TOLERANCE" "10%"
					( Origin gFrontEnd )
				)
				( attribute "VALUE" "0.1UF"
					( Origin gFrontEnd )
				)
				( attribute "VER" "1"
					( Origin gFrontEnd )
				)
				( attribute "VOLTAGE" "16V"
					( Units "uVoltage" "V" 1.000000)
					( Origin gFrontEnd )
				)
				( attribute "XY" "(-6075,575)"
					( Origin gFrontEnd )
				)
				( attribute "CHIPS_PART_NAME" "CAP_A"
					( Origin gPackager )
				)
				( attribute "CDS_PART_NAME" "CAP_A_0402V-0.1UF,16V,10%,X7R,A"
					( Origin gPackager )
				)
				( attribute "GROUP" "NI_I210&RJ45"
					( Origin gFrontEnd )
				)
				( objectStatus "C9G4" )
			)
			( gate "@baseboard_fab2_lib.baseboard_fab2(sch_1):page141_i47"
				( attribute "BOM_COST" "NT_GBE_BASE"
					( Origin gFrontEnd )
				)
				( attribute "CDS_LIB" "dev_discrete"
					( Origin gPackager )
				)
				( attribute "CDS_LOCATION" "C9G6"
					( Origin gPackager )
				)
				( attribute "CDS_SEC" "1"
					( Origin gPackager )
				)
				( attribute "LOCATION" "C9G6"
					( Origin gFrontEnd )
				)
				( attribute "MATERIAL" "X7R"
					( Origin gFrontEnd )
				)
				( attribute "PACK_TYPE" "0402V"
					( Origin gFrontEnd )
				)
				( attribute "PART_NUMBER" "A36096-030"
					( Origin gFrontEnd )
				)
				( attribute "PHYS_PAGE" "141"
					( Origin gFrontEnd )
				)
				( attribute "ROOM" "NIC_SPRV"
					( Origin gFrontEnd )
				)
				( attribute "ROT" "0"
					( Origin gFrontEnd )
				)
				( attribute "SEC" "1"
					( Origin gFrontEnd )
				)
				( attribute "SEC_TYPE" "0402V"
					( Origin gFrontEnd )
				)
				( attribute "TOLERANCE" "10%"
					( Origin gFrontEnd )
				)
				( attribute "VALUE" "0.1UF"
					( Origin gFrontEnd )
				)
				( attribute "VER" "1"
					( Origin gFrontEnd )
				)
				( attribute "VOLTAGE" "16V"
					( Units "uVoltage" "V" 1.000000)
					( Origin gFrontEnd )
				)
				( attribute "XY" "(-6400,575)"
					( Origin gFrontEnd )
				)
				( attribute "CHIPS_PART_NAME" "CAP_A"
					( Origin gPackager )
				)
				( attribute "CDS_PART_NAME" "CAP_A_0402V-0.1UF,16V,10%,X7R,A"
					( Origin gPackager )
				)
				( attribute "GROUP" "NI_I210&RJ45"
					( Origin gFrontEnd )
				)
				( objectStatus "C9G6" )
			)
			( gate "@baseboard_fab2_lib.baseboard_fab2(sch_1):page141_i48"
				( attribute "BOM_COST" "NT_GBE_BASE"
					( Origin gFrontEnd )
				)
				( attribute "CDS_LIB" "mstr_discrete"
					( Origin gPackager )
				)
				( attribute "CDS_LOCATION" "C9G5"
					( Origin gPackager )
				)
				( attribute "CDS_SEC" "1"
					( Origin gPackager )
				)
				( attribute "LOCATION" "C9G5"
					( Origin gFrontEnd )
				)
				( attribute "MATERIAL" "X7S"
					( Origin gFrontEnd )
				)
				( attribute "PACK_TYPE" "0402"
					( Origin gFrontEnd )
				)
				( attribute "PART_NUMBER" "G71842-007"
					( Origin gFrontEnd )
				)
				( attribute "PHYS_PAGE" "141"
					( Origin gFrontEnd )
				)
				( attribute "ROOM" "NIC_SPRV"
					( Origin gFrontEnd )
				)
				( attribute "ROT" "0"
					( Origin gFrontEnd )
				)
				( attribute "SEC" "1"
					( Origin gFrontEnd )
				)
				( attribute "SEC_TYPE" "0402"
					( Origin gFrontEnd )
				)
				( attribute "TOLERANCE" "10%"
					( Origin gFrontEnd )
				)
				( attribute "VALUE" "1.0UF"
					( Origin gFrontEnd )
				)
				( attribute "VER" "1"
					( Origin gFrontEnd )
				)
				( attribute "VOLTAGE" "16V"
					( Units "uVoltage" "V" 1.000000)
					( Origin gFrontEnd )
				)
				( attribute "XY" "(-6750,575)"
					( Origin gFrontEnd )
				)
				( attribute "CHIPS_PART_NAME" "CAP"
					( Origin gPackager )
				)
				( attribute "CDS_PART_NAME" "CAP_0402-1.0UF,16V,10%,X7S,G71A"
					( Origin gPackager )
				)
				( attribute "GROUP" "NI_I210&RJ45"
					( Origin gFrontEnd )
				)
				( objectStatus "C9G5" )
			)
			( gate "@baseboard_fab2_lib.baseboard_fab2(sch_1):page141_i75"
				( attribute "BOM_COST" "NT_GBE_BASE"
					( Origin gFrontEnd )
				)
				( attribute "CDS_LIB" "mstr_discrete"
					( Origin gPackager )
				)
				( attribute "CDS_LOCATION" "R9G9"
					( Origin gPackager )
				)
				( attribute "LOCATION" "R9G9"
					( Origin gFrontEnd )
				)
				( attribute "MATERIAL" "CHIP"
					( Origin gFrontEnd )
				)
				( attribute "PACK_TYPE" "0402"
					( Origin gFrontEnd )
				)
				( attribute "PART_NUMBER" "G21497-005"
					( Origin gFrontEnd )
				)
				( attribute "PHYS_PAGE" "141"
					( Origin gFrontEnd )
				)
				( attribute "ROOM" "NIC_SPRV"
					( Origin gFrontEnd )
				)
				( attribute "ROT" "0"
					( Origin gFrontEnd )
				)
				( attribute "SEC" "1"
					( Origin gFrontEnd )
				)
				( attribute "TOLERANCE" "5%"
					( Origin gFrontEnd )
				)
				( attribute "VALUE" "0.0"
					( Origin gFrontEnd )
				)
				( attribute "VER" "1"
					( Origin gFrontEnd )
				)
				( attribute "WATTAGE" "1/16W"
					( Origin gFrontEnd )
				)
				( attribute "XY" "(-3275,3775)"
					( Origin gFrontEnd )
				)
				( attribute "CHIPS_PART_NAME" "RES"
					( Origin gPackager )
				)
				( attribute "CDS_PART_NAME" "RES_0402-0.0,5%,1/16W,CHIP,G21A"
					( Origin gPackager )
				)
				( attribute "SEC_TYPE" "0402"
					( Origin gFrontEnd )
				)
				( attribute "CDS_SEC" "1"
					( Origin gPackager )
				)
				( attribute "GROUP" "NI_I210&RJ45"
					( Origin gFrontEnd )
				)
				( objectStatus "R9G9" )
			)
			( gate "@baseboard_fab2_lib.baseboard_fab2(sch_1):page141_i76"
				( attribute "BOM_COST" "NT_GBE_BASE"
					( Origin gFrontEnd )
				)
				( attribute "CDS_LIB" "mstr_discrete"
					( Origin gPackager )
				)
				( attribute "CDS_LOCATION" "R9G11"
					( Origin gPackager )
				)
				( attribute "LOCATION" "R9G11"
					( Origin gFrontEnd )
				)
				( attribute "MATERIAL" "CHIP"
					( Origin gFrontEnd )
				)
				( attribute "PACK_TYPE" "0402"
					( Origin gFrontEnd )
				)
				( attribute "PART_NUMBER" "G21497-005"
					( Origin gFrontEnd )
				)
				( attribute "PHYS_PAGE" "141"
					( Origin gFrontEnd )
				)
				( attribute "ROOM" "NIC_SPRV"
					( Origin gFrontEnd )
				)
				( attribute "ROT" "0"
					( Origin gFrontEnd )
				)
				( attribute "SEC" "1"
					( Origin gFrontEnd )
				)
				( attribute "TOLERANCE" "5%"
					( Origin gFrontEnd )
				)
				( attribute "VALUE" "0.0"
					( Origin gFrontEnd )
				)
				( attribute "VER" "1"
					( Origin gFrontEnd )
				)
				( attribute "WATTAGE" "1/16W"
					( Origin gFrontEnd )
				)
				( attribute "XY" "(-3275,3725)"
					( Origin gFrontEnd )
				)
				( attribute "CHIPS_PART_NAME" "RES"
					( Origin gPackager )
				)
				( attribute "CDS_PART_NAME" "RES_0402-0.0,5%,1/16W,CHIP,G21A"
					( Origin gPackager )
				)
				( attribute "SEC_TYPE" "0402"
					( Origin gFrontEnd )
				)
				( attribute "CDS_SEC" "1"
					( Origin gPackager )
				)
				( attribute "GROUP" "NI_I210&RJ45"
					( Origin gFrontEnd )
				)
				( objectStatus "R9G11" )
			)
			( gate "@baseboard_fab2_lib.baseboard_fab2(sch_1):page141_i77"
				( attribute "BOM_COST" "NT_GBE_BASE"
					( Origin gFrontEnd )
				)
				( attribute "CDS_LIB" "mstr_discrete"
					( Origin gPackager )
				)
				( attribute "CDS_LOCATION" "R9G18"
					( Origin gPackager )
				)
				( attribute "LOCATION" "R9G18"
					( Origin gFrontEnd )
				)
				( attribute "MATERIAL" "CHIP"
					( Origin gFrontEnd )
				)
				( attribute "PACK_TYPE" "0402"
					( Origin gFrontEnd )
				)
				( attribute "PART_NUMBER" "G21497-005"
					( Origin gFrontEnd )
				)
				( attribute "PHYS_PAGE" "141"
					( Origin gFrontEnd )
				)
				( attribute "ROOM" "NIC_SPRV"
					( Origin gFrontEnd )
				)
				( attribute "ROT" "0"
					( Origin gFrontEnd )
				)
				( attribute "SEC" "1"
					( Origin gFrontEnd )
				)
				( attribute "TOLERANCE" "5%"
					( Origin gFrontEnd )
				)
				( attribute "VALUE" "0.0"
					( Origin gFrontEnd )
				)
				( attribute "VER" "1"
					( Origin gFrontEnd )
				)
				( attribute "WATTAGE" "1/16W"
					( Origin gFrontEnd )
				)
				( attribute "XY" "(-3275,3675)"
					( Origin gFrontEnd )
				)
				( attribute "CHIPS_PART_NAME" "RES"
					( Origin gPackager )
				)
				( attribute "CDS_PART_NAME" "RES_0402-0.0,5%,1/16W,CHIP,G21A"
					( Origin gPackager )
				)
				( attribute "SEC_TYPE" "0402"
					( Origin gFrontEnd )
				)
				( attribute "CDS_SEC" "1"
					( Origin gPackager )
				)
				( attribute "GROUP" "NI_I210&RJ45"
					( Origin gFrontEnd )
				)
				( objectStatus "R9G18" )
			)
			( gate "@baseboard_fab2_lib.baseboard_fab2(sch_1):page141_i78"
				( attribute "BOM_COST" "NT_GBE_BASE"
					( Origin gFrontEnd )
				)
				( attribute "CDS_LIB" "mstr_discrete"
					( Origin gPackager )
				)
				( attribute "CDS_LOCATION" "R9G17"
					( Origin gPackager )
				)
				( attribute "LOCATION" "R9G17"
					( Origin gFrontEnd )
				)
				( attribute "MATERIAL" "CHIP"
					( Origin gFrontEnd )
				)
				( attribute "PACK_TYPE" "0402"
					( Origin gFrontEnd )
				)
				( attribute "PART_NUMBER" "G21497-005"
					( Origin gFrontEnd )
				)
				( attribute "PHYS_PAGE" "141"
					( Origin gFrontEnd )
				)
				( attribute "ROOM" "NIC_SPRV"
					( Origin gFrontEnd )
				)
				( attribute "ROT" "0"
					( Origin gFrontEnd )
				)
				( attribute "SEC" "1"
					( Origin gFrontEnd )
				)
				( attribute "TOLERANCE" "5%"
					( Origin gFrontEnd )
				)
				( attribute "VALUE" "0.0"
					( Origin gFrontEnd )
				)
				( attribute "VER" "1"
					( Origin gFrontEnd )
				)
				( attribute "WATTAGE" "1/16W"
					( Origin gFrontEnd )
				)
				( attribute "XY" "(-3275,3625)"
					( Origin gFrontEnd )
				)
				( attribute "CHIPS_PART_NAME" "RES"
					( Origin gPackager )
				)
				( attribute "CDS_PART_NAME" "RES_0402-0.0,5%,1/16W,CHIP,G21A"
					( Origin gPackager )
				)
				( attribute "SEC_TYPE" "0402"
					( Origin gFrontEnd )
				)
				( attribute "CDS_SEC" "1"
					( Origin gPackager )
				)
				( attribute "GROUP" "NI_I210&RJ45"
					( Origin gFrontEnd )
				)
				( objectStatus "R9G17" )
			)
			( gate "@baseboard_fab2_lib.baseboard_fab2(sch_1):page141_i79"
				( attribute "BOM_COST" "NT_GBE_BASE"
					( Origin gFrontEnd )
				)
				( attribute "CDS_LIB" "mstr_discrete"
					( Origin gPackager )
				)
				( attribute "CDS_LOCATION" "R9G19"
					( Origin gPackager )
				)
				( attribute "LOCATION" "R9G19"
					( Origin gFrontEnd )
				)
				( attribute "MATERIAL" "CHIP"
					( Origin gFrontEnd )
				)
				( attribute "PACK_TYPE" "0402"
					( Origin gFrontEnd )
				)
				( attribute "PART_NUMBER" "G21497-005"
					( Origin gFrontEnd )
				)
				( attribute "PHYS_PAGE" "141"
					( Origin gFrontEnd )
				)
				( attribute "ROOM" "NIC_SPRV"
					( Origin gFrontEnd )
				)
				( attribute "ROT" "0"
					( Origin gFrontEnd )
				)
				( attribute "SEC" "1"
					( Origin gFrontEnd )
				)
				( attribute "TOLERANCE" "5%"
					( Origin gFrontEnd )
				)
				( attribute "VALUE" "0.0"
					( Origin gFrontEnd )
				)
				( attribute "VER" "1"
					( Origin gFrontEnd )
				)
				( attribute "WATTAGE" "1/16W"
					( Origin gFrontEnd )
				)
				( attribute "XY" "(-3275,3575)"
					( Origin gFrontEnd )
				)
				( attribute "CHIPS_PART_NAME" "RES"
					( Origin gPackager )
				)
				( attribute "CDS_PART_NAME" "RES_0402-0.0,5%,1/16W,CHIP,G21A"
					( Origin gPackager )
				)
				( attribute "SEC_TYPE" "0402"
					( Origin gFrontEnd )
				)
				( attribute "CDS_SEC" "1"
					( Origin gPackager )
				)
				( attribute "GROUP" "NI_I210&RJ45"
					( Origin gFrontEnd )
				)
				( objectStatus "R9G19" )
			)
			( gate "@baseboard_fab2_lib.baseboard_fab2(sch_1):page141_i80"
				( attribute "BOM_COST" "NT_GBE_BASE"
					( Origin gFrontEnd )
				)
				( attribute "CDS_LIB" "mstr_discrete"
					( Origin gPackager )
				)
				( attribute "CDS_LOCATION" "R9G20"
					( Origin gPackager )
				)
				( attribute "LOCATION" "R9G20"
					( Origin gFrontEnd )
				)
				( attribute "MATERIAL" "CHIP"
					( Origin gFrontEnd )
				)
				( attribute "PACK_TYPE" "0402"
					( Origin gFrontEnd )
				)
				( attribute "PART_NUMBER" "G21497-005"
					( Origin gFrontEnd )
				)
				( attribute "PHYS_PAGE" "141"
					( Origin gFrontEnd )
				)
				( attribute "ROOM" "NIC_SPRV"
					( Origin gFrontEnd )
				)
				( attribute "ROT" "0"
					( Origin gFrontEnd )
				)
				( attribute "SEC" "1"
					( Origin gFrontEnd )
				)
				( attribute "TOLERANCE" "5%"
					( Origin gFrontEnd )
				)
				( attribute "VALUE" "0.0"
					( Origin gFrontEnd )
				)
				( attribute "VER" "1"
					( Origin gFrontEnd )
				)
				( attribute "WATTAGE" "1/16W"
					( Origin gFrontEnd )
				)
				( attribute "XY" "(-3275,3525)"
					( Origin gFrontEnd )
				)
				( attribute "CHIPS_PART_NAME" "RES"
					( Origin gPackager )
				)
				( attribute "CDS_PART_NAME" "RES_0402-0.0,5%,1/16W,CHIP,G21A"
					( Origin gPackager )
				)
				( attribute "SEC_TYPE" "0402"
					( Origin gFrontEnd )
				)
				( attribute "CDS_SEC" "1"
					( Origin gPackager )
				)
				( attribute "GROUP" "NI_I210&RJ45"
					( Origin gFrontEnd )
				)
				( objectStatus "R9G20" )
			)
			( gate "@baseboard_fab2_lib.baseboard_fab2(sch_1):page141_i81"
				( attribute "BOM_COST" "NT_GBE_BASE"
					( Origin gFrontEnd )
				)
				( attribute "CDS_LIB" "mstr_discrete"
					( Origin gPackager )
				)
				( attribute "CDS_LOCATION" "R9G24"
					( Origin gPackager )
				)
				( attribute "LOCATION" "R9G24"
					( Origin gFrontEnd )
				)
				( attribute "MATERIAL" "CHIP"
					( Origin gFrontEnd )
				)
				( attribute "PACK_TYPE" "0402"
					( Origin gFrontEnd )
				)
				( attribute "PART_NUMBER" "G21497-005"
					( Origin gFrontEnd )
				)
				( attribute "PHYS_PAGE" "141"
					( Origin gFrontEnd )
				)
				( attribute "ROOM" "NIC_SPRV"
					( Origin gFrontEnd )
				)
				( attribute "ROT" "0"
					( Origin gFrontEnd )
				)
				( attribute "SEC" "1"
					( Origin gFrontEnd )
				)
				( attribute "TOLERANCE" "5%"
					( Origin gFrontEnd )
				)
				( attribute "VALUE" "0.0"
					( Origin gFrontEnd )
				)
				( attribute "VER" "1"
					( Origin gFrontEnd )
				)
				( attribute "WATTAGE" "1/16W"
					( Origin gFrontEnd )
				)
				( attribute "XY" "(-3275,3475)"
					( Origin gFrontEnd )
				)
				( attribute "CHIPS_PART_NAME" "RES"
					( Origin gPackager )
				)
				( attribute "CDS_PART_NAME" "RES_0402-0.0,5%,1/16W,CHIP,G21A"
					( Origin gPackager )
				)
				( attribute "SEC_TYPE" "0402"
					( Origin gFrontEnd )
				)
				( attribute "CDS_SEC" "1"
					( Origin gPackager )
				)
				( attribute "GROUP" "NI_I210&RJ45"
					( Origin gFrontEnd )
				)
				( objectStatus "R9G24" )
			)
			( gate "@baseboard_fab2_lib.baseboard_fab2(sch_1):page141_i82"
				( attribute "BOM_COST" "NT_GBE_BASE"
					( Origin gFrontEnd )
				)
				( attribute "CDS_LIB" "mstr_discrete"
					( Origin gPackager )
				)
				( attribute "CDS_LOCATION" "R9G22"
					( Origin gPackager )
				)
				( attribute "LOCATION" "R9G22"
					( Origin gFrontEnd )
				)
				( attribute "MATERIAL" "CHIP"
					( Origin gFrontEnd )
				)
				( attribute "PACK_TYPE" "0402"
					( Origin gFrontEnd )
				)
				( attribute "PART_NUMBER" "G21497-005"
					( Origin gFrontEnd )
				)
				( attribute "PHYS_PAGE" "141"
					( Origin gFrontEnd )
				)
				( attribute "ROOM" "NIC_SPRV"
					( Origin gFrontEnd )
				)
				( attribute "ROT" "0"
					( Origin gFrontEnd )
				)
				( attribute "SEC" "1"
					( Origin gFrontEnd )
				)
				( attribute "TOLERANCE" "5%"
					( Origin gFrontEnd )
				)
				( attribute "VALUE" "0.0"
					( Origin gFrontEnd )
				)
				( attribute "VER" "1"
					( Origin gFrontEnd )
				)
				( attribute "WATTAGE" "1/16W"
					( Origin gFrontEnd )
				)
				( attribute "XY" "(-3275,3425)"
					( Origin gFrontEnd )
				)
				( attribute "CHIPS_PART_NAME" "RES"
					( Origin gPackager )
				)
				( attribute "CDS_PART_NAME" "RES_0402-0.0,5%,1/16W,CHIP,G21A"
					( Origin gPackager )
				)
				( attribute "SEC_TYPE" "0402"
					( Origin gFrontEnd )
				)
				( attribute "CDS_SEC" "1"
					( Origin gPackager )
				)
				( attribute "GROUP" "NI_I210&RJ45"
					( Origin gFrontEnd )
				)
				( objectStatus "R9G22" )
			)
			( gate "@baseboard_fab2_lib.baseboard_fab2(sch_1):page141_i99"
				( attribute "BOM_COST" "NT_GBE_BASE"
					( Origin gFrontEnd )
				)
				( attribute "CDS_LIB" "mstr_discrete"
					( Origin gPackager )
				)
				( attribute "CDS_LOCATION" "C9G9"
					( Origin gPackager )
				)
				( attribute "LOCATION" "C9G9"
					( Origin gFrontEnd )
				)
				( attribute "MATERIAL" "EMPTY"
					( Origin gFrontEnd )
				)
				( attribute "NO_XNET_CONNECTION" "1"
					( Origin gFrontEnd )
				)
				( attribute "PACK_TYPE" "0402LF"
					( Origin gFrontEnd )
				)
				( attribute "PART_NUMBER" "A36096-066"
					( Origin gFrontEnd )
				)
				( attribute "PHYS_PAGE" "141"
					( Origin gFrontEnd )
				)
				( attribute "ROOM" "NIC_SPRV"
					( Origin gFrontEnd )
				)
				( attribute "ROT" "0"
					( Origin gFrontEnd )
				)
				( attribute "SEC" "1"
					( Origin gFrontEnd )
				)
				( attribute "TOLERANCE" "10%"
					( Origin gFrontEnd )
				)
				( attribute "VALUE" "4700PF"
					( Origin gFrontEnd )
				)
				( attribute "VER" "2"
					( Origin gFrontEnd )
				)
				( attribute "VOLTAGE" "50V"
					( Units "uVoltage" "V" 1.000000)
					( Origin gFrontEnd )
				)
				( attribute "XY" "(-2875,4425)"
					( Origin gFrontEnd )
				)
				( attribute "CHIPS_PART_NAME" "CAP"
					( Origin gPackager )
				)
				( attribute "CDS_PART_NAME" "CAP_0402LF-4700PF,50V,10%,EMPTA"
					( Origin gPackager )
				)
				( attribute "SEC_TYPE" "0402LF"
					( Origin gFrontEnd )
				)
				( attribute "CDS_SEC" "1"
					( Origin gPackager )
				)
				( attribute "GROUP" "NI_I210&RJ45"
					( Origin gFrontEnd )
				)
				( objectStatus "C9G9" )
			)
			( gate "@baseboard_fab2_lib.baseboard_fab2(sch_1):page141_i100"
				( attribute "BOM_COST" "NT_GBE_BASE"
					( Origin gFrontEnd )
				)
				( attribute "CDS_LIB" "mstr_discrete"
					( Origin gPackager )
				)
				( attribute "CDS_LOCATION" "C9G12"
					( Origin gPackager )
				)
				( attribute "CDS_SEC" "1"
					( Origin gPackager )
				)
				( attribute "LOCATION" "C9G12"
					( Origin gFrontEnd )
				)
				( attribute "MATERIAL" "EMPTY"
					( Origin gFrontEnd )
				)
				( attribute "NO_XNET_CONNECTION" "1"
					( Origin gFrontEnd )
				)
				( attribute "PACK_TYPE" "0402LF"
					( Origin gFrontEnd )
				)
				( attribute "PART_NUMBER" "A36096-066"
					( Origin gFrontEnd )
				)
				( attribute "PHYS_PAGE" "141"
					( Origin gFrontEnd )
				)
				( attribute "ROOM" "NIC_SPRV"
					( Origin gFrontEnd )
				)
				( attribute "ROT" "0"
					( Origin gFrontEnd )
				)
				( attribute "SEC" "1"
					( Origin gPackager )
				)
				( attribute "TOLERANCE" "10%"
					( Origin gFrontEnd )
				)
				( attribute "VALUE" "4700PF"
					( Origin gFrontEnd )
				)
				( attribute "VER" "2"
					( Origin gFrontEnd )
				)
				( attribute "VOLTAGE" "50V"
					( Units "uVoltage" "V" 1.000000)
					( Origin gFrontEnd )
				)
				( attribute "XY" "(-3150,4375)"
					( Origin gFrontEnd )
				)
				( attribute "CHIPS_PART_NAME" "CAP"
					( Origin gPackager )
				)
				( attribute "CDS_PART_NAME" "CAP_0402LF-4700PF,50V,10%,EMPTA"
					( Origin gPackager )
				)
				( attribute "GROUP" "NI_I210&RJ45"
					( Origin gFrontEnd )
				)
				( objectStatus "C9G12" )
			)
			( gate "@baseboard_fab2_lib.baseboard_fab2(sch_1):page141_i101"
				( attribute "BOM_COST" "NT_GBE_BASE"
					( Origin gFrontEnd )
				)
				( attribute "CDS_LIB" "mstr_discrete"
					( Origin gPackager )
				)
				( attribute "CDS_LOCATION" "C9G16"
					( Origin gPackager )
				)
				( attribute "LOCATION" "C9G16"
					( Origin gFrontEnd )
				)
				( attribute "MATERIAL" "EMPTY"
					( Origin gFrontEnd )
				)
				( attribute "NO_XNET_CONNECTION" "1"
					( Origin gFrontEnd )
				)
				( attribute "PACK_TYPE" "0402LF"
					( Origin gFrontEnd )
				)
				( attribute "PART_NUMBER" "A36096-066"
					( Origin gFrontEnd )
				)
				( attribute "PHYS_PAGE" "141"
					( Origin gFrontEnd )
				)
				( attribute "ROOM" "NIC_SPRV"
					( Origin gFrontEnd )
				)
				( attribute "ROT" "0"
					( Origin gFrontEnd )
				)
				( attribute "SEC" "1"
					( Origin gFrontEnd )
				)
				( attribute "TOLERANCE" "10%"
					( Origin gFrontEnd )
				)
				( attribute "VALUE" "4700PF"
					( Origin gFrontEnd )
				)
				( attribute "VER" "2"
					( Origin gFrontEnd )
				)
				( attribute "VOLTAGE" "50V"
					( Units "uVoltage" "V" 1.000000)
					( Origin gFrontEnd )
				)
				( attribute "XY" "(-2825,4075)"
					( Origin gFrontEnd )
				)
				( attribute "CHIPS_PART_NAME" "CAP"
					( Origin gPackager )
				)
				( attribute "CDS_PART_NAME" "CAP_0402LF-4700PF,50V,10%,EMPTA"
					( Origin gPackager )
				)
				( attribute "SEC_TYPE" "0402LF"
					( Origin gFrontEnd )
				)
				( attribute "CDS_SEC" "1"
					( Origin gPackager )
				)
				( attribute "GROUP" "NI_I210&RJ45"
					( Origin gFrontEnd )
				)
				( objectStatus "C9G16" )
			)
			( gate "@baseboard_fab2_lib.baseboard_fab2(sch_1):page141_i102"
				( attribute "BOM_COST" "NT_GBE_BASE"
					( Origin gFrontEnd )
				)
				( attribute "CDS_LIB" "mstr_discrete"
					( Origin gPackager )
				)
				( attribute "CDS_LOCATION" "C9G13"
					( Origin gPackager )
				)
				( attribute "LOCATION" "C9G13"
					( Origin gFrontEnd )
				)
				( attribute "MATERIAL" "EMPTY"
					( Origin gFrontEnd )
				)
				( attribute "NO_XNET_CONNECTION" "1"
					( Origin gFrontEnd )
				)
				( attribute "PACK_TYPE" "0402LF"
					( Origin gFrontEnd )
				)
				( attribute "PART_NUMBER" "A36096-066"
					( Origin gFrontEnd )
				)
				( attribute "PHYS_PAGE" "141"
					( Origin gFrontEnd )
				)
				( attribute "ROOM" "NIC_SPRV"
					( Origin gFrontEnd )
				)
				( attribute "ROT" "0"
					( Origin gFrontEnd )
				)
				( attribute "SEC" "1"
					( Origin gFrontEnd )
				)
				( attribute "TOLERANCE" "10%"
					( Origin gFrontEnd )
				)
				( attribute "VALUE" "4700PF"
					( Origin gFrontEnd )
				)
				( attribute "VER" "2"
					( Origin gFrontEnd )
				)
				( attribute "VOLTAGE" "50V"
					( Units "uVoltage" "V" 1.000000)
					( Origin gFrontEnd )
				)
				( attribute "XY" "(-3100,4025)"
					( Origin gFrontEnd )
				)
				( attribute "CHIPS_PART_NAME" "CAP"
					( Origin gPackager )
				)
				( attribute "CDS_PART_NAME" "CAP_0402LF-4700PF,50V,10%,EMPTA"
					( Origin gPackager )
				)
				( attribute "SEC_TYPE" "0402LF"
					( Origin gFrontEnd )
				)
				( attribute "CDS_SEC" "1"
					( Origin gPackager )
				)
				( attribute "GROUP" "NI_I210&RJ45"
					( Origin gFrontEnd )
				)
				( objectStatus "C9G13" )
			)
			( gate "@baseboard_fab2_lib.baseboard_fab2(sch_1):page114_i193"
				( attribute "CDS_LIB" "mstr_discrete"
					( Origin gPackager )
				)
				( attribute "LOCATION" "C3W1"
					( Origin gFrontEnd )
				)
				( attribute "MATERIAL" "EMPTY"
					( Origin gFrontEnd )
				)
				( attribute "PACK_TYPE" "0402"
					( Origin gFrontEnd )
				)
				( attribute "PART_NUMBER" "D97712-004"
					( Origin gFrontEnd )
				)
				( attribute "PHYS_PAGE" "114"
					( Origin gFrontEnd )
				)
				( attribute "ROT" "0"
					( Origin gFrontEnd )
				)
				( attribute "SEC" "1"
					( Origin gFrontEnd )
				)
				( attribute "SEC_TYPE" "0402"
					( Origin gFrontEnd )
				)
				( attribute "TOLERANCE" "10%"
					( Origin gFrontEnd )
				)
				( attribute "VALUE" "1.0UF"
					( Origin gFrontEnd )
				)
				( attribute "VER" "1"
					( Origin gFrontEnd )
				)
				( attribute "VOLTAGE" "6.3V"
					( Units "uVoltage" "V" 1.000000)
					( Origin gFrontEnd )
				)
				( attribute "XY" "(-2850,2750)"
					( Origin gFrontEnd )
				)
				( attribute "CHIPS_PART_NAME" "CAP"
					( Origin gPackager )
				)
				( attribute "CDS_PART_NAME" "CAP_0402-1.0UF,6.3V,10%,EMPTY,A"
					( Origin gPackager )
				)
				( attribute "CDS_LOCATION" "C3W1"
					( Origin gPackager )
				)
				( attribute "CDS_SEC" "1"
					( Origin gPackager )
				)
				( objectStatus "C3W1" )
			)
			( gate "@baseboard_fab2_lib.baseboard_fab2(sch_1):page142_i1"
				( attribute "BOM_COST" "SB"
					( Origin gFrontEnd )
				)
				( attribute "CDS_LIB" "mstr_ttl"
					( Origin gPackager )
				)
				( attribute "CDS_LOCATION" "U8E4"
					( Origin gPackager )
				)
				( attribute "CDS_SEC" "1"
					( Origin gPackager )
				)
				( attribute "LOCATION" "U8E4"
					( Origin gFrontEnd )
				)
				( attribute "MATERIAL" "IC"
					( Origin gFrontEnd )
				)
				( attribute "PACK_TYPE" "SOT"
					( Origin gFrontEnd )
				)
				( attribute "PART_NUMBER" "A79322-001"
					( Origin gFrontEnd )
				)
				( attribute "PHYS_PAGE" "142"
					( Origin gFrontEnd )
				)
				( attribute "ROOM" "PCIE_WAKE_BUFFER"
					( Origin gFrontEnd )
				)
				( attribute "ROT" "6"
					( Origin gFrontEnd )
				)
				( attribute "SEC" "1"
					( Origin gFrontEnd )
				)
				( attribute "SEC_TYPE" "SOT"
					( Origin gFrontEnd )
				)
				( attribute "VALUE" "74HC1G126"
					( Origin gFrontEnd )
				)
				( attribute "VER" "1"
					( Origin gFrontEnd )
				)
				( attribute "XY" "(-3500,2250)"
					( Origin gFrontEnd )
				)
				( attribute "CHIPS_PART_NAME" "TTL1G126_A"
					( Origin gPackager )
				)
				( attribute "CDS_PART_NAME" "TTL1G126_A_SOT-74HC1G126,IC,A7B"
					( Origin gPackager )
				)
				( objectStatus "U8E4" )
			)
			( gate "@baseboard_fab2_lib.baseboard_fab2(sch_1):page142_i2"
				( attribute "BOM_COST" "SB"
					( Origin gFrontEnd )
				)
				( attribute "CDS_LIB" "mstr_discrete"
					( Origin gPackager )
				)
				( attribute "CDS_LOCATION" "R8E17"
					( Origin gPackager )
				)
				( attribute "CDS_SEC" "1"
					( Origin gPackager )
				)
				( attribute "LOCATION" "R8E17"
					( Origin gFrontEnd )
				)
				( attribute "MATERIAL" "CHIP"
					( Origin gFrontEnd )
				)
				( attribute "PACK_TYPE" "0402"
					( Origin gFrontEnd )
				)
				( attribute "PART_NUMBER" "G21796-074"
					( Origin gFrontEnd )
				)
				( attribute "PHYS_PAGE" "142"
					( Origin gFrontEnd )
				)
				( attribute "ROOM" "PCIE_WAKE_BUFFER"
					( Origin gFrontEnd )
				)
				( attribute "ROT" "0"
					( Origin gFrontEnd )
				)
				( attribute "SEC" "1"
					( Origin gFrontEnd )
				)
				( attribute "SEC_TYPE" "0402"
					( Origin gFrontEnd )
				)
				( attribute "TOLERANCE" "1%"
					( Origin gFrontEnd )
				)
				( attribute "VALUE" "33.2"
					( Origin gFrontEnd )
				)
				( attribute "VER" "1"
					( Origin gFrontEnd )
				)
				( attribute "WATTAGE" "1/16W"
					( Origin gFrontEnd )
				)
				( attribute "XY" "(-2600,2250)"
					( Origin gFrontEnd )
				)
				( attribute "CHIPS_PART_NAME" "RES"
					( Origin gPackager )
				)
				( attribute "CDS_PART_NAME" "RES_0402-33.2,1%,1/16W,CHIP,G2A"
					( Origin gPackager )
				)
				( objectStatus "R8E17" )
			)
			( gate "@baseboard_fab2_lib.baseboard_fab2(sch_1):page142_i3"
				( attribute "BOM_COST" "SB"
					( Origin gFrontEnd )
				)
				( attribute "CDS_LIB" "mstr_discrete"
					( Origin gPackager )
				)
				( attribute "CDS_LOCATION" "R8E23"
					( Origin gPackager )
				)
				( attribute "CDS_SEC" "1"
					( Origin gPackager )
				)
				( attribute "LOCATION" "R8E23"
					( Origin gFrontEnd )
				)
				( attribute "MATERIAL" "CHIP"
					( Origin gFrontEnd )
				)
				( attribute "PACK_TYPE" "0402"
					( Origin gFrontEnd )
				)
				( attribute "PART_NUMBER" "G21796-072"
					( Origin gFrontEnd )
				)
				( attribute "PHYS_PAGE" "142"
					( Origin gFrontEnd )
				)
				( attribute "ROOM" "PCIE_WAKE_BUFFER"
					( Origin gFrontEnd )
				)
				( attribute "ROT" "0"
					( Origin gFrontEnd )
				)
				( attribute "SEC" "1"
					( Origin gFrontEnd )
				)
				( attribute "SEC_TYPE" "0402"
					( Origin gFrontEnd )
				)
				( attribute "TOLERANCE" "1%"
					( Origin gFrontEnd )
				)
				( attribute "VALUE" "4.75K"
					( Origin gFrontEnd )
				)
				( attribute "VER" "1"
					( Origin gFrontEnd )
				)
				( attribute "WATTAGE" "1/16W"
					( Origin gFrontEnd )
				)
				( attribute "XY" "(-2850,2700)"
					( Origin gFrontEnd )
				)
				( attribute "CHIPS_PART_NAME" "RES"
					( Origin gPackager )
				)
				( attribute "CDS_PART_NAME" "RES_0402-4.75K,1%,1/16W,CHIP,GA"
					( Origin gPackager )
				)
				( objectStatus "R8E23" )
			)
			( gate "@baseboard_fab2_lib.baseboard_fab2(sch_1):page142_i18"
				( attribute "BOM_COST" "SB"
					( Origin gFrontEnd )
				)
				( attribute "CDS_LIB" "mstr_discrete"
					( Origin gPackager )
				)
				( attribute "CDS_LOCATION" "R8E29"
					( Origin gPackager )
				)
				( attribute "CDS_SEC" "1"
					( Origin gPackager )
				)
				( attribute "LOCATION" "R8E29"
					( Origin gFrontEnd )
				)
				( attribute "MATERIAL" "EMPTY"
					( Origin gFrontEnd )
				)
				( attribute "PACK_TYPE" "0402"
					( Origin gFrontEnd )
				)
				( attribute "PART_NUMBER" "G21497-005"
					( Origin gFrontEnd )
				)
				( attribute "PHYS_PAGE" "142"
					( Origin gFrontEnd )
				)
				( attribute "ROOM" "PCIE_WAKE_BUFFER"
					( Origin gFrontEnd )
				)
				( attribute "ROT" "0"
					( Origin gFrontEnd )
				)
				( attribute "SEC" "1"
					( Origin gFrontEnd )
				)
				( attribute "SEC_TYPE" "0402"
					( Origin gFrontEnd )
				)
				( attribute "TOLERANCE" "5%"
					( Origin gFrontEnd )
				)
				( attribute "VALUE" "0.0"
					( Origin gFrontEnd )
				)
				( attribute "VER" "1"
					( Origin gFrontEnd )
				)
				( attribute "WATTAGE" "1/16W"
					( Origin gFrontEnd )
				)
				( attribute "XY" "(-4550,3100)"
					( Origin gFrontEnd )
				)
				( attribute "CHIPS_PART_NAME" "RES"
					( Origin gPackager )
				)
				( attribute "CDS_PART_NAME" "RES_0402-0.0,5%,1/16W,EMPTY,G2A"
					( Origin gPackager )
				)
				( objectStatus "R8E29" )
			)
			( gate "@baseboard_fab2_lib.baseboard_fab2(sch_1):page142_i20"
				( attribute "BOM_COST" "SB"
					( Origin gFrontEnd )
				)
				( attribute "CDS_LIB" "dev_discrete"
					( Origin gPackager )
				)
				( attribute "CDS_LOCATION" "C8E5"
					( Origin gPackager )
				)
				( attribute "CDS_SEC" "1"
					( Origin gPackager )
				)
				( attribute "LOCATION" "C8E5"
					( Origin gFrontEnd )
				)
				( attribute "MATERIAL" "X7R"
					( Origin gFrontEnd )
				)
				( attribute "PACK_TYPE" "0402V"
					( Origin gFrontEnd )
				)
				( attribute "PART_NUMBER" "A36096-030"
					( Origin gFrontEnd )
				)
				( attribute "PHYS_PAGE" "142"
					( Origin gFrontEnd )
				)
				( attribute "ROOM" "PCIE_WAKE_BUFFER"
					( Origin gFrontEnd )
				)
				( attribute "ROT" "0"
					( Origin gFrontEnd )
				)
				( attribute "SEC" "1"
					( Origin gFrontEnd )
				)
				( attribute "SEC_TYPE" "0402V"
					( Origin gFrontEnd )
				)
				( attribute "TOLERANCE" "10%"
					( Origin gFrontEnd )
				)
				( attribute "VALUE" "0.1UF"
					( Origin gFrontEnd )
				)
				( attribute "VER" "1"
					( Origin gFrontEnd )
				)
				( attribute "VOLTAGE" "16V"
					( Units "uVoltage" "V" 1.000000)
					( Origin gFrontEnd )
				)
				( attribute "XY" "(-3500,1550)"
					( Origin gFrontEnd )
				)
				( attribute "CHIPS_PART_NAME" "CAP_A"
					( Origin gPackager )
				)
				( attribute "CDS_PART_NAME" "CAP_A_0402V-0.1UF,16V,10%,X7R,A"
					( Origin gPackager )
				)
				( objectStatus "C8E5" )
			)
			( gate "@baseboard_fab2_lib.baseboard_fab2(sch_1):page92_i111"
				( attribute "CDS_LIB" "w_hdl"
					( Origin gPackager )
				)
				( attribute "CDS_LMAN_SYM_OUTLINE" "-50,75,50,-75"
					( Origin gPackager )
				)
				( attribute "LOCATION" "R7D33"
					( Origin gFrontEnd )
				)
				( attribute "PACK_TYPE" "SMD-RG"
					( Origin gFrontEnd )
				)
				( attribute "PART_NUMBER" "64.37405.6DL"
					( Origin gFrontEnd )
				)
				( attribute "PHYS_PAGE" "92"
					( Origin gFrontEnd )
				)
				( attribute "ROT" "0"
					( Origin gFrontEnd )
				)
				( attribute "VALUE" "374R2F-1-GP"
					( Origin gFrontEnd )
				)
				( attribute "VER" "1"
					( Origin gFrontEnd )
				)
				( attribute "XY" "(350,3025)"
					( Origin gFrontEnd )
				)
				( attribute "CHIPS_PART_NAME" "374R2F-1-GP"
					( Origin gPackager )
				)
				( attribute "CDS_PART_NAME" "374R2F-1-GP_SMD-RG-374R2F-1-GPA"
					( Origin gPackager )
				)
				( attribute "CDS_LOCATION" "R7D33"
					( Origin gPackager )
				)
				( attribute "CDS_SEC" "1"
					( Origin gPackager )
				)
				( attribute "SEC" "1"
					( Origin gPackager )
				)
				( attribute "ATTRIBUTE" "374 OHM"
					( Origin gFrontEnd )
				)
				( attribute "PACK_SIZE" "0402"
					( Origin gFrontEnd )
				)
				( attribute "RATED" "1/16W"
					( Origin gFrontEnd )
				)
				( attribute "TOLERANCE" "1%"
					( Origin gFrontEnd )
				)
				( objectStatus "R7D33" )
			)
			( gate "@baseboard_fab2_lib.baseboard_fab2(sch_1):page92_i110"
				( attribute "CDS_LIB" "w_hdl"
					( Origin gPackager )
				)
				( attribute "CDS_LMAN_SYM_OUTLINE" "-50,75,50,-75"
					( Origin gPackager )
				)
				( attribute "LOCATION" "R3P45"
					( Origin gFrontEnd )
				)
				( attribute "PACK_TYPE" "SMD-RG"
					( Origin gFrontEnd )
				)
				( attribute "PART_NUMBER" "64.37405.6DL"
					( Origin gFrontEnd )
				)
				( attribute "PHYS_PAGE" "92"
					( Origin gFrontEnd )
				)
				( attribute "ROT" "0"
					( Origin gFrontEnd )
				)
				( attribute "VALUE" "374R2F-1-GP"
					( Origin gFrontEnd )
				)
				( attribute "VER" "1"
					( Origin gFrontEnd )
				)
				( attribute "XY" "(100,5325)"
					( Origin gFrontEnd )
				)
				( attribute "CHIPS_PART_NAME" "374R2F-1-GP"
					( Origin gPackager )
				)
				( attribute "CDS_PART_NAME" "374R2F-1-GP_SMD-RG-374R2F-1-GPA"
					( Origin gPackager )
				)
				( attribute "CDS_LOCATION" "R3P45"
					( Origin gPackager )
				)
				( attribute "CDS_SEC" "1"
					( Origin gPackager )
				)
				( attribute "SEC" "1"
					( Origin gPackager )
				)
				( attribute "ATTRIBUTE" "374 OHM"
					( Origin gFrontEnd )
				)
				( attribute "PACK_SIZE" "0402"
					( Origin gFrontEnd )
				)
				( attribute "RATED" "1/16W"
					( Origin gFrontEnd )
				)
				( attribute "TOLERANCE" "1%"
					( Origin gFrontEnd )
				)
				( objectStatus "R3P45" )
			)
			( gate "@baseboard_fab2_lib.baseboard_fab2(sch_1):page142_i30"
				( attribute "CDS_LIB" "mstr_discrete"
					( Origin gPackager )
				)
				( attribute "CDS_LOCATION" "R8E26"
					( Origin gPackager )
				)
				( attribute "CDS_SEC" "1"
					( Origin gPackager )
				)
				( attribute "LOCATION" "R8E26"
					( Origin gFrontEnd )
				)
				( attribute "MATERIAL" "CHIP"
					( Origin gFrontEnd )
				)
				( attribute "PACK_TYPE" "0402"
					( Origin gFrontEnd )
				)
				( attribute "PART_NUMBER" "G21497-005"
					( Origin gFrontEnd )
				)
				( attribute "PHYS_PAGE" "142"
					( Origin gFrontEnd )
				)
				( attribute "ROOM" "PCIE_WAKE_BUFFER"
					( Origin gFrontEnd )
				)
				( attribute "ROT" "0"
					( Origin gFrontEnd )
				)
				( attribute "SEC" "1"
					( Origin gFrontEnd )
				)
				( attribute "SEC_TYPE" "0402"
					( Origin gFrontEnd )
				)
				( attribute "TOLERANCE" "5%"
					( Origin gFrontEnd )
				)
				( attribute "VALUE" "0.0"
					( Origin gFrontEnd )
				)
				( attribute "VER" "1"
					( Origin gFrontEnd )
				)
				( attribute "WATTAGE" "1/16W"
					( Origin gFrontEnd )
				)
				( attribute "XY" "(-4550,2250)"
					( Origin gFrontEnd )
				)
				( attribute "CHIPS_PART_NAME" "RES"
					( Origin gPackager )
				)
				( attribute "CDS_PART_NAME" "RES_0402-0.0,5%,1/16W,CHIP,G21A"
					( Origin gPackager )
				)
				( objectStatus "R8E26" )
			)
			( gate "@baseboard_fab2_lib.baseboard_fab2(sch_1):page142_i31"
				( attribute "CDS_LIB" "mstr_discrete"
					( Origin gPackager )
				)
				( attribute "CDS_LOCATION" "R8E28"
					( Origin gPackager )
				)
				( attribute "CDS_SEC" "1"
					( Origin gPackager )
				)
				( attribute "LOCATION" "R8E28"
					( Origin gFrontEnd )
				)
				( attribute "MATERIAL" "CHIP"
					( Origin gFrontEnd )
				)
				( attribute "PACK_TYPE" "0402"
					( Origin gFrontEnd )
				)
				( attribute "PART_NUMBER" "G21497-005"
					( Origin gFrontEnd )
				)
				( attribute "PHYS_PAGE" "142"
					( Origin gFrontEnd )
				)
				( attribute "ROOM" "PCIE_WAKE_BUFFER"
					( Origin gFrontEnd )
				)
				( attribute "ROT" "0"
					( Origin gFrontEnd )
				)
				( attribute "SEC" "1"
					( Origin gFrontEnd )
				)
				( attribute "SEC_TYPE" "0402"
					( Origin gFrontEnd )
				)
				( attribute "TOLERANCE" "5%"
					( Origin gFrontEnd )
				)
				( attribute "VALUE" "0.0"
					( Origin gFrontEnd )
				)
				( attribute "VER" "1"
					( Origin gFrontEnd )
				)
				( attribute "WATTAGE" "1/16W"
					( Origin gFrontEnd )
				)
				( attribute "XY" "(-4550,2450)"
					( Origin gFrontEnd )
				)
				( attribute "CHIPS_PART_NAME" "RES"
					( Origin gPackager )
				)
				( attribute "CDS_PART_NAME" "RES_0402-0.0,5%,1/16W,CHIP,G21A"
					( Origin gPackager )
				)
				( objectStatus "R8E28" )
			)
			( gate "@baseboard_fab2_lib.baseboard_fab2(sch_1):page142_i32"
				( attribute "CDS_LIB" "mstr_discrete"
					( Origin gPackager )
				)
				( attribute "CDS_LOCATION" "R8E27"
					( Origin gPackager )
				)
				( attribute "CDS_SEC" "1"
					( Origin gPackager )
				)
				( attribute "LOCATION" "R8E27"
					( Origin gFrontEnd )
				)
				( attribute "MATERIAL" "CHIP"
					( Origin gFrontEnd )
				)
				( attribute "PACK_TYPE" "0402"
					( Origin gFrontEnd )
				)
				( attribute "PART_NUMBER" "G21497-005"
					( Origin gFrontEnd )
				)
				( attribute "PHYS_PAGE" "142"
					( Origin gFrontEnd )
				)
				( attribute "ROOM" "PCIE_WAKE_BUFFER"
					( Origin gFrontEnd )
				)
				( attribute "ROT" "0"
					( Origin gFrontEnd )
				)
				( attribute "SEC" "1"
					( Origin gFrontEnd )
				)
				( attribute "SEC_TYPE" "0402"
					( Origin gFrontEnd )
				)
				( attribute "TOLERANCE" "5%"
					( Origin gFrontEnd )
				)
				( attribute "VALUE" "0.0"
					( Origin gFrontEnd )
				)
				( attribute "VER" "1"
					( Origin gFrontEnd )
				)
				( attribute "WATTAGE" "1/16W"
					( Origin gFrontEnd )
				)
				( attribute "XY" "(-4550,2650)"
					( Origin gFrontEnd )
				)
				( attribute "CHIPS_PART_NAME" "RES"
					( Origin gPackager )
				)
				( attribute "CDS_PART_NAME" "RES_0402-0.0,5%,1/16W,CHIP,G21A"
					( Origin gPackager )
				)
				( objectStatus "R8E27" )
			)
			( gate "@baseboard_fab2_lib.baseboard_fab2(sch_1):page142_i33"
				( attribute "CDS_LIB" "mstr_discrete"
					( Origin gPackager )
				)
				( attribute "CDS_LOCATION" "R8E21"
					( Origin gPackager )
				)
				( attribute "CDS_SEC" "1"
					( Origin gPackager )
				)
				( attribute "LOCATION" "R8E21"
					( Origin gFrontEnd )
				)
				( attribute "MATERIAL" "CHIP"
					( Origin gFrontEnd )
				)
				( attribute "PACK_TYPE" "0402"
					( Origin gFrontEnd )
				)
				( attribute "PART_NUMBER" "G21497-005"
					( Origin gFrontEnd )
				)
				( attribute "PHYS_PAGE" "142"
					( Origin gFrontEnd )
				)
				( attribute "ROOM" "PCIE_WAKE_BUFFER"
					( Origin gFrontEnd )
				)
				( attribute "ROT" "0"
					( Origin gFrontEnd )
				)
				( attribute "SEC" "1"
					( Origin gFrontEnd )
				)
				( attribute "SEC_TYPE" "0402"
					( Origin gFrontEnd )
				)
				( attribute "TOLERANCE" "5%"
					( Origin gFrontEnd )
				)
				( attribute "VALUE" "0.0"
					( Origin gFrontEnd )
				)
				( attribute "VER" "1"
					( Origin gFrontEnd )
				)
				( attribute "WATTAGE" "1/16W"
					( Origin gFrontEnd )
				)
				( attribute "XY" "(-4550,2850)"
					( Origin gFrontEnd )
				)
				( attribute "CHIPS_PART_NAME" "RES"
					( Origin gPackager )
				)
				( attribute "CDS_PART_NAME" "RES_0402-0.0,5%,1/16W,CHIP,G21A"
					( Origin gPackager )
				)
				( objectStatus "R8E21" )
			)
			( gate "@baseboard_fab2_lib.baseboard_fab2(sch_1):page145_i117"
				( attribute "CDS_LIB" "w_hdl"
					( Origin gPackager )
				)
				( attribute "CDS_LMAN_SYM_OUTLINE" "-1150,1400,1150,-1400"
					( Origin gPackager )
				)
				( attribute "LOCATION" "U25W4"
					( Origin gFrontEnd )
				)
				( attribute "PACK_TYPE" "ASIC2-GB1"
					( Origin gFrontEnd )
				)
				( attribute "PART_NUMBER" "071.2520A.M001"
					( Origin gFrontEnd )
				)
				( attribute "PHYS_PAGE" "145"
					( Origin gFrontEnd )
				)
				( attribute "ROT" "0"
					( Origin gFrontEnd )
				)
				( attribute "VALUE" "AST2520A1-GP-GP"
					( Origin gFrontEnd )
				)
				( attribute "VER" "3"
					( Origin gFrontEnd )
				)
				( attribute "XY" "(-3800,-2550)"
					( Origin gFrontEnd )
				)
				( attribute "CHIPS_PART_NAME" "AST2520A1-GP-GP"
					( Origin gPackager )
				)
				( attribute "CDS_PART_NAME" "AST2520A1-GP-GP_ASIC2-GB1-AST2A"
					( Origin gPackager )
				)
				( attribute "SEC" "3"
					( Origin gFrontEnd )
				)
				( attribute "SEC_TYPE" "ASIC2-GB1"
					( Origin gFrontEnd )
				)
				( attribute "CDS_LOCATION" "U25W4"
					( Origin gPackager )
				)
				( attribute "CDS_SEC" "3"
					( Origin gPackager )
				)
				( objectStatus "U25W4" )
			)
			( gate "@baseboard_fab2_lib.baseboard_fab2(sch_1):page151_i141"
				( attribute "CDS_LIB" "mstr_discrete"
					( Origin gPackager )
				)
				( attribute "CDS_LOCATION" "C25W4"
					( Origin gPackager )
				)
				( attribute "CDS_SEC" "1"
					( Origin gPackager )
				)
				( attribute "LOCATION" "C25W4"
					( Origin gFrontEnd )
				)
				( attribute "MATERIAL" "X6S"
					( Origin gFrontEnd )
				)
				( attribute "PACK_TYPE" "0402"
					( Origin gFrontEnd )
				)
				( attribute "PART_NUMBER" "D97712-011"
					( Origin gFrontEnd )
				)
				( attribute "PHYS_PAGE" "151"
					( Origin gFrontEnd )
				)
				( attribute "ROOM" "VDDQ_KLM_PWR_VR"
					( Origin gFrontEnd )
				)
				( attribute "ROT" "1"
					( Origin gFrontEnd )
				)
				( attribute "SEC" "1"
					( Origin gPackager )
				)
				( attribute "TOLERANCE" "10%"
					( Origin gFrontEnd )
				)
				( attribute "VALUE" "1.0UF"
					( Origin gFrontEnd )
				)
				( attribute "VER" "1"
					( Origin gFrontEnd )
				)
				( attribute "VOLTAGE" "16V"
					( Units "uVoltage" "V" 1.000000)
					( Origin gFrontEnd )
				)
				( attribute "XY" "(325,925)"
					( Origin gFrontEnd )
				)
				( attribute "CHIPS_PART_NAME" "CAP"
					( Origin gPackager )
				)
				( attribute "CDS_PART_NAME" "CAP_0402-1.0UF,16V,10%,X6S,D97A"
					( Origin gPackager )
				)
				( objectStatus "C25W4" )
			)
			( gate "@baseboard_fab2_lib.baseboard_fab2(sch_1):page151_i140"
				( attribute "CDS_LIB" "mstr_discrete"
					( Origin gPackager )
				)
				( attribute "CDS_LOCATION" "C25W3"
					( Origin gPackager )
				)
				( attribute "CDS_SEC" "1"
					( Origin gPackager )
				)
				( attribute "LOCATION" "C25W3"
					( Origin gFrontEnd )
				)
				( attribute "MATERIAL" "X6S"
					( Origin gFrontEnd )
				)
				( attribute "PACK_TYPE" "0402"
					( Origin gFrontEnd )
				)
				( attribute "PART_NUMBER" "D97712-011"
					( Origin gFrontEnd )
				)
				( attribute "PHYS_PAGE" "151"
					( Origin gFrontEnd )
				)
				( attribute "ROOM" "VDDQ_KLM_PWR_VR"
					( Origin gFrontEnd )
				)
				( attribute "ROT" "1"
					( Origin gFrontEnd )
				)
				( attribute "SEC" "1"
					( Origin gPackager )
				)
				( attribute "TOLERANCE" "10%"
					( Origin gFrontEnd )
				)
				( attribute "VALUE" "1.0UF"
					( Origin gFrontEnd )
				)
				( attribute "VER" "1"
					( Origin gFrontEnd )
				)
				( attribute "VOLTAGE" "16V"
					( Units "uVoltage" "V" 1.000000)
					( Origin gFrontEnd )
				)
				( attribute "XY" "(325,1175)"
					( Origin gFrontEnd )
				)
				( attribute "CHIPS_PART_NAME" "CAP"
					( Origin gPackager )
				)
				( attribute "CDS_PART_NAME" "CAP_0402-1.0UF,16V,10%,X6S,D97A"
					( Origin gPackager )
				)
				( objectStatus "C25W3" )
			)
			( gate "@baseboard_fab2_lib.baseboard_fab2(sch_1):page151_i139"
				( attribute "CDS_LIB" "mstr_discrete"
					( Origin gPackager )
				)
				( attribute "CDS_LOCATION" "C25W2"
					( Origin gPackager )
				)
				( attribute "CDS_SEC" "1"
					( Origin gPackager )
				)
				( attribute "LOCATION" "C25W2"
					( Origin gFrontEnd )
				)
				( attribute "MATERIAL" "X6S"
					( Origin gFrontEnd )
				)
				( attribute "PACK_TYPE" "0402"
					( Origin gFrontEnd )
				)
				( attribute "PART_NUMBER" "D97712-011"
					( Origin gFrontEnd )
				)
				( attribute "PHYS_PAGE" "151"
					( Origin gFrontEnd )
				)
				( attribute "ROOM" "VDDQ_KLM_PWR_VR"
					( Origin gFrontEnd )
				)
				( attribute "ROT" "1"
					( Origin gFrontEnd )
				)
				( attribute "SEC" "1"
					( Origin gPackager )
				)
				( attribute "TOLERANCE" "10%"
					( Origin gFrontEnd )
				)
				( attribute "VALUE" "1.0UF"
					( Origin gFrontEnd )
				)
				( attribute "VER" "1"
					( Origin gFrontEnd )
				)
				( attribute "VOLTAGE" "16V"
					( Units "uVoltage" "V" 1.000000)
					( Origin gFrontEnd )
				)
				( attribute "XY" "(325,1425)"
					( Origin gFrontEnd )
				)
				( attribute "CHIPS_PART_NAME" "CAP"
					( Origin gPackager )
				)
				( attribute "CDS_PART_NAME" "CAP_0402-1.0UF,16V,10%,X6S,D97A"
					( Origin gPackager )
				)
				( objectStatus "C25W2" )
			)
			( gate "@baseboard_fab2_lib.baseboard_fab2(sch_1):page143_i58"
				( attribute "BOM_COST" "SM_MEM"
					( Origin gFrontEnd )
				)
				( attribute "CDS_LIB" "mstr_discrete"
					( Origin gPackager )
				)
				( attribute "LOCATION" "R1T27"
					( Origin gFrontEnd )
				)
				( attribute "MATERIAL" "CHIP"
					( Origin gFrontEnd )
				)
				( attribute "PACK_TYPE" "0402"
					( Origin gFrontEnd )
				)
				( attribute "PART_NUMBER" "G21796-294"
					( Origin gFrontEnd )
				)
				( attribute "PHYS_PAGE" "143"
					( Origin gFrontEnd )
				)
				( attribute "ROOM" "BMC_MEMORY"
					( Origin gFrontEnd )
				)
				( attribute "ROT" "7"
					( Origin gFrontEnd )
				)
				( attribute "TOLERANCE" "1.0%"
					( Origin gFrontEnd )
				)
				( attribute "VALUE" "240"
					( Origin gFrontEnd )
				)
				( attribute "VER" "2"
					( Origin gFrontEnd )
				)
				( attribute "WATTAGE" "1/16W"
					( Origin gFrontEnd )
				)
				( attribute "XY" "(-11000,-2150)"
					( Origin gFrontEnd )
				)
				( attribute "CHIPS_PART_NAME" "RES"
					( Origin gPackager )
				)
				( attribute "CDS_PART_NAME" "RES_0402-240,1.0%,1/16W,CHIP,GA"
					( Origin gPackager )
				)
				( attribute "CDS_LOCATION" "R1T27"
					( Origin gPackager )
				)
				( attribute "SEC" "1"
					( Origin gFrontEnd )
				)
				( attribute "SEC_TYPE" "0402"
					( Origin gFrontEnd )
				)
				( attribute "CDS_SEC" "1"
					( Origin gPackager )
				)
				( objectStatus "R1T27" )
			)
			( gate "@baseboard_fab2_lib.baseboard_fab2(sch_1):page151_i142"
				( attribute "CDS_LIB" "mstr_discrete"
					( Origin gPackager )
				)
				( attribute "CDS_LOCATION" "C25W5"
					( Origin gPackager )
				)
				( attribute "CDS_SEC" "1"
					( Origin gPackager )
				)
				( attribute "LOCATION" "C25W5"
					( Origin gFrontEnd )
				)
				( attribute "MATERIAL" "X6S"
					( Origin gFrontEnd )
				)
				( attribute "PACK_TYPE" "0402"
					( Origin gFrontEnd )
				)
				( attribute "PART_NUMBER" "D97712-011"
					( Origin gFrontEnd )
				)
				( attribute "PHYS_PAGE" "151"
					( Origin gFrontEnd )
				)
				( attribute "ROOM" "VDDQ_KLM_PWR_VR"
					( Origin gFrontEnd )
				)
				( attribute "ROT" "1"
					( Origin gFrontEnd )
				)
				( attribute "SEC" "1"
					( Origin gPackager )
				)
				( attribute "TOLERANCE" "10%"
					( Origin gFrontEnd )
				)
				( attribute "VALUE" "1.0UF"
					( Origin gFrontEnd )
				)
				( attribute "VER" "1"
					( Origin gFrontEnd )
				)
				( attribute "VOLTAGE" "16V"
					( Units "uVoltage" "V" 1.000000)
					( Origin gFrontEnd )
				)
				( attribute "XY" "(325,675)"
					( Origin gFrontEnd )
				)
				( attribute "CHIPS_PART_NAME" "CAP"
					( Origin gPackager )
				)
				( attribute "CDS_PART_NAME" "CAP_0402-1.0UF,16V,10%,X6S,D97A"
					( Origin gPackager )
				)
				( objectStatus "C25W5" )
			)
			( gate "@baseboard_fab2_lib.baseboard_fab2(sch_1):page151_i143"
				( attribute "CDS_LIB" "mstr_discrete"
					( Origin gPackager )
				)
				( attribute "CDS_LOCATION" "C25W6"
					( Origin gPackager )
				)
				( attribute "CDS_SEC" "1"
					( Origin gPackager )
				)
				( attribute "LOCATION" "C25W6"
					( Origin gFrontEnd )
				)
				( attribute "MATERIAL" "X6S"
					( Origin gFrontEnd )
				)
				( attribute "PACK_TYPE" "0402"
					( Origin gFrontEnd )
				)
				( attribute "PART_NUMBER" "D97712-011"
					( Origin gFrontEnd )
				)
				( attribute "PHYS_PAGE" "151"
					( Origin gFrontEnd )
				)
				( attribute "ROOM" "VDDQ_KLM_PWR_VR"
					( Origin gFrontEnd )
				)
				( attribute "ROT" "1"
					( Origin gFrontEnd )
				)
				( attribute "SEC" "1"
					( Origin gPackager )
				)
				( attribute "TOLERANCE" "10%"
					( Origin gFrontEnd )
				)
				( attribute "VALUE" "1.0UF"
					( Origin gFrontEnd )
				)
				( attribute "VER" "1"
					( Origin gFrontEnd )
				)
				( attribute "VOLTAGE" "16V"
					( Units "uVoltage" "V" 1.000000)
					( Origin gFrontEnd )
				)
				( attribute "XY" "(325,425)"
					( Origin gFrontEnd )
				)
				( attribute "CHIPS_PART_NAME" "CAP"
					( Origin gPackager )
				)
				( attribute "CDS_PART_NAME" "CAP_0402-1.0UF,16V,10%,X6S,D97A"
					( Origin gPackager )
				)
				( objectStatus "C25W6" )
			)
			( gate "@baseboard_fab2_lib.baseboard_fab2(sch_1):page151_i227"
				( attribute "ATTRIBUTE" "120OHM"
					( Origin gFrontEnd )
				)
				( attribute "CDS_LIB" "w_hdl"
					( Origin gPackager )
				)
				( attribute "CDS_LMAN_SYM_OUTLINE" "-50,75,50,-75"
					( Origin gPackager )
				)
				( attribute "LOCATION" "R25W32"
					( Origin gFrontEnd )
				)
				( attribute "PACK_TYPE" "RCL_GP"
					( Origin gFrontEnd )
				)
				( attribute "PART_NUMBER" "64.12005.6DL"
					( Origin gFrontEnd )
				)
				( attribute "PHYS_PAGE" "151"
					( Origin gFrontEnd )
				)
				( attribute "RATED" "1/16W"
					( Origin gFrontEnd )
				)
				( attribute "ROT" "1"
					( Origin gFrontEnd )
				)
				( attribute "SEC" "1"
					( Origin gFrontEnd )
				)
				( attribute "SEC_TYPE" "RCL_GP"
					( Origin gFrontEnd )
				)
				( attribute "TOLERANCE" "1%"
					( Origin gFrontEnd )
				)
				( attribute "VALUE" "120R2F-GP"
					( Origin gFrontEnd )
				)
				( attribute "VER" "1"
					( Origin gFrontEnd )
				)
				( attribute "XY" "(-950,1425)"
					( Origin gFrontEnd )
				)
				( attribute "CHIPS_PART_NAME" "120R2F-GP"
					( Origin gPackager )
				)
				( attribute "CDS_PART_NAME" "120R2F-GP_RCL_GP-120R2F-GP,64.A"
					( Origin gPackager )
				)
				( attribute "PACK_SIZE" "0402"
					( Origin gFrontEnd )
				)
				( attribute "CDS_LOCATION" "R25W32"
					( Origin gPackager )
				)
				( attribute "CDS_SEC" "1"
					( Origin gPackager )
				)
				( objectStatus "R25W32" )
			)
			( gate "@baseboard_fab2_lib.baseboard_fab2(sch_1):page151_i226"
				( attribute "ATTRIBUTE" "120OHM"
					( Origin gFrontEnd )
				)
				( attribute "CDS_LIB" "w_hdl"
					( Origin gPackager )
				)
				( attribute "CDS_LMAN_SYM_OUTLINE" "-50,75,50,-75"
					( Origin gPackager )
				)
				( attribute "LOCATION" "R25W31"
					( Origin gFrontEnd )
				)
				( attribute "PACK_TYPE" "RCL_GP"
					( Origin gFrontEnd )
				)
				( attribute "PART_NUMBER" "64.12005.6DL"
					( Origin gFrontEnd )
				)
				( attribute "PHYS_PAGE" "151"
					( Origin gFrontEnd )
				)
				( attribute "RATED" "1/16W"
					( Origin gFrontEnd )
				)
				( attribute "ROT" "1"
					( Origin gFrontEnd )
				)
				( attribute "SEC" "1"
					( Origin gFrontEnd )
				)
				( attribute "SEC_TYPE" "RCL_GP"
					( Origin gFrontEnd )
				)
				( attribute "TOLERANCE" "1%"
					( Origin gFrontEnd )
				)
				( attribute "VALUE" "120R2F-GP"
					( Origin gFrontEnd )
				)
				( attribute "VER" "1"
					( Origin gFrontEnd )
				)
				( attribute "XY" "(-950,1475)"
					( Origin gFrontEnd )
				)
				( attribute "CHIPS_PART_NAME" "120R2F-GP"
					( Origin gPackager )
				)
				( attribute "CDS_PART_NAME" "120R2F-GP_RCL_GP-120R2F-GP,64.A"
					( Origin gPackager )
				)
				( attribute "PACK_SIZE" "0402"
					( Origin gFrontEnd )
				)
				( attribute "CDS_LOCATION" "R25W31"
					( Origin gPackager )
				)
				( attribute "CDS_SEC" "1"
					( Origin gPackager )
				)
				( objectStatus "R25W31" )
			)
			( gate "@baseboard_fab2_lib.baseboard_fab2(sch_1):page139_i249"
				( attribute "BOM_COST" "SYS_CLOCK"
					( Origin gFrontEnd )
				)
				( attribute "CDS_LIB" "mstr_discrete"
					( Origin gPackager )
				)
				( attribute "CDS_LOCATION" "C9E9"
					( Origin gPackager )
				)
				( attribute "CDS_SEC" "1"
					( Origin gPackager )
				)
				( attribute "LOCATION" "C9E9"
					( Origin gFrontEnd )
				)
				( attribute "MATERIAL" "COG"
					( Origin gFrontEnd )
				)
				( attribute "PACK_TYPE" "0402LF"
					( Origin gFrontEnd )
				)
				( attribute "PART_NUMBER" "A36095-047"
					( Origin gFrontEnd )
				)
				( attribute "PHYS_PAGE" "139"
					( Origin gFrontEnd )
				)
				( attribute "ROOM" "SB"
					( Origin gFrontEnd )
				)
				( attribute "ROT" "0"
					( Origin gFrontEnd )
				)
				( attribute "SEC" "1"
					( Origin gFrontEnd )
				)
				( attribute "SEC_TYPE" "0402LF"
					( Origin gFrontEnd )
				)
				( attribute "TOLERANCE" "5%"
					( Origin gFrontEnd )
				)
				( attribute "VALUE" "15.0PF"
					( Origin gFrontEnd )
				)
				( attribute "VER" "1"
					( Origin gFrontEnd )
				)
				( attribute "VOLTAGE" "50V"
					( Units "uVoltage" "V" 1.000000)
					( Origin gFrontEnd )
				)
				( attribute "XY" "(-7750,1200)"
					( Origin gFrontEnd )
				)
				( attribute "CHIPS_PART_NAME" "CAP"
					( Origin gPackager )
				)
				( attribute "CDS_PART_NAME" "CAP_0402LF-15.0PF,50V,5%,COG,AA"
					( Origin gPackager )
				)
				( attribute "GROUP" "NI_I210&RJ45"
					( Origin gFrontEnd )
				)
				( objectStatus "C9E9" )
			)
			( gate "@baseboard_fab2_lib.baseboard_fab2(sch_1):page251_i10"
				( attribute "BOM_COST" "SM_THERM"
					( Origin gFrontEnd )
				)
				( attribute "CDS_LIB" "mstr_discrete"
					( Origin gPackager )
				)
				( attribute "CDS_LOCATION" "CR10W2"
					( Origin gPackager )
				)
				( attribute "CDS_SEC" "1"
					( Origin gPackager )
				)
				( attribute "LOCATION" "CR10W2"
					( Origin gFrontEnd )
				)
				( attribute "MATERIAL" "EMPTY"
					( Origin gFrontEnd )
				)
				( attribute "PACK_TYPE" "SM"
					( Origin gFrontEnd )
				)
				( attribute "PART_NUMBER" "H71799-001"
					( Origin gFrontEnd )
				)
				( attribute "PHYS_PAGE" "251"
					( Origin gFrontEnd )
				)
				( attribute "ROOM" "CPU_FANS"
					( Origin gFrontEnd )
				)
				( attribute "ROT" "0"
					( Origin gFrontEnd )
				)
				( attribute "SEC" "1"
					( Origin gFrontEnd )
				)
				( attribute "SEC_TYPE" "SM"
					( Origin gFrontEnd )
				)
				( attribute "VALUE" "SDMK0340L"
					( Origin gFrontEnd )
				)
				( attribute "VER" "4"
					( Origin gFrontEnd )
				)
				( attribute "XY" "(-3000,4625)"
					( Origin gFrontEnd )
				)
				( attribute "CHIPS_PART_NAME" "DIODE"
					( Origin gPackager )
				)
				( attribute "CDS_PART_NAME" "DIODE_SM-SDMK0340L,EMPTY,H7179A"
					( Origin gPackager )
				)
				( objectStatus "CR10W2" )
			)
			( gate "@baseboard_fab2_lib.baseboard_fab2(sch_1):page168_i43"
				( attribute "CDS_LIB" "mstr_discrete"
					( Origin gPackager )
				)
				( attribute "CDS_LOCATION" "Q6W4"
					( Origin gPackager )
				)
				( attribute "CDS_SEC" "1"
					( Origin gPackager )
				)
				( attribute "LOCATION" "Q6W4"
					( Origin gFrontEnd )
				)
				( attribute "MATERIAL" "FET"
					( Origin gFrontEnd )
				)
				( attribute "PACK_TYPE" "SOT23LF"
					( Origin gFrontEnd )
				)
				( attribute "PART_NUMBER" "C79254-001"
					( Origin gFrontEnd )
				)
				( attribute "PHYS_PAGE" "168"
					( Origin gFrontEnd )
				)
				( attribute "ROOM" "HOT_SWAP"
					( Origin gFrontEnd )
				)
				( attribute "ROT" "0"
					( Origin gFrontEnd )
				)
				( attribute "SEC" "1"
					( Origin gFrontEnd )
				)
				( attribute "SEC_TYPE" "SOT23LF"
					( Origin gFrontEnd )
				)
				( attribute "VALUE" "2N7002"
					( Origin gFrontEnd )
				)
				( attribute "VER" "8"
					( Origin gFrontEnd )
				)
				( attribute "XY" "(-1450,2650)"
					( Origin gFrontEnd )
				)
				( attribute "CHIPS_PART_NAME" "FET_N"
					( Origin gPackager )
				)
				( attribute "CDS_PART_NAME" "FET_N_SOT23LF-2N7002,FET,C7925A"
					( Origin gPackager )
				)
				( objectStatus "Q6W4" )
			)
			( gate "@baseboard_fab2_lib.baseboard_fab2(sch_1):page145_i22"
				( attribute "BOM_COST" "SM_CONTROLLER"
					( Origin gFrontEnd )
				)
				( attribute "CDS_LIB" "mstr_discrete"
					( Origin gPackager )
				)
				( attribute "CDS_LOCATION" "R9F20"
					( Origin gPackager )
				)
				( attribute "CDS_SEC" "1"
					( Origin gPackager )
				)
				( attribute "LOCATION" "R9F20"
					( Origin gFrontEnd )
				)
				( attribute "MATERIAL" "EMPTY"
					( Origin gFrontEnd )
				)
				( attribute "PACK_TYPE" "0402"
					( Origin gFrontEnd )
				)
				( attribute "PART_NUMBER" "G21796-340"
					( Origin gFrontEnd )
				)
				( attribute "PHYS_PAGE" "145"
					( Origin gFrontEnd )
				)
				( attribute "ROOM" "BMC"
					( Origin gFrontEnd )
				)
				( attribute "ROT" "0"
					( Origin gFrontEnd )
				)
				( attribute "SEC" "1"
					( Origin gFrontEnd )
				)
				( attribute "SEC_TYPE" "0402"
					( Origin gFrontEnd )
				)
				( attribute "TOLERANCE" "1%"
					( Origin gFrontEnd )
				)
				( attribute "VALUE" "348"
					( Origin gFrontEnd )
				)
				( attribute "VER" "2"
					( Origin gFrontEnd )
				)
				( attribute "WATTAGE" "1/16W"
					( Origin gFrontEnd )
				)
				( attribute "XY" "(-7650,-3425)"
					( Origin gFrontEnd )
				)
				( attribute "CHIPS_PART_NAME" "RES"
					( Origin gPackager )
				)
				( attribute "CDS_PART_NAME" "RES_0402-348,1%,1/16W,EMPTY,G2A"
					( Origin gPackager )
				)
				( objectStatus "R9F20" )
			)
			( gate "@baseboard_fab2_lib.baseboard_fab2(sch_1):page145_i136"
				( attribute "BOM_COST" "SM_CONTROLLER"
					( Origin gFrontEnd )
				)
				( attribute "CDS_LIB" "mstr_discrete"
					( Origin gPackager )
				)
				( attribute "CDS_LOCATION" "R2T41"
					( Origin gPackager )
				)
				( attribute "CDS_SEC" "1"
					( Origin gPackager )
				)
				( attribute "LOCATION" "R2T41"
					( Origin gFrontEnd )
				)
				( attribute "MATERIAL" "CHIP"
					( Origin gFrontEnd )
				)
				( attribute "PACK_TYPE" "0402"
					( Origin gFrontEnd )
				)
				( attribute "PART_NUMBER" "G21796-250"
					( Origin gFrontEnd )
				)
				( attribute "PHYS_PAGE" "145"
					( Origin gFrontEnd )
				)
				( attribute "ROOM" "BMC"
					( Origin gFrontEnd )
				)
				( attribute "ROT" "0"
					( Origin gFrontEnd )
				)
				( attribute "SEC" "1"
					( Origin gFrontEnd )
				)
				( attribute "SEC_TYPE" "0402"
					( Origin gFrontEnd )
				)
				( attribute "TOLERANCE" "1.0%"
					( Origin gFrontEnd )
				)
				( attribute "VALUE" "22.1"
					( Origin gFrontEnd )
				)
				( attribute "VER" "1"
					( Origin gFrontEnd )
				)
				( attribute "WATTAGE" "1/16W"
					( Origin gFrontEnd )
				)
				( attribute "XY" "(-6450,-2950)"
					( Origin gFrontEnd )
				)
				( attribute "CHIPS_PART_NAME" "RES"
					( Origin gPackager )
				)
				( attribute "CDS_PART_NAME" "RES_0402-22.1,1.0%,1/16W,CHIP,A"
					( Origin gPackager )
				)
				( objectStatus "R2T41" )
			)
			( gate "@baseboard_fab2_lib.baseboard_fab2(sch_1):page151_i175"
				( attribute "BOM_COST" "SM_CONTROLLER"
					( Origin gFrontEnd )
				)
				( attribute "CDS_LIB" "mstr_discrete"
					( Origin gPackager )
				)
				( attribute "CDS_LOCATION" "R8B25"
					( Origin gPackager )
				)
				( attribute "CDS_SEC" "1"
					( Origin gPackager )
				)
				( attribute "LOCATION" "R8B25"
					( Origin gFrontEnd )
				)
				( attribute "MATERIAL" "CHIP"
					( Origin gFrontEnd )
				)
				( attribute "PACK_TYPE" "0402"
					( Origin gFrontEnd )
				)
				( attribute "PART_NUMBER" "G21796-072"
					( Origin gFrontEnd )
				)
				( attribute "PHYS_PAGE" "151"
					( Origin gFrontEnd )
				)
				( attribute "ROOM" "BMC"
					( Origin gFrontEnd )
				)
				( attribute "ROT" "0"
					( Origin gFrontEnd )
				)
				( attribute "SEC" "1"
					( Origin gFrontEnd )
				)
				( attribute "SEC_TYPE" "0402"
					( Origin gFrontEnd )
				)
				( attribute "TOLERANCE" "1%"
					( Origin gFrontEnd )
				)
				( attribute "VALUE" "4.75K"
					( Origin gFrontEnd )
				)
				( attribute "VER" "2"
					( Origin gFrontEnd )
				)
				( attribute "WATTAGE" "1/16W"
					( Origin gFrontEnd )
				)
				( attribute "XY" "(-2175,-475)"
					( Origin gFrontEnd )
				)
				( attribute "CHIPS_PART_NAME" "RES"
					( Origin gPackager )
				)
				( attribute "CDS_PART_NAME" "RES_0402-4.75K,1%,1/16W,CHIP,GA"
					( Origin gPackager )
				)
				( objectStatus "R8B25" )
			)
			( gate "@baseboard_fab2_lib.baseboard_fab2(sch_1):page152_i1"
				( attribute "BOM_COST" "PROC_SIDEBAND"
					( Origin gFrontEnd )
				)
				( attribute "CDS_LIB" "mstr_digital"
					( Origin gPackager )
				)
				( attribute "CDS_LOCATION" "U9G1"
					( Origin gPackager )
				)
				( attribute "CDS_SEC" "1"
					( Origin gPackager )
				)
				( attribute "LOCATION" "U9G1"
					( Origin gFrontEnd )
				)
				( attribute "MATERIAL" "IC"
					( Origin gFrontEnd )
				)
				( attribute "PACK_TYPE" "SM"
					( Origin gFrontEnd )
				)
				( attribute "PART_NUMBER" "D66151-001"
					( Origin gFrontEnd )
				)
				( attribute "PHYS_PAGE" "152"
					( Origin gFrontEnd )
				)
				( attribute "ROOM" "PROC_SIDEBAND"
					( Origin gFrontEnd )
				)
				( attribute "ROT" "2"
					( Origin gFrontEnd )
				)
				( attribute "SEC" "1"
					( Origin gFrontEnd )
				)
				( attribute "SEC_TYPE" "SM"
					( Origin gFrontEnd )
				)
				( attribute "VER" "1"
					( Origin gFrontEnd )
				)
				( attribute "XY" "(-5400,4050)"
					( Origin gFrontEnd )
				)
				( attribute "CHIPS_PART_NAME" "GTL2014"
					( Origin gPackager )
				)
				( attribute "CDS_PART_NAME" "GTL2014_SM-IC,D66151-001"
					( Origin gPackager )
				)
				( objectStatus "U9G1" )
			)
			( gate "@baseboard_fab2_lib.baseboard_fab2(sch_1):page152_i2"
				( attribute "BOM_COST" "PROC_SIDEBAND"
					( Origin gFrontEnd )
				)
				( attribute "CDS_LIB" "mstr_discrete"
					( Origin gPackager )
				)
				( attribute "CDS_LOCATION" "R1U30"
					( Origin gPackager )
				)
				( attribute "CDS_SEC" "1"
					( Origin gPackager )
				)
				( attribute "LOCATION" "R1U30"
					( Origin gFrontEnd )
				)
				( attribute "MATERIAL" "CHIP"
					( Origin gFrontEnd )
				)
				( attribute "PACK_TYPE" "0402"
					( Origin gFrontEnd )
				)
				( attribute "PART_NUMBER" "G21796-026"
					( Origin gFrontEnd )
				)
				( attribute "PHYS_PAGE" "152"
					( Origin gFrontEnd )
				)
				( attribute "ROOM" "PROC_TRANSLATORS"
					( Origin gFrontEnd )
				)
				( attribute "ROT" "0"
					( Origin gFrontEnd )
				)
				( attribute "SEC" "1"
					( Origin gFrontEnd )
				)
				( attribute "SEC_TYPE" "0402"
					( Origin gFrontEnd )
				)
				( attribute "TOLERANCE" "1%"
					( Origin gFrontEnd )
				)
				( attribute "VALUE" "1.00K"
					( Origin gFrontEnd )
				)
				( attribute "VER" "1"
					( Origin gFrontEnd )
				)
				( attribute "WATTAGE" "1/16W"
					( Origin gFrontEnd )
				)
				( attribute "XY" "(-4350,4200)"
					( Origin gFrontEnd )
				)
				( attribute "CHIPS_PART_NAME" "RES"
					( Origin gPackager )
				)
				( attribute "CDS_PART_NAME" "RES_0402-1.00K,1%,1/16W,CHIP,GA"
					( Origin gPackager )
				)
				( objectStatus "R1U30" )
			)
			( gate "@baseboard_fab2_lib.baseboard_fab2(sch_1):page152_i6"
				( attribute "BOM_COST" "PROC_SIDEBAND"
					( Origin gFrontEnd )
				)
				( attribute "CDS_LIB" "mstr_discrete"
					( Origin gPackager )
				)
				( attribute "CDS_LOCATION" "R1U46"
					( Origin gPackager )
				)
				( attribute "CDS_SEC" "1"
					( Origin gPackager )
				)
				( attribute "LOCATION" "R1U46"
					( Origin gFrontEnd )
				)
				( attribute "MATERIAL" "CHIP"
					( Origin gFrontEnd )
				)
				( attribute "PACK_TYPE" "0402"
					( Origin gFrontEnd )
				)
				( attribute "PART_NUMBER" "G21796-074"
					( Origin gFrontEnd )
				)
				( attribute "PHYS_PAGE" "152"
					( Origin gFrontEnd )
				)
				( attribute "ROOM" "PROC_SIDEBAND"
					( Origin gFrontEnd )
				)
				( attribute "ROT" "0"
					( Origin gFrontEnd )
				)
				( attribute "SEC" "1"
					( Origin gFrontEnd )
				)
				( attribute "SEC_TYPE" "0402"
					( Origin gFrontEnd )
				)
				( attribute "TOLERANCE" "1%"
					( Origin gFrontEnd )
				)
				( attribute "VALUE" "33.2"
					( Origin gFrontEnd )
				)
				( attribute "VER" "1"
					( Origin gFrontEnd )
				)
				( attribute "WATTAGE" "1/16W"
					( Origin gFrontEnd )
				)
				( attribute "XY" "(-2400,4250)"
					( Origin gFrontEnd )
				)
				( attribute "CHIPS_PART_NAME" "RES"
					( Origin gPackager )
				)
				( attribute "CDS_PART_NAME" "RES_0402-33.2,1%,1/16W,CHIP,G2A"
					( Origin gPackager )
				)
				( objectStatus "R1U46" )
			)
			( gate "@baseboard_fab2_lib.baseboard_fab2(sch_1):page152_i14"
				( attribute "BOM_COST" "PROC_SIDEBAND"
					( Origin gFrontEnd )
				)
				( attribute "CDS_LIB" "mstr_discrete"
					( Origin gPackager )
				)
				( attribute "CDS_LOCATION" "R9G31"
					( Origin gPackager )
				)
				( attribute "CDS_SEC" "1"
					( Origin gPackager )
				)
				( attribute "LOCATION" "R9G31"
					( Origin gFrontEnd )
				)
				( attribute "MATERIAL" "CHIP"
					( Origin gFrontEnd )
				)
				( attribute "PACK_TYPE" "0402"
					( Origin gFrontEnd )
				)
				( attribute "PART_NUMBER" "G21796-074"
					( Origin gFrontEnd )
				)
				( attribute "PHYS_PAGE" "152"
					( Origin gFrontEnd )
				)
				( attribute "ROOM" "PROC_SIDEBAND"
					( Origin gFrontEnd )
				)
				( attribute "ROT" "0"
					( Origin gFrontEnd )
				)
				( attribute "SEC" "1"
					( Origin gFrontEnd )
				)
				( attribute "SEC_TYPE" "0402"
					( Origin gFrontEnd )
				)
				( attribute "TOLERANCE" "1%"
					( Origin gFrontEnd )
				)
				( attribute "VALUE" "33.2"
					( Origin gFrontEnd )
				)
				( attribute "VER" "1"
					( Origin gFrontEnd )
				)
				( attribute "WATTAGE" "1/16W"
					( Origin gFrontEnd )
				)
				( attribute "XY" "(-2400,4075)"
					( Origin gFrontEnd )
				)
				( attribute "CHIPS_PART_NAME" "RES"
					( Origin gPackager )
				)
				( attribute "CDS_PART_NAME" "RES_0402-33.2,1%,1/16W,CHIP,G2A"
					( Origin gPackager )
				)
				( objectStatus "R9G31" )
			)
			( gate "@baseboard_fab2_lib.baseboard_fab2(sch_1):page152_i15"
				( attribute "BOM_COST" "PROC_SIDEBAND"
					( Origin gFrontEnd )
				)
				( attribute "CDS_LIB" "mstr_discrete"
					( Origin gPackager )
				)
				( attribute "CDS_LOCATION" "R1U36"
					( Origin gPackager )
				)
				( attribute "CDS_SEC" "1"
					( Origin gPackager )
				)
				( attribute "LOCATION" "R1U36"
					( Origin gFrontEnd )
				)
				( attribute "MATERIAL" "CHIP"
					( Origin gFrontEnd )
				)
				( attribute "PACK_TYPE" "0402"
					( Origin gFrontEnd )
				)
				( attribute "PART_NUMBER" "G21796-074"
					( Origin gFrontEnd )
				)
				( attribute "PHYS_PAGE" "152"
					( Origin gFrontEnd )
				)
				( attribute "ROOM" "PROC_SIDEBAND"
					( Origin gFrontEnd )
				)
				( attribute "ROT" "0"
					( Origin gFrontEnd )
				)
				( attribute "SEC" "1"
					( Origin gFrontEnd )
				)
				( attribute "SEC_TYPE" "0402"
					( Origin gFrontEnd )
				)
				( attribute "TOLERANCE" "1%"
					( Origin gFrontEnd )
				)
				( attribute "VALUE" "33.2"
					( Origin gFrontEnd )
				)
				( attribute "VER" "1"
					( Origin gFrontEnd )
				)
				( attribute "WATTAGE" "1/16W"
					( Origin gFrontEnd )
				)
				( attribute "XY" "(-2400,3900)"
					( Origin gFrontEnd )
				)
				( attribute "CHIPS_PART_NAME" "RES"
					( Origin gPackager )
				)
				( attribute "CDS_PART_NAME" "RES_0402-33.2,1%,1/16W,CHIP,G2A"
					( Origin gPackager )
				)
				( objectStatus "R1U36" )
			)
			( gate "@baseboard_fab2_lib.baseboard_fab2(sch_1):page152_i16"
				( attribute "BOM_COST" "PROC_SIDEBAND"
					( Origin gFrontEnd )
				)
				( attribute "CDS_LIB" "mstr_discrete"
					( Origin gPackager )
				)
				( attribute "CDS_LOCATION" "R1U34"
					( Origin gPackager )
				)
				( attribute "CDS_SEC" "1"
					( Origin gPackager )
				)
				( attribute "LOCATION" "R1U34"
					( Origin gFrontEnd )
				)
				( attribute "MATERIAL" "CHIP"
					( Origin gFrontEnd )
				)
				( attribute "PACK_TYPE" "0402"
					( Origin gFrontEnd )
				)
				( attribute "PART_NUMBER" "G21796-074"
					( Origin gFrontEnd )
				)
				( attribute "PHYS_PAGE" "152"
					( Origin gFrontEnd )
				)
				( attribute "ROOM" "PROC_TRANSLATORS"
					( Origin gFrontEnd )
				)
				( attribute "ROT" "0"
					( Origin gFrontEnd )
				)
				( attribute "SEC" "1"
					( Origin gFrontEnd )
				)
				( attribute "SEC_TYPE" "0402"
					( Origin gFrontEnd )
				)
				( attribute "TOLERANCE" "1%"
					( Origin gFrontEnd )
				)
				( attribute "VALUE" "33.2"
					( Origin gFrontEnd )
				)
				( attribute "VER" "1"
					( Origin gFrontEnd )
				)
				( attribute "WATTAGE" "1/16W"
					( Origin gFrontEnd )
				)
				( attribute "XY" "(-2400,3725)"
					( Origin gFrontEnd )
				)
				( attribute "CHIPS_PART_NAME" "RES"
					( Origin gPackager )
				)
				( attribute "CDS_PART_NAME" "RES_0402-33.2,1%,1/16W,CHIP,G2A"
					( Origin gPackager )
				)
				( objectStatus "R1U34" )
			)
			( gate "@baseboard_fab2_lib.baseboard_fab2(sch_1):page152_i18"
				( attribute "BOM_COST" "PROC_SIDEBAND"
					( Origin gFrontEnd )
				)
				( attribute "CDS_LIB" "mstr_discrete"
					( Origin gPackager )
				)
				( attribute "CDS_LOCATION" "C1U19"
					( Origin gPackager )
				)
				( attribute "CDS_SEC" "1"
					( Origin gPackager )
				)
				( attribute "LOCATION" "C1U19"
					( Origin gFrontEnd )
				)
				( attribute "MATERIAL" "X6S"
					( Origin gFrontEnd )
				)
				( attribute "PACK_TYPE" "0402"
					( Origin gFrontEnd )
				)
				( attribute "PART_NUMBER" "D97712-011"
					( Origin gFrontEnd )
				)
				( attribute "PHYS_PAGE" "152"
					( Origin gFrontEnd )
				)
				( attribute "ROOM" "PROC_SIDEBAND"
					( Origin gFrontEnd )
				)
				( attribute "ROT" "0"
					( Origin gFrontEnd )
				)
				( attribute "SEC" "1"
					( Origin gFrontEnd )
				)
				( attribute "SEC_TYPE" "0402"
					( Origin gFrontEnd )
				)
				( attribute "TOLERANCE" "10%"
					( Origin gFrontEnd )
				)
				( attribute "VALUE" "1.0UF"
					( Origin gFrontEnd )
				)
				( attribute "VER" "1"
					( Origin gFrontEnd )
				)
				( attribute "VOLTAGE" "16V"
					( Units "uVoltage" "V" 1.000000)
					( Origin gFrontEnd )
				)
				( attribute "XY" "(-4525,4650)"
					( Origin gFrontEnd )
				)
				( attribute "CHIPS_PART_NAME" "CAP"
					( Origin gPackager )
				)
				( attribute "CDS_PART_NAME" "CAP_0402-1.0UF,16V,10%,X6S,D97A"
					( Origin gPackager )
				)
				( objectStatus "C1U19" )
			)
			( gate "@baseboard_fab2_lib.baseboard_fab2(sch_1):page152_i26"
				( attribute "BOM_COST" "PROC_SIDEBAND"
					( Origin gFrontEnd )
				)
				( attribute "CDS_LIB" "mstr_discrete"
					( Origin gPackager )
				)
				( attribute "CDS_LOCATION" "R1U37"
					( Origin gPackager )
				)
				( attribute "LOCATION" "R1U37"
					( Origin gFrontEnd )
				)
				( attribute "MATERIAL" "CHIP"
					( Origin gFrontEnd )
				)
				( attribute "PACK_TYPE" "0402"
					( Origin gFrontEnd )
				)
				( attribute "PART_NUMBER" "G21796-017"
					( Origin gFrontEnd )
				)
				( attribute "PHYS_PAGE" "152"
					( Origin gFrontEnd )
				)
				( attribute "ROOM" "PROC_SIDEBAND"
					( Origin gFrontEnd )
				)
				( attribute "ROT" "0"
					( Origin gFrontEnd )
				)
				( attribute "SEC" "1"
					( Origin gFrontEnd )
				)
				( attribute "TOLERANCE" "1%"
					( Origin gFrontEnd )
				)
				( attribute "VALUE" "100.0"
					( Origin gFrontEnd )
				)
				( attribute "VER" "2"
					( Origin gFrontEnd )
				)
				( attribute "WATTAGE" "1/16W"
					( Origin gFrontEnd )
				)
				( attribute "XY" "(-2550,1600)"
					( Origin gFrontEnd )
				)
				( attribute "CHIPS_PART_NAME" "RES"
					( Origin gPackager )
				)
				( attribute "CDS_PART_NAME" "RES_0402-100.0,1%,1/16W,CHIP,GA"
					( Origin gPackager )
				)
				( attribute "SEC_TYPE" "0402"
					( Origin gFrontEnd )
				)
				( attribute "CDS_SEC" "1"
					( Origin gPackager )
				)
				( objectStatus "R1U37" )
			)
			( gate "@baseboard_fab2_lib.baseboard_fab2(sch_1):page152_i27"
				( attribute "BOM_COST" "PROC_SIDEBAND"
					( Origin gFrontEnd )
				)
				( attribute "CDS_LIB" "dev_discrete"
					( Origin gPackager )
				)
				( attribute "CDS_LOCATION" "C1U22"
					( Origin gPackager )
				)
				( attribute "LOCATION" "C1U22"
					( Origin gFrontEnd )
				)
				( attribute "MATERIAL" "X7R"
					( Origin gFrontEnd )
				)
				( attribute "PACK_TYPE" "0402V"
					( Origin gFrontEnd )
				)
				( attribute "PART_NUMBER" "A36096-030"
					( Origin gFrontEnd )
				)
				( attribute "PHYS_PAGE" "152"
					( Origin gFrontEnd )
				)
				( attribute "ROOM" "PROC_SIDEBAND"
					( Origin gFrontEnd )
				)
				( attribute "ROT" "0"
					( Origin gFrontEnd )
				)
				( attribute "SEC" "1"
					( Origin gFrontEnd )
				)
				( attribute "TOLERANCE" "10%"
					( Origin gFrontEnd )
				)
				( attribute "VALUE" "0.1UF"
					( Origin gFrontEnd )
				)
				( attribute "VER" "1"
					( Origin gFrontEnd )
				)
				( attribute "VOLTAGE" "16V"
					( Units "uVoltage" "V" 1.000000)
					( Origin gFrontEnd )
				)
				( attribute "XY" "(-2925,1600)"
					( Origin gFrontEnd )
				)
				( attribute "CHIPS_PART_NAME" "CAP_A"
					( Origin gPackager )
				)
				( attribute "CDS_PART_NAME" "CAP_A_0402V-0.1UF,16V,10%,X7R,A"
					( Origin gPackager )
				)
				( attribute "SEC_TYPE" "0402V"
					( Origin gFrontEnd )
				)
				( attribute "CDS_SEC" "1"
					( Origin gPackager )
				)
				( objectStatus "C1U22" )
			)
			( gate "@baseboard_fab2_lib.baseboard_fab2(sch_1):page152_i45"
				( attribute "CDS_LIB" "mstr_discrete"
					( Origin gPackager )
				)
				( attribute "CDS_LOCATION" "R9G34"
					( Origin gPackager )
				)
				( attribute "CDS_SEC" "1"
					( Origin gPackager )
				)
				( attribute "LOCATION" "R9G34"
					( Origin gFrontEnd )
				)
				( attribute "MATERIAL" "CHIP"
					( Origin gFrontEnd )
				)
				( attribute "PACK_TYPE" "0402"
					( Origin gFrontEnd )
				)
				( attribute "PART_NUMBER" "G21497-005"
					( Origin gFrontEnd )
				)
				( attribute "PHYS_PAGE" "152"
					( Origin gFrontEnd )
				)
				( attribute "ROT" "0"
					( Origin gFrontEnd )
				)
				( attribute "SEC" "1"
					( Origin gFrontEnd )
				)
				( attribute "SEC_TYPE" "0402"
					( Origin gFrontEnd )
				)
				( attribute "TOLERANCE" "5%"
					( Origin gFrontEnd )
				)
				( attribute "VALUE" "0.0"
					( Origin gFrontEnd )
				)
				( attribute "VER" "1"
					( Origin gFrontEnd )
				)
				( attribute "WATTAGE" "1/16W"
					( Origin gFrontEnd )
				)
				( attribute "XY" "(-6950,4225)"
					( Origin gFrontEnd )
				)
				( attribute "CHIPS_PART_NAME" "RES"
					( Origin gPackager )
				)
				( attribute "CDS_PART_NAME" "RES_0402-0.0,5%,1/16W,CHIP,G21A"
					( Origin gPackager )
				)
				( objectStatus "R9G34" )
			)
			( gate "@baseboard_fab2_lib.baseboard_fab2(sch_1):page152_i47"
				( attribute "CDS_LIB" "mstr_discrete"
					( Origin gPackager )
				)
				( attribute "CDS_LOCATION" "R9G27"
					( Origin gPackager )
				)
				( attribute "CDS_SEC" "1"
					( Origin gPackager )
				)
				( attribute "LOCATION" "R9G27"
					( Origin gFrontEnd )
				)
				( attribute "MATERIAL" "EMPTY"
					( Origin gFrontEnd )
				)
				( attribute "PACK_TYPE" "0402"
					( Origin gFrontEnd )
				)
				( attribute "PART_NUMBER" "G21497-005"
					( Origin gFrontEnd )
				)
				( attribute "PHYS_PAGE" "152"
					( Origin gFrontEnd )
				)
				( attribute "ROT" "0"
					( Origin gFrontEnd )
				)
				( attribute "SEC" "1"
					( Origin gFrontEnd )
				)
				( attribute "SEC_TYPE" "0402"
					( Origin gFrontEnd )
				)
				( attribute "TOLERANCE" "5%"
					( Origin gFrontEnd )
				)
				( attribute "VALUE" "0.0"
					( Origin gFrontEnd )
				)
				( attribute "VER" "2"
					( Origin gFrontEnd )
				)
				( attribute "WATTAGE" "1/16W"
					( Origin gFrontEnd )
				)
				( attribute "XY" "(-3150,4600)"
					( Origin gFrontEnd )
				)
				( attribute "CHIPS_PART_NAME" "RES"
					( Origin gPackager )
				)
				( attribute "CDS_PART_NAME" "RES_0402-0.0,5%,1/16W,EMPTY,G2A"
					( Origin gPackager )
				)
				( objectStatus "R9G27" )
			)
			( gate "@baseboard_fab2_lib.baseboard_fab2(sch_1):page152_i49"
				( attribute "CDS_LIB" "mstr_discrete"
					( Origin gPackager )
				)
				( attribute "CDS_LOCATION" "R1U58"
					( Origin gPackager )
				)
				( attribute "CDS_SEC" "1"
					( Origin gPackager )
				)
				( attribute "LOCATION" "R1U58"
					( Origin gFrontEnd )
				)
				( attribute "MATERIAL" "CHIP"
					( Origin gFrontEnd )
				)
				( attribute "PACK_TYPE" "0402"
					( Origin gFrontEnd )
				)
				( attribute "PART_NUMBER" "G21497-005"
					( Origin gFrontEnd )
				)
				( attribute "PHYS_PAGE" "152"
					( Origin gFrontEnd )
				)
				( attribute "ROT" "0"
					( Origin gFrontEnd )
				)
				( attribute "SEC" "1"
					( Origin gFrontEnd )
				)
				( attribute "SEC_TYPE" "0402"
					( Origin gFrontEnd )
				)
				( attribute "TOLERANCE" "5%"
					( Origin gFrontEnd )
				)
				( attribute "VALUE" "0.0"
					( Origin gFrontEnd )
				)
				( attribute "VER" "1"
					( Origin gFrontEnd )
				)
				( attribute "WATTAGE" "1/16W"
					( Origin gFrontEnd )
				)
				( attribute "XY" "(-6950,4050)"
					( Origin gFrontEnd )
				)
				( attribute "CHIPS_PART_NAME" "RES"
					( Origin gPackager )
				)
				( attribute "CDS_PART_NAME" "RES_0402-0.0,5%,1/16W,CHIP,G21A"
					( Origin gPackager )
				)
				( objectStatus "R1U58" )
			)
			( gate "@baseboard_fab2_lib.baseboard_fab2(sch_1):page152_i50"
				( attribute "CDS_LIB" "mstr_discrete"
					( Origin gPackager )
				)
				( attribute "CDS_LOCATION" "R1U56"
					( Origin gPackager )
				)
				( attribute "CDS_SEC" "1"
					( Origin gPackager )
				)
				( attribute "LOCATION" "R1U56"
					( Origin gFrontEnd )
				)
				( attribute "MATERIAL" "EMPTY"
					( Origin gFrontEnd )
				)
				( attribute "PACK_TYPE" "0402"
					( Origin gFrontEnd )
				)
				( attribute "PART_NUMBER" "G21497-005"
					( Origin gFrontEnd )
				)
				( attribute "PHYS_PAGE" "152"
					( Origin gFrontEnd )
				)
				( attribute "ROT" "0"
					( Origin gFrontEnd )
				)
				( attribute "SEC" "1"
					( Origin gFrontEnd )
				)
				( attribute "SEC_TYPE" "0402"
					( Origin gFrontEnd )
				)
				( attribute "TOLERANCE" "5%"
					( Origin gFrontEnd )
				)
				( attribute "VALUE" "0.0"
					( Origin gFrontEnd )
				)
				( attribute "VER" "2"
					( Origin gFrontEnd )
				)
				( attribute "WATTAGE" "1/16W"
					( Origin gFrontEnd )
				)
				( attribute "XY" "(-7175,4525)"
					( Origin gFrontEnd )
				)
				( attribute "CHIPS_PART_NAME" "RES"
					( Origin gPackager )
				)
				( attribute "CDS_PART_NAME" "RES_0402-0.0,5%,1/16W,EMPTY,G2A"
					( Origin gPackager )
				)
				( objectStatus "R1U56" )
			)
			( gate "@baseboard_fab2_lib.baseboard_fab2(sch_1):page152_i51"
				( attribute "CDS_LIB" "mstr_discrete"
					( Origin gPackager )
				)
				( attribute "CDS_LOCATION" "R2U51"
					( Origin gPackager )
				)
				( attribute "CDS_SEC" "1"
					( Origin gPackager )
				)
				( attribute "LOCATION" "R2U51"
					( Origin gFrontEnd )
				)
				( attribute "MATERIAL" "EMPTY"
					( Origin gFrontEnd )
				)
				( attribute "PACK_TYPE" "0402"
					( Origin gFrontEnd )
				)
				( attribute "PART_NUMBER" "G21497-005"
					( Origin gFrontEnd )
				)
				( attribute "PHYS_PAGE" "152"
					( Origin gFrontEnd )
				)
				( attribute "ROT" "0"
					( Origin gFrontEnd )
				)
				( attribute "SEC" "1"
					( Origin gFrontEnd )
				)
				( attribute "SEC_TYPE" "0402"
					( Origin gFrontEnd )
				)
				( attribute "TOLERANCE" "5%"
					( Origin gFrontEnd )
				)
				( attribute "VALUE" "0.0"
					( Origin gFrontEnd )
				)
				( attribute "VER" "2"
					( Origin gFrontEnd )
				)
				( attribute "WATTAGE" "1/16W"
					( Origin gFrontEnd )
				)
				( attribute "XY" "(-7450,4525)"
					( Origin gFrontEnd )
				)
				( attribute "CHIPS_PART_NAME" "RES"
					( Origin gPackager )
				)
				( attribute "CDS_PART_NAME" "RES_0402-0.0,5%,1/16W,EMPTY,G2A"
					( Origin gPackager )
				)
				( objectStatus "R2U51" )
			)
			( gate "@baseboard_fab2_lib.baseboard_fab2(sch_1):page152_i53"
				( attribute "BOM_COST" "PROC_SIDEBAND"
					( Origin gFrontEnd )
				)
				( attribute "CDS_LIB" "mstr_discrete"
					( Origin gPackager )
				)
				( attribute "CDS_LOCATION" "R2U40"
					( Origin gPackager )
				)
				( attribute "CDS_SEC" "1"
					( Origin gPackager )
				)
				( attribute "LOCATION" "R2U40"
					( Origin gFrontEnd )
				)
				( attribute "MATERIAL" "CHIP"
					( Origin gFrontEnd )
				)
				( attribute "PACK_TYPE" "0402"
					( Origin gFrontEnd )
				)
				( attribute "PART_NUMBER" "G21796-009"
					( Origin gFrontEnd )
				)
				( attribute "PHYS_PAGE" "152"
					( Origin gFrontEnd )
				)
				( attribute "ROOM" "PROC_SIDEBAND"
					( Origin gFrontEnd )
				)
				( attribute "ROT" "0"
					( Origin gFrontEnd )
				)
				( attribute "SEC" "1"
					( Origin gFrontEnd )
				)
				( attribute "SEC_TYPE" "0402"
					( Origin gFrontEnd )
				)
				( attribute "TOLERANCE" "1%"
					( Origin gFrontEnd )
				)
				( attribute "VALUE" "150.0"
					( Origin gFrontEnd )
				)
				( attribute "VER" "2"
					( Origin gFrontEnd )
				)
				( attribute "WATTAGE" "1/16W"
					( Origin gFrontEnd )
				)
				( attribute "XY" "(-7875,4650)"
					( Origin gFrontEnd )
				)
				( attribute "CHIPS_PART_NAME" "RES"
					( Origin gPackager )
				)
				( attribute "CDS_PART_NAME" "RES_0402-150.0,1%,1/16W,CHIP,GA"
					( Origin gPackager )
				)
				( objectStatus "R2U40" )
			)
			( gate "@baseboard_fab2_lib.baseboard_fab2(sch_1):page152_i54"
				( attribute "BOM_COST" "PROC_SIDEBAND"
					( Origin gFrontEnd )
				)
				( attribute "CDS_LIB" "mstr_discrete"
					( Origin gPackager )
				)
				( attribute "CDS_LOCATION" "R2U41"
					( Origin gPackager )
				)
				( attribute "CDS_SEC" "1"
					( Origin gPackager )
				)
				( attribute "LOCATION" "R2U41"
					( Origin gFrontEnd )
				)
				( attribute "MATERIAL" "CHIP"
					( Origin gFrontEnd )
				)
				( attribute "PACK_TYPE" "0402"
					( Origin gFrontEnd )
				)
				( attribute "PART_NUMBER" "G21796-009"
					( Origin gFrontEnd )
				)
				( attribute "PHYS_PAGE" "152"
					( Origin gFrontEnd )
				)
				( attribute "ROOM" "PROC_SIDEBAND"
					( Origin gFrontEnd )
				)
				( attribute "ROT" "2"
					( Origin gFrontEnd )
				)
				( attribute "SEC" "1"
					( Origin gFrontEnd )
				)
				( attribute "SEC_TYPE" "0402"
					( Origin gFrontEnd )
				)
				( attribute "TOLERANCE" "1%"
					( Origin gFrontEnd )
				)
				( attribute "VALUE" "150.0"
					( Origin gFrontEnd )
				)
				( attribute "VER" "2"
					( Origin gFrontEnd )
				)
				( attribute "WATTAGE" "1/16W"
					( Origin gFrontEnd )
				)
				( attribute "XY" "(-7975,4650)"
					( Origin gFrontEnd )
				)
				( attribute "CHIPS_PART_NAME" "RES"
					( Origin gPackager )
				)
				( attribute "CDS_PART_NAME" "RES_0402-150.0,1%,1/16W,CHIP,GA"
					( Origin gPackager )
				)
				( objectStatus "R2U41" )
			)
			( gate "@baseboard_fab2_lib.baseboard_fab2(sch_1):page152_i56"
				( attribute "BOM_COST" "PROC_SIDEBAND"
					( Origin gFrontEnd )
				)
				( attribute "CDS_LIB" "mstr_discrete"
					( Origin gPackager )
				)
				( attribute "CDS_LOCATION" "R1U41"
					( Origin gPackager )
				)
				( attribute "CDS_SEC" "1"
					( Origin gPackager )
				)
				( attribute "LOCATION" "R1U41"
					( Origin gFrontEnd )
				)
				( attribute "MATERIAL" "CHIP"
					( Origin gFrontEnd )
				)
				( attribute "PACK_TYPE" "0402"
					( Origin gFrontEnd )
				)
				( attribute "PART_NUMBER" "G21796-009"
					( Origin gFrontEnd )
				)
				( attribute "PHYS_PAGE" "152"
					( Origin gFrontEnd )
				)
				( attribute "ROOM" "PROC_SIDEBAND"
					( Origin gFrontEnd )
				)
				( attribute "ROT" "0"
					( Origin gFrontEnd )
				)
				( attribute "SEC" "1"
					( Origin gFrontEnd )
				)
				( attribute "SEC_TYPE" "0402"
					( Origin gFrontEnd )
				)
				( attribute "TOLERANCE" "1%"
					( Origin gFrontEnd )
				)
				( attribute "VALUE" "150.0"
					( Origin gFrontEnd )
				)
				( attribute "VER" "2"
					( Origin gFrontEnd )
				)
				( attribute "WATTAGE" "1/16W"
					( Origin gFrontEnd )
				)
				( attribute "XY" "(-8325,4650)"
					( Origin gFrontEnd )
				)
				( attribute "CHIPS_PART_NAME" "RES"
					( Origin gPackager )
				)
				( attribute "CDS_PART_NAME" "RES_0402-150.0,1%,1/16W,CHIP,GA"
					( Origin gPackager )
				)
				( objectStatus "R1U41" )
			)
			( gate "@baseboard_fab2_lib.baseboard_fab2(sch_1):page152_i57"
				( attribute "BOM_COST" "PROC_SIDEBAND"
					( Origin gFrontEnd )
				)
				( attribute "CDS_LIB" "mstr_discrete"
					( Origin gPackager )
				)
				( attribute "CDS_LOCATION" "R1U35"
					( Origin gPackager )
				)
				( attribute "CDS_SEC" "1"
					( Origin gPackager )
				)
				( attribute "LOCATION" "R1U35"
					( Origin gFrontEnd )
				)
				( attribute "MATERIAL" "CHIP"
					( Origin gFrontEnd )
				)
				( attribute "PACK_TYPE" "0402"
					( Origin gFrontEnd )
				)
				( attribute "PART_NUMBER" "G21796-009"
					( Origin gFrontEnd )
				)
				( attribute "PHYS_PAGE" "152"
					( Origin gFrontEnd )
				)
				( attribute "ROOM" "PROC_SIDEBAND"
					( Origin gFrontEnd )
				)
				( attribute "ROT" "2"
					( Origin gFrontEnd )
				)
				( attribute "SEC" "1"
					( Origin gFrontEnd )
				)
				( attribute "SEC_TYPE" "0402"
					( Origin gFrontEnd )
				)
				( attribute "TOLERANCE" "1%"
					( Origin gFrontEnd )
				)
				( attribute "VALUE" "150.0"
					( Origin gFrontEnd )
				)
				( attribute "VER" "2"
					( Origin gFrontEnd )
				)
				( attribute "WATTAGE" "1/16W"
					( Origin gFrontEnd )
				)
				( attribute "XY" "(-8425,4650)"
					( Origin gFrontEnd )
				)
				( attribute "CHIPS_PART_NAME" "RES"
					( Origin gPackager )
				)
				( attribute "CDS_PART_NAME" "RES_0402-150.0,1%,1/16W,CHIP,GA"
					( Origin gPackager )
				)
				( objectStatus "R1U35" )
			)
			( gate "@baseboard_fab2_lib.baseboard_fab2(sch_1):page152_i58"
				( attribute "BOM_COST" "PROC_SIDEBAND"
					( Origin gFrontEnd )
				)
				( attribute "CDS_LIB" "mstr_discrete"
					( Origin gPackager )
				)
				( attribute "CDS_LOCATION" "R4P17"
					( Origin gPackager )
				)
				( attribute "CDS_SEC" "1"
					( Origin gPackager )
				)
				( attribute "LOCATION" "R4P17"
					( Origin gFrontEnd )
				)
				( attribute "MATERIAL" "CHIP"
					( Origin gFrontEnd )
				)
				( attribute "PACK_TYPE" "0402"
					( Origin gFrontEnd )
				)
				( attribute "PART_NUMBER" "G21796-009"
					( Origin gFrontEnd )
				)
				( attribute "PHYS_PAGE" "152"
					( Origin gFrontEnd )
				)
				( attribute "ROOM" "PROC_SIDEBAND"
					( Origin gFrontEnd )
				)
				( attribute "ROT" "0"
					( Origin gFrontEnd )
				)
				( attribute "SEC" "1"
					( Origin gFrontEnd )
				)
				( attribute "SEC_TYPE" "0402"
					( Origin gFrontEnd )
				)
				( attribute "TOLERANCE" "1%"
					( Origin gFrontEnd )
				)
				( attribute "VALUE" "150.0"
					( Origin gFrontEnd )
				)
				( attribute "VER" "2"
					( Origin gFrontEnd )
				)
				( attribute "WATTAGE" "1/16W"
					( Origin gFrontEnd )
				)
				( attribute "XY" "(-7800,3250)"
					( Origin gFrontEnd )
				)
				( attribute "CHIPS_PART_NAME" "RES"
					( Origin gPackager )
				)
				( attribute "CDS_PART_NAME" "RES_0402-150.0,1%,1/16W,CHIP,GA"
					( Origin gPackager )
				)
				( objectStatus "R4P17" )
			)
			( gate "@baseboard_fab2_lib.baseboard_fab2(sch_1):page152_i59"
				( attribute "BOM_COST" "PROC_SIDEBAND"
					( Origin gFrontEnd )
				)
				( attribute "CDS_LIB" "mstr_discrete"
					( Origin gPackager )
				)
				( attribute "CDS_LOCATION" "R4P20"
					( Origin gPackager )
				)
				( attribute "CDS_SEC" "1"
					( Origin gPackager )
				)
				( attribute "LOCATION" "R4P20"
					( Origin gFrontEnd )
				)
				( attribute "MATERIAL" "CHIP"
					( Origin gFrontEnd )
				)
				( attribute "PACK_TYPE" "0402"
					( Origin gFrontEnd )
				)
				( attribute "PART_NUMBER" "G21796-009"
					( Origin gFrontEnd )
				)
				( attribute "PHYS_PAGE" "152"
					( Origin gFrontEnd )
				)
				( attribute "ROOM" "PROC_SIDEBAND"
					( Origin gFrontEnd )
				)
				( attribute "ROT" "2"
					( Origin gFrontEnd )
				)
				( attribute "SEC" "1"
					( Origin gFrontEnd )
				)
				( attribute "SEC_TYPE" "0402"
					( Origin gFrontEnd )
				)
				( attribute "TOLERANCE" "1%"
					( Origin gFrontEnd )
				)
				( attribute "VALUE" "150.0"
					( Origin gFrontEnd )
				)
				( attribute "VER" "2"
					( Origin gFrontEnd )
				)
				( attribute "WATTAGE" "1/16W"
					( Origin gFrontEnd )
				)
				( attribute "XY" "(-7900,3250)"
					( Origin gFrontEnd )
				)
				( attribute "CHIPS_PART_NAME" "RES"
					( Origin gPackager )
				)
				( attribute "CDS_PART_NAME" "RES_0402-150.0,1%,1/16W,CHIP,GA"
					( Origin gPackager )
				)
				( objectStatus "R4P20" )
			)
			( gate "@baseboard_fab2_lib.baseboard_fab2(sch_1):page152_i61"
				( attribute "BOM_COST" "PROC_SIDEBAND"
					( Origin gFrontEnd )
				)
				( attribute "CDS_LIB" "mstr_discrete"
					( Origin gPackager )
				)
				( attribute "CDS_LOCATION" "R7P5"
					( Origin gPackager )
				)
				( attribute "CDS_SEC" "1"
					( Origin gPackager )
				)
				( attribute "LOCATION" "R7P5"
					( Origin gFrontEnd )
				)
				( attribute "MATERIAL" "CHIP"
					( Origin gFrontEnd )
				)
				( attribute "PACK_TYPE" "0402"
					( Origin gFrontEnd )
				)
				( attribute "PART_NUMBER" "G21796-009"
					( Origin gFrontEnd )
				)
				( attribute "PHYS_PAGE" "152"
					( Origin gFrontEnd )
				)
				( attribute "ROOM" "PROC_SIDEBAND"
					( Origin gFrontEnd )
				)
				( attribute "ROT" "0"
					( Origin gFrontEnd )
				)
				( attribute "SEC" "1"
					( Origin gFrontEnd )
				)
				( attribute "SEC_TYPE" "0402"
					( Origin gFrontEnd )
				)
				( attribute "TOLERANCE" "1%"
					( Origin gFrontEnd )
				)
				( attribute "VALUE" "150.0"
					( Origin gFrontEnd )
				)
				( attribute "VER" "2"
					( Origin gFrontEnd )
				)
				( attribute "WATTAGE" "1/16W"
					( Origin gFrontEnd )
				)
				( attribute "XY" "(-8250,3275)"
					( Origin gFrontEnd )
				)
				( attribute "CHIPS_PART_NAME" "RES"
					( Origin gPackager )
				)
				( attribute "CDS_PART_NAME" "RES_0402-150.0,1%,1/16W,CHIP,GA"
					( Origin gPackager )
				)
				( objectStatus "R7P5" )
			)
			( gate "@baseboard_fab2_lib.baseboard_fab2(sch_1):page152_i62"
				( attribute "BOM_COST" "PROC_SIDEBAND"
					( Origin gFrontEnd )
				)
				( attribute "CDS_LIB" "mstr_discrete"
					( Origin gPackager )
				)
				( attribute "CDS_LOCATION" "R7P21"
					( Origin gPackager )
				)
				( attribute "CDS_SEC" "1"
					( Origin gPackager )
				)
				( attribute "LOCATION" "R7P21"
					( Origin gFrontEnd )
				)
				( attribute "MATERIAL" "CHIP"
					( Origin gFrontEnd )
				)
				( attribute "PACK_TYPE" "0402"
					( Origin gFrontEnd )
				)
				( attribute "PART_NUMBER" "G21796-009"
					( Origin gFrontEnd )
				)
				( attribute "PHYS_PAGE" "152"
					( Origin gFrontEnd )
				)
				( attribute "ROOM" "PROC_SIDEBAND"
					( Origin gFrontEnd )
				)
				( attribute "ROT" "2"
					( Origin gFrontEnd )
				)
				( attribute "SEC" "1"
					( Origin gFrontEnd )
				)
				( attribute "SEC_TYPE" "0402"
					( Origin gFrontEnd )
				)
				( attribute "TOLERANCE" "1%"
					( Origin gFrontEnd )
				)
				( attribute "VALUE" "150.0"
					( Origin gFrontEnd )
				)
				( attribute "VER" "2"
					( Origin gFrontEnd )
				)
				( attribute "WATTAGE" "1/16W"
					( Origin gFrontEnd )
				)
				( attribute "XY" "(-8350,3275)"
					( Origin gFrontEnd )
				)
				( attribute "CHIPS_PART_NAME" "RES"
					( Origin gPackager )
				)
				( attribute "CDS_PART_NAME" "RES_0402-150.0,1%,1/16W,CHIP,GA"
					( Origin gPackager )
				)
				( objectStatus "R7P21" )
			)
			( gate "@baseboard_fab2_lib.baseboard_fab2(sch_1):page152_i64"
				( attribute "CDS_LIB" "mstr_discrete"
					( Origin gPackager )
				)
				( attribute "CDS_LOCATION" "R1U53"
					( Origin gPackager )
				)
				( attribute "CDS_SEC" "1"
					( Origin gPackager )
				)
				( attribute "LOCATION" "R1U53"
					( Origin gFrontEnd )
				)
				( attribute "MATERIAL" "CHIP"
					( Origin gFrontEnd )
				)
				( attribute "PACK_TYPE" "0402"
					( Origin gFrontEnd )
				)
				( attribute "PART_NUMBER" "G21497-005"
					( Origin gFrontEnd )
				)
				( attribute "PHYS_PAGE" "152"
					( Origin gFrontEnd )
				)
				( attribute "ROT" "0"
					( Origin gFrontEnd )
				)
				( attribute "SEC" "1"
					( Origin gFrontEnd )
				)
				( attribute "SEC_TYPE" "0402"
					( Origin gFrontEnd )
				)
				( attribute "TOLERANCE" "5%"
					( Origin gFrontEnd )
				)
				( attribute "VALUE" "0.0"
					( Origin gFrontEnd )
				)
				( attribute "VER" "1"
					( Origin gFrontEnd )
				)
				( attribute "WATTAGE" "1/16W"
					( Origin gFrontEnd )
				)
				( attribute "XY" "(-6950,3900)"
					( Origin gFrontEnd )
				)
				( attribute "CHIPS_PART_NAME" "RES"
					( Origin gPackager )
				)
				( attribute "CDS_PART_NAME" "RES_0402-0.0,5%,1/16W,CHIP,G21A"
					( Origin gPackager )
				)
				( objectStatus "R1U53" )
			)
			( gate "@baseboard_fab2_lib.baseboard_fab2(sch_1):page152_i65"
				( attribute "CDS_LIB" "mstr_discrete"
					( Origin gPackager )
				)
				( attribute "CDS_LOCATION" "R1U60"
					( Origin gPackager )
				)
				( attribute "CDS_SEC" "1"
					( Origin gPackager )
				)
				( attribute "LOCATION" "R1U60"
					( Origin gFrontEnd )
				)
				( attribute "MATERIAL" "CHIP"
					( Origin gFrontEnd )
				)
				( attribute "PACK_TYPE" "0402"
					( Origin gFrontEnd )
				)
				( attribute "PART_NUMBER" "G21497-005"
					( Origin gFrontEnd )
				)
				( attribute "PHYS_PAGE" "152"
					( Origin gFrontEnd )
				)
				( attribute "ROT" "0"
					( Origin gFrontEnd )
				)
				( attribute "SEC" "1"
					( Origin gFrontEnd )
				)
				( attribute "SEC_TYPE" "0402"
					( Origin gFrontEnd )
				)
				( attribute "TOLERANCE" "5%"
					( Origin gFrontEnd )
				)
				( attribute "VALUE" "0.0"
					( Origin gFrontEnd )
				)
				( attribute "VER" "1"
					( Origin gFrontEnd )
				)
				( attribute "WATTAGE" "1/16W"
					( Origin gFrontEnd )
				)
				( attribute "XY" "(-6950,3750)"
					( Origin gFrontEnd )
				)
				( attribute "CHIPS_PART_NAME" "RES"
					( Origin gPackager )
				)
				( attribute "CDS_PART_NAME" "RES_0402-0.0,5%,1/16W,CHIP,G21A"
					( Origin gPackager )
				)
				( objectStatus "R1U60" )
			)
			( gate "@baseboard_fab2_lib.baseboard_fab2(sch_1):page152_i66"
				( attribute "CDS_LIB" "mstr_discrete"
					( Origin gPackager )
				)
				( attribute "CDS_LOCATION" "R2U49"
					( Origin gPackager )
				)
				( attribute "CDS_SEC" "1"
					( Origin gPackager )
				)
				( attribute "LOCATION" "R2U49"
					( Origin gFrontEnd )
				)
				( attribute "MATERIAL" "EMPTY"
					( Origin gFrontEnd )
				)
				( attribute "PACK_TYPE" "0402"
					( Origin gFrontEnd )
				)
				( attribute "PART_NUMBER" "G21497-005"
					( Origin gFrontEnd )
				)
				( attribute "PHYS_PAGE" "152"
					( Origin gFrontEnd )
				)
				( attribute "ROT" "0"
					( Origin gFrontEnd )
				)
				( attribute "SEC" "1"
					( Origin gFrontEnd )
				)
				( attribute "SEC_TYPE" "0402"
					( Origin gFrontEnd )
				)
				( attribute "TOLERANCE" "5%"
					( Origin gFrontEnd )
				)
				( attribute "VALUE" "0.0"
					( Origin gFrontEnd )
				)
				( attribute "VER" "2"
					( Origin gFrontEnd )
				)
				( attribute "WATTAGE" "1/16W"
					( Origin gFrontEnd )
				)
				( attribute "XY" "(-2850,4600)"
					( Origin gFrontEnd )
				)
				( attribute "CHIPS_PART_NAME" "RES"
					( Origin gPackager )
				)
				( attribute "CDS_PART_NAME" "RES_0402-0.0,5%,1/16W,EMPTY,G2A"
					( Origin gPackager )
				)
				( objectStatus "R2U49" )
			)
			( gate "@baseboard_fab2_lib.baseboard_fab2(sch_1):page152_i67"
				( attribute "CDS_LIB" "mstr_discrete"
					( Origin gPackager )
				)
				( attribute "CDS_LOCATION" "R1U55"
					( Origin gPackager )
				)
				( attribute "CDS_SEC" "1"
					( Origin gPackager )
				)
				( attribute "LOCATION" "R1U55"
					( Origin gFrontEnd )
				)
				( attribute "MATERIAL" "EMPTY"
					( Origin gFrontEnd )
				)
				( attribute "PACK_TYPE" "0402"
					( Origin gFrontEnd )
				)
				( attribute "PART_NUMBER" "G21497-005"
					( Origin gFrontEnd )
				)
				( attribute "PHYS_PAGE" "152"
					( Origin gFrontEnd )
				)
				( attribute "ROT" "0"
					( Origin gFrontEnd )
				)
				( attribute "SEC" "1"
					( Origin gFrontEnd )
				)
				( attribute "SEC_TYPE" "0402"
					( Origin gFrontEnd )
				)
				( attribute "TOLERANCE" "5%"
					( Origin gFrontEnd )
				)
				( attribute "VALUE" "0.0"
					( Origin gFrontEnd )
				)
				( attribute "VER" "2"
					( Origin gFrontEnd )
				)
				( attribute "WATTAGE" "1/16W"
					( Origin gFrontEnd )
				)
				( attribute "XY" "(-7175,3500)"
					( Origin gFrontEnd )
				)
				( attribute "CHIPS_PART_NAME" "RES"
					( Origin gPackager )
				)
				( attribute "CDS_PART_NAME" "RES_0402-0.0,5%,1/16W,EMPTY,G2A"
					( Origin gPackager )
				)
				( objectStatus "R1U55" )
			)
			( gate "@baseboard_fab2_lib.baseboard_fab2(sch_1):page152_i68"
				( attribute "CDS_LIB" "mstr_discrete"
					( Origin gPackager )
				)
				( attribute "CDS_LOCATION" "R1U62"
					( Origin gPackager )
				)
				( attribute "CDS_SEC" "1"
					( Origin gPackager )
				)
				( attribute "LOCATION" "R1U62"
					( Origin gFrontEnd )
				)
				( attribute "MATERIAL" "EMPTY"
					( Origin gFrontEnd )
				)
				( attribute "PACK_TYPE" "0402"
					( Origin gFrontEnd )
				)
				( attribute "PART_NUMBER" "G21497-005"
					( Origin gFrontEnd )
				)
				( attribute "PHYS_PAGE" "152"
					( Origin gFrontEnd )
				)
				( attribute "ROT" "0"
					( Origin gFrontEnd )
				)
				( attribute "SEC" "1"
					( Origin gFrontEnd )
				)
				( attribute "SEC_TYPE" "0402"
					( Origin gFrontEnd )
				)
				( attribute "TOLERANCE" "5%"
					( Origin gFrontEnd )
				)
				( attribute "VALUE" "0.0"
					( Origin gFrontEnd )
				)
				( attribute "VER" "2"
					( Origin gFrontEnd )
				)
				( attribute "WATTAGE" "1/16W"
					( Origin gFrontEnd )
				)
				( attribute "XY" "(-7450,3500)"
					( Origin gFrontEnd )
				)
				( attribute "CHIPS_PART_NAME" "RES"
					( Origin gPackager )
				)
				( attribute "CDS_PART_NAME" "RES_0402-0.0,5%,1/16W,EMPTY,G2A"
					( Origin gPackager )
				)
				( objectStatus "R1U62" )
			)
			( gate "@baseboard_fab2_lib.baseboard_fab2(sch_1):page152_i69"
				( attribute "CDS_LIB" "mstr_discrete"
					( Origin gPackager )
				)
				( attribute "CDS_LOCATION" "R1U57"
					( Origin gPackager )
				)
				( attribute "CDS_SEC" "1"
					( Origin gPackager )
				)
				( attribute "LOCATION" "R1U57"
					( Origin gFrontEnd )
				)
				( attribute "MATERIAL" "EMPTY"
					( Origin gFrontEnd )
				)
				( attribute "PACK_TYPE" "0402"
					( Origin gFrontEnd )
				)
				( attribute "PART_NUMBER" "G21497-005"
					( Origin gFrontEnd )
				)
				( attribute "PHYS_PAGE" "152"
					( Origin gFrontEnd )
				)
				( attribute "ROT" "0"
					( Origin gFrontEnd )
				)
				( attribute "SEC" "1"
					( Origin gFrontEnd )
				)
				( attribute "SEC_TYPE" "0402"
					( Origin gFrontEnd )
				)
				( attribute "TOLERANCE" "5%"
					( Origin gFrontEnd )
				)
				( attribute "VALUE" "0.0"
					( Origin gFrontEnd )
				)
				( attribute "VER" "2"
					( Origin gFrontEnd )
				)
				( attribute "WATTAGE" "1/16W"
					( Origin gFrontEnd )
				)
				( attribute "XY" "(-3175,3425)"
					( Origin gFrontEnd )
				)
				( attribute "CHIPS_PART_NAME" "RES"
					( Origin gPackager )
				)
				( attribute "CDS_PART_NAME" "RES_0402-0.0,5%,1/16W,EMPTY,G2A"
					( Origin gPackager )
				)
				( objectStatus "R1U57" )
			)
			( gate "@baseboard_fab2_lib.baseboard_fab2(sch_1):page152_i70"
				( attribute "CDS_LIB" "mstr_discrete"
					( Origin gPackager )
				)
				( attribute "CDS_LOCATION" "R1U61"
					( Origin gPackager )
				)
				( attribute "CDS_SEC" "1"
					( Origin gPackager )
				)
				( attribute "LOCATION" "R1U61"
					( Origin gFrontEnd )
				)
				( attribute "MATERIAL" "EMPTY"
					( Origin gFrontEnd )
				)
				( attribute "PACK_TYPE" "0402"
					( Origin gFrontEnd )
				)
				( attribute "PART_NUMBER" "G21497-005"
					( Origin gFrontEnd )
				)
				( attribute "PHYS_PAGE" "152"
					( Origin gFrontEnd )
				)
				( attribute "ROT" "0"
					( Origin gFrontEnd )
				)
				( attribute "SEC" "1"
					( Origin gFrontEnd )
				)
				( attribute "SEC_TYPE" "0402"
					( Origin gFrontEnd )
				)
				( attribute "TOLERANCE" "5%"
					( Origin gFrontEnd )
				)
				( attribute "VALUE" "0.0"
					( Origin gFrontEnd )
				)
				( attribute "VER" "2"
					( Origin gFrontEnd )
				)
				( attribute "WATTAGE" "1/16W"
					( Origin gFrontEnd )
				)
				( attribute "XY" "(-2875,3425)"
					( Origin gFrontEnd )
				)
				( attribute "CHIPS_PART_NAME" "RES"
					( Origin gPackager )
				)
				( attribute "CDS_PART_NAME" "RES_0402-0.0,5%,1/16W,EMPTY,G2A"
					( Origin gPackager )
				)
				( objectStatus "R1U61" )
			)
			( gate "@baseboard_fab2_lib.baseboard_fab2(sch_1):page152_i71"
				( attribute "CDS_LIB" "mstr_discrete"
					( Origin gPackager )
				)
				( attribute "CDS_LOCATION" "R9G28"
					( Origin gPackager )
				)
				( attribute "CDS_SEC" "1"
					( Origin gPackager )
				)
				( attribute "LOCATION" "R9G28"
					( Origin gFrontEnd )
				)
				( attribute "MATERIAL" "CHIP"
					( Origin gFrontEnd )
				)
				( attribute "PACK_TYPE" "0402"
					( Origin gFrontEnd )
				)
				( attribute "PART_NUMBER" "G21497-005"
					( Origin gFrontEnd )
				)
				( attribute "PHYS_PAGE" "152"
					( Origin gFrontEnd )
				)
				( attribute "ROT" "0"
					( Origin gFrontEnd )
				)
				( attribute "SEC" "1"
					( Origin gFrontEnd )
				)
				( attribute "SEC_TYPE" "0402"
					( Origin gFrontEnd )
				)
				( attribute "TOLERANCE" "5%"
					( Origin gFrontEnd )
				)
				( attribute "VALUE" "0.0"
					( Origin gFrontEnd )
				)
				( attribute "VER" "1"
					( Origin gFrontEnd )
				)
				( attribute "WATTAGE" "1/16W"
					( Origin gFrontEnd )
				)
				( attribute "XY" "(-3375,3725)"
					( Origin gFrontEnd )
				)
				( attribute "CHIPS_PART_NAME" "RES"
					( Origin gPackager )
				)
				( attribute "CDS_PART_NAME" "RES_0402-0.0,5%,1/16W,CHIP,G21A"
					( Origin gPackager )
				)
				( objectStatus "R9G28" )
			)
			( gate "@baseboard_fab2_lib.baseboard_fab2(sch_1):page152_i72"
				( attribute "CDS_LIB" "mstr_discrete"
					( Origin gPackager )
				)
				( attribute "CDS_LOCATION" "R9G32"
					( Origin gPackager )
				)
				( attribute "CDS_SEC" "1"
					( Origin gPackager )
				)
				( attribute "LOCATION" "R9G32"
					( Origin gFrontEnd )
				)
				( attribute "MATERIAL" "CHIP"
					( Origin gFrontEnd )
				)
				( attribute "PACK_TYPE" "0402"
					( Origin gFrontEnd )
				)
				( attribute "PART_NUMBER" "G21497-005"
					( Origin gFrontEnd )
				)
				( attribute "PHYS_PAGE" "152"
					( Origin gFrontEnd )
				)
				( attribute "ROT" "0"
					( Origin gFrontEnd )
				)
				( attribute "SEC" "1"
					( Origin gFrontEnd )
				)
				( attribute "SEC_TYPE" "0402"
					( Origin gFrontEnd )
				)
				( attribute "TOLERANCE" "5%"
					( Origin gFrontEnd )
				)
				( attribute "VALUE" "0.0"
					( Origin gFrontEnd )
				)
				( attribute "VER" "1"
					( Origin gFrontEnd )
				)
				( attribute "WATTAGE" "1/16W"
					( Origin gFrontEnd )
				)
				( attribute "XY" "(-3375,3900)"
					( Origin gFrontEnd )
				)
				( attribute "CHIPS_PART_NAME" "RES"
					( Origin gPackager )
				)
				( attribute "CDS_PART_NAME" "RES_0402-0.0,5%,1/16W,CHIP,G21A"
					( Origin gPackager )
				)
				( objectStatus "R9G32" )
			)
			( gate "@baseboard_fab2_lib.baseboard_fab2(sch_1):page152_i73"
				( attribute "CDS_LIB" "mstr_discrete"
					( Origin gPackager )
				)
				( attribute "CDS_LOCATION" "R9G33"
					( Origin gPackager )
				)
				( attribute "CDS_SEC" "1"
					( Origin gPackager )
				)
				( attribute "LOCATION" "R9G33"
					( Origin gFrontEnd )
				)
				( attribute "MATERIAL" "CHIP"
					( Origin gFrontEnd )
				)
				( attribute "PACK_TYPE" "0402"
					( Origin gFrontEnd )
				)
				( attribute "PART_NUMBER" "G21497-005"
					( Origin gFrontEnd )
				)
				( attribute "PHYS_PAGE" "152"
					( Origin gFrontEnd )
				)
				( attribute "ROT" "0"
					( Origin gFrontEnd )
				)
				( attribute "SEC" "1"
					( Origin gFrontEnd )
				)
				( attribute "SEC_TYPE" "0402"
					( Origin gFrontEnd )
				)
				( attribute "TOLERANCE" "5%"
					( Origin gFrontEnd )
				)
				( attribute "VALUE" "0.0"
					( Origin gFrontEnd )
				)
				( attribute "VER" "1"
					( Origin gFrontEnd )
				)
				( attribute "WATTAGE" "1/16W"
					( Origin gFrontEnd )
				)
				( attribute "XY" "(-3375,4075)"
					( Origin gFrontEnd )
				)
				( attribute "CHIPS_PART_NAME" "RES"
					( Origin gPackager )
				)
				( attribute "CDS_PART_NAME" "RES_0402-0.0,5%,1/16W,CHIP,G21A"
					( Origin gPackager )
				)
				( objectStatus "R9G33" )
			)
			( gate "@baseboard_fab2_lib.baseboard_fab2(sch_1):page152_i74"
				( attribute "CDS_LIB" "mstr_discrete"
					( Origin gPackager )
				)
				( attribute "CDS_LOCATION" "R1U59"
					( Origin gPackager )
				)
				( attribute "CDS_SEC" "1"
					( Origin gPackager )
				)
				( attribute "LOCATION" "R1U59"
					( Origin gFrontEnd )
				)
				( attribute "MATERIAL" "CHIP"
					( Origin gFrontEnd )
				)
				( attribute "PACK_TYPE" "0402"
					( Origin gFrontEnd )
				)
				( attribute "PART_NUMBER" "G21497-005"
					( Origin gFrontEnd )
				)
				( attribute "PHYS_PAGE" "152"
					( Origin gFrontEnd )
				)
				( attribute "ROT" "0"
					( Origin gFrontEnd )
				)
				( attribute "SEC" "1"
					( Origin gFrontEnd )
				)
				( attribute "SEC_TYPE" "0402"
					( Origin gFrontEnd )
				)
				( attribute "TOLERANCE" "5%"
					( Origin gFrontEnd )
				)
				( attribute "VALUE" "0.0"
					( Origin gFrontEnd )
				)
				( attribute "VER" "1"
					( Origin gFrontEnd )
				)
				( attribute "WATTAGE" "1/16W"
					( Origin gFrontEnd )
				)
				( attribute "XY" "(-3375,4250)"
					( Origin gFrontEnd )
				)
				( attribute "CHIPS_PART_NAME" "RES"
					( Origin gPackager )
				)
				( attribute "CDS_PART_NAME" "RES_0402-0.0,5%,1/16W,CHIP,G21A"
					( Origin gPackager )
				)
				( objectStatus "R1U59" )
			)
			( gate "@baseboard_fab2_lib.baseboard_fab2(sch_1):page152_i79"
				( attribute "CDS_LIB" "mstr_discrete"
					( Origin gPackager )
				)
				( attribute "CDS_LOCATION" "R2U47"
					( Origin gPackager )
				)
				( attribute "CDS_SEC" "1"
					( Origin gPackager )
				)
				( attribute "LOCATION" "R2U47"
					( Origin gFrontEnd )
				)
				( attribute "MATERIAL" "CHIP"
					( Origin gFrontEnd )
				)
				( attribute "PACK_TYPE" "0402"
					( Origin gFrontEnd )
				)
				( attribute "PART_NUMBER" "G21497-005"
					( Origin gFrontEnd )
				)
				( attribute "PHYS_PAGE" "152"
					( Origin gFrontEnd )
				)
				( attribute "ROT" "0"
					( Origin gFrontEnd )
				)
				( attribute "SEC" "1"
					( Origin gFrontEnd )
				)
				( attribute "SEC_TYPE" "0402"
					( Origin gFrontEnd )
				)
				( attribute "TOLERANCE" "5%"
					( Origin gFrontEnd )
				)
				( attribute "VALUE" "0.0"
					( Origin gFrontEnd )
				)
				( attribute "VER" "1"
					( Origin gFrontEnd )
				)
				( attribute "WATTAGE" "1/16W"
					( Origin gFrontEnd )
				)
				( attribute "XY" "(-6700,2475)"
					( Origin gFrontEnd )
				)
				( attribute "CHIPS_PART_NAME" "RES"
					( Origin gPackager )
				)
				( attribute "CDS_PART_NAME" "RES_0402-0.0,5%,1/16W,CHIP,G21A"
					( Origin gPackager )
				)
				( objectStatus "R2U47" )
			)
			( gate "@baseboard_fab2_lib.baseboard_fab2(sch_1):page152_i92"
				( attribute "CDS_LIB" "mstr_discrete"
					( Origin gPackager )
				)
				( attribute "CDS_LOCATION" "R9G29"
					( Origin gPackager )
				)
				( attribute "CDS_SEC" "1"
					( Origin gPackager )
				)
				( attribute "LOCATION" "R9G29"
					( Origin gFrontEnd )
				)
				( attribute "MATERIAL" "CHIP"
					( Origin gFrontEnd )
				)
				( attribute "PACK_TYPE" "0402"
					( Origin gFrontEnd )
				)
				( attribute "PART_NUMBER" "G21497-005"
					( Origin gFrontEnd )
				)
				( attribute "PHYS_PAGE" "152"
					( Origin gFrontEnd )
				)
				( attribute "ROT" "0"
					( Origin gFrontEnd )
				)
				( attribute "SEC" "1"
					( Origin gFrontEnd )
				)
				( attribute "SEC_TYPE" "0402"
					( Origin gFrontEnd )
				)
				( attribute "TOLERANCE" "5%"
					( Origin gFrontEnd )
				)
				( attribute "VALUE" "0.0"
					( Origin gFrontEnd )
				)
				( attribute "VER" "1"
					( Origin gFrontEnd )
				)
				( attribute "WATTAGE" "1/16W"
					( Origin gFrontEnd )
				)
				( attribute "XY" "(-6700,2025)"
					( Origin gFrontEnd )
				)
				( attribute "CHIPS_PART_NAME" "RES"
					( Origin gPackager )
				)
				( attribute "CDS_PART_NAME" "RES_0402-0.0,5%,1/16W,CHIP,G21A"
					( Origin gPackager )
				)
				( objectStatus "R9G29" )
			)
			( gate "@baseboard_fab2_lib.baseboard_fab2(sch_1):page152_i93"
				( attribute "CDS_LIB" "mstr_discrete"
					( Origin gPackager )
				)
				( attribute "CDS_LOCATION" "R1U54"
					( Origin gPackager )
				)
				( attribute "CDS_SEC" "1"
					( Origin gPackager )
				)
				( attribute "LOCATION" "R1U54"
					( Origin gFrontEnd )
				)
				( attribute "MATERIAL" "CHIP"
					( Origin gFrontEnd )
				)
				( attribute "PACK_TYPE" "0402"
					( Origin gFrontEnd )
				)
				( attribute "PART_NUMBER" "G21497-005"
					( Origin gFrontEnd )
				)
				( attribute "PHYS_PAGE" "152"
					( Origin gFrontEnd )
				)
				( attribute "ROT" "0"
					( Origin gFrontEnd )
				)
				( attribute "SEC" "1"
					( Origin gFrontEnd )
				)
				( attribute "SEC_TYPE" "0402"
					( Origin gFrontEnd )
				)
				( attribute "TOLERANCE" "5%"
					( Origin gFrontEnd )
				)
				( attribute "VALUE" "0.0"
					( Origin gFrontEnd )
				)
				( attribute "VER" "1"
					( Origin gFrontEnd )
				)
				( attribute "WATTAGE" "1/16W"
					( Origin gFrontEnd )
				)
				( attribute "XY" "(-6700,1600)"
					( Origin gFrontEnd )
				)
				( attribute "CHIPS_PART_NAME" "RES"
					( Origin gPackager )
				)
				( attribute "CDS_PART_NAME" "RES_0402-0.0,5%,1/16W,CHIP,G21A"
					( Origin gPackager )
				)
				( objectStatus "R1U54" )
			)
			( gate "@baseboard_fab2_lib.baseboard_fab2(sch_1):page152_i94"
				( attribute "CDS_LIB" "mstr_discrete"
					( Origin gPackager )
				)
				( attribute "CDS_LOCATION" "R2U46"
					( Origin gPackager )
				)
				( attribute "CDS_SEC" "1"
					( Origin gPackager )
				)
				( attribute "LOCATION" "R2U46"
					( Origin gFrontEnd )
				)
				( attribute "MATERIAL" "CHIP"
					( Origin gFrontEnd )
				)
				( attribute "PACK_TYPE" "0402"
					( Origin gFrontEnd )
				)
				( attribute "PART_NUMBER" "G21497-005"
					( Origin gFrontEnd )
				)
				( attribute "PHYS_PAGE" "152"
					( Origin gFrontEnd )
				)
				( attribute "ROT" "0"
					( Origin gFrontEnd )
				)
				( attribute "SEC" "1"
					( Origin gFrontEnd )
				)
				( attribute "SEC_TYPE" "0402"
					( Origin gFrontEnd )
				)
				( attribute "TOLERANCE" "5%"
					( Origin gFrontEnd )
				)
				( attribute "VALUE" "0.0"
					( Origin gFrontEnd )
				)
				( attribute "VER" "1"
					( Origin gFrontEnd )
				)
				( attribute "WATTAGE" "1/16W"
					( Origin gFrontEnd )
				)
				( attribute "XY" "(-6700,1175)"
					( Origin gFrontEnd )
				)
				( attribute "CHIPS_PART_NAME" "RES"
					( Origin gPackager )
				)
				( attribute "CDS_PART_NAME" "RES_0402-0.0,5%,1/16W,CHIP,G21A"
					( Origin gPackager )
				)
				( objectStatus "R2U46" )
			)
			( gate "@baseboard_fab2_lib.baseboard_fab2(sch_1):page152_i95"
				( attribute "CDS_LIB" "mstr_discrete"
					( Origin gPackager )
				)
				( attribute "CDS_LOCATION" "R3N30"
					( Origin gPackager )
				)
				( attribute "LOCATION" "R3N30"
					( Origin gFrontEnd )
				)
				( attribute "MATERIAL" "EMPTY"
					( Origin gFrontEnd )
				)
				( attribute "PACK_TYPE" "0402"
					( Origin gFrontEnd )
				)
				( attribute "PART_NUMBER" "G21497-005"
					( Origin gFrontEnd )
				)
				( attribute "PHYS_PAGE" "152"
					( Origin gFrontEnd )
				)
				( attribute "ROT" "0"
					( Origin gFrontEnd )
				)
				( attribute "SEC" "1"
					( Origin gFrontEnd )
				)
				( attribute "TOLERANCE" "5%"
					( Origin gFrontEnd )
				)
				( attribute "VALUE" "0.0"
					( Origin gFrontEnd )
				)
				( attribute "VER" "1"
					( Origin gFrontEnd )
				)
				( attribute "WATTAGE" "1/16W"
					( Origin gFrontEnd )
				)
				( attribute "XY" "(-6700,2275)"
					( Origin gFrontEnd )
				)
				( attribute "CHIPS_PART_NAME" "RES"
					( Origin gPackager )
				)
				( attribute "CDS_PART_NAME" "RES_0402-0.0,5%,1/16W,EMPTY,G2A"
					( Origin gPackager )
				)
				( attribute "SEC_TYPE" "0402"
					( Origin gFrontEnd )
				)
				( attribute "CDS_SEC" "1"
					( Origin gPackager )
				)
				( objectStatus "R3N30" )
			)
			( gate "@baseboard_fab2_lib.baseboard_fab2(sch_1):page152_i98"
				( attribute "CDS_LIB" "mstr_discrete"
					( Origin gPackager )
				)
				( attribute "CDS_LOCATION" "R9G30"
					( Origin gPackager )
				)
				( attribute "LOCATION" "R9G30"
					( Origin gFrontEnd )
				)
				( attribute "MATERIAL" "EMPTY"
					( Origin gFrontEnd )
				)
				( attribute "PACK_TYPE" "0402"
					( Origin gFrontEnd )
				)
				( attribute "PART_NUMBER" "G21497-005"
					( Origin gFrontEnd )
				)
				( attribute "PHYS_PAGE" "152"
					( Origin gFrontEnd )
				)
				( attribute "ROT" "0"
					( Origin gFrontEnd )
				)
				( attribute "SEC" "1"
					( Origin gFrontEnd )
				)
				( attribute "TOLERANCE" "5%"
					( Origin gFrontEnd )
				)
				( attribute "VALUE" "0.0"
					( Origin gFrontEnd )
				)
				( attribute "VER" "1"
					( Origin gFrontEnd )
				)
				( attribute "WATTAGE" "1/16W"
					( Origin gFrontEnd )
				)
				( attribute "XY" "(-6700,1825)"
					( Origin gFrontEnd )
				)
				( attribute "CHIPS_PART_NAME" "RES"
					( Origin gPackager )
				)
				( attribute "CDS_PART_NAME" "RES_0402-0.0,5%,1/16W,EMPTY,G2A"
					( Origin gPackager )
				)
				( attribute "SEC_TYPE" "0402"
					( Origin gFrontEnd )
				)
				( attribute "CDS_SEC" "1"
					( Origin gPackager )
				)
				( objectStatus "R9G30" )
			)
			( gate "@baseboard_fab2_lib.baseboard_fab2(sch_1):page152_i100"
				( attribute "CDS_LIB" "mstr_discrete"
					( Origin gPackager )
				)
				( attribute "CDS_LOCATION" "R3P63"
					( Origin gPackager )
				)
				( attribute "LOCATION" "R3P63"
					( Origin gFrontEnd )
				)
				( attribute "MATERIAL" "EMPTY"
					( Origin gFrontEnd )
				)
				( attribute "PACK_TYPE" "0402"
					( Origin gFrontEnd )
				)
				( attribute "PART_NUMBER" "G21497-005"
					( Origin gFrontEnd )
				)
				( attribute "PHYS_PAGE" "152"
					( Origin gFrontEnd )
				)
				( attribute "ROT" "0"
					( Origin gFrontEnd )
				)
				( attribute "SEC" "1"
					( Origin gFrontEnd )
				)
				( attribute "TOLERANCE" "5%"
					( Origin gFrontEnd )
				)
				( attribute "VALUE" "0.0"
					( Origin gFrontEnd )
				)
				( attribute "VER" "1"
					( Origin gFrontEnd )
				)
				( attribute "WATTAGE" "1/16W"
					( Origin gFrontEnd )
				)
				( attribute "XY" "(-6700,1400)"
					( Origin gFrontEnd )
				)
				( attribute "CHIPS_PART_NAME" "RES"
					( Origin gPackager )
				)
				( attribute "CDS_PART_NAME" "RES_0402-0.0,5%,1/16W,EMPTY,G2A"
					( Origin gPackager )
				)
				( attribute "SEC_TYPE" "0402"
					( Origin gFrontEnd )
				)
				( attribute "CDS_SEC" "1"
					( Origin gPackager )
				)
				( objectStatus "R3P63" )
			)
			( gate "@baseboard_fab2_lib.baseboard_fab2(sch_1):page152_i102"
				( attribute "CDS_LIB" "mstr_discrete"
					( Origin gPackager )
				)
				( attribute "CDS_LOCATION" "R2U45"
					( Origin gPackager )
				)
				( attribute "LOCATION" "R2U45"
					( Origin gFrontEnd )
				)
				( attribute "MATERIAL" "EMPTY"
					( Origin gFrontEnd )
				)
				( attribute "PACK_TYPE" "0402"
					( Origin gFrontEnd )
				)
				( attribute "PART_NUMBER" "G21497-005"
					( Origin gFrontEnd )
				)
				( attribute "PHYS_PAGE" "152"
					( Origin gFrontEnd )
				)
				( attribute "ROT" "0"
					( Origin gFrontEnd )
				)
				( attribute "SEC" "1"
					( Origin gFrontEnd )
				)
				( attribute "TOLERANCE" "5%"
					( Origin gFrontEnd )
				)
				( attribute "VALUE" "0.0"
					( Origin gFrontEnd )
				)
				( attribute "VER" "1"
					( Origin gFrontEnd )
				)
				( attribute "WATTAGE" "1/16W"
					( Origin gFrontEnd )
				)
				( attribute "XY" "(-6700,975)"
					( Origin gFrontEnd )
				)
				( attribute "CHIPS_PART_NAME" "RES"
					( Origin gPackager )
				)
				( attribute "CDS_PART_NAME" "RES_0402-0.0,5%,1/16W,EMPTY,G2A"
					( Origin gPackager )
				)
				( attribute "SEC_TYPE" "0402"
					( Origin gFrontEnd )
				)
				( attribute "CDS_SEC" "1"
					( Origin gPackager )
				)
				( objectStatus "R2U45" )
			)
			( gate "@baseboard_fab2_lib.baseboard_fab2(sch_1):page153_i90"
				( attribute "BOM_COST" "MIO_BIOS_MEM"
					( Origin gFrontEnd )
				)
				( attribute "CDS_LIB" "mstr_discrete"
					( Origin gPackager )
				)
				( attribute "CDS_LOCATION" "R7F6"
					( Origin gPackager )
				)
				( attribute "CDS_SEC" "1"
					( Origin gPackager )
				)
				( attribute "LOCATION" "R7F6"
					( Origin gFrontEnd )
				)
				( attribute "MATERIAL" "EMPTY"
					( Origin gFrontEnd )
				)
				( attribute "NO_XNET_CONNECTION" "1"
					( Origin gFrontEnd )
				)
				( attribute "PACK_TYPE" "0402"
					( Origin gFrontEnd )
				)
				( attribute "PART_NUMBER" "G21796-072"
					( Origin gFrontEnd )
				)
				( attribute "PHYS_PAGE" "153"
					( Origin gFrontEnd )
				)
				( attribute "ROOM" "SB_SPI"
					( Origin gFrontEnd )
				)
				( attribute "ROT" "2"
					( Origin gFrontEnd )
				)
				( attribute "SEC" "1"
					( Origin gFrontEnd )
				)
				( attribute "SEC_TYPE" "0402"
					( Origin gFrontEnd )
				)
				( attribute "TOLERANCE" "1%"
					( Origin gFrontEnd )
				)
				( attribute "VALUE" "4.75K"
					( Origin gFrontEnd )
				)
				( attribute "VER" "2"
					( Origin gFrontEnd )
				)
				( attribute "WATTAGE" "1/16W"
					( Origin gFrontEnd )
				)
				( attribute "XY" "(-5950,4425)"
					( Origin gFrontEnd )
				)
				( attribute "CHIPS_PART_NAME" "RES"
					( Origin gPackager )
				)
				( attribute "CDS_PART_NAME" "RES_0402-4.75K,1%,1/16W,EMPTY,A"
					( Origin gPackager )
				)
				( objectStatus "R7F6" )
			)
			( gate "@baseboard_fab2_lib.baseboard_fab2(sch_1):page153_i94"
				( attribute "BOM_COST" "MIO_BIOS_MEM"
					( Origin gFrontEnd )
				)
				( attribute "CDS_LIB" "mstr_discrete"
					( Origin gPackager )
				)
				( attribute "CDS_LOCATION" "R7F5"
					( Origin gPackager )
				)
				( attribute "CDS_SEC" "1"
					( Origin gPackager )
				)
				( attribute "LOCATION" "R7F5"
					( Origin gFrontEnd )
				)
				( attribute "MATERIAL" "CHIP"
					( Origin gFrontEnd )
				)
				( attribute "NO_XNET_CONNECTION" "1"
					( Origin gFrontEnd )
				)
				( attribute "PACK_TYPE" "0402"
					( Origin gFrontEnd )
				)
				( attribute "PART_NUMBER" "G21796-072"
					( Origin gFrontEnd )
				)
				( attribute "PHYS_PAGE" "153"
					( Origin gFrontEnd )
				)
				( attribute "ROOM" "SB_SPI"
					( Origin gFrontEnd )
				)
				( attribute "ROT" "2"
					( Origin gFrontEnd )
				)
				( attribute "SEC" "1"
					( Origin gFrontEnd )
				)
				( attribute "SEC_TYPE" "0402"
					( Origin gFrontEnd )
				)
				( attribute "TOLERANCE" "1%"
					( Origin gFrontEnd )
				)
				( attribute "VALUE" "4.75K"
					( Origin gFrontEnd )
				)
				( attribute "VER" "2"
					( Origin gFrontEnd )
				)
				( attribute "WATTAGE" "1/16W"
					( Origin gFrontEnd )
				)
				( attribute "XY" "(-6250,4425)"
					( Origin gFrontEnd )
				)
				( attribute "CHIPS_PART_NAME" "RES"
					( Origin gPackager )
				)
				( attribute "CDS_PART_NAME" "RES_0402-4.75K,1%,1/16W,CHIP,GA"
					( Origin gPackager )
				)
				( objectStatus "R7F5" )
			)
			( gate "@baseboard_fab2_lib.baseboard_fab2(sch_1):page153_i98"
				( attribute "BOM_COST" "MIO_BIOS_MEM"
					( Origin gFrontEnd )
				)
				( attribute "CDS_LIB" "mstr_discrete"
					( Origin gPackager )
				)
				( attribute "CDS_LOCATION" "R7F4"
					( Origin gPackager )
				)
				( attribute "CDS_SEC" "1"
					( Origin gPackager )
				)
				( attribute "LOCATION" "R7F4"
					( Origin gFrontEnd )
				)
				( attribute "MATERIAL" "CHIP"
					( Origin gFrontEnd )
				)
				( attribute "PACK_TYPE" "0402"
					( Origin gFrontEnd )
				)
				( attribute "PART_NUMBER" "G21796-074"
					( Origin gFrontEnd )
				)
				( attribute "PHYS_PAGE" "153"
					( Origin gFrontEnd )
				)
				( attribute "ROOM" "SB_SPI"
					( Origin gFrontEnd )
				)
				( attribute "ROT" "0"
					( Origin gFrontEnd )
				)
				( attribute "SEC" "1"
					( Origin gFrontEnd )
				)
				( attribute "SEC_TYPE" "0402"
					( Origin gFrontEnd )
				)
				( attribute "TOLERANCE" "1%"
					( Origin gFrontEnd )
				)
				( attribute "VALUE" "33.2"
					( Origin gFrontEnd )
				)
				( attribute "VER" "1"
					( Origin gFrontEnd )
				)
				( attribute "WATTAGE" "1/16W"
					( Origin gFrontEnd )
				)
				( attribute "XY" "(-6275,3975)"
					( Origin gFrontEnd )
				)
				( attribute "CHIPS_PART_NAME" "RES"
					( Origin gPackager )
				)
				( attribute "CDS_PART_NAME" "RES_0402-33.2,1%,1/16W,CHIP,G2A"
					( Origin gPackager )
				)
				( objectStatus "R7F4" )
			)
			( gate "@baseboard_fab2_lib.baseboard_fab2(sch_1):page153_i108"
				( attribute "BOM_COST" "MIO_BIOS_MEM"
					( Origin gFrontEnd )
				)
				( attribute "CDS_LIB" "mstr_discrete"
					( Origin gPackager )
				)
				( attribute "CDS_LOCATION" "R7F37"
					( Origin gPackager )
				)
				( attribute "LOCATION" "R7F37"
					( Origin gFrontEnd )
				)
				( attribute "MATERIAL" "CHIP"
					( Origin gFrontEnd )
				)
				( attribute "PACK_TYPE" "0402"
					( Origin gFrontEnd )
				)
				( attribute "PART_NUMBER" "G21796-074"
					( Origin gFrontEnd )
				)
				( attribute "PHYS_PAGE" "153"
					( Origin gFrontEnd )
				)
				( attribute "ROOM" "SB_SPI"
					( Origin gFrontEnd )
				)
				( attribute "ROT" "0"
					( Origin gFrontEnd )
				)
				( attribute "SEC" "1"
					( Origin gFrontEnd )
				)
				( attribute "TOLERANCE" "1%"
					( Origin gFrontEnd )
				)
				( attribute "VALUE" "33.2"
					( Origin gFrontEnd )
				)
				( attribute "VER" "1"
					( Origin gFrontEnd )
				)
				( attribute "WATTAGE" "1/16W"
					( Origin gFrontEnd )
				)
				( attribute "XY" "(-6500,3350)"
					( Origin gFrontEnd )
				)
				( attribute "CHIPS_PART_NAME" "RES"
					( Origin gPackager )
				)
				( attribute "CDS_PART_NAME" "RES_0402-33.2,1%,1/16W,CHIP,G2A"
					( Origin gPackager )
				)
				( attribute "SEC_TYPE" "0402"
					( Origin gFrontEnd )
				)
				( attribute "CDS_SEC" "1"
					( Origin gPackager )
				)
				( objectStatus "R7F37" )
			)
			( gate "@baseboard_fab2_lib.baseboard_fab2(sch_1):page153_i109"
				( attribute "BOM_COST" "MIO_BIOS_MEM"
					( Origin gFrontEnd )
				)
				( attribute "CDS_LIB" "mstr_discrete"
					( Origin gPackager )
				)
				( attribute "CDS_LOCATION" "R7F3"
					( Origin gPackager )
				)
				( attribute "LOCATION" "R7F3"
					( Origin gFrontEnd )
				)
				( attribute "MATERIAL" "CHIP"
					( Origin gFrontEnd )
				)
				( attribute "NO_XNET_CONNECTION" "1"
					( Origin gFrontEnd )
				)
				( attribute "PACK_TYPE" "0402"
					( Origin gFrontEnd )
				)
				( attribute "PART_NUMBER" "G21796-074"
					( Origin gFrontEnd )
				)
				( attribute "PHYS_PAGE" "153"
					( Origin gFrontEnd )
				)
				( attribute "ROOM" "SB_SPI"
					( Origin gFrontEnd )
				)
				( attribute "ROT" "0"
					( Origin gFrontEnd )
				)
				( attribute "SEC" "1"
					( Origin gFrontEnd )
				)
				( attribute "TOLERANCE" "1%"
					( Origin gFrontEnd )
				)
				( attribute "VALUE" "33.2"
					( Origin gFrontEnd )
				)
				( attribute "VER" "1"
					( Origin gFrontEnd )
				)
				( attribute "WATTAGE" "1/16W"
					( Origin gFrontEnd )
				)
				( attribute "XY" "(-6475,3075)"
					( Origin gFrontEnd )
				)
				( attribute "CHIPS_PART_NAME" "RES"
					( Origin gPackager )
				)
				( attribute "CDS_PART_NAME" "RES_0402-33.2,1%,1/16W,CHIP,G2A"
					( Origin gPackager )
				)
				( attribute "SEC_TYPE" "0402"
					( Origin gFrontEnd )
				)
				( attribute "CDS_SEC" "1"
					( Origin gPackager )
				)
				( objectStatus "R7F3" )
			)
			( gate "@baseboard_fab2_lib.baseboard_fab2(sch_1):page153_i130"
				( attribute "BOM_COST" "MIO_BIOS_MEM"
					( Origin gFrontEnd )
				)
				( attribute "CDS_LIB" "dev_discrete"
					( Origin gPackager )
				)
				( attribute "CDS_LOCATION" "C7F2"
					( Origin gPackager )
				)
				( attribute "CDS_SEC" "1"
					( Origin gPackager )
				)
				( attribute "LOCATION" "C7F2"
					( Origin gFrontEnd )
				)
				( attribute "MATERIAL" "X6S"
					( Origin gFrontEnd )
				)
				( attribute "NO_XNET_CONNECTION" "1"
					( Origin gFrontEnd )
				)
				( attribute "PACK_TYPE" "0402V"
					( Origin gFrontEnd )
				)
				( attribute "PART_NUMBER" "D97712-004"
					( Origin gFrontEnd )
				)
				( attribute "PHYS_PAGE" "153"
					( Origin gFrontEnd )
				)
				( attribute "ROOM" "SB_SPI"
					( Origin gFrontEnd )
				)
				( attribute "ROT" "0"
					( Origin gFrontEnd )
				)
				( attribute "SEC" "1"
					( Origin gFrontEnd )
				)
				( attribute "SEC_TYPE" "0402V"
					( Origin gFrontEnd )
				)
				( attribute "TOLERANCE" "10%"
					( Origin gFrontEnd )
				)
				( attribute "VALUE" "1.0UF"
					( Origin gFrontEnd )
				)
				( attribute "VER" "1"
					( Origin gFrontEnd )
				)
				( attribute "VOLTAGE" "6.3V"
					( Units "uVoltage" "V" 1.000000)
					( Origin gFrontEnd )
				)
				( attribute "XY" "(-3925,4500)"
					( Origin gFrontEnd )
				)
				( attribute "CHIPS_PART_NAME" "CAP_A"
					( Origin gPackager )
				)
				( attribute "CDS_PART_NAME" "CAP_A_0402V-1.0UF,6.3V,10%,X6SA"
					( Origin gPackager )
				)
				( objectStatus "C7F2" )
			)
			( gate "@baseboard_fab2_lib.baseboard_fab2(sch_1):page153_i131"
				( attribute "BOM_COST" "MIO_BIOS_MEM"
					( Origin gFrontEnd )
				)
				( attribute "CDS_LIB" "dev_discrete"
					( Origin gPackager )
				)
				( attribute "CDS_LOCATION" "C7F1"
					( Origin gPackager )
				)
				( attribute "CDS_SEC" "1"
					( Origin gPackager )
				)
				( attribute "LOCATION" "C7F1"
					( Origin gFrontEnd )
				)
				( attribute "MATERIAL" "X7R"
					( Origin gFrontEnd )
				)
				( attribute "NO_XNET_CONNECTION" "1"
					( Origin gFrontEnd )
				)
				( attribute "PACK_TYPE" "0402V"
					( Origin gFrontEnd )
				)
				( attribute "PART_NUMBER" "A36096-045"
					( Origin gFrontEnd )
				)
				( attribute "PHYS_PAGE" "153"
					( Origin gFrontEnd )
				)
				( attribute "ROOM" "SB_SPI"
					( Origin gFrontEnd )
				)
				( attribute "ROT" "0"
					( Origin gFrontEnd )
				)
				( attribute "SEC" "1"
					( Origin gFrontEnd )
				)
				( attribute "SEC_TYPE" "0402V"
					( Origin gFrontEnd )
				)
				( attribute "TOLERANCE" "10%"
					( Origin gFrontEnd )
				)
				( attribute "VALUE" "0.01UF"
					( Origin gFrontEnd )
				)
				( attribute "VER" "1"
					( Origin gFrontEnd )
				)
				( attribute "VOLTAGE" "25V"
					( Units "uVoltage" "V" 1.000000)
					( Origin gFrontEnd )
				)
				( attribute "XY" "(-3625,4500)"
					( Origin gFrontEnd )
				)
				( attribute "CHIPS_PART_NAME" "CAP_A"
					( Origin gPackager )
				)
				( attribute "CDS_PART_NAME" "CAP_A_0402V-0.01UF,25V,10%,X7RA"
					( Origin gPackager )
				)
				( objectStatus "C7F1" )
			)
			( gate "@baseboard_fab2_lib.baseboard_fab2(sch_1):page153_i136"
				( attribute "BOM_COST" "MIO_BIOS_MEM"
					( Origin gFrontEnd )
				)
				( attribute "CDS_LIB" "dev_discrete"
					( Origin gPackager )
				)
				( attribute "CDS_LOCATION" "C3T5"
					( Origin gPackager )
				)
				( attribute "CDS_SEC" "1"
					( Origin gPackager )
				)
				( attribute "LOCATION" "C3T5"
					( Origin gFrontEnd )
				)
				( attribute "MATERIAL" "X7R"
					( Origin gFrontEnd )
				)
				( attribute "NO_XNET_CONNECTION" "1"
					( Origin gFrontEnd )
				)
				( attribute "PACK_TYPE" "0402V"
					( Origin gFrontEnd )
				)
				( attribute "PART_NUMBER" "A36096-045"
					( Origin gFrontEnd )
				)
				( attribute "PHYS_PAGE" "153"
					( Origin gFrontEnd )
				)
				( attribute "ROOM" "SB_SPI"
					( Origin gFrontEnd )
				)
				( attribute "ROT" "0"
					( Origin gFrontEnd )
				)
				( attribute "SEC" "1"
					( Origin gFrontEnd )
				)
				( attribute "SEC_TYPE" "0402V"
					( Origin gFrontEnd )
				)
				( attribute "TOLERANCE" "10%"
					( Origin gFrontEnd )
				)
				( attribute "VALUE" "0.01UF"
					( Origin gFrontEnd )
				)
				( attribute "VER" "1"
					( Origin gFrontEnd )
				)
				( attribute "VOLTAGE" "25V"
					( Units "uVoltage" "V" 1.000000)
					( Origin gFrontEnd )
				)
				( attribute "XY" "(-3625,2400)"
					( Origin gFrontEnd )
				)
				( attribute "CHIPS_PART_NAME" "CAP_A"
					( Origin gPackager )
				)
				( attribute "CDS_PART_NAME" "CAP_A_0402V-0.01UF,25V,10%,X7RA"
					( Origin gPackager )
				)
				( attribute "GROUP" "NI_BIOS_ROM2"
					( Origin gFrontEnd )
				)
				( objectStatus "C3T5" )
			)
			( gate "@baseboard_fab2_lib.baseboard_fab2(sch_1):page153_i138"
				( attribute "BOM_COST" "MIO_BIOS_MEM"
					( Origin gFrontEnd )
				)
				( attribute "CDS_LIB" "dev_discrete"
					( Origin gPackager )
				)
				( attribute "CDS_LOCATION" "C3T4"
					( Origin gPackager )
				)
				( attribute "LOCATION" "C3T4"
					( Origin gFrontEnd )
				)
				( attribute "MATERIAL" "X6S"
					( Origin gFrontEnd )
				)
				( attribute "NO_XNET_CONNECTION" "1"
					( Origin gFrontEnd )
				)
				( attribute "PACK_TYPE" "0402V"
					( Origin gFrontEnd )
				)
				( attribute "PART_NUMBER" "D97712-004"
					( Origin gFrontEnd )
				)
				( attribute "PHYS_PAGE" "153"
					( Origin gFrontEnd )
				)
				( attribute "ROOM" "SB_SPI"
					( Origin gFrontEnd )
				)
				( attribute "ROT" "0"
					( Origin gFrontEnd )
				)
				( attribute "SEC" "1"
					( Origin gFrontEnd )
				)
				( attribute "TOLERANCE" "10%"
					( Origin gFrontEnd )
				)
				( attribute "VALUE" "1.0UF"
					( Origin gFrontEnd )
				)
				( attribute "VER" "1"
					( Origin gFrontEnd )
				)
				( attribute "VOLTAGE" "6.3V"
					( Units "uVoltage" "V" 1.000000)
					( Origin gFrontEnd )
				)
				( attribute "XY" "(-3925,2400)"
					( Origin gFrontEnd )
				)
				( attribute "CHIPS_PART_NAME" "CAP_A"
					( Origin gPackager )
				)
				( attribute "CDS_PART_NAME" "CAP_A_0402V-1.0UF,6.3V,10%,X6SA"
					( Origin gPackager )
				)
				( attribute "SEC_TYPE" "0402V"
					( Origin gFrontEnd )
				)
				( attribute "CDS_SEC" "1"
					( Origin gPackager )
				)
				( attribute "GROUP" "NI_BIOS_ROM2"
					( Origin gFrontEnd )
				)
				( objectStatus "C3T4" )
			)
			( gate "@baseboard_fab2_lib.baseboard_fab2(sch_1):page153_i140"
				( attribute "BOM_COST" "MIO_BIOS_MEM"
					( Origin gFrontEnd )
				)
				( attribute "CDS_LIB" "mstr_discrete"
					( Origin gPackager )
				)
				( attribute "CDS_LOCATION" "R7F32"
					( Origin gPackager )
				)
				( attribute "CDS_SEC" "1"
					( Origin gPackager )
				)
				( attribute "LOCATION" "R7F32"
					( Origin gFrontEnd )
				)
				( attribute "MATERIAL" "CHIP"
					( Origin gFrontEnd )
				)
				( attribute "NO_XNET_CONNECTION" "1"
					( Origin gFrontEnd )
				)
				( attribute "PACK_TYPE" "0402"
					( Origin gFrontEnd )
				)
				( attribute "PART_NUMBER" "G21796-016"
					( Origin gFrontEnd )
				)
				( attribute "PHYS_PAGE" "153"
					( Origin gFrontEnd )
				)
				( attribute "ROOM" "SB_SPI"
					( Origin gFrontEnd )
				)
				( attribute "ROT" "0"
					( Origin gFrontEnd )
				)
				( attribute "SEC" "1"
					( Origin gFrontEnd )
				)
				( attribute "SEC_TYPE" "0402"
					( Origin gFrontEnd )
				)
				( attribute "TOLERANCE" "1%"
					( Origin gFrontEnd )
				)
				( attribute "VALUE" "10.0K"
					( Origin gFrontEnd )
				)
				( attribute "VER" "1"
					( Origin gFrontEnd )
				)
				( attribute "WATTAGE" "1/16W"
					( Origin gFrontEnd )
				)
				( attribute "XY" "(-1450,4425)"
					( Origin gFrontEnd )
				)
				( attribute "CHIPS_PART_NAME" "RES"
					( Origin gPackager )
				)
				( attribute "CDS_PART_NAME" "RES_0402-10.0K,1%,1/16W,CHIP,GA"
					( Origin gPackager )
				)
				( objectStatus "R7F32" )
			)
			( gate "@baseboard_fab2_lib.baseboard_fab2(sch_1):page153_i146"
				( attribute "BOM_COST" "MIO_BIOS_MEM"
					( Origin gFrontEnd )
				)
				( attribute "CDS_LIB" "mstr_memory"
					( Origin gPackager )
				)
				( attribute "CDS_LOCATION" "U7F1"
					( Origin gPackager )
				)
				( attribute "CDS_SEC" "1"
					( Origin gPackager )
				)
				( attribute "LOCATION" "U7F1"
					( Origin gFrontEnd )
				)
				( attribute "MATERIAL" "IC"
					( Origin gFrontEnd )
				)
				( attribute "PACK_TYPE" "XSOI"
					( Origin gFrontEnd )
				)
				( attribute "PART_NUMBER" "H25002-001"
					( Origin gFrontEnd )
				)
				( attribute "PHYS_PAGE" "153"
					( Origin gFrontEnd )
				)
				( attribute "ROOM" "SB_SPI"
					( Origin gFrontEnd )
				)
				( attribute "ROT" "0"
					( Origin gFrontEnd )
				)
				( attribute "SEC" "1"
					( Origin gFrontEnd )
				)
				( attribute "SEC_TYPE" "XSOI"
					( Origin gFrontEnd )
				)
				( attribute "VER" "1"
					( Origin gFrontEnd )
				)
				( attribute "XY" "(-4700,3975)"
					( Origin gFrontEnd )
				)
				( attribute "CHIPS_PART_NAME" "W25Q256"
					( Origin gPackager )
				)
				( attribute "CDS_PART_NAME" "W25Q256_XSOI-IC,H25002-001"
					( Origin gPackager )
				)
				( objectStatus "U7F1" )
			)
			( gate "@baseboard_fab2_lib.baseboard_fab2(sch_1):page153_i150"
				( attribute "BOM_COST" "MIO_BIOS_MEM"
					( Origin gFrontEnd )
				)
				( attribute "CDS_LIB" "mstr_discrete"
					( Origin gPackager )
				)
				( attribute "CDS_LOCATION" "R3T3"
					( Origin gPackager )
				)
				( attribute "CDS_SEC" "1"
					( Origin gPackager )
				)
				( attribute "LOCATION" "R3T3"
					( Origin gFrontEnd )
				)
				( attribute "MATERIAL" "EMPTY"
					( Origin gFrontEnd )
				)
				( attribute "NO_XNET_CONNECTION" "1"
					( Origin gFrontEnd )
				)
				( attribute "PACK_TYPE" "0402"
					( Origin gFrontEnd )
				)
				( attribute "PART_NUMBER" "G21796-072"
					( Origin gFrontEnd )
				)
				( attribute "PHYS_PAGE" "153"
					( Origin gFrontEnd )
				)
				( attribute "ROOM" "SB_SPI"
					( Origin gFrontEnd )
				)
				( attribute "ROT" "2"
					( Origin gFrontEnd )
				)
				( attribute "SEC" "1"
					( Origin gFrontEnd )
				)
				( attribute "SEC_TYPE" "0402"
					( Origin gFrontEnd )
				)
				( attribute "TOLERANCE" "1%"
					( Origin gFrontEnd )
				)
				( attribute "VALUE" "4.75K"
					( Origin gFrontEnd )
				)
				( attribute "VER" "2"
					( Origin gFrontEnd )
				)
				( attribute "WATTAGE" "1/16W"
					( Origin gFrontEnd )
				)
				( attribute "XY" "(-5875,2325)"
					( Origin gFrontEnd )
				)
				( attribute "CHIPS_PART_NAME" "RES"
					( Origin gPackager )
				)
				( attribute "CDS_PART_NAME" "RES_0402-4.75K,1%,1/16W,EMPTY,A"
					( Origin gPackager )
				)
				( attribute "GROUP" "NI_BIOS_ROM2"
					( Origin gFrontEnd )
				)
				( objectStatus "R3T3" )
			)
			( gate "@baseboard_fab2_lib.baseboard_fab2(sch_1):page153_i152"
				( attribute "BOM_COST" "MIO_BIOS_MEM"
					( Origin gFrontEnd )
				)
				( attribute "CDS_LIB" "mstr_discrete"
					( Origin gPackager )
				)
				( attribute "CDS_LOCATION" "R3T5"
					( Origin gPackager )
				)
				( attribute "CDS_SEC" "1"
					( Origin gPackager )
				)
				( attribute "LOCATION" "R3T5"
					( Origin gFrontEnd )
				)
				( attribute "MATERIAL" "CHIP"
					( Origin gFrontEnd )
				)
				( attribute "NO_XNET_CONNECTION" "1"
					( Origin gFrontEnd )
				)
				( attribute "PACK_TYPE" "0402"
					( Origin gFrontEnd )
				)
				( attribute "PART_NUMBER" "G21796-072"
					( Origin gFrontEnd )
				)
				( attribute "PHYS_PAGE" "153"
					( Origin gFrontEnd )
				)
				( attribute "ROOM" "SB_SPI"
					( Origin gFrontEnd )
				)
				( attribute "ROT" "2"
					( Origin gFrontEnd )
				)
				( attribute "SEC" "1"
					( Origin gFrontEnd )
				)
				( attribute "SEC_TYPE" "0402"
					( Origin gFrontEnd )
				)
				( attribute "TOLERANCE" "1%"
					( Origin gFrontEnd )
				)
				( attribute "VALUE" "4.75K"
					( Origin gFrontEnd )
				)
				( attribute "VER" "2"
					( Origin gFrontEnd )
				)
				( attribute "WATTAGE" "1/16W"
					( Origin gFrontEnd )
				)
				( attribute "XY" "(-6175,2325)"
					( Origin gFrontEnd )
				)
				( attribute "CHIPS_PART_NAME" "RES"
					( Origin gPackager )
				)
				( attribute "CDS_PART_NAME" "RES_0402-4.75K,1%,1/16W,CHIP,GA"
					( Origin gPackager )
				)
				( attribute "GROUP" "NI_BIOS_ROM2"
					( Origin gFrontEnd )
				)
				( objectStatus "R3T5" )
			)
			( gate "@baseboard_fab2_lib.baseboard_fab2(sch_1):page153_i155"
				( attribute "BOM_COST" "MIO_BIOS_MEM"
					( Origin gFrontEnd )
				)
				( attribute "CDS_LIB" "mstr_discrete"
					( Origin gPackager )
				)
				( attribute "CDS_LOCATION" "R3T2"
					( Origin gPackager )
				)
				( attribute "CDS_SEC" "1"
					( Origin gPackager )
				)
				( attribute "LOCATION" "R3T2"
					( Origin gFrontEnd )
				)
				( attribute "MATERIAL" "CHIP"
					( Origin gFrontEnd )
				)
				( attribute "PACK_TYPE" "0402"
					( Origin gFrontEnd )
				)
				( attribute "PART_NUMBER" "G21796-074"
					( Origin gFrontEnd )
				)
				( attribute "PHYS_PAGE" "153"
					( Origin gFrontEnd )
				)
				( attribute "ROOM" "SB_SPI"
					( Origin gFrontEnd )
				)
				( attribute "ROT" "0"
					( Origin gFrontEnd )
				)
				( attribute "SEC" "1"
					( Origin gFrontEnd )
				)
				( attribute "SEC_TYPE" "0402"
					( Origin gFrontEnd )
				)
				( attribute "TOLERANCE" "1%"
					( Origin gFrontEnd )
				)
				( attribute "VALUE" "33.2"
					( Origin gFrontEnd )
				)
				( attribute "VER" "1"
					( Origin gFrontEnd )
				)
				( attribute "WATTAGE" "1/16W"
					( Origin gFrontEnd )
				)
				( attribute "XY" "(-6275,1675)"
					( Origin gFrontEnd )
				)
				( attribute "CHIPS_PART_NAME" "RES"
					( Origin gPackager )
				)
				( attribute "CDS_PART_NAME" "RES_0402-33.2,1%,1/16W,CHIP,G2A"
					( Origin gPackager )
				)
				( attribute "GROUP" "NI_BIOS_ROM2"
					( Origin gFrontEnd )
				)
				( objectStatus "R3T2" )
			)
			( gate "@baseboard_fab2_lib.baseboard_fab2(sch_1):page153_i156"
				( attribute "BOM_COST" "MIO_BIOS_MEM"
					( Origin gFrontEnd )
				)
				( attribute "CDS_LIB" "mstr_discrete"
					( Origin gPackager )
				)
				( attribute "CDS_LOCATION" "R3U1"
					( Origin gPackager )
				)
				( attribute "LOCATION" "R3U1"
					( Origin gFrontEnd )
				)
				( attribute "MATERIAL" "CHIP"
					( Origin gFrontEnd )
				)
				( attribute "NO_XNET_CONNECTION" "1"
					( Origin gFrontEnd )
				)
				( attribute "PACK_TYPE" "0402"
					( Origin gFrontEnd )
				)
				( attribute "PART_NUMBER" "G21796-074"
					( Origin gFrontEnd )
				)
				( attribute "PHYS_PAGE" "153"
					( Origin gFrontEnd )
				)
				( attribute "ROOM" "SB_SPI"
					( Origin gFrontEnd )
				)
				( attribute "ROT" "0"
					( Origin gFrontEnd )
				)
				( attribute "SEC" "1"
					( Origin gFrontEnd )
				)
				( attribute "TOLERANCE" "1%"
					( Origin gFrontEnd )
				)
				( attribute "VALUE" "33.2"
					( Origin gFrontEnd )
				)
				( attribute "VER" "1"
					( Origin gFrontEnd )
				)
				( attribute "WATTAGE" "1/16W"
					( Origin gFrontEnd )
				)
				( attribute "XY" "(-6425,1425)"
					( Origin gFrontEnd )
				)
				( attribute "CHIPS_PART_NAME" "RES"
					( Origin gPackager )
				)
				( attribute "CDS_PART_NAME" "RES_0402-33.2,1%,1/16W,CHIP,G2A"
					( Origin gPackager )
				)
				( attribute "SEC_TYPE" "0402"
					( Origin gFrontEnd )
				)
				( attribute "CDS_SEC" "1"
					( Origin gPackager )
				)
				( attribute "GROUP" "NI_BIOS_ROM2"
					( Origin gFrontEnd )
				)
				( objectStatus "R3U1" )
			)
			( gate "@baseboard_fab2_lib.baseboard_fab2(sch_1):page153_i157"
				( attribute "BOM_COST" "MIO_BIOS_MEM"
					( Origin gFrontEnd )
				)
				( attribute "CDS_LIB" "mstr_discrete"
					( Origin gPackager )
				)
				( attribute "CDS_LOCATION" "R3T1"
					( Origin gPackager )
				)
				( attribute "LOCATION" "R3T1"
					( Origin gFrontEnd )
				)
				( attribute "MATERIAL" "CHIP"
					( Origin gFrontEnd )
				)
				( attribute "NO_XNET_CONNECTION" "1"
					( Origin gFrontEnd )
				)
				( attribute "PACK_TYPE" "0402"
					( Origin gFrontEnd )
				)
				( attribute "PART_NUMBER" "G21796-074"
					( Origin gFrontEnd )
				)
				( attribute "PHYS_PAGE" "153"
					( Origin gFrontEnd )
				)
				( attribute "ROOM" "SB_SPI"
					( Origin gFrontEnd )
				)
				( attribute "ROT" "0"
					( Origin gFrontEnd )
				)
				( attribute "SEC" "1"
					( Origin gFrontEnd )
				)
				( attribute "TOLERANCE" "1%"
					( Origin gFrontEnd )
				)
				( attribute "VALUE" "33.2"
					( Origin gFrontEnd )
				)
				( attribute "VER" "1"
					( Origin gFrontEnd )
				)
				( attribute "WATTAGE" "1/16W"
					( Origin gFrontEnd )
				)
				( attribute "XY" "(-6425,1200)"
					( Origin gFrontEnd )
				)
				( attribute "CHIPS_PART_NAME" "RES"
					( Origin gPackager )
				)
				( attribute "CDS_PART_NAME" "RES_0402-33.2,1%,1/16W,CHIP,G2A"
					( Origin gPackager )
				)
				( attribute "SEC_TYPE" "0402"
					( Origin gFrontEnd )
				)
				( attribute "CDS_SEC" "1"
					( Origin gPackager )
				)
				( attribute "GROUP" "NI_BIOS_ROM2"
					( Origin gFrontEnd )
				)
				( objectStatus "R3T1" )
			)
			( gate "@baseboard_fab2_lib.baseboard_fab2(sch_1):page153_i166"
				( attribute "CDS_LIB" "mstr_discrete"
					( Origin gPackager )
				)
				( attribute "CDS_LOCATION" "R8F8"
					( Origin gPackager )
				)
				( attribute "CDS_SEC" "1"
					( Origin gPackager )
				)
				( attribute "LOCATION" "R8F8"
					( Origin gFrontEnd )
				)
				( attribute "MATERIAL" "CHIP"
					( Origin gFrontEnd )
				)
				( attribute "PACK_TYPE" "0402"
					( Origin gFrontEnd )
				)
				( attribute "PART_NUMBER" "G21796-074"
					( Origin gFrontEnd )
				)
				( attribute "PHYS_PAGE" "153"
					( Origin gFrontEnd )
				)
				( attribute "ROOM" "MIO_BIOS_MEM"
					( Origin gFrontEnd )
				)
				( attribute "ROT" "0"
					( Origin gFrontEnd )
				)
				( attribute "SEC" "1"
					( Origin gPackager )
				)
				( attribute "TOLERANCE" "1%"
					( Origin gFrontEnd )
				)
				( attribute "VALUE" "33.2"
					( Origin gFrontEnd )
				)
				( attribute "VER" "1"
					( Origin gFrontEnd )
				)
				( attribute "WATTAGE" "1/16W"
					( Origin gFrontEnd )
				)
				( attribute "XY" "(-6550,3825)"
					( Origin gFrontEnd )
				)
				( attribute "CHIPS_PART_NAME" "RES"
					( Origin gPackager )
				)
				( attribute "CDS_PART_NAME" "RES_0402-33.2,1%,1/16W,CHIP,G2A"
					( Origin gPackager )
				)
				( objectStatus "R8F8" )
			)
			( gate "@baseboard_fab2_lib.baseboard_fab2(sch_1):page153_i167"
				( attribute "CDS_LIB" "mstr_discrete"
					( Origin gPackager )
				)
				( attribute "CDS_LOCATION" "R8F7"
					( Origin gPackager )
				)
				( attribute "LOCATION" "R8F7"
					( Origin gFrontEnd )
				)
				( attribute "MATERIAL" "CHIP"
					( Origin gFrontEnd )
				)
				( attribute "PACK_TYPE" "0402"
					( Origin gFrontEnd )
				)
				( attribute "PART_NUMBER" "G21796-074"
					( Origin gFrontEnd )
				)
				( attribute "PHYS_PAGE" "153"
					( Origin gFrontEnd )
				)
				( attribute "ROOM" "MIO_BIOS_MEM"
					( Origin gFrontEnd )
				)
				( attribute "ROT" "0"
					( Origin gFrontEnd )
				)
				( attribute "SEC" "1"
					( Origin gFrontEnd )
				)
				( attribute "TOLERANCE" "1%"
					( Origin gFrontEnd )
				)
				( attribute "VALUE" "33.2"
					( Origin gFrontEnd )
				)
				( attribute "VER" "1"
					( Origin gFrontEnd )
				)
				( attribute "WATTAGE" "1/16W"
					( Origin gFrontEnd )
				)
				( attribute "XY" "(-6275,1825)"
					( Origin gFrontEnd )
				)
				( attribute "CHIPS_PART_NAME" "RES"
					( Origin gPackager )
				)
				( attribute "CDS_PART_NAME" "RES_0402-33.2,1%,1/16W,CHIP,G2A"
					( Origin gPackager )
				)
				( attribute "SEC_TYPE" "0402"
					( Origin gFrontEnd )
				)
				( attribute "CDS_SEC" "1"
					( Origin gPackager )
				)
				( attribute "GROUP" "NI_BIOS_ROM2"
					( Origin gFrontEnd )
				)
				( objectStatus "R8F7" )
			)
			( gate "@baseboard_fab2_lib.baseboard_fab2(sch_1):page153_i168"
				( attribute "BOM_COST" "MIO_BIOS_MEM"
					( Origin gFrontEnd )
				)
				( attribute "CDS_LIB" "mstr_discrete"
					( Origin gPackager )
				)
				( attribute "CDS_LOCATION" "R7F28"
					( Origin gPackager )
				)
				( attribute "CDS_SEC" "1"
					( Origin gPackager )
				)
				( attribute "LOCATION" "R7F28"
					( Origin gFrontEnd )
				)
				( attribute "MATERIAL" "CHIP"
					( Origin gFrontEnd )
				)
				( attribute "NO_XNET_CONNECTION" "1"
					( Origin gFrontEnd )
				)
				( attribute "PACK_TYPE" "0402"
					( Origin gFrontEnd )
				)
				( attribute "PART_NUMBER" "G21796-016"
					( Origin gFrontEnd )
				)
				( attribute "PHYS_PAGE" "153"
					( Origin gFrontEnd )
				)
				( attribute "ROOM" "SB_SPI"
					( Origin gFrontEnd )
				)
				( attribute "ROT" "0"
					( Origin gFrontEnd )
				)
				( attribute "SEC" "1"
					( Origin gFrontEnd )
				)
				( attribute "SEC_TYPE" "0402"
					( Origin gFrontEnd )
				)
				( attribute "TOLERANCE" "1%"
					( Origin gFrontEnd )
				)
				( attribute "VALUE" "10.0K"
					( Origin gFrontEnd )
				)
				( attribute "VER" "2"
					( Origin gFrontEnd )
				)
				( attribute "WATTAGE" "1/16W"
					( Origin gFrontEnd )
				)
				( attribute "XY" "(-1750,3925)"
					( Origin gFrontEnd )
				)
				( attribute "CHIPS_PART_NAME" "RES"
					( Origin gPackager )
				)
				( attribute "CDS_PART_NAME" "RES_0402-10.0K,1%,1/16W,CHIP,GA"
					( Origin gPackager )
				)
				( objectStatus "R7F28" )
			)
			( gate "@baseboard_fab2_lib.baseboard_fab2(sch_1):page153_i170"
				( attribute "BOM_COST" "MIO_BIOS_MEM"
					( Origin gFrontEnd )
				)
				( attribute "CDS_LIB" "mstr_discrete"
					( Origin gPackager )
				)
				( attribute "CDS_LOCATION" "R7F30"
					( Origin gPackager )
				)
				( attribute "CDS_SEC" "1"
					( Origin gPackager )
				)
				( attribute "LOCATION" "R7F30"
					( Origin gFrontEnd )
				)
				( attribute "MATERIAL" "EMPTY"
					( Origin gFrontEnd )
				)
				( attribute "PACK_TYPE" "0402"
					( Origin gFrontEnd )
				)
				( attribute "PART_NUMBER" "G21796-016"
					( Origin gFrontEnd )
				)
				( attribute "PHYS_PAGE" "153"
					( Origin gFrontEnd )
				)
				( attribute "ROOM" "SB_SPI"
					( Origin gFrontEnd )
				)
				( attribute "ROT" "0"
					( Origin gFrontEnd )
				)
				( attribute "SEC" "1"
					( Origin gFrontEnd )
				)
				( attribute "SEC_TYPE" "0402"
					( Origin gFrontEnd )
				)
				( attribute "TOLERANCE" "1%"
					( Origin gFrontEnd )
				)
				( attribute "VALUE" "10.0K"
					( Origin gFrontEnd )
				)
				( attribute "VER" "2"
					( Origin gFrontEnd )
				)
				( attribute "WATTAGE" "1/16W"
					( Origin gFrontEnd )
				)
				( attribute "XY" "(-1750,3550)"
					( Origin gFrontEnd )
				)
				( attribute "CHIPS_PART_NAME" "RES"
					( Origin gPackager )
				)
				( attribute "CDS_PART_NAME" "RES_0402-10.0K,1%,1/16W,EMPTY,A"
					( Origin gPackager )
				)
				( objectStatus "R7F30" )
			)
			( gate "@baseboard_fab2_lib.baseboard_fab2(sch_1):page153_i174"
				( attribute "BOM_COST" "MIO_BIOS_MEM"
					( Origin gFrontEnd )
				)
				( attribute "CDS_LIB" "mstr_discrete"
					( Origin gPackager )
				)
				( attribute "CDS_LOCATION" "R3T4"
					( Origin gPackager )
				)
				( attribute "CDS_SEC" "1"
					( Origin gPackager )
				)
				( attribute "LOCATION" "R3T4"
					( Origin gFrontEnd )
				)
				( attribute "MATERIAL" "CHIP"
					( Origin gFrontEnd )
				)
				( attribute "PACK_TYPE" "0402"
					( Origin gFrontEnd )
				)
				( attribute "PART_NUMBER" "G21796-016"
					( Origin gFrontEnd )
				)
				( attribute "PHYS_PAGE" "153"
					( Origin gFrontEnd )
				)
				( attribute "ROOM" "SB_SPI"
					( Origin gFrontEnd )
				)
				( attribute "ROT" "0"
					( Origin gFrontEnd )
				)
				( attribute "SEC" "1"
					( Origin gFrontEnd )
				)
				( attribute "SEC_TYPE" "0402"
					( Origin gFrontEnd )
				)
				( attribute "TOLERANCE" "1%"
					( Origin gFrontEnd )
				)
				( attribute "VALUE" "10.0K"
					( Origin gFrontEnd )
				)
				( attribute "VER" "1"
					( Origin gFrontEnd )
				)
				( attribute "WATTAGE" "1/16W"
					( Origin gFrontEnd )
				)
				( attribute "XY" "(-1450,2325)"
					( Origin gFrontEnd )
				)
				( attribute "CHIPS_PART_NAME" "RES"
					( Origin gPackager )
				)
				( attribute "CDS_PART_NAME" "RES_0402-10.0K,1%,1/16W,CHIP,GA"
					( Origin gPackager )
				)
				( attribute "GROUP" "NI_BIOS_ROM2"
					( Origin gFrontEnd )
				)
				( objectStatus "R3T4" )
			)
			( gate "@baseboard_fab2_lib.baseboard_fab2(sch_1):page153_i178"
				( attribute "BOM_COST" "MIO_BIOS_MEM"
					( Origin gFrontEnd )
				)
				( attribute "CDS_LIB" "mstr_discrete"
					( Origin gPackager )
				)
				( attribute "CDS_LOCATION" "R3T12"
					( Origin gPackager )
				)
				( attribute "CDS_SEC" "1"
					( Origin gPackager )
				)
				( attribute "LOCATION" "R3T12"
					( Origin gFrontEnd )
				)
				( attribute "MATERIAL" "CHIP"
					( Origin gFrontEnd )
				)
				( attribute "PACK_TYPE" "0402"
					( Origin gFrontEnd )
				)
				( attribute "PART_NUMBER" "G21796-016"
					( Origin gFrontEnd )
				)
				( attribute "PHYS_PAGE" "153"
					( Origin gFrontEnd )
				)
				( attribute "ROOM" "SB_SPI"
					( Origin gFrontEnd )
				)
				( attribute "ROT" "0"
					( Origin gFrontEnd )
				)
				( attribute "SEC" "1"
					( Origin gFrontEnd )
				)
				( attribute "SEC_TYPE" "0402"
					( Origin gFrontEnd )
				)
				( attribute "TOLERANCE" "1%"
					( Origin gFrontEnd )
				)
				( attribute "VALUE" "10.0K"
					( Origin gFrontEnd )
				)
				( attribute "VER" "2"
					( Origin gFrontEnd )
				)
				( attribute "WATTAGE" "1/16W"
					( Origin gFrontEnd )
				)
				( attribute "XY" "(-1750,1825)"
					( Origin gFrontEnd )
				)
				( attribute "CHIPS_PART_NAME" "RES"
					( Origin gPackager )
				)
				( attribute "CDS_PART_NAME" "RES_0402-10.0K,1%,1/16W,CHIP,GA"
					( Origin gPackager )
				)
				( attribute "GROUP" "NI_BIOS_ROM2"
					( Origin gFrontEnd )
				)
				( objectStatus "R3T12" )
			)
			( gate "@baseboard_fab2_lib.baseboard_fab2(sch_1):page153_i179"
				( attribute "BOM_COST" "MIO_BIOS_MEM"
					( Origin gFrontEnd )
				)
				( attribute "CDS_LIB" "mstr_discrete"
					( Origin gPackager )
				)
				( attribute "CDS_LOCATION" "R3T9"
					( Origin gPackager )
				)
				( attribute "CDS_SEC" "1"
					( Origin gPackager )
				)
				( attribute "LOCATION" "R3T9"
					( Origin gFrontEnd )
				)
				( attribute "MATERIAL" "EMPTY"
					( Origin gFrontEnd )
				)
				( attribute "PACK_TYPE" "0402"
					( Origin gFrontEnd )
				)
				( attribute "PART_NUMBER" "G21796-016"
					( Origin gFrontEnd )
				)
				( attribute "PHYS_PAGE" "153"
					( Origin gFrontEnd )
				)
				( attribute "ROOM" "SB_SPI"
					( Origin gFrontEnd )
				)
				( attribute "ROT" "0"
					( Origin gFrontEnd )
				)
				( attribute "SEC" "1"
					( Origin gFrontEnd )
				)
				( attribute "SEC_TYPE" "0402"
					( Origin gFrontEnd )
				)
				( attribute "TOLERANCE" "1%"
					( Origin gFrontEnd )
				)
				( attribute "VALUE" "10.0K"
					( Origin gFrontEnd )
				)
				( attribute "VER" "2"
					( Origin gFrontEnd )
				)
				( attribute "WATTAGE" "1/16W"
					( Origin gFrontEnd )
				)
				( attribute "XY" "(-1750,1450)"
					( Origin gFrontEnd )
				)
				( attribute "CHIPS_PART_NAME" "RES"
					( Origin gPackager )
				)
				( attribute "CDS_PART_NAME" "RES_0402-10.0K,1%,1/16W,EMPTY,A"
					( Origin gPackager )
				)
				( attribute "GROUP" "NI_BIOS_ROM2"
					( Origin gFrontEnd )
				)
				( objectStatus "R3T9" )
			)
			( gate "@baseboard_fab2_lib.baseboard_fab2(sch_1):page153_i181"
				( attribute "BOM_COST" "MIO_BIOS_MEM"
					( Origin gFrontEnd )
				)
				( attribute "CDS_LIB" "mstr_discrete"
					( Origin gPackager )
				)
				( attribute "CDS_LOCATION" "R7F29"
					( Origin gPackager )
				)
				( attribute "CDS_SEC" "1"
					( Origin gPackager )
				)
				( attribute "LOCATION" "R7F29"
					( Origin gFrontEnd )
				)
				( attribute "MATERIAL" "CHIP"
					( Origin gFrontEnd )
				)
				( attribute "PACK_TYPE" "0402"
					( Origin gFrontEnd )
				)
				( attribute "PART_NUMBER" "G21796-074"
					( Origin gFrontEnd )
				)
				( attribute "PHYS_PAGE" "153"
					( Origin gFrontEnd )
				)
				( attribute "ROOM" "SB_SPI"
					( Origin gFrontEnd )
				)
				( attribute "ROT" "0"
					( Origin gFrontEnd )
				)
				( attribute "SEC" "1"
					( Origin gFrontEnd )
				)
				( attribute "SEC_TYPE" "0402"
					( Origin gFrontEnd )
				)
				( attribute "TOLERANCE" "1%"
					( Origin gFrontEnd )
				)
				( attribute "VALUE" "33.2"
					( Origin gFrontEnd )
				)
				( attribute "VER" "1"
					( Origin gFrontEnd )
				)
				( attribute "WATTAGE" "1/16W"
					( Origin gFrontEnd )
				)
				( attribute "XY" "(-6525,3925)"
					( Origin gFrontEnd )
				)
				( attribute "CHIPS_PART_NAME" "RES"
					( Origin gPackager )
				)
				( attribute "CDS_PART_NAME" "RES_0402-33.2,1%,1/16W,CHIP,G2A"
					( Origin gPackager )
				)
				( objectStatus "R7F29" )
			)
			( gate "@baseboard_fab2_lib.baseboard_fab2(sch_1):page153_i184"
				( attribute "BOM_COST" "MIO_BIOS_MEM"
					( Origin gFrontEnd )
				)
				( attribute "CDS_LIB" "mstr_discrete"
					( Origin gPackager )
				)
				( attribute "CDS_LOCATION" "R3T10"
					( Origin gPackager )
				)
				( attribute "CDS_SEC" "1"
					( Origin gPackager )
				)
				( attribute "LOCATION" "R3T10"
					( Origin gFrontEnd )
				)
				( attribute "MATERIAL" "CHIP"
					( Origin gFrontEnd )
				)
				( attribute "PACK_TYPE" "0402"
					( Origin gFrontEnd )
				)
				( attribute "PART_NUMBER" "G21796-074"
					( Origin gFrontEnd )
				)
				( attribute "PHYS_PAGE" "153"
					( Origin gFrontEnd )
				)
				( attribute "ROOM" "SB_SPI"
					( Origin gFrontEnd )
				)
				( attribute "ROT" "0"
					( Origin gFrontEnd )
				)
				( attribute "SEC" "1"
					( Origin gFrontEnd )
				)
				( attribute "SEC_TYPE" "0402"
					( Origin gFrontEnd )
				)
				( attribute "TOLERANCE" "1%"
					( Origin gFrontEnd )
				)
				( attribute "VALUE" "33.2"
					( Origin gFrontEnd )
				)
				( attribute "VER" "1"
					( Origin gFrontEnd )
				)
				( attribute "WATTAGE" "1/16W"
					( Origin gFrontEnd )
				)
				( attribute "XY" "(-6275,1725)"
					( Origin gFrontEnd )
				)
				( attribute "CHIPS_PART_NAME" "RES"
					( Origin gPackager )
				)
				( attribute "CDS_PART_NAME" "RES_0402-33.2,1%,1/16W,CHIP,G2A"
					( Origin gPackager )
				)
				( attribute "GROUP" "NI_BIOS_ROM2"
					( Origin gFrontEnd )
				)
				( objectStatus "R3T10" )
			)
			( gate "@baseboard_fab2_lib.baseboard_fab2(sch_1):page154_i14"
				( attribute "BOM_COST" "MIO_BIOS_MEM"
					( Origin gFrontEnd )
				)
				( attribute "CDS_LIB" "dev_discrete"
					( Origin gPackager )
				)
				( attribute "CDS_LOCATION" "C8E18"
					( Origin gPackager )
				)
				( attribute "CDS_SEC" "1"
					( Origin gPackager )
				)
				( attribute "LOCATION" "C8E18"
					( Origin gFrontEnd )
				)
				( attribute "MATERIAL" "X7R"
					( Origin gFrontEnd )
				)
				( attribute "PACK_TYPE" "0402V"
					( Origin gFrontEnd )
				)
				( attribute "PART_NUMBER" "A36096-030"
					( Origin gFrontEnd )
				)
				( attribute "PHYS_PAGE" "154"
					( Origin gFrontEnd )
				)
				( attribute "ROOM" "SB_BMC_SPI_MUX"
					( Origin gFrontEnd )
				)
				( attribute "ROT" "0"
					( Origin gFrontEnd )
				)
				( attribute "SEC" "1"
					( Origin gFrontEnd )
				)
				( attribute "SEC_TYPE" "0402V"
					( Origin gFrontEnd )
				)
				( attribute "TOLERANCE" "10%"
					( Origin gFrontEnd )
				)
				( attribute "VALUE" "0.1UF"
					( Origin gFrontEnd )
				)
				( attribute "VER" "1"
					( Origin gFrontEnd )
				)
				( attribute "VOLTAGE" "16V"
					( Units "uVoltage" "V" 1.000000)
					( Origin gFrontEnd )
				)
				( attribute "XY" "(-5400,4350)"
					( Origin gFrontEnd )
				)
				( attribute "CHIPS_PART_NAME" "CAP_A"
					( Origin gPackager )
				)
				( attribute "CDS_PART_NAME" "CAP_A_0402V-0.1UF,16V,10%,X7R,A"
					( Origin gPackager )
				)
				( objectStatus "C8E18" )
			)
			( gate "@baseboard_fab2_lib.baseboard_fab2(sch_1):page154_i62"
				( attribute "BOM_COST" "MIO_BIOS_MEM"
					( Origin gFrontEnd )
				)
				( attribute "CDS_LIB" "mstr_discrete"
					( Origin gPackager )
				)
				( attribute "CDS_LOCATION" "R2T9"
					( Origin gPackager )
				)
				( attribute "CDS_SEC" "1"
					( Origin gPackager )
				)
				( attribute "LOCATION" "R2T9"
					( Origin gFrontEnd )
				)
				( attribute "MATERIAL" "CHIP"
					( Origin gFrontEnd )
				)
				( attribute "PACK_TYPE" "0402"
					( Origin gFrontEnd )
				)
				( attribute "PART_NUMBER" "G21796-267"
					( Origin gFrontEnd )
				)
				( attribute "PHYS_PAGE" "154"
					( Origin gFrontEnd )
				)
				( attribute "ROOM" "SB_BMC_SPI_MUX"
					( Origin gFrontEnd )
				)
				( attribute "ROT" "0"
					( Origin gFrontEnd )
				)
				( attribute "SEC" "1"
					( Origin gFrontEnd )
				)
				( attribute "SEC_TYPE" "0402"
					( Origin gFrontEnd )
				)
				( attribute "TOLERANCE" "1.0%"
					( Origin gFrontEnd )
				)
				( attribute "VALUE" "75"
					( Origin gFrontEnd )
				)
				( attribute "VER" "1"
					( Origin gFrontEnd )
				)
				( attribute "WATTAGE" "1/16W"
					( Origin gFrontEnd )
				)
				( attribute "XY" "(-1450,1150)"
					( Origin gFrontEnd )
				)
				( attribute "CHIPS_PART_NAME" "RES"
					( Origin gPackager )
				)
				( attribute "CDS_PART_NAME" "RES_0402-75,1.0%,1/16W,CHIP,G2A"
					( Origin gPackager )
				)
				( attribute "GROUP" "NI_BIOS_ROM2"
					( Origin gFrontEnd )
				)
				( objectStatus "R2T9" )
			)
			( gate "@baseboard_fab2_lib.baseboard_fab2(sch_1):page154_i74"
				( attribute "BOM_COST" "MIO_BIOS_MEM"
					( Origin gFrontEnd )
				)
				( attribute "CDS_LIB" "mstr_digital"
					( Origin gPackager )
				)
				( attribute "CDS_LOCATION" "U8F1"
					( Origin gPackager )
				)
				( attribute "CDS_SEC" "1"
					( Origin gPackager )
				)
				( attribute "LOCATION" "U8F1"
					( Origin gFrontEnd )
				)
				( attribute "MATERIAL" "IC"
					( Origin gFrontEnd )
				)
				( attribute "PACK_TYPE" "TSSOPLF"
					( Origin gFrontEnd )
				)
				( attribute "PART_NUMBER" "E16801-001"
					( Origin gFrontEnd )
				)
				( attribute "PHYS_PAGE" "154"
					( Origin gFrontEnd )
				)
				( attribute "ROOM" "SB_BMC_SPI_MUX"
					( Origin gFrontEnd )
				)
				( attribute "ROT" "2"
					( Origin gFrontEnd )
				)
				( attribute "SEC" "1"
					( Origin gFrontEnd )
				)
				( attribute "SEC_TYPE" "TSSOPLF"
					( Origin gFrontEnd )
				)
				( attribute "VER" "1"
					( Origin gFrontEnd )
				)
				( attribute "XY" "(-5900,3700)"
					( Origin gFrontEnd )
				)
				( attribute "CHIPS_PART_NAME" "PI3B3257A"
					( Origin gPackager )
				)
				( attribute "CDS_PART_NAME" "PI3B3257A_TSSOPLF-IC,E16801-001"
					( Origin gPackager )
				)
				( objectStatus "U8F1" )
			)
			( gate "@baseboard_fab2_lib.baseboard_fab2(sch_1):page154_i75"
				( attribute "BOM_COST" "MIO_BIOS_MEM"
					( Origin gFrontEnd )
				)
				( attribute "CDS_LIB" "mstr_digital"
					( Origin gPackager )
				)
				( attribute "CDS_LOCATION" "U2T1"
					( Origin gPackager )
				)
				( attribute "CDS_SEC" "1"
					( Origin gPackager )
				)
				( attribute "LOCATION" "U2T1"
					( Origin gFrontEnd )
				)
				( attribute "MATERIAL" "IC"
					( Origin gFrontEnd )
				)
				( attribute "PACK_TYPE" "TSSOPLF"
					( Origin gFrontEnd )
				)
				( attribute "PART_NUMBER" "E16801-001"
					( Origin gFrontEnd )
				)
				( attribute "PHYS_PAGE" "154"
					( Origin gFrontEnd )
				)
				( attribute "ROOM" "SB_BMC_SPI_MUX"
					( Origin gFrontEnd )
				)
				( attribute "ROT" "2"
					( Origin gFrontEnd )
				)
				( attribute "SEC" "1"
					( Origin gFrontEnd )
				)
				( attribute "SEC_TYPE" "TSSOPLF"
					( Origin gFrontEnd )
				)
				( attribute "VER" "1"
					( Origin gFrontEnd )
				)
				( attribute "XY" "(-2000,3875)"
					( Origin gFrontEnd )
				)
				( attribute "CHIPS_PART_NAME" "PI3B3257A"
					( Origin gPackager )
				)
				( attribute "CDS_PART_NAME" "PI3B3257A_TSSOPLF-IC,E16801-001"
					( Origin gPackager )
				)
				( objectStatus "U2T1" )
			)
			( gate "@baseboard_fab2_lib.baseboard_fab2(sch_1):page154_i92"
				( attribute "BOM_COST" "MIO_BIOS_MEM"
					( Origin gFrontEnd )
				)
				( attribute "CDS_LIB" "mstr_discrete"
					( Origin gPackager )
				)
				( attribute "CDS_LOCATION" "R2T2"
					( Origin gPackager )
				)
				( attribute "CDS_SEC" "1"
					( Origin gPackager )
				)
				( attribute "LOCATION" "R2T2"
					( Origin gFrontEnd )
				)
				( attribute "MATERIAL" "CHIP"
					( Origin gFrontEnd )
				)
				( attribute "PACK_TYPE" "0402"
					( Origin gFrontEnd )
				)
				( attribute "PART_NUMBER" "G21497-005"
					( Origin gFrontEnd )
				)
				( attribute "PHYS_PAGE" "154"
					( Origin gFrontEnd )
				)
				( attribute "ROOM" "SB_BMC_SPI_MUX"
					( Origin gFrontEnd )
				)
				( attribute "ROT" "0"
					( Origin gFrontEnd )
				)
				( attribute "SEC" "1"
					( Origin gFrontEnd )
				)
				( attribute "SEC_TYPE" "0402"
					( Origin gFrontEnd )
				)
				( attribute "TOLERANCE" "5%"
					( Origin gFrontEnd )
				)
				( attribute "VALUE" "0.0"
					( Origin gFrontEnd )
				)
				( attribute "VER" "1"
					( Origin gFrontEnd )
				)
				( attribute "WATTAGE" "1/16W"
					( Origin gFrontEnd )
				)
				( attribute "XY" "(-3200,3975)"
					( Origin gFrontEnd )
				)
				( attribute "CHIPS_PART_NAME" "RES"
					( Origin gPackager )
				)
				( attribute "CDS_PART_NAME" "RES_0402-0.0,5%,1/16W,CHIP,G21A"
					( Origin gPackager )
				)
				( objectStatus "R2T2" )
			)
			( gate "@baseboard_fab2_lib.baseboard_fab2(sch_1):page154_i93"
				( attribute "BOM_COST" "MIO_BIOS_MEM"
					( Origin gFrontEnd )
				)
				( attribute "CDS_LIB" "mstr_discrete"
					( Origin gPackager )
				)
				( attribute "CDS_LOCATION" "R2R12"
					( Origin gPackager )
				)
				( attribute "CDS_SEC" "1"
					( Origin gPackager )
				)
				( attribute "LOCATION" "R2R12"
					( Origin gFrontEnd )
				)
				( attribute "MATERIAL" "CHIP"
					( Origin gFrontEnd )
				)
				( attribute "PACK_TYPE" "0402"
					( Origin gFrontEnd )
				)
				( attribute "PART_NUMBER" "G21497-005"
					( Origin gFrontEnd )
				)
				( attribute "PHYS_PAGE" "154"
					( Origin gFrontEnd )
				)
				( attribute "ROOM" "SB_BMC_SPI_MUX"
					( Origin gFrontEnd )
				)
				( attribute "ROT" "0"
					( Origin gFrontEnd )
				)
				( attribute "SEC" "1"
					( Origin gFrontEnd )
				)
				( attribute "SEC_TYPE" "0402"
					( Origin gFrontEnd )
				)
				( attribute "TOLERANCE" "5%"
					( Origin gFrontEnd )
				)
				( attribute "VALUE" "0.0"
					( Origin gFrontEnd )
				)
				( attribute "VER" "1"
					( Origin gFrontEnd )
				)
				( attribute "WATTAGE" "1/16W"
					( Origin gFrontEnd )
				)
				( attribute "XY" "(-3200,4075)"
					( Origin gFrontEnd )
				)
				( attribute "CHIPS_PART_NAME" "RES"
					( Origin gPackager )
				)
				( attribute "CDS_PART_NAME" "RES_0402-0.0,5%,1/16W,CHIP,G21A"
					( Origin gPackager )
				)
				( objectStatus "R2R12" )
			)
			( gate "@baseboard_fab2_lib.baseboard_fab2(sch_1):page154_i94"
				( attribute "BOM_COST" "MIO_BIOS_MEM"
					( Origin gFrontEnd )
				)
				( attribute "CDS_LIB" "dev_discrete"
					( Origin gPackager )
				)
				( attribute "CDS_LOCATION" "C2T1"
					( Origin gPackager )
				)
				( attribute "CDS_SEC" "1"
					( Origin gPackager )
				)
				( attribute "LOCATION" "C2T1"
					( Origin gFrontEnd )
				)
				( attribute "MATERIAL" "X7R"
					( Origin gFrontEnd )
				)
				( attribute "PACK_TYPE" "0402V"
					( Origin gFrontEnd )
				)
				( attribute "PART_NUMBER" "A36096-030"
					( Origin gFrontEnd )
				)
				( attribute "PHYS_PAGE" "154"
					( Origin gFrontEnd )
				)
				( attribute "ROOM" "SB_BMC_SPI_MUX"
					( Origin gFrontEnd )
				)
				( attribute "ROT" "0"
					( Origin gFrontEnd )
				)
				( attribute "SEC" "1"
					( Origin gFrontEnd )
				)
				( attribute "SEC_TYPE" "0402V"
					( Origin gFrontEnd )
				)
				( attribute "TOLERANCE" "10%"
					( Origin gFrontEnd )
				)
				( attribute "VALUE" "0.1UF"
					( Origin gFrontEnd )
				)
				( attribute "VER" "1"
					( Origin gFrontEnd )
				)
				( attribute "VOLTAGE" "16V"
					( Units "uVoltage" "V" 1.000000)
					( Origin gFrontEnd )
				)
				( attribute "XY" "(-1500,4525)"
					( Origin gFrontEnd )
				)
				( attribute "CHIPS_PART_NAME" "CAP_A"
					( Origin gPackager )
				)
				( attribute "CDS_PART_NAME" "CAP_A_0402V-0.1UF,16V,10%,X7R,A"
					( Origin gPackager )
				)
				( objectStatus "C2T1" )
			)
			( gate "@baseboard_fab2_lib.baseboard_fab2(sch_1):page154_i99"
				( attribute "BOM_COST" "MIO_BIOS_MEM"
					( Origin gFrontEnd )
				)
				( attribute "CDS_LIB" "mstr_ttl"
					( Origin gPackager )
				)
				( attribute "CDS_LOCATION" "U2T3"
					( Origin gPackager )
				)
				( attribute "CDS_SEC" "1"
					( Origin gPackager )
				)
				( attribute "LOCATION" "U2T3"
					( Origin gFrontEnd )
				)
				( attribute "MATERIAL" "IC"
					( Origin gFrontEnd )
				)
				( attribute "PACK_TYPE" "SOT"
					( Origin gFrontEnd )
				)
				( attribute "PART_NUMBER" "E60229-001"
					( Origin gFrontEnd )
				)
				( attribute "PHYS_PAGE" "154"
					( Origin gFrontEnd )
				)
				( attribute "ROOM" "SB_BMC_SPI_MUX"
					( Origin gFrontEnd )
				)
				( attribute "ROT" "0"
					( Origin gFrontEnd )
				)
				( attribute "SEC" "1"
					( Origin gFrontEnd )
				)
				( attribute "SEC_TYPE" "SOT"
					( Origin gFrontEnd )
				)
				( attribute "VALUE" "74LVC1G32"
					( Origin gFrontEnd )
				)
				( attribute "VER" "1"
					( Origin gFrontEnd )
				)
				( attribute "XY" "(-2275,1875)"
					( Origin gFrontEnd )
				)
				( attribute "CHIPS_PART_NAME" "TTL1G32_A"
					( Origin gPackager )
				)
				( attribute "CDS_PART_NAME" "TTL1G32_A_SOT-74LVC1G32,IC,E60B"
					( Origin gPackager )
				)
				( attribute "GROUP" "NI_BIOS_ROM2"
					( Origin gFrontEnd )
				)
				( objectStatus "U2T3" )
			)
			( gate "@baseboard_fab2_lib.baseboard_fab2(sch_1):page154_i100"
				( attribute "BOM_COST" "MIO_BIOS_MEM"
					( Origin gFrontEnd )
				)
				( attribute "CDS_LIB" "mstr_ttl"
					( Origin gPackager )
				)
				( attribute "CDS_LOCATION" "U2T2"
					( Origin gPackager )
				)
				( attribute "CDS_SEC" "1"
					( Origin gPackager )
				)
				( attribute "LOCATION" "U2T2"
					( Origin gFrontEnd )
				)
				( attribute "MATERIAL" "IC"
					( Origin gFrontEnd )
				)
				( attribute "PACK_TYPE" "SOT"
					( Origin gFrontEnd )
				)
				( attribute "PART_NUMBER" "E60229-001"
					( Origin gFrontEnd )
				)
				( attribute "PHYS_PAGE" "154"
					( Origin gFrontEnd )
				)
				( attribute "ROOM" "SB_BMC_SPI_MUX"
					( Origin gFrontEnd )
				)
				( attribute "ROT" "0"
					( Origin gFrontEnd )
				)
				( attribute "SEC" "1"
					( Origin gFrontEnd )
				)
				( attribute "SEC_TYPE" "SOT"
					( Origin gFrontEnd )
				)
				( attribute "VALUE" "74LVC1G32"
					( Origin gFrontEnd )
				)
				( attribute "VER" "1"
					( Origin gFrontEnd )
				)
				( attribute "XY" "(-2275,1150)"
					( Origin gFrontEnd )
				)
				( attribute "CHIPS_PART_NAME" "TTL1G32_A"
					( Origin gPackager )
				)
				( attribute "CDS_PART_NAME" "TTL1G32_A_SOT-74LVC1G32,IC,E60B"
					( Origin gPackager )
				)
				( attribute "GROUP" "NI_BIOS_ROM2"
					( Origin gFrontEnd )
				)
				( objectStatus "U2T2" )
			)
			( gate "@baseboard_fab2_lib.baseboard_fab2(sch_1):page154_i101"
				( attribute "BOM_COST" "MIO_BIOS_MEM"
					( Origin gFrontEnd )
				)
				( attribute "CDS_LIB" "mstr_discrete"
					( Origin gPackager )
				)
				( attribute "CDS_LOCATION" "R2T13"
					( Origin gPackager )
				)
				( attribute "CDS_SEC" "1"
					( Origin gPackager )
				)
				( attribute "LOCATION" "R2T13"
					( Origin gFrontEnd )
				)
				( attribute "MATERIAL" "CHIP"
					( Origin gFrontEnd )
				)
				( attribute "PACK_TYPE" "0402"
					( Origin gFrontEnd )
				)
				( attribute "PART_NUMBER" "G21796-004"
					( Origin gFrontEnd )
				)
				( attribute "PHYS_PAGE" "154"
					( Origin gFrontEnd )
				)
				( attribute "ROOM" "SB_BMC_SPI_MUX"
					( Origin gFrontEnd )
				)
				( attribute "ROT" "0"
					( Origin gFrontEnd )
				)
				( attribute "SEC" "1"
					( Origin gFrontEnd )
				)
				( attribute "SEC_TYPE" "0402"
					( Origin gFrontEnd )
				)
				( attribute "TOLERANCE" "1%"
					( Origin gFrontEnd )
				)
				( attribute "VALUE" "200.0"
					( Origin gFrontEnd )
				)
				( attribute "VER" "1"
					( Origin gFrontEnd )
				)
				( attribute "WATTAGE" "1/16W"
					( Origin gFrontEnd )
				)
				( attribute "XY" "(-1450,1875)"
					( Origin gFrontEnd )
				)
				( attribute "CHIPS_PART_NAME" "RES"
					( Origin gPackager )
				)
				( attribute "CDS_PART_NAME" "RES_0402-200.0,1%,1/16W,CHIP,GA"
					( Origin gPackager )
				)
				( attribute "GROUP" "NI_BIOS_ROM2"
					( Origin gFrontEnd )
				)
				( objectStatus "R2T13" )
			)
			( gate "@baseboard_fab2_lib.baseboard_fab2(sch_1):page154_i105"
				( attribute "BOM_COST" "MIO_BIOS_MEM"
					( Origin gFrontEnd )
				)
				( attribute "CDS_LIB" "mstr_discrete"
					( Origin gPackager )
				)
				( attribute "CDS_LOCATION" "R2T11"
					( Origin gPackager )
				)
				( attribute "CDS_SEC" "1"
					( Origin gPackager )
				)
				( attribute "LOCATION" "R2T11"
					( Origin gFrontEnd )
				)
				( attribute "MATERIAL" "CHIP"
					( Origin gFrontEnd )
				)
				( attribute "PACK_TYPE" "0402"
					( Origin gFrontEnd )
				)
				( attribute "PART_NUMBER" "G21796-072"
					( Origin gFrontEnd )
				)
				( attribute "PHYS_PAGE" "154"
					( Origin gFrontEnd )
				)
				( attribute "ROOM" "SB_BMC_SPI_MUX"
					( Origin gFrontEnd )
				)
				( attribute "ROT" "0"
					( Origin gFrontEnd )
				)
				( attribute "SEC" "1"
					( Origin gFrontEnd )
				)
				( attribute "SEC_TYPE" "0402"
					( Origin gFrontEnd )
				)
				( attribute "TOLERANCE" "1%"
					( Origin gFrontEnd )
				)
				( attribute "VALUE" "4.75K"
					( Origin gFrontEnd )
				)
				( attribute "VER" "2"
					( Origin gFrontEnd )
				)
				( attribute "WATTAGE" "1/16W"
					( Origin gFrontEnd )
				)
				( attribute "XY" "(-3100,2200)"
					( Origin gFrontEnd )
				)
				( attribute "CHIPS_PART_NAME" "RES"
					( Origin gPackager )
				)
				( attribute "CDS_PART_NAME" "RES_0402-4.75K,1%,1/16W,CHIP,GA"
					( Origin gPackager )
				)
				( attribute "GROUP" "NI_BIOS_ROM2"
					( Origin gFrontEnd )
				)
				( objectStatus "R2T11" )
			)
			( gate "@baseboard_fab2_lib.baseboard_fab2(sch_1):page154_i106"
				( attribute "BOM_COST" "MIO_BIOS_MEM"
					( Origin gFrontEnd )
				)
				( attribute "CDS_LIB" "mstr_discrete"
					( Origin gPackager )
				)
				( attribute "CDS_LOCATION" "R2T8"
					( Origin gPackager )
				)
				( attribute "CDS_SEC" "1"
					( Origin gPackager )
				)
				( attribute "LOCATION" "R2T8"
					( Origin gFrontEnd )
				)
				( attribute "MATERIAL" "CHIP"
					( Origin gFrontEnd )
				)
				( attribute "PACK_TYPE" "0402"
					( Origin gFrontEnd )
				)
				( attribute "PART_NUMBER" "G21796-016"
					( Origin gFrontEnd )
				)
				( attribute "PHYS_PAGE" "154"
					( Origin gFrontEnd )
				)
				( attribute "ROOM" "SB_BMC_SPI_MUX"
					( Origin gFrontEnd )
				)
				( attribute "ROT" "2"
					( Origin gFrontEnd )
				)
				( attribute "SEC" "1"
					( Origin gFrontEnd )
				)
				( attribute "SEC_TYPE" "0402"
					( Origin gFrontEnd )
				)
				( attribute "TOLERANCE" "1%"
					( Origin gFrontEnd )
				)
				( attribute "VALUE" "10.0K"
					( Origin gFrontEnd )
				)
				( attribute "VER" "2"
					( Origin gFrontEnd )
				)
				( attribute "WATTAGE" "1/16W"
					( Origin gFrontEnd )
				)
				( attribute "XY" "(-3775,1750)"
					( Origin gFrontEnd )
				)
				( attribute "CHIPS_PART_NAME" "RES"
					( Origin gPackager )
				)
				( attribute "CDS_PART_NAME" "RES_0402-10.0K,1%,1/16W,CHIP,GA"
					( Origin gPackager )
				)
				( attribute "GROUP" "NI_BIOS_ROM2"
					( Origin gFrontEnd )
				)
				( objectStatus "R2T8" )
			)
			( gate "@baseboard_fab2_lib.baseboard_fab2(sch_1):page154_i119"
				( attribute "CDS_LIB" "mstr_discrete"
					( Origin gPackager )
				)
				( attribute "CDS_LOCATION" "R8F6"
					( Origin gPackager )
				)
				( attribute "CDS_SEC" "1"
					( Origin gPackager )
				)
				( attribute "LOCATION" "R8F6"
					( Origin gFrontEnd )
				)
				( attribute "MATERIAL" "CHIP"
					( Origin gFrontEnd )
				)
				( attribute "PACK_TYPE" "0402"
					( Origin gFrontEnd )
				)
				( attribute "PART_NUMBER" "G21497-005"
					( Origin gFrontEnd )
				)
				( attribute "PHYS_PAGE" "154"
					( Origin gFrontEnd )
				)
				( attribute "ROOM" "MIO_BIOS_MEM"
					( Origin gFrontEnd )
				)
				( attribute "ROT" "0"
					( Origin gFrontEnd )
				)
				( attribute "SEC" "1"
					( Origin gPackager )
				)
				( attribute "TOLERANCE" "5%"
					( Origin gFrontEnd )
				)
				( attribute "VALUE" "0.0"
					( Origin gFrontEnd )
				)
				( attribute "VER" "1"
					( Origin gFrontEnd )
				)
				( attribute "WATTAGE" "1/16W"
					( Origin gFrontEnd )
				)
				( attribute "XY" "(-6725,3600)"
					( Origin gFrontEnd )
				)
				( attribute "CHIPS_PART_NAME" "RES"
					( Origin gPackager )
				)
				( attribute "CDS_PART_NAME" "RES_0402-0.0,5%,1/16W,CHIP,G21A"
					( Origin gPackager )
				)
				( objectStatus "R8F6" )
			)
			( gate "@baseboard_fab2_lib.baseboard_fab2(sch_1):page154_i126"
				( attribute "BOM_COST" "MIO_BIOS_MEM"
					( Origin gFrontEnd )
				)
				( attribute "CDS_LIB" "mstr_discrete"
					( Origin gPackager )
				)
				( attribute "CDS_LOCATION" "Q8F1"
					( Origin gPackager )
				)
				( attribute "CDS_SEC" "1"
					( Origin gPackager )
				)
				( attribute "LOCATION" "Q8F1"
					( Origin gFrontEnd )
				)
				( attribute "MATERIAL" "FET"
					( Origin gFrontEnd )
				)
				( attribute "PACK_TYPE" "SOT23LF"
					( Origin gFrontEnd )
				)
				( attribute "PART_NUMBER" "C79254-001"
					( Origin gFrontEnd )
				)
				( attribute "PHYS_PAGE" "154"
					( Origin gFrontEnd )
				)
				( attribute "ROOM" "SB_BMC_SPI_MUX"
					( Origin gFrontEnd )
				)
				( attribute "ROT" "0"
					( Origin gFrontEnd )
				)
				( attribute "SEC" "1"
					( Origin gFrontEnd )
				)
				( attribute "SEC_TYPE" "SOT23LF"
					( Origin gFrontEnd )
				)
				( attribute "VALUE" "2N7002"
					( Origin gFrontEnd )
				)
				( attribute "VER" "8"
					( Origin gFrontEnd )
				)
				( attribute "XY" "(-3100,1575)"
					( Origin gFrontEnd )
				)
				( attribute "CHIPS_PART_NAME" "FET_N"
					( Origin gPackager )
				)
				( attribute "CDS_PART_NAME" "FET_N_SOT23LF-2N7002,FET,C7925A"
					( Origin gPackager )
				)
				( attribute "GROUP" "NI_BIOS_ROM2"
					( Origin gFrontEnd )
				)
				( objectStatus "Q8F1" )
			)
			( gate "@baseboard_fab2_lib.baseboard_fab2(sch_1):page154_i127"
				( attribute "BOM_COST" "MIO_BIOS_MEM"
					( Origin gFrontEnd )
				)
				( attribute "CDS_LIB" "mstr_discrete"
					( Origin gPackager )
				)
				( attribute "CDS_LOCATION" "R2T6"
					( Origin gPackager )
				)
				( attribute "LOCATION" "R2T6"
					( Origin gFrontEnd )
				)
				( attribute "MATERIAL" "CHIP"
					( Origin gFrontEnd )
				)
				( attribute "PACK_TYPE" "0402"
					( Origin gFrontEnd )
				)
				( attribute "PART_NUMBER" "G21796-072"
					( Origin gFrontEnd )
				)
				( attribute "PHYS_PAGE" "154"
					( Origin gFrontEnd )
				)
				( attribute "ROOM" "SB_BMC_SPI_MUX"
					( Origin gFrontEnd )
				)
				( attribute "ROT" "2"
					( Origin gFrontEnd )
				)
				( attribute "SEC" "1"
					( Origin gFrontEnd )
				)
				( attribute "TOLERANCE" "1%"
					( Origin gFrontEnd )
				)
				( attribute "VALUE" "4.75K"
					( Origin gFrontEnd )
				)
				( attribute "VER" "2"
					( Origin gFrontEnd )
				)
				( attribute "WATTAGE" "1/16W"
					( Origin gFrontEnd )
				)
				( attribute "XY" "(-3400,1750)"
					( Origin gFrontEnd )
				)
				( attribute "CHIPS_PART_NAME" "RES"
					( Origin gPackager )
				)
				( attribute "CDS_PART_NAME" "RES_0402-4.75K,1%,1/16W,CHIP,GA"
					( Origin gPackager )
				)
				( attribute "SEC_TYPE" "0402"
					( Origin gFrontEnd )
				)
				( attribute "CDS_SEC" "1"
					( Origin gPackager )
				)
				( objectStatus "R2T6" )
			)
			( gate "@baseboard_fab2_lib.baseboard_fab2(sch_1):page154_i128"
				( attribute "BOM_COST" "MIO_BIOS_MEM"
					( Origin gFrontEnd )
				)
				( attribute "CDS_LIB" "mstr_discrete"
					( Origin gPackager )
				)
				( attribute "CDS_LOCATION" "R1U6"
					( Origin gPackager )
				)
				( attribute "CDS_SEC" "1"
					( Origin gPackager )
				)
				( attribute "LOCATION" "R1U6"
					( Origin gFrontEnd )
				)
				( attribute "MATERIAL" "CHIP"
					( Origin gFrontEnd )
				)
				( attribute "PACK_TYPE" "0402"
					( Origin gFrontEnd )
				)
				( attribute "PART_NUMBER" "G21796-016"
					( Origin gFrontEnd )
				)
				( attribute "PHYS_PAGE" "154"
					( Origin gFrontEnd )
				)
				( attribute "ROOM" "SB_BMC_BPI_MUX"
					( Origin gFrontEnd )
				)
				( attribute "ROT" "0"
					( Origin gFrontEnd )
				)
				( attribute "SEC" "1"
					( Origin gFrontEnd )
				)
				( attribute "SEC_TYPE" "0402"
					( Origin gFrontEnd )
				)
				( attribute "TOLERANCE" "1%"
					( Origin gFrontEnd )
				)
				( attribute "VALUE" "10.0K"
					( Origin gFrontEnd )
				)
				( attribute "VER" "2"
					( Origin gFrontEnd )
				)
				( attribute "WATTAGE" "1/16W"
					( Origin gFrontEnd )
				)
				( attribute "XY" "(-6250,2750)"
					( Origin gFrontEnd )
				)
				( attribute "CHIPS_PART_NAME" "RES"
					( Origin gPackager )
				)
				( attribute "CDS_PART_NAME" "RES_0402-10.0K,1%,1/16W,CHIP,GA"
					( Origin gPackager )
				)
				( objectStatus "R1U6" )
			)
			( gate "@baseboard_fab2_lib.baseboard_fab2(sch_1):page154_i132"
				( attribute "BOM_COST" "MIO_BIOS_MEM"
					( Origin gFrontEnd )
				)
				( attribute "CDS_LIB" "dev_discrete"
					( Origin gPackager )
				)
				( attribute "CDS_LOCATION" "C2T12"
					( Origin gPackager )
				)
				( attribute "CDS_SEC" "1"
					( Origin gPackager )
				)
				( attribute "LOCATION" "C2T12"
					( Origin gFrontEnd )
				)
				( attribute "MATERIAL" "X7R"
					( Origin gFrontEnd )
				)
				( attribute "PACK_TYPE" "0402V"
					( Origin gFrontEnd )
				)
				( attribute "PART_NUMBER" "A36096-030"
					( Origin gFrontEnd )
				)
				( attribute "PHYS_PAGE" "154"
					( Origin gFrontEnd )
				)
				( attribute "ROOM" "SB_BMC_SPI_MUX"
					( Origin gFrontEnd )
				)
				( attribute "ROT" "0"
					( Origin gFrontEnd )
				)
				( attribute "SEC" "1"
					( Origin gFrontEnd )
				)
				( attribute "SEC_TYPE" "0402V"
					( Origin gFrontEnd )
				)
				( attribute "TOLERANCE" "10%"
					( Origin gFrontEnd )
				)
				( attribute "VALUE" "0.1UF"
					( Origin gFrontEnd )
				)
				( attribute "VER" "1"
					( Origin gFrontEnd )
				)
				( attribute "VOLTAGE" "16V"
					( Units "uVoltage" "V" 1.000000)
					( Origin gFrontEnd )
				)
				( attribute "XY" "(-375,2225)"
					( Origin gFrontEnd )
				)
				( attribute "CHIPS_PART_NAME" "CAP_A"
					( Origin gPackager )
				)
				( attribute "CDS_PART_NAME" "CAP_A_0402V-0.1UF,16V,10%,X7R,A"
					( Origin gPackager )
				)
				( objectStatus "C2T12" )
			)
			( gate "@baseboard_fab2_lib.baseboard_fab2(sch_1):page154_i135"
				( attribute "BOM_COST" "MIO_BIOS_MEM"
					( Origin gFrontEnd )
				)
				( attribute "CDS_LIB" "dev_discrete"
					( Origin gPackager )
				)
				( attribute "CDS_LOCATION" "C2T8"
					( Origin gPackager )
				)
				( attribute "CDS_SEC" "1"
					( Origin gPackager )
				)
				( attribute "LOCATION" "C2T8"
					( Origin gFrontEnd )
				)
				( attribute "MATERIAL" "X7R"
					( Origin gFrontEnd )
				)
				( attribute "PACK_TYPE" "0402V"
					( Origin gFrontEnd )
				)
				( attribute "PART_NUMBER" "A36096-030"
					( Origin gFrontEnd )
				)
				( attribute "PHYS_PAGE" "154"
					( Origin gFrontEnd )
				)
				( attribute "ROOM" "SB_BMC_SPI_MUX"
					( Origin gFrontEnd )
				)
				( attribute "ROT" "0"
					( Origin gFrontEnd )
				)
				( attribute "SEC" "1"
					( Origin gFrontEnd )
				)
				( attribute "SEC_TYPE" "0402V"
					( Origin gFrontEnd )
				)
				( attribute "TOLERANCE" "10%"
					( Origin gFrontEnd )
				)
				( attribute "VALUE" "0.1UF"
					( Origin gFrontEnd )
				)
				( attribute "VER" "1"
					( Origin gFrontEnd )
				)
				( attribute "VOLTAGE" "16V"
					( Units "uVoltage" "V" 1.000000)
					( Origin gFrontEnd )
				)
				( attribute "XY" "(-375,1475)"
					( Origin gFrontEnd )
				)
				( attribute "CHIPS_PART_NAME" "CAP_A"
					( Origin gPackager )
				)
				( attribute "CDS_PART_NAME" "CAP_A_0402V-0.1UF,16V,10%,X7R,A"
					( Origin gPackager )
				)
				( objectStatus "C2T8" )
			)
			( gate "@baseboard_fab2_lib.baseboard_fab2(sch_1):page155_i53"
				( attribute "BOM_COST" "DEBUG"
					( Origin gFrontEnd )
				)
				( attribute "CDS_LIB" "mstr_discrete"
					( Origin gPackager )
				)
				( attribute "CDS_LOCATION" "R9A8"
					( Origin gPackager )
				)
				( attribute "CDS_SEC" "1"
					( Origin gPackager )
				)
				( attribute "LOCATION" "R9A8"
					( Origin gFrontEnd )
				)
				( attribute "MATERIAL" "CHIP"
					( Origin gFrontEnd )
				)
				( attribute "PACK_TYPE" "0402"
					( Origin gFrontEnd )
				)
				( attribute "PART_NUMBER" "G21497-005"
					( Origin gFrontEnd )
				)
				( attribute "PHYS_PAGE" "155"
					( Origin gFrontEnd )
				)
				( attribute "ROOM" "BMC_DEBUG_HEADER"
					( Origin gFrontEnd )
				)
				( attribute "ROT" "0"
					( Origin gFrontEnd )
				)
				( attribute "SEC" "1"
					( Origin gFrontEnd )
				)
				( attribute "SEC_TYPE" "0402"
					( Origin gFrontEnd )
				)
				( attribute "TOLERANCE" "5%"
					( Origin gFrontEnd )
				)
				( attribute "VALUE" "0.0"
					( Origin gFrontEnd )
				)
				( attribute "VER" "1"
					( Origin gFrontEnd )
				)
				( attribute "WATTAGE" "1/16W"
					( Origin gFrontEnd )
				)
				( attribute "XY" "(-1125,1400)"
					( Origin gFrontEnd )
				)
				( attribute "CHIPS_PART_NAME" "RES"
					( Origin gPackager )
				)
				( attribute "CDS_PART_NAME" "RES_0402-0.0,5%,1/16W,CHIP,G21A"
					( Origin gPackager )
				)
				( objectStatus "R9A8" )
			)
			( gate "@baseboard_fab2_lib.baseboard_fab2(sch_1):page155_i65"
				( attribute "BOM_COST" "DEBUG"
					( Origin gFrontEnd )
				)
				( attribute "CDS_LIB" "mstr_discrete"
					( Origin gPackager )
				)
				( attribute "CDS_LOCATION" "R1L32"
					( Origin gPackager )
				)
				( attribute "CDS_SEC" "1"
					( Origin gPackager )
				)
				( attribute "LOCATION" "R1L32"
					( Origin gFrontEnd )
				)
				( attribute "MATERIAL" "CHIP"
					( Origin gFrontEnd )
				)
				( attribute "PACK_TYPE" "0402"
					( Origin gFrontEnd )
				)
				( attribute "PART_NUMBER" "G21796-066"
					( Origin gFrontEnd )
				)
				( attribute "PHYS_PAGE" "155"
					( Origin gFrontEnd )
				)
				( attribute "ROOM" "BMC_DEBUG_HEADER"
					( Origin gFrontEnd )
				)
				( attribute "ROT" "0"
					( Origin gFrontEnd )
				)
				( attribute "SEC" "1"
					( Origin gPackager )
				)
				( attribute "TOLERANCE" "1%"
					( Origin gFrontEnd )
				)
				( attribute "VALUE" "10.0"
					( Origin gFrontEnd )
				)
				( attribute "VER" "1"
					( Origin gFrontEnd )
				)
				( attribute "WATTAGE" "1/16W"
					( Origin gFrontEnd )
				)
				( attribute "XY" "(-6900,4650)"
					( Origin gFrontEnd )
				)
				( attribute "CHIPS_PART_NAME" "RES"
					( Origin gPackager )
				)
				( attribute "CDS_PART_NAME" "RES_0402-10.0,1%,1/16W,CHIP,G2A"
					( Origin gPackager )
				)
				( objectStatus "R1L32" )
			)
			( gate "@baseboard_fab2_lib.baseboard_fab2(sch_1):page155_i66"
				( attribute "BOM_COST" "DEBUG"
					( Origin gFrontEnd )
				)
				( attribute "CDS_LIB" "mstr_discrete"
					( Origin gPackager )
				)
				( attribute "CDS_LOCATION" "R1L30"
					( Origin gPackager )
				)
				( attribute "CDS_SEC" "1"
					( Origin gPackager )
				)
				( attribute "LOCATION" "R1L30"
					( Origin gFrontEnd )
				)
				( attribute "MATERIAL" "CHIP"
					( Origin gFrontEnd )
				)
				( attribute "PACK_TYPE" "0402"
					( Origin gFrontEnd )
				)
				( attribute "PART_NUMBER" "G21796-066"
					( Origin gFrontEnd )
				)
				( attribute "PHYS_PAGE" "155"
					( Origin gFrontEnd )
				)
				( attribute "ROOM" "BMC_DEBUG_HEADER"
					( Origin gFrontEnd )
				)
				( attribute "ROT" "0"
					( Origin gFrontEnd )
				)
				( attribute "SEC" "1"
					( Origin gPackager )
				)
				( attribute "TOLERANCE" "1%"
					( Origin gFrontEnd )
				)
				( attribute "VALUE" "10.0"
					( Origin gFrontEnd )
				)
				( attribute "VER" "1"
					( Origin gFrontEnd )
				)
				( attribute "WATTAGE" "1/16W"
					( Origin gFrontEnd )
				)
				( attribute "XY" "(-6900,4500)"
					( Origin gFrontEnd )
				)
				( attribute "CHIPS_PART_NAME" "RES"
					( Origin gPackager )
				)
				( attribute "CDS_PART_NAME" "RES_0402-10.0,1%,1/16W,CHIP,G2A"
					( Origin gPackager )
				)
				( objectStatus "R1L30" )
			)
			( gate "@baseboard_fab2_lib.baseboard_fab2(sch_1):page155_i67"
				( attribute "BOM_COST" "DEBUG"
					( Origin gFrontEnd )
				)
				( attribute "CDS_LIB" "mstr_discrete"
					( Origin gPackager )
				)
				( attribute "CDS_LOCATION" "R1L25"
					( Origin gPackager )
				)
				( attribute "CDS_SEC" "1"
					( Origin gPackager )
				)
				( attribute "LOCATION" "R1L25"
					( Origin gFrontEnd )
				)
				( attribute "MATERIAL" "CHIP"
					( Origin gFrontEnd )
				)
				( attribute "PACK_TYPE" "0402"
					( Origin gFrontEnd )
				)
				( attribute "PART_NUMBER" "G21796-066"
					( Origin gFrontEnd )
				)
				( attribute "PHYS_PAGE" "155"
					( Origin gFrontEnd )
				)
				( attribute "ROOM" "BMC_DEBUG_HEADER"
					( Origin gFrontEnd )
				)
				( attribute "ROT" "0"
					( Origin gFrontEnd )
				)
				( attribute "SEC" "1"
					( Origin gPackager )
				)
				( attribute "TOLERANCE" "1%"
					( Origin gFrontEnd )
				)
				( attribute "VALUE" "10.0"
					( Origin gFrontEnd )
				)
				( attribute "VER" "1"
					( Origin gFrontEnd )
				)
				( attribute "WATTAGE" "1/16W"
					( Origin gFrontEnd )
				)
				( attribute "XY" "(-6900,4350)"
					( Origin gFrontEnd )
				)
				( attribute "CHIPS_PART_NAME" "RES"
					( Origin gPackager )
				)
				( attribute "CDS_PART_NAME" "RES_0402-10.0,1%,1/16W,CHIP,G2A"
					( Origin gPackager )
				)
				( objectStatus "R1L25" )
			)
			( gate "@baseboard_fab2_lib.baseboard_fab2(sch_1):page155_i68"
				( attribute "BOM_COST" "DEBUG"
					( Origin gFrontEnd )
				)
				( attribute "CDS_LIB" "mstr_discrete"
					( Origin gPackager )
				)
				( attribute "CDS_LOCATION" "R1L24"
					( Origin gPackager )
				)
				( attribute "CDS_SEC" "1"
					( Origin gPackager )
				)
				( attribute "LOCATION" "R1L24"
					( Origin gFrontEnd )
				)
				( attribute "MATERIAL" "CHIP"
					( Origin gFrontEnd )
				)
				( attribute "PACK_TYPE" "0402"
					( Origin gFrontEnd )
				)
				( attribute "PART_NUMBER" "G21796-066"
					( Origin gFrontEnd )
				)
				( attribute "PHYS_PAGE" "155"
					( Origin gFrontEnd )
				)
				( attribute "ROOM" "BMC_DEBUG_HEADER"
					( Origin gFrontEnd )
				)
				( attribute "ROT" "0"
					( Origin gFrontEnd )
				)
				( attribute "SEC" "1"
					( Origin gPackager )
				)
				( attribute "TOLERANCE" "1%"
					( Origin gFrontEnd )
				)
				( attribute "VALUE" "10.0"
					( Origin gFrontEnd )
				)
				( attribute "VER" "1"
					( Origin gFrontEnd )
				)
				( attribute "WATTAGE" "1/16W"
					( Origin gFrontEnd )
				)
				( attribute "XY" "(-6900,4200)"
					( Origin gFrontEnd )
				)
				( attribute "CHIPS_PART_NAME" "RES"
					( Origin gPackager )
				)
				( attribute "CDS_PART_NAME" "RES_0402-10.0,1%,1/16W,CHIP,G2A"
					( Origin gPackager )
				)
				( objectStatus "R1L24" )
			)
			( gate "@baseboard_fab2_lib.baseboard_fab2(sch_1):page155_i73"
				( attribute "BOM_COST" "DEBUG"
					( Origin gFrontEnd )
				)
				( attribute "CDS_LIB" "mstr_discrete"
					( Origin gPackager )
				)
				( attribute "CDS_LOCATION" "R1L20"
					( Origin gPackager )
				)
				( attribute "CDS_SEC" "1"
					( Origin gPackager )
				)
				( attribute "LOCATION" "R1L20"
					( Origin gFrontEnd )
				)
				( attribute "MATERIAL" "CHIP"
					( Origin gFrontEnd )
				)
				( attribute "PACK_TYPE" "0402"
					( Origin gFrontEnd )
				)
				( attribute "PART_NUMBER" "G21796-066"
					( Origin gFrontEnd )
				)
				( attribute "PHYS_PAGE" "155"
					( Origin gFrontEnd )
				)
				( attribute "ROOM" "BMC_DEBUG_HEADER"
					( Origin gFrontEnd )
				)
				( attribute "ROT" "0"
					( Origin gFrontEnd )
				)
				( attribute "SEC" "1"
					( Origin gPackager )
				)
				( attribute "TOLERANCE" "1%"
					( Origin gFrontEnd )
				)
				( attribute "VALUE" "10.0"
					( Origin gFrontEnd )
				)
				( attribute "VER" "1"
					( Origin gFrontEnd )
				)
				( attribute "WATTAGE" "1/16W"
					( Origin gFrontEnd )
				)
				( attribute "XY" "(-6900,4050)"
					( Origin gFrontEnd )
				)
				( attribute "CHIPS_PART_NAME" "RES"
					( Origin gPackager )
				)
				( attribute "CDS_PART_NAME" "RES_0402-10.0,1%,1/16W,CHIP,G2A"
					( Origin gPackager )
				)
				( objectStatus "R1L20" )
			)
			( gate "@baseboard_fab2_lib.baseboard_fab2(sch_1):page155_i74"
				( attribute "BOM_COST" "DEBUG"
					( Origin gFrontEnd )
				)
				( attribute "CDS_LIB" "mstr_discrete"
					( Origin gPackager )
				)
				( attribute "CDS_LOCATION" "R1L18"
					( Origin gPackager )
				)
				( attribute "CDS_SEC" "1"
					( Origin gPackager )
				)
				( attribute "LOCATION" "R1L18"
					( Origin gFrontEnd )
				)
				( attribute "MATERIAL" "CHIP"
					( Origin gFrontEnd )
				)
				( attribute "PACK_TYPE" "0402"
					( Origin gFrontEnd )
				)
				( attribute "PART_NUMBER" "G21796-066"
					( Origin gFrontEnd )
				)
				( attribute "PHYS_PAGE" "155"
					( Origin gFrontEnd )
				)
				( attribute "ROOM" "BMC_DEBUG_HEADER"
					( Origin gFrontEnd )
				)
				( attribute "ROT" "0"
					( Origin gFrontEnd )
				)
				( attribute "SEC" "1"
					( Origin gPackager )
				)
				( attribute "TOLERANCE" "1%"
					( Origin gFrontEnd )
				)
				( attribute "VALUE" "10.0"
					( Origin gFrontEnd )
				)
				( attribute "VER" "1"
					( Origin gFrontEnd )
				)
				( attribute "WATTAGE" "1/16W"
					( Origin gFrontEnd )
				)
				( attribute "XY" "(-6900,3900)"
					( Origin gFrontEnd )
				)
				( attribute "CHIPS_PART_NAME" "RES"
					( Origin gPackager )
				)
				( attribute "CDS_PART_NAME" "RES_0402-10.0,1%,1/16W,CHIP,G2A"
					( Origin gPackager )
				)
				( objectStatus "R1L18" )
			)
			( gate "@baseboard_fab2_lib.baseboard_fab2(sch_1):page155_i75"
				( attribute "BOM_COST" "DEBUG"
					( Origin gFrontEnd )
				)
				( attribute "CDS_LIB" "mstr_discrete"
					( Origin gPackager )
				)
				( attribute "CDS_LOCATION" "R1L14"
					( Origin gPackager )
				)
				( attribute "CDS_SEC" "1"
					( Origin gPackager )
				)
				( attribute "LOCATION" "R1L14"
					( Origin gFrontEnd )
				)
				( attribute "MATERIAL" "CHIP"
					( Origin gFrontEnd )
				)
				( attribute "PACK_TYPE" "0402"
					( Origin gFrontEnd )
				)
				( attribute "PART_NUMBER" "G21796-066"
					( Origin gFrontEnd )
				)
				( attribute "PHYS_PAGE" "155"
					( Origin gFrontEnd )
				)
				( attribute "ROOM" "BMC_DEBUG_HEADER"
					( Origin gFrontEnd )
				)
				( attribute "ROT" "0"
					( Origin gFrontEnd )
				)
				( attribute "SEC" "1"
					( Origin gPackager )
				)
				( attribute "TOLERANCE" "1%"
					( Origin gFrontEnd )
				)
				( attribute "VALUE" "10.0"
					( Origin gFrontEnd )
				)
				( attribute "VER" "1"
					( Origin gFrontEnd )
				)
				( attribute "WATTAGE" "1/16W"
					( Origin gFrontEnd )
				)
				( attribute "XY" "(-6900,3750)"
					( Origin gFrontEnd )
				)
				( attribute "CHIPS_PART_NAME" "RES"
					( Origin gPackager )
				)
				( attribute "CDS_PART_NAME" "RES_0402-10.0,1%,1/16W,CHIP,G2A"
					( Origin gPackager )
				)
				( objectStatus "R1L14" )
			)
			( gate "@baseboard_fab2_lib.baseboard_fab2(sch_1):page155_i76"
				( attribute "BOM_COST" "DEBUG"
					( Origin gFrontEnd )
				)
				( attribute "CDS_LIB" "mstr_discrete"
					( Origin gPackager )
				)
				( attribute "CDS_LOCATION" "R1L11"
					( Origin gPackager )
				)
				( attribute "CDS_SEC" "1"
					( Origin gPackager )
				)
				( attribute "LOCATION" "R1L11"
					( Origin gFrontEnd )
				)
				( attribute "MATERIAL" "CHIP"
					( Origin gFrontEnd )
				)
				( attribute "PACK_TYPE" "0402"
					( Origin gFrontEnd )
				)
				( attribute "PART_NUMBER" "G21796-066"
					( Origin gFrontEnd )
				)
				( attribute "PHYS_PAGE" "155"
					( Origin gFrontEnd )
				)
				( attribute "ROOM" "BMC_DEBUG_HEADER"
					( Origin gFrontEnd )
				)
				( attribute "ROT" "0"
					( Origin gFrontEnd )
				)
				( attribute "SEC" "1"
					( Origin gPackager )
				)
				( attribute "TOLERANCE" "1%"
					( Origin gFrontEnd )
				)
				( attribute "VALUE" "10.0"
					( Origin gFrontEnd )
				)
				( attribute "VER" "1"
					( Origin gFrontEnd )
				)
				( attribute "WATTAGE" "1/16W"
					( Origin gFrontEnd )
				)
				( attribute "XY" "(-6900,3600)"
					( Origin gFrontEnd )
				)
				( attribute "CHIPS_PART_NAME" "RES"
					( Origin gPackager )
				)
				( attribute "CDS_PART_NAME" "RES_0402-10.0,1%,1/16W,CHIP,G2A"
					( Origin gPackager )
				)
				( objectStatus "R1L11" )
			)
			( gate "@baseboard_fab2_lib.baseboard_fab2(sch_1):page155_i80"
				( attribute "BOM_COST" "DEBUG"
					( Origin gFrontEnd )
				)
				( attribute "CDS_LIB" "mstr_discrete"
					( Origin gPackager )
				)
				( attribute "CDS_LOCATION" "R9A7"
					( Origin gPackager )
				)
				( attribute "CDS_SEC" "1"
					( Origin gPackager )
				)
				( attribute "LOCATION" "R9A7"
					( Origin gFrontEnd )
				)
				( attribute "MATERIAL" "CHIP"
					( Origin gFrontEnd )
				)
				( attribute "PACK_TYPE" "0402"
					( Origin gFrontEnd )
				)
				( attribute "PART_NUMBER" "G21796-112"
					( Origin gFrontEnd )
				)
				( attribute "PHYS_PAGE" "155"
					( Origin gFrontEnd )
				)
				( attribute "ROOM" "BMC_DEBUG_HEADER"
					( Origin gFrontEnd )
				)
				( attribute "ROT" "0"
					( Origin gFrontEnd )
				)
				( attribute "SEC" "1"
					( Origin gFrontEnd )
				)
				( attribute "SEC_TYPE" "0402"
					( Origin gFrontEnd )
				)
				( attribute "TOLERANCE" "1%"
					( Origin gFrontEnd )
				)
				( attribute "VALUE" "2.21K"
					( Origin gFrontEnd )
				)
				( attribute "VER" "2"
					( Origin gFrontEnd )
				)
				( attribute "WATTAGE" "1/16W"
					( Origin gFrontEnd )
				)
				( attribute "XY" "(-1450,1725)"
					( Origin gFrontEnd )
				)
				( attribute "CHIPS_PART_NAME" "RES"
					( Origin gPackager )
				)
				( attribute "CDS_PART_NAME" "RES_0402-2.21K,1%,1/16W,CHIP,GA"
					( Origin gPackager )
				)
				( objectStatus "R9A7" )
			)
			( gate "@baseboard_fab2_lib.baseboard_fab2(sch_1):page155_i127"
				( attribute "BOM_COST" "DEBUG"
					( Origin gFrontEnd )
				)
				( attribute "CDS_LIB" "dev_discrete"
					( Origin gPackager )
				)
				( attribute "CDS_LOCATION" "C9A1"
					( Origin gPackager )
				)
				( attribute "CDS_SEC" "1"
					( Origin gPackager )
				)
				( attribute "LOCATION" "C9A1"
					( Origin gFrontEnd )
				)
				( attribute "MATERIAL" "X7R"
					( Origin gFrontEnd )
				)
				( attribute "PACK_TYPE" "0402V"
					( Origin gFrontEnd )
				)
				( attribute "PART_NUMBER" "A36096-030"
					( Origin gFrontEnd )
				)
				( attribute "PHYS_PAGE" "155"
					( Origin gFrontEnd )
				)
				( attribute "ROOM" "BMC_DEBUG_HEADER"
					( Origin gFrontEnd )
				)
				( attribute "ROT" "0"
					( Origin gFrontEnd )
				)
				( attribute "SEC" "1"
					( Origin gPackager )
				)
				( attribute "TOLERANCE" "10%"
					( Origin gFrontEnd )
				)
				( attribute "VALUE" "0.1UF"
					( Origin gFrontEnd )
				)
				( attribute "VER" "1"
					( Origin gFrontEnd )
				)
				( attribute "VOLTAGE" "16V"
					( Units "uVoltage" "V" 1.000000)
					( Origin gFrontEnd )
				)
				( attribute "XY" "(-4100,1050)"
					( Origin gFrontEnd )
				)
				( attribute "CHIPS_PART_NAME" "CAP_A"
					( Origin gPackager )
				)
				( attribute "CDS_PART_NAME" "CAP_A_0402V-0.1UF,16V,10%,X7R,A"
					( Origin gPackager )
				)
				( objectStatus "C9A1" )
			)
			( gate "@baseboard_fab2_lib.baseboard_fab2(sch_1):page155_i129"
				( attribute "BOM_COST" "DEBUG"
					( Origin gFrontEnd )
				)
				( attribute "CDS_LIB" "mstr_discrete"
					( Origin gPackager )
				)
				( attribute "CDS_LOCATION" "F1L1"
					( Origin gPackager )
				)
				( attribute "CDS_SEC" "1"
					( Origin gPackager )
				)
				( attribute "LOCATION" "F1L1"
					( Origin gFrontEnd )
				)
				( attribute "MATERIAL" "IC"
					( Origin gFrontEnd )
				)
				( attribute "PACK_TYPE" "SMT"
					( Origin gFrontEnd )
				)
				( attribute "PART_NUMBER" "H45581-001"
					( Origin gFrontEnd )
				)
				( attribute "PHYS_PAGE" "155"
					( Origin gFrontEnd )
				)
				( attribute "ROOM" "BMC_DEBUG_HEADER"
					( Origin gFrontEnd )
				)
				( attribute "ROT" "0"
					( Origin gFrontEnd )
				)
				( attribute "SEC" "1"
					( Origin gFrontEnd )
				)
				( attribute "SEC_TYPE" "SMT"
					( Origin gFrontEnd )
				)
				( attribute "VER" "1"
					( Origin gFrontEnd )
				)
				( attribute "XY" "(-4275,2625)"
					( Origin gFrontEnd )
				)
				( attribute "CHIPS_PART_NAME" "FUSE"
					( Origin gPackager )
				)
				( attribute "CDS_PART_NAME" "FUSE_SMT-IC,H45581-001"
					( Origin gPackager )
				)
				( attribute "CONFIG" "069.50018.0001"
					( Origin gFrontEnd )
				)
				( objectStatus "F1L1" )
			)
			( gate "@baseboard_fab2_lib.baseboard_fab2(sch_1):page155_i130"
				( attribute "BOM_COST" "DEBUG"
					( Origin gFrontEnd )
				)
				( attribute "CDS_LIB" "mstr_discrete"
					( Origin gPackager )
				)
				( attribute "CDS_LOCATION" "R1L9"
					( Origin gPackager )
				)
				( attribute "CDS_SEC" "1"
					( Origin gPackager )
				)
				( attribute "LOCATION" "R1L9"
					( Origin gFrontEnd )
				)
				( attribute "MATERIAL" "CHIP"
					( Origin gFrontEnd )
				)
				( attribute "PACK_TYPE" "0402"
					( Origin gFrontEnd )
				)
				( attribute "PART_NUMBER" "G21796-010"
					( Origin gFrontEnd )
				)
				( attribute "PHYS_PAGE" "155"
					( Origin gFrontEnd )
				)
				( attribute "ROOM" "BMC_DEBUG_HEADER"
					( Origin gFrontEnd )
				)
				( attribute "ROT" "0"
					( Origin gFrontEnd )
				)
				( attribute "SEC" "1"
					( Origin gFrontEnd )
				)
				( attribute "SEC_TYPE" "0402"
					( Origin gFrontEnd )
				)
				( attribute "TOLERANCE" "1%"
					( Origin gFrontEnd )
				)
				( attribute "VALUE" "100.0K"
					( Origin gFrontEnd )
				)
				( attribute "VER" "2"
					( Origin gFrontEnd )
				)
				( attribute "WATTAGE" "1/16W"
					( Origin gFrontEnd )
				)
				( attribute "XY" "(-5950,2575)"
					( Origin gFrontEnd )
				)
				( attribute "CHIPS_PART_NAME" "RES"
					( Origin gPackager )
				)
				( attribute "CDS_PART_NAME" "RES_0402-100.0K,1%,1/16W,CHIP,A"
					( Origin gPackager )
				)
				( objectStatus "R1L9" )
			)
			( gate "@baseboard_fab2_lib.baseboard_fab2(sch_1):page176_i122"
				( attribute "CHIPS_PART_NAME" "TTL1G08"
					( Origin gPackager )
				)
			)
			( gate "@baseboard_fab2_lib.baseboard_fab2(sch_1):page155_i171"
				( attribute "BOM_COST" "DEBUG"
					( Origin gFrontEnd )
				)
				( attribute "CDS_LIB" "mstr_conn"
					( Origin gPackager )
				)
				( attribute "CDS_LMAN_SYM_OUTLINE" "-250,250,250,-250"
					( Origin gPackager )
				)
				( attribute "CDS_LOCATION" "J9A2"
					( Origin gPackager )
				)
				( attribute "CDS_SEC" "1"
					( Origin gPackager )
				)
				( attribute "LOCATION" "J9A2"
					( Origin gFrontEnd )
				)
				( attribute "MATERIAL" "CONN"
					( Origin gFrontEnd )
				)
				( attribute "PACK_TYPE" "PIP"
					( Origin gFrontEnd )
				)
				( attribute "PART_NUMBER" "H54902-001"
					( Origin gFrontEnd )
				)
				( attribute "PHYS_PAGE" "155"
					( Origin gFrontEnd )
				)
				( attribute "ROOM" "BMC_DEBUG_HEADER"
					( Origin gFrontEnd )
				)
				( attribute "ROT" "0"
					( Origin gFrontEnd )
				)
				( attribute "SEC" "1"
					( Origin gPackager )
				)
				( attribute "VER" "1"
					( Origin gFrontEnd )
				)
				( attribute "XY" "(-4450,1500)"
					( Origin gFrontEnd )
				)
				( attribute "CHIPS_PART_NAME" "CONN14_H54902001"
					( Origin gPackager )
				)
				( attribute "CDS_PART_NAME" "CONN14_H54902001_PIP-CONN,H549A"
					( Origin gPackager )
				)
				( objectStatus "J9A2" )
			)
			( gate "@baseboard_fab2_lib.baseboard_fab2(sch_1):page155_i178"
				( attribute "BOM_COST" "DEBUG"
					( Origin gFrontEnd )
				)
				( attribute "CDS_LIB" "mstr_ttl"
					( Origin gPackager )
				)
				( attribute "CDS_LOCATION" "U9A1"
					( Origin gPackager )
				)
				( attribute "CDS_SEC" "1"
					( Origin gPackager )
				)
				( attribute "LOCATION" "U9A1"
					( Origin gFrontEnd )
				)
				( attribute "MATERIAL" "IC"
					( Origin gFrontEnd )
				)
				( attribute "PACK_TYPE" "SOP"
					( Origin gFrontEnd )
				)
				( attribute "PART_NUMBER" "C88419-001"
					( Origin gFrontEnd )
				)
				( attribute "PHYS_PAGE" "155"
					( Origin gFrontEnd )
				)
				( attribute "ROOM" "BMC_DEBUG_HEADER"
					( Origin gFrontEnd )
				)
				( attribute "ROT" "0"
					( Origin gFrontEnd )
				)
				( attribute "SEC" "1"
					( Origin gFrontEnd )
				)
				( attribute "SEC_TYPE" "SOP"
					( Origin gFrontEnd )
				)
				( attribute "VALUE" "74LVC1G07"
					( Origin gFrontEnd )
				)
				( attribute "VER" "1"
					( Origin gFrontEnd )
				)
				( attribute "XY" "(-2100,1400)"
					( Origin gFrontEnd )
				)
				( attribute "CHIPS_PART_NAME" "TTL1G07_A"
					( Origin gPackager )
				)
				( attribute "CDS_PART_NAME" "TTL1G07_A_SOP-74LVC1G07,IC,C88B"
					( Origin gPackager )
				)
				( objectStatus "U9A1" )
			)
			( gate "@baseboard_fab2_lib.baseboard_fab2(sch_1):page155_i184"
				( attribute "BOM_COST" "DEBUG"
					( Origin gFrontEnd )
				)
				( attribute "CDS_LIB" "dev_discrete"
					( Origin gPackager )
				)
				( attribute "CDS_LOCATION" "C1T56"
					( Origin gPackager )
				)
				( attribute "CDS_SEC" "1"
					( Origin gPackager )
				)
				( attribute "LOCATION" "C1T56"
					( Origin gFrontEnd )
				)
				( attribute "MATERIAL" "X7R"
					( Origin gFrontEnd )
				)
				( attribute "PACK_TYPE" "0402V"
					( Origin gFrontEnd )
				)
				( attribute "PART_NUMBER" "A36096-030"
					( Origin gFrontEnd )
				)
				( attribute "PHYS_PAGE" "155"
					( Origin gFrontEnd )
				)
				( attribute "ROOM" "BMC_DEBUG_HEADER"
					( Origin gFrontEnd )
				)
				( attribute "ROT" "0"
					( Origin gFrontEnd )
				)
				( attribute "SEC" "1"
					( Origin gFrontEnd )
				)
				( attribute "SEC_TYPE" "0402V"
					( Origin gFrontEnd )
				)
				( attribute "TOLERANCE" "10%"
					( Origin gFrontEnd )
				)
				( attribute "VALUE" "0.1UF"
					( Origin gFrontEnd )
				)
				( attribute "VER" "1"
					( Origin gFrontEnd )
				)
				( attribute "VOLTAGE" "16V"
					( Units "uVoltage" "V" 1.000000)
					( Origin gFrontEnd )
				)
				( attribute "XY" "(-1550,3025)"
					( Origin gFrontEnd )
				)
				( attribute "CHIPS_PART_NAME" "CAP_A"
					( Origin gPackager )
				)
				( attribute "CDS_PART_NAME" "CAP_A_0402V-0.1UF,16V,10%,X7R,A"
					( Origin gPackager )
				)
				( objectStatus "C1T56" )
			)
			( gate "@baseboard_fab2_lib.baseboard_fab2(sch_1):page155_i186"
				( attribute "BOM_COST" "DEBUG"
					( Origin gFrontEnd )
				)
				( attribute "CDS_LIB" "mstr_discrete"
					( Origin gPackager )
				)
				( attribute "CDS_LOCATION" "R1L2"
					( Origin gPackager )
				)
				( attribute "CDS_SEC" "1"
					( Origin gPackager )
				)
				( attribute "LOCATION" "R1L2"
					( Origin gFrontEnd )
				)
				( attribute "MATERIAL" "CHIP"
					( Origin gFrontEnd )
				)
				( attribute "PACK_TYPE" "0402"
					( Origin gFrontEnd )
				)
				( attribute "PART_NUMBER" "G21796-066"
					( Origin gFrontEnd )
				)
				( attribute "PHYS_PAGE" "155"
					( Origin gFrontEnd )
				)
				( attribute "ROOM" "BMC_DEBUG_HEADER"
					( Origin gFrontEnd )
				)
				( attribute "ROT" "0"
					( Origin gFrontEnd )
				)
				( attribute "SEC" "1"
					( Origin gPackager )
				)
				( attribute "TOLERANCE" "1%"
					( Origin gFrontEnd )
				)
				( attribute "VALUE" "10.0"
					( Origin gFrontEnd )
				)
				( attribute "VER" "1"
					( Origin gFrontEnd )
				)
				( attribute "WATTAGE" "1/16W"
					( Origin gFrontEnd )
				)
				( attribute "XY" "(-7050,2000)"
					( Origin gFrontEnd )
				)
				( attribute "CHIPS_PART_NAME" "RES"
					( Origin gPackager )
				)
				( attribute "CDS_PART_NAME" "RES_0402-10.0,1%,1/16W,CHIP,G2A"
					( Origin gPackager )
				)
				( objectStatus "R1L2" )
			)
			( gate "@baseboard_fab2_lib.baseboard_fab2(sch_1):page155_i187"
				( attribute "BOM_COST" "BMC_DEBUG_HEADER"
					( Origin gFrontEnd )
				)
				( attribute "CDS_LIB" "mstr_discrete"
					( Origin gPackager )
				)
				( attribute "CDS_LOCATION" "Q1L2"
					( Origin gPackager )
				)
				( attribute "LOCATION" "Q1L2"
					( Origin gFrontEnd )
				)
				( attribute "MATERIAL" "FET"
					( Origin gFrontEnd )
				)
				( attribute "PACK_TYPE" "SMLF"
					( Origin gFrontEnd )
				)
				( attribute "PART_NUMBER" "E40049-001"
					( Origin gFrontEnd )
				)
				( attribute "PHYS_PAGE" "155"
					( Origin gFrontEnd )
				)
				( attribute "ROOM" "BMC"
					( Origin gFrontEnd )
				)
				( attribute "ROT" "0"
					( Origin gFrontEnd )
				)
				( attribute "SEC" "2"
					( Origin gFrontEnd )
				)
				( attribute "SEC_TYPE" "SMLF"
					( Origin gFrontEnd )
				)
				( attribute "VALUE" "NTJD4001N"
					( Origin gFrontEnd )
				)
				( attribute "VER" "5"
					( Origin gFrontEnd )
				)
				( attribute "XY" "(-5950,2100)"
					( Origin gFrontEnd )
				)
				( attribute "CHIPS_PART_NAME" "FET_N_DUAL"
					( Origin gPackager )
				)
				( attribute "CDS_PART_NAME" "FET_N_DUAL_SMLF-NTJD4001N,FET,A"
					( Origin gPackager )
				)
				( attribute "CDS_SEC" "2"
					( Origin gPackager )
				)
				( objectStatus "Q1L2" )
			)
			( gate "@baseboard_fab2_lib.baseboard_fab2(sch_1):page155_i188"
				( attribute "BOM_COST" "BMC_DEBUG_HEADER"
					( Origin gFrontEnd )
				)
				( attribute "CDS_LIB" "mstr_discrete"
					( Origin gPackager )
				)
				( attribute "CDS_LOCATION" "Q1L2"
					( Origin gPackager )
				)
				( attribute "CDS_SEC" "1"
					( Origin gPackager )
				)
				( attribute "LOCATION" "Q1L2"
					( Origin gFrontEnd )
				)
				( attribute "MATERIAL" "FET"
					( Origin gFrontEnd )
				)
				( attribute "PACK_TYPE" "SMLF"
					( Origin gFrontEnd )
				)
				( attribute "PART_NUMBER" "E40049-001"
					( Origin gFrontEnd )
				)
				( attribute "PHYS_PAGE" "155"
					( Origin gFrontEnd )
				)
				( attribute "ROOM" "BMC"
					( Origin gFrontEnd )
				)
				( attribute "ROT" "1"
					( Origin gFrontEnd )
				)
				( attribute "SEC" "1"
					( Origin gFrontEnd )
				)
				( attribute "SEC_TYPE" "SMLF"
					( Origin gFrontEnd )
				)
				( attribute "VALUE" "NTJD4001N"
					( Origin gFrontEnd )
				)
				( attribute "VER" "5"
					( Origin gFrontEnd )
				)
				( attribute "XY" "(-4950,2625)"
					( Origin gFrontEnd )
				)
				( attribute "CHIPS_PART_NAME" "FET_N_DUAL"
					( Origin gPackager )
				)
				( attribute "CDS_PART_NAME" "FET_N_DUAL_SMLF-NTJD4001N,FET,A"
					( Origin gPackager )
				)
				( objectStatus "Q1L2" )
			)
			( gate "@baseboard_fab2_lib.baseboard_fab2(sch_1):page156_i269"
				( attribute "CHIPS_PART_NAME" "TTL2G07"
					( Origin gPackager )
				)
			)
			( gate "@baseboard_fab2_lib.baseboard_fab2(sch_1):page156_i206"
				( attribute "BOM_COST" "SM_CONTROLLER"
					( Origin gFrontEnd )
				)
				( attribute "CDS_LIB" "mstr_discrete"
					( Origin gPackager )
				)
				( attribute "CDS_LOCATION" "R2T34"
					( Origin gPackager )
				)
				( attribute "CDS_SEC" "1"
					( Origin gPackager )
				)
				( attribute "LOCATION" "R2T34"
					( Origin gFrontEnd )
				)
				( attribute "MATERIAL" "CHIP"
					( Origin gFrontEnd )
				)
				( attribute "PACK_TYPE" "0402"
					( Origin gFrontEnd )
				)
				( attribute "PART_NUMBER" "G21796-072"
					( Origin gFrontEnd )
				)
				( attribute "PHYS_PAGE" "156"
					( Origin gFrontEnd )
				)
				( attribute "ROOM" "BMC_MISC"
					( Origin gFrontEnd )
				)
				( attribute "ROT" "0"
					( Origin gFrontEnd )
				)
				( attribute "SEC" "1"
					( Origin gFrontEnd )
				)
				( attribute "SEC_TYPE" "0402"
					( Origin gFrontEnd )
				)
				( attribute "TOLERANCE" "1%"
					( Origin gFrontEnd )
				)
				( attribute "VALUE" "4.75K"
					( Origin gFrontEnd )
				)
				( attribute "VER" "2"
					( Origin gFrontEnd )
				)
				( attribute "WATTAGE" "1/16W"
					( Origin gFrontEnd )
				)
				( attribute "XY" "(-4150,4450)"
					( Origin gFrontEnd )
				)
				( attribute "CHIPS_PART_NAME" "RES"
					( Origin gPackager )
				)
				( attribute "CDS_PART_NAME" "RES_0402-4.75K,1%,1/16W,CHIP,GA"
					( Origin gPackager )
				)
				( objectStatus "R2T34" )
			)
			( gate "@baseboard_fab2_lib.baseboard_fab2(sch_1):page156_i207"
				( attribute "BOM_COST" "SM_CONTROLLER"
					( Origin gFrontEnd )
				)
				( attribute "CDS_LIB" "mstr_discrete"
					( Origin gPackager )
				)
				( attribute "CDS_LOCATION" "R2T35"
					( Origin gPackager )
				)
				( attribute "CDS_SEC" "1"
					( Origin gPackager )
				)
				( attribute "LOCATION" "R2T35"
					( Origin gFrontEnd )
				)
				( attribute "MATERIAL" "CHIP"
					( Origin gFrontEnd )
				)
				( attribute "PACK_TYPE" "0402"
					( Origin gFrontEnd )
				)
				( attribute "PART_NUMBER" "G21796-072"
					( Origin gFrontEnd )
				)
				( attribute "PHYS_PAGE" "156"
					( Origin gFrontEnd )
				)
				( attribute "ROOM" "BMC_MISC"
					( Origin gFrontEnd )
				)
				( attribute "ROT" "0"
					( Origin gFrontEnd )
				)
				( attribute "SEC" "1"
					( Origin gFrontEnd )
				)
				( attribute "SEC_TYPE" "0402"
					( Origin gFrontEnd )
				)
				( attribute "TOLERANCE" "1%"
					( Origin gFrontEnd )
				)
				( attribute "VALUE" "4.75K"
					( Origin gFrontEnd )
				)
				( attribute "VER" "2"
					( Origin gFrontEnd )
				)
				( attribute "WATTAGE" "1/16W"
					( Origin gFrontEnd )
				)
				( attribute "XY" "(-3825,4450)"
					( Origin gFrontEnd )
				)
				( attribute "CHIPS_PART_NAME" "RES"
					( Origin gPackager )
				)
				( attribute "CDS_PART_NAME" "RES_0402-4.75K,1%,1/16W,CHIP,GA"
					( Origin gPackager )
				)
				( objectStatus "R2T35" )
			)
			( gate "@baseboard_fab2_lib.baseboard_fab2(sch_1):page156_i210"
				( attribute "BOM_COST" "SM_CONTROLLER"
					( Origin gFrontEnd )
				)
				( attribute "CDS_LIB" "mstr_discrete"
					( Origin gPackager )
				)
				( attribute "CDS_LOCATION" "R2T22"
					( Origin gPackager )
				)
				( attribute "CDS_SEC" "1"
					( Origin gPackager )
				)
				( attribute "LOCATION" "R2T22"
					( Origin gFrontEnd )
				)
				( attribute "MATERIAL" "CHIP"
					( Origin gFrontEnd )
				)
				( attribute "PACK_TYPE" "0402"
					( Origin gFrontEnd )
				)
				( attribute "PART_NUMBER" "G21796-016"
					( Origin gFrontEnd )
				)
				( attribute "PHYS_PAGE" "156"
					( Origin gFrontEnd )
				)
				( attribute "ROOM" "BMC_MISC"
					( Origin gFrontEnd )
				)
				( attribute "ROT" "0"
					( Origin gFrontEnd )
				)
				( attribute "SEC" "1"
					( Origin gFrontEnd )
				)
				( attribute "SEC_TYPE" "0402"
					( Origin gFrontEnd )
				)
				( attribute "TOLERANCE" "1%"
					( Origin gFrontEnd )
				)
				( attribute "VALUE" "10.0K"
					( Origin gFrontEnd )
				)
				( attribute "VER" "2"
					( Origin gFrontEnd )
				)
				( attribute "WATTAGE" "1/16W"
					( Origin gFrontEnd )
				)
				( attribute "XY" "(-2275,4425)"
					( Origin gFrontEnd )
				)
				( attribute "CHIPS_PART_NAME" "RES"
					( Origin gPackager )
				)
				( attribute "CDS_PART_NAME" "RES_0402-10.0K,1%,1/16W,CHIP,GA"
					( Origin gPackager )
				)
				( objectStatus "R2T22" )
			)
			( gate "@baseboard_fab2_lib.baseboard_fab2(sch_1):page156_i211"
				( attribute "BOM_COST" "SM_CONTROLLER"
					( Origin gFrontEnd )
				)
				( attribute "CDS_LIB" "mstr_discrete"
					( Origin gPackager )
				)
				( attribute "CDS_LOCATION" "R8F26"
					( Origin gPackager )
				)
				( attribute "CDS_SEC" "1"
					( Origin gPackager )
				)
				( attribute "LOCATION" "R8F26"
					( Origin gFrontEnd )
				)
				( attribute "MATERIAL" "CHIP"
					( Origin gFrontEnd )
				)
				( attribute "PACK_TYPE" "0402"
					( Origin gFrontEnd )
				)
				( attribute "PART_NUMBER" "G21796-016"
					( Origin gFrontEnd )
				)
				( attribute "PHYS_PAGE" "156"
					( Origin gFrontEnd )
				)
				( attribute "ROOM" "BMC_MISC"
					( Origin gFrontEnd )
				)
				( attribute "ROT" "0"
					( Origin gFrontEnd )
				)
				( attribute "SEC" "1"
					( Origin gFrontEnd )
				)
				( attribute "SEC_TYPE" "0402"
					( Origin gFrontEnd )
				)
				( attribute "TOLERANCE" "1%"
					( Origin gFrontEnd )
				)
				( attribute "VALUE" "10.0K"
					( Origin gFrontEnd )
				)
				( attribute "VER" "2"
					( Origin gFrontEnd )
				)
				( attribute "WATTAGE" "1/16W"
					( Origin gFrontEnd )
				)
				( attribute "XY" "(-2550,4450)"
					( Origin gFrontEnd )
				)
				( attribute "CHIPS_PART_NAME" "RES"
					( Origin gPackager )
				)
				( attribute "CDS_PART_NAME" "RES_0402-10.0K,1%,1/16W,CHIP,GA"
					( Origin gPackager )
				)
				( objectStatus "R8F26" )
			)
			( gate "@baseboard_fab2_lib.baseboard_fab2(sch_1):page156_i214"
				( attribute "BOM_COST" "SM_CONTROLLER"
					( Origin gFrontEnd )
				)
				( attribute "CDS_LIB" "mstr_discrete"
					( Origin gPackager )
				)
				( attribute "CDS_LOCATION" "R8E24"
					( Origin gPackager )
				)
				( attribute "CDS_SEC" "1"
					( Origin gPackager )
				)
				( attribute "LOCATION" "R8E24"
					( Origin gFrontEnd )
				)
				( attribute "MATERIAL" "CHIP"
					( Origin gFrontEnd )
				)
				( attribute "PACK_TYPE" "0402"
					( Origin gFrontEnd )
				)
				( attribute "PART_NUMBER" "G21796-074"
					( Origin gFrontEnd )
				)
				( attribute "PHYS_PAGE" "156"
					( Origin gFrontEnd )
				)
				( attribute "ROOM" "BMC_MISC"
					( Origin gFrontEnd )
				)
				( attribute "ROT" "0"
					( Origin gFrontEnd )
				)
				( attribute "SEC" "1"
					( Origin gFrontEnd )
				)
				( attribute "SEC_TYPE" "0402"
					( Origin gFrontEnd )
				)
				( attribute "TOLERANCE" "1%"
					( Origin gFrontEnd )
				)
				( attribute "VALUE" "33.2"
					( Origin gFrontEnd )
				)
				( attribute "VER" "1"
					( Origin gFrontEnd )
				)
				( attribute "WATTAGE" "1/16W"
					( Origin gFrontEnd )
				)
				( attribute "XY" "(-6575,2775)"
					( Origin gFrontEnd )
				)
				( attribute "CHIPS_PART_NAME" "RES"
					( Origin gPackager )
				)
				( attribute "CDS_PART_NAME" "RES_0402-33.2,1%,1/16W,CHIP,G2A"
					( Origin gPackager )
				)
				( objectStatus "R8E24" )
			)
			( gate "@baseboard_fab2_lib.baseboard_fab2(sch_1):page156_i215"
				( attribute "BOM_COST" "SM_CONTROLLER"
					( Origin gFrontEnd )
				)
				( attribute "CDS_LIB" "mstr_discrete"
					( Origin gPackager )
				)
				( attribute "CDS_LOCATION" "R8E22"
					( Origin gPackager )
				)
				( attribute "CDS_SEC" "1"
					( Origin gPackager )
				)
				( attribute "LOCATION" "R8E22"
					( Origin gFrontEnd )
				)
				( attribute "MATERIAL" "CHIP"
					( Origin gFrontEnd )
				)
				( attribute "PACK_TYPE" "0402"
					( Origin gFrontEnd )
				)
				( attribute "PART_NUMBER" "G21796-072"
					( Origin gFrontEnd )
				)
				( attribute "PHYS_PAGE" "156"
					( Origin gFrontEnd )
				)
				( attribute "ROOM" "BMC_MISC"
					( Origin gFrontEnd )
				)
				( attribute "ROT" "0"
					( Origin gFrontEnd )
				)
				( attribute "SEC" "1"
					( Origin gFrontEnd )
				)
				( attribute "SEC_TYPE" "0402"
					( Origin gFrontEnd )
				)
				( attribute "TOLERANCE" "1%"
					( Origin gFrontEnd )
				)
				( attribute "VALUE" "4.75K"
					( Origin gFrontEnd )
				)
				( attribute "VER" "2"
					( Origin gFrontEnd )
				)
				( attribute "WATTAGE" "1/16W"
					( Origin gFrontEnd )
				)
				( attribute "XY" "(-6825,3025)"
					( Origin gFrontEnd )
				)
				( attribute "CHIPS_PART_NAME" "RES"
					( Origin gPackager )
				)
				( attribute "CDS_PART_NAME" "RES_0402-4.75K,1%,1/16W,CHIP,GA"
					( Origin gPackager )
				)
				( objectStatus "R8E22" )
			)
			( gate "@baseboard_fab2_lib.baseboard_fab2(sch_1):page156_i265"
				( attribute "BOM_COST" "SM_CONTROLLER"
					( Origin gFrontEnd )
				)
				( attribute "CDS_LIB" "mstr_discrete"
					( Origin gPackager )
				)
				( attribute "CDS_LOCATION" "R2U2"
					( Origin gPackager )
				)
				( attribute "CDS_SEC" "1"
					( Origin gPackager )
				)
				( attribute "LOCATION" "R2U2"
					( Origin gFrontEnd )
				)
				( attribute "MATERIAL" "CHIP"
					( Origin gFrontEnd )
				)
				( attribute "PACK_TYPE" "0402"
					( Origin gFrontEnd )
				)
				( attribute "PART_NUMBER" "G21796-072"
					( Origin gFrontEnd )
				)
				( attribute "PHYS_PAGE" "156"
					( Origin gFrontEnd )
				)
				( attribute "ROOM" "BMC_MISC"
					( Origin gFrontEnd )
				)
				( attribute "ROT" "0"
					( Origin gFrontEnd )
				)
				( attribute "SEC" "1"
					( Origin gFrontEnd )
				)
				( attribute "SEC_TYPE" "0402"
					( Origin gFrontEnd )
				)
				( attribute "TOLERANCE" "1%"
					( Origin gFrontEnd )
				)
				( attribute "VALUE" "4.75K"
					( Origin gFrontEnd )
				)
				( attribute "VER" "2"
					( Origin gFrontEnd )
				)
				( attribute "WATTAGE" "1/16W"
					( Origin gFrontEnd )
				)
				( attribute "XY" "(-3825,3250)"
					( Origin gFrontEnd )
				)
				( attribute "CHIPS_PART_NAME" "RES"
					( Origin gPackager )
				)
				( attribute "CDS_PART_NAME" "RES_0402-4.75K,1%,1/16W,CHIP,GA"
					( Origin gPackager )
				)
				( objectStatus "R2U2" )
			)
			( gate "@baseboard_fab2_lib.baseboard_fab2(sch_1):page156_i267"
				( attribute "BOM_COST" "SM_CONTROLLER"
					( Origin gFrontEnd )
				)
				( attribute "CDS_LIB" "mstr_discrete"
					( Origin gPackager )
				)
				( attribute "CDS_LOCATION" "R8G2"
					( Origin gPackager )
				)
				( attribute "CDS_SEC" "1"
					( Origin gPackager )
				)
				( attribute "LOCATION" "R8G2"
					( Origin gFrontEnd )
				)
				( attribute "MATERIAL" "CHIP"
					( Origin gFrontEnd )
				)
				( attribute "PACK_TYPE" "0402"
					( Origin gFrontEnd )
				)
				( attribute "PART_NUMBER" "G21796-072"
					( Origin gFrontEnd )
				)
				( attribute "PHYS_PAGE" "156"
					( Origin gFrontEnd )
				)
				( attribute "ROOM" "BMC_MISC"
					( Origin gFrontEnd )
				)
				( attribute "ROT" "0"
					( Origin gFrontEnd )
				)
				( attribute "SEC" "1"
					( Origin gFrontEnd )
				)
				( attribute "SEC_TYPE" "0402"
					( Origin gFrontEnd )
				)
				( attribute "TOLERANCE" "1%"
					( Origin gFrontEnd )
				)
				( attribute "VALUE" "4.75K"
					( Origin gFrontEnd )
				)
				( attribute "VER" "2"
					( Origin gFrontEnd )
				)
				( attribute "WATTAGE" "1/16W"
					( Origin gFrontEnd )
				)
				( attribute "XY" "(-4150,3250)"
					( Origin gFrontEnd )
				)
				( attribute "CHIPS_PART_NAME" "RES"
					( Origin gPackager )
				)
				( attribute "CDS_PART_NAME" "RES_0402-4.75K,1%,1/16W,CHIP,GA"
					( Origin gPackager )
				)
				( objectStatus "R8G2" )
			)
			( gate "@baseboard_fab2_lib.baseboard_fab2(sch_1):page156_i201"
				( attribute "CHIPS_PART_NAME" "TTL2G07"
					( Origin gPackager )
				)
			)
			( gate "@baseboard_fab2_lib.baseboard_fab2(sch_1):page156_i273"
				( attribute "BOM_COST" "SM_CONTROLLER"
					( Origin gFrontEnd )
				)
				( attribute "CDS_LIB" "dev_discrete"
					( Origin gPackager )
				)
				( attribute "CDS_LOCATION" "C2T35"
					( Origin gPackager )
				)
				( attribute "CDS_SEC" "1"
					( Origin gPackager )
				)
				( attribute "LOCATION" "C2T35"
					( Origin gFrontEnd )
				)
				( attribute "MATERIAL" "X7R"
					( Origin gFrontEnd )
				)
				( attribute "PACK_TYPE" "0402V"
					( Origin gFrontEnd )
				)
				( attribute "PART_NUMBER" "A36096-030"
					( Origin gFrontEnd )
				)
				( attribute "PHYS_PAGE" "156"
					( Origin gFrontEnd )
				)
				( attribute "ROOM" "BMC_MISC"
					( Origin gFrontEnd )
				)
				( attribute "ROT" "0"
					( Origin gFrontEnd )
				)
				( attribute "SEC" "1"
					( Origin gFrontEnd )
				)
				( attribute "SEC_TYPE" "0402V"
					( Origin gFrontEnd )
				)
				( attribute "TOLERANCE" "10%"
					( Origin gFrontEnd )
				)
				( attribute "VALUE" "0.1UF"
					( Origin gFrontEnd )
				)
				( attribute "VER" "1"
					( Origin gFrontEnd )
				)
				( attribute "VOLTAGE" "16V"
					( Units "uVoltage" "V" 1.000000)
					( Origin gFrontEnd )
				)
				( attribute "XY" "(-3200,3450)"
					( Origin gFrontEnd )
				)
				( attribute "CHIPS_PART_NAME" "CAP_A"
					( Origin gPackager )
				)
				( attribute "CDS_PART_NAME" "CAP_A_0402V-0.1UF,16V,10%,X7R,A"
					( Origin gPackager )
				)
				( objectStatus "C2T35" )
			)
			( gate "@baseboard_fab2_lib.baseboard_fab2(sch_1):page156_i275"
				( attribute "BOM_COST" "SM_CONTROLLER"
					( Origin gFrontEnd )
				)
				( attribute "CDS_LIB" "dev_discrete"
					( Origin gPackager )
				)
				( attribute "CDS_LOCATION" "C8F16"
					( Origin gPackager )
				)
				( attribute "CDS_SEC" "1"
					( Origin gPackager )
				)
				( attribute "LOCATION" "C8F16"
					( Origin gFrontEnd )
				)
				( attribute "MATERIAL" "X7R"
					( Origin gFrontEnd )
				)
				( attribute "PACK_TYPE" "0402V"
					( Origin gFrontEnd )
				)
				( attribute "PART_NUMBER" "A36096-030"
					( Origin gFrontEnd )
				)
				( attribute "PHYS_PAGE" "156"
					( Origin gFrontEnd )
				)
				( attribute "ROOM" "BMC_MISC"
					( Origin gFrontEnd )
				)
				( attribute "ROT" "0"
					( Origin gFrontEnd )
				)
				( attribute "SEC" "1"
					( Origin gFrontEnd )
				)
				( attribute "SEC_TYPE" "0402V"
					( Origin gFrontEnd )
				)
				( attribute "TOLERANCE" "10%"
					( Origin gFrontEnd )
				)
				( attribute "VALUE" "0.1UF"
					( Origin gFrontEnd )
				)
				( attribute "VER" "1"
					( Origin gFrontEnd )
				)
				( attribute "VOLTAGE" "16V"
					( Units "uVoltage" "V" 1.000000)
					( Origin gFrontEnd )
				)
				( attribute "XY" "(-3200,4600)"
					( Origin gFrontEnd )
				)
				( attribute "CHIPS_PART_NAME" "CAP_A"
					( Origin gPackager )
				)
				( attribute "CDS_PART_NAME" "CAP_A_0402V-0.1UF,16V,10%,X7R,A"
					( Origin gPackager )
				)
				( objectStatus "C8F16" )
			)
			( gate "@baseboard_fab2_lib.baseboard_fab2(sch_1):page156_i279"
				( attribute "BOM_COST" "SM_CONTROLLER"
					( Origin gFrontEnd )
				)
				( attribute "CDS_LIB" "mstr_discrete"
					( Origin gPackager )
				)
				( attribute "CDS_LOCATION" "R8E11"
					( Origin gPackager )
				)
				( attribute "CDS_SEC" "1"
					( Origin gPackager )
				)
				( attribute "LOCATION" "R8E11"
					( Origin gFrontEnd )
				)
				( attribute "MATERIAL" "EMPTY"
					( Origin gFrontEnd )
				)
				( attribute "PACK_TYPE" "0402"
					( Origin gFrontEnd )
				)
				( attribute "PART_NUMBER" "G21497-005"
					( Origin gFrontEnd )
				)
				( attribute "PHYS_PAGE" "156"
					( Origin gFrontEnd )
				)
				( attribute "ROOM" "BMC_MISC"
					( Origin gFrontEnd )
				)
				( attribute "ROT" "0"
					( Origin gFrontEnd )
				)
				( attribute "SEC" "1"
					( Origin gFrontEnd )
				)
				( attribute "SEC_TYPE" "0402"
					( Origin gFrontEnd )
				)
				( attribute "TOLERANCE" "5%"
					( Origin gFrontEnd )
				)
				( attribute "VALUE" "0.0"
					( Origin gFrontEnd )
				)
				( attribute "VER" "1"
					( Origin gFrontEnd )
				)
				( attribute "WATTAGE" "1/16W"
					( Origin gFrontEnd )
				)
				( attribute "XY" "(-6600,2350)"
					( Origin gFrontEnd )
				)
				( attribute "CHIPS_PART_NAME" "RES"
					( Origin gPackager )
				)
				( attribute "CDS_PART_NAME" "RES_0402-0.0,5%,1/16W,EMPTY,G2A"
					( Origin gPackager )
				)
				( objectStatus "R8E11" )
			)
			( gate "@baseboard_fab2_lib.baseboard_fab2(sch_1):page156_i281"
				( attribute "BOM_COST" "DEBUG"
					( Origin gFrontEnd )
				)
				( attribute "CDS_LIB" "mstr_conn"
					( Origin gPackager )
				)
				( attribute "CDS_LOCATION" "J9B2"
					( Origin gPackager )
				)
				( attribute "CDS_SEC" "1"
					( Origin gPackager )
				)
				( attribute "LOCATION" "J9B2"
					( Origin gFrontEnd )
				)
				( attribute "MATERIAL" "CONN"
					( Origin gFrontEnd )
				)
				( attribute "PACK_TYPE" "PIP"
					( Origin gFrontEnd )
				)
				( attribute "PART_NUMBER" "C95678-002"
					( Origin gFrontEnd )
				)
				( attribute "PHYS_PAGE" "156"
					( Origin gFrontEnd )
				)
				( attribute "ROOM" "DEBUG"
					( Origin gFrontEnd )
				)
				( attribute "ROT" "0"
					( Origin gFrontEnd )
				)
				( attribute "SEC" "1"
					( Origin gFrontEnd )
				)
				( attribute "SEC_TYPE" "PIP"
					( Origin gFrontEnd )
				)
				( attribute "VER" "1"
					( Origin gFrontEnd )
				)
				( attribute "XY" "(-7575,3700)"
					( Origin gFrontEnd )
				)
				( attribute "CHIPS_PART_NAME" "CONN3_C95678002"
					( Origin gPackager )
				)
				( attribute "CDS_PART_NAME" "CONN3_C95678002_PIP-CONN,C9567A"
					( Origin gPackager )
				)
				( attribute "CONFIG" "021.60545.0103"
					( Origin gFrontEnd )
				)
				( objectStatus "J9B2" )
			)
			( gate "@baseboard_fab2_lib.baseboard_fab2(sch_1):page156_i285"
				( attribute "BOM_COST" "DEBUG"
					( Origin gFrontEnd )
				)
				( attribute "CDS_LIB" "mstr_conn"
					( Origin gPackager )
				)
				( attribute "CDS_LOCATION" "J8C1"
					( Origin gPackager )
				)
				( attribute "CDS_SEC" "1"
					( Origin gPackager )
				)
				( attribute "LOCATION" "J8C1"
					( Origin gFrontEnd )
				)
				( attribute "MATERIAL" "CONN"
					( Origin gFrontEnd )
				)
				( attribute "PACK_TYPE" "PIP"
					( Origin gFrontEnd )
				)
				( attribute "PART_NUMBER" "C95678-002"
					( Origin gFrontEnd )
				)
				( attribute "PHYS_PAGE" "156"
					( Origin gFrontEnd )
				)
				( attribute "ROOM" "DEBUG"
					( Origin gFrontEnd )
				)
				( attribute "ROT" "0"
					( Origin gFrontEnd )
				)
				( attribute "SEC" "1"
					( Origin gFrontEnd )
				)
				( attribute "SEC_TYPE" "PIP"
					( Origin gFrontEnd )
				)
				( attribute "VER" "1"
					( Origin gFrontEnd )
				)
				( attribute "XY" "(-7600,4475)"
					( Origin gFrontEnd )
				)
				( attribute "CHIPS_PART_NAME" "CONN3_C95678002"
					( Origin gPackager )
				)
				( attribute "CDS_PART_NAME" "CONN3_C95678002_PIP-CONN,C9567A"
					( Origin gPackager )
				)
				( attribute "CONFIG" "021.60545.0103"
					( Origin gFrontEnd )
				)
				( objectStatus "J8C1" )
			)
			( gate "@baseboard_fab2_lib.baseboard_fab2(sch_1):page156_i288"
				( attribute "BOM_COST" "SM_CONTROLLER"
					( Origin gFrontEnd )
				)
				( attribute "CDS_LIB" "mstr_discrete"
					( Origin gPackager )
				)
				( attribute "CDS_LOCATION" "R2T18"
					( Origin gPackager )
				)
				( attribute "CDS_SEC" "1"
					( Origin gPackager )
				)
				( attribute "LOCATION" "R2T18"
					( Origin gFrontEnd )
				)
				( attribute "MATERIAL" "CHIP"
					( Origin gFrontEnd )
				)
				( attribute "PACK_TYPE" "0402"
					( Origin gFrontEnd )
				)
				( attribute "PART_NUMBER" "G21796-047"
					( Origin gFrontEnd )
				)
				( attribute "PHYS_PAGE" "156"
					( Origin gFrontEnd )
				)
				( attribute "ROOM" "BMC_MISC"
					( Origin gFrontEnd )
				)
				( attribute "ROT" "0"
					( Origin gFrontEnd )
				)
				( attribute "SEC" "1"
					( Origin gFrontEnd )
				)
				( attribute "SEC_TYPE" "0402"
					( Origin gFrontEnd )
				)
				( attribute "TOLERANCE" "1%"
					( Origin gFrontEnd )
				)
				( attribute "VALUE" "49.9"
					( Origin gFrontEnd )
				)
				( attribute "VER" "1"
					( Origin gFrontEnd )
				)
				( attribute "WATTAGE" "1/16W"
					( Origin gFrontEnd )
				)
				( attribute "XY" "(-1700,4200)"
					( Origin gFrontEnd )
				)
				( attribute "CHIPS_PART_NAME" "RES"
					( Origin gPackager )
				)
				( attribute "CDS_PART_NAME" "RES_0402-49.9,1%,1/16W,CHIP,G2A"
					( Origin gPackager )
				)
				( objectStatus "R2T18" )
			)
			( gate "@baseboard_fab2_lib.baseboard_fab2(sch_1):page156_i289"
				( attribute "BOM_COST" "SM_CONTROLLER"
					( Origin gFrontEnd )
				)
				( attribute "CDS_LIB" "mstr_discrete"
					( Origin gPackager )
				)
				( attribute "CDS_LOCATION" "R2T28"
					( Origin gPackager )
				)
				( attribute "CDS_SEC" "1"
					( Origin gPackager )
				)
				( attribute "LOCATION" "R2T28"
					( Origin gFrontEnd )
				)
				( attribute "MATERIAL" "CHIP"
					( Origin gFrontEnd )
				)
				( attribute "PACK_TYPE" "0402"
					( Origin gFrontEnd )
				)
				( attribute "PART_NUMBER" "G21796-074"
					( Origin gFrontEnd )
				)
				( attribute "PHYS_PAGE" "156"
					( Origin gFrontEnd )
				)
				( attribute "ROOM" "BMC_MISC"
					( Origin gFrontEnd )
				)
				( attribute "ROT" "6"
					( Origin gFrontEnd )
				)
				( attribute "SEC" "1"
					( Origin gFrontEnd )
				)
				( attribute "SEC_TYPE" "0402"
					( Origin gFrontEnd )
				)
				( attribute "TOLERANCE" "1%"
					( Origin gFrontEnd )
				)
				( attribute "VALUE" "33.2"
					( Origin gFrontEnd )
				)
				( attribute "VER" "1"
					( Origin gFrontEnd )
				)
				( attribute "WATTAGE" "1/16W"
					( Origin gFrontEnd )
				)
				( attribute "XY" "(-1700,4100)"
					( Origin gFrontEnd )
				)
				( attribute "CHIPS_PART_NAME" "RES"
					( Origin gPackager )
				)
				( attribute "CDS_PART_NAME" "RES_0402-33.2,1%,1/16W,CHIP,G2A"
					( Origin gPackager )
				)
				( objectStatus "R2T28" )
			)
			( gate "@baseboard_fab2_lib.baseboard_fab2(sch_1):page156_i299"
				( attribute "BOM_COST" "SM_CONTROLLER"
					( Origin gFrontEnd )
				)
				( attribute "CDS_LIB" "mstr_discrete"
					( Origin gPackager )
				)
				( attribute "CDS_LOCATION" "R6D16"
					( Origin gPackager )
				)
				( attribute "CDS_SEC" "1"
					( Origin gPackager )
				)
				( attribute "LOCATION" "R6D16"
					( Origin gFrontEnd )
				)
				( attribute "MATERIAL" "EMPTY"
					( Origin gFrontEnd )
				)
				( attribute "PACK_TYPE" "0402"
					( Origin gFrontEnd )
				)
				( attribute "PART_NUMBER" "G21497-005"
					( Origin gFrontEnd )
				)
				( attribute "PHYS_PAGE" "156"
					( Origin gFrontEnd )
				)
				( attribute "ROOM" "BMC_MISC"
					( Origin gFrontEnd )
				)
				( attribute "ROT" "0"
					( Origin gFrontEnd )
				)
				( attribute "SEC" "1"
					( Origin gFrontEnd )
				)
				( attribute "SEC_TYPE" "0402"
					( Origin gFrontEnd )
				)
				( attribute "TOLERANCE" "5%"
					( Origin gFrontEnd )
				)
				( attribute "VALUE" "0.0"
					( Origin gFrontEnd )
				)
				( attribute "VER" "1"
					( Origin gFrontEnd )
				)
				( attribute "WATTAGE" "1/16W"
					( Origin gFrontEnd )
				)
				( attribute "XY" "(-2900,1825)"
					( Origin gFrontEnd )
				)
				( attribute "CHIPS_PART_NAME" "RES"
					( Origin gPackager )
				)
				( attribute "CDS_PART_NAME" "RES_0402-0.0,5%,1/16W,EMPTY,G2A"
					( Origin gPackager )
				)
				( objectStatus "R6D16" )
			)
			( gate "@baseboard_fab2_lib.baseboard_fab2(sch_1):page156_i300"
				( attribute "BOM_COST" "SM_CONTROLLER"
					( Origin gFrontEnd )
				)
				( attribute "CDS_LIB" "mstr_discrete"
					( Origin gPackager )
				)
				( attribute "CDS_LOCATION" "R3D31"
					( Origin gPackager )
				)
				( attribute "CDS_SEC" "1"
					( Origin gPackager )
				)
				( attribute "LOCATION" "R3D31"
					( Origin gFrontEnd )
				)
				( attribute "MATERIAL" "EMPTY"
					( Origin gFrontEnd )
				)
				( attribute "PACK_TYPE" "0402"
					( Origin gFrontEnd )
				)
				( attribute "PART_NUMBER" "G21497-005"
					( Origin gFrontEnd )
				)
				( attribute "PHYS_PAGE" "156"
					( Origin gFrontEnd )
				)
				( attribute "ROOM" "BMC_MISC"
					( Origin gFrontEnd )
				)
				( attribute "ROT" "0"
					( Origin gFrontEnd )
				)
				( attribute "SEC" "1"
					( Origin gFrontEnd )
				)
				( attribute "SEC_TYPE" "0402"
					( Origin gFrontEnd )
				)
				( attribute "TOLERANCE" "5%"
					( Origin gFrontEnd )
				)
				( attribute "VALUE" "0.0"
					( Origin gFrontEnd )
				)
				( attribute "VER" "1"
					( Origin gFrontEnd )
				)
				( attribute "WATTAGE" "1/16W"
					( Origin gFrontEnd )
				)
				( attribute "XY" "(-2900,1550)"
					( Origin gFrontEnd )
				)
				( attribute "CHIPS_PART_NAME" "RES"
					( Origin gPackager )
				)
				( attribute "CDS_PART_NAME" "RES_0402-0.0,5%,1/16W,EMPTY,G2A"
					( Origin gPackager )
				)
				( objectStatus "R3D31" )
			)
			( gate "@baseboard_fab2_lib.baseboard_fab2(sch_1):page156_i302"
				( attribute "CDS_LIB" "mstr_discrete"
					( Origin gPackager )
				)
				( attribute "CDS_LOCATION" "R6N14"
					( Origin gPackager )
				)
				( attribute "CDS_SEC" "1"
					( Origin gPackager )
				)
				( attribute "LOCATION" "R6N14"
					( Origin gFrontEnd )
				)
				( attribute "MATERIAL" "CHIP"
					( Origin gFrontEnd )
				)
				( attribute "PACK_TYPE" "0402"
					( Origin gFrontEnd )
				)
				( attribute "PART_NUMBER" "G21796-026"
					( Origin gFrontEnd )
				)
				( attribute "PHYS_PAGE" "156"
					( Origin gFrontEnd )
				)
				( attribute "ROOM" "CPU0"
					( Origin gFrontEnd )
				)
				( attribute "ROT" "0"
					( Origin gFrontEnd )
				)
				( attribute "SEC" "1"
					( Origin gFrontEnd )
				)
				( attribute "SEC_TYPE" "0402"
					( Origin gFrontEnd )
				)
				( attribute "TOLERANCE" "1%"
					( Origin gFrontEnd )
				)
				( attribute "VALUE" "1.00K"
					( Origin gFrontEnd )
				)
				( attribute "VER" "1"
					( Origin gFrontEnd )
				)
				( attribute "WATTAGE" "1/16W"
					( Origin gFrontEnd )
				)
				( attribute "XY" "(-4000,975)"
					( Origin gFrontEnd )
				)
				( attribute "CHIPS_PART_NAME" "RES"
					( Origin gPackager )
				)
				( attribute "CDS_PART_NAME" "RES_0402-1.00K,1%,1/16W,CHIP,GA"
					( Origin gPackager )
				)
				( objectStatus "R6N14" )
			)
			( gate "@baseboard_fab2_lib.baseboard_fab2(sch_1):page156_i303"
				( attribute "CDS_LIB" "mstr_discrete"
					( Origin gPackager )
				)
				( attribute "CDS_LOCATION" "R6N13"
					( Origin gPackager )
				)
				( attribute "CDS_SEC" "1"
					( Origin gPackager )
				)
				( attribute "LOCATION" "R6N13"
					( Origin gFrontEnd )
				)
				( attribute "MATERIAL" "CHIP"
					( Origin gFrontEnd )
				)
				( attribute "PACK_TYPE" "0402"
					( Origin gFrontEnd )
				)
				( attribute "PART_NUMBER" "G21796-026"
					( Origin gFrontEnd )
				)
				( attribute "PHYS_PAGE" "156"
					( Origin gFrontEnd )
				)
				( attribute "ROOM" "CPU0"
					( Origin gFrontEnd )
				)
				( attribute "ROT" "0"
					( Origin gFrontEnd )
				)
				( attribute "SEC" "1"
					( Origin gFrontEnd )
				)
				( attribute "SEC_TYPE" "0402"
					( Origin gFrontEnd )
				)
				( attribute "TOLERANCE" "1%"
					( Origin gFrontEnd )
				)
				( attribute "VALUE" "1.00K"
					( Origin gFrontEnd )
				)
				( attribute "VER" "1"
					( Origin gFrontEnd )
				)
				( attribute "WATTAGE" "1/16W"
					( Origin gFrontEnd )
				)
				( attribute "XY" "(-4000,775)"
					( Origin gFrontEnd )
				)
				( attribute "CHIPS_PART_NAME" "RES"
					( Origin gPackager )
				)
				( attribute "CDS_PART_NAME" "RES_0402-1.00K,1%,1/16W,CHIP,GA"
					( Origin gPackager )
				)
				( objectStatus "R6N13" )
			)
			( gate "@baseboard_fab2_lib.baseboard_fab2(sch_1):page156_i304"
				( attribute "CDS_LIB" "mstr_discrete"
					( Origin gPackager )
				)
				( attribute "CDS_LOCATION" "R6N15"
					( Origin gPackager )
				)
				( attribute "CDS_SEC" "1"
					( Origin gPackager )
				)
				( attribute "LOCATION" "R6N15"
					( Origin gFrontEnd )
				)
				( attribute "MATERIAL" "CHIP"
					( Origin gFrontEnd )
				)
				( attribute "PACK_TYPE" "0402"
					( Origin gFrontEnd )
				)
				( attribute "PART_NUMBER" "G21796-026"
					( Origin gFrontEnd )
				)
				( attribute "PHYS_PAGE" "156"
					( Origin gFrontEnd )
				)
				( attribute "ROOM" "CPU0"
					( Origin gFrontEnd )
				)
				( attribute "ROT" "0"
					( Origin gFrontEnd )
				)
				( attribute "SEC" "1"
					( Origin gFrontEnd )
				)
				( attribute "SEC_TYPE" "0402"
					( Origin gFrontEnd )
				)
				( attribute "TOLERANCE" "1%"
					( Origin gFrontEnd )
				)
				( attribute "VALUE" "1.00K"
					( Origin gFrontEnd )
				)
				( attribute "VER" "1"
					( Origin gFrontEnd )
				)
				( attribute "WATTAGE" "1/16W"
					( Origin gFrontEnd )
				)
				( attribute "XY" "(-4000,575)"
					( Origin gFrontEnd )
				)
				( attribute "CHIPS_PART_NAME" "RES"
					( Origin gPackager )
				)
				( attribute "CDS_PART_NAME" "RES_0402-1.00K,1%,1/16W,CHIP,GA"
					( Origin gPackager )
				)
				( objectStatus "R6N15" )
			)
			( gate "@baseboard_fab2_lib.baseboard_fab2(sch_1):page156_i312"
				( attribute "CDS_LIB" "mstr_discrete"
					( Origin gPackager )
				)
				( attribute "CDS_LOCATION" "R1C32"
					( Origin gPackager )
				)
				( attribute "CDS_SEC" "1"
					( Origin gPackager )
				)
				( attribute "LOCATION" "R1C32"
					( Origin gFrontEnd )
				)
				( attribute "MATERIAL" "CHIP"
					( Origin gFrontEnd )
				)
				( attribute "PACK_TYPE" "0402"
					( Origin gFrontEnd )
				)
				( attribute "PART_NUMBER" "G21796-026"
					( Origin gFrontEnd )
				)
				( attribute "PHYS_PAGE" "156"
					( Origin gFrontEnd )
				)
				( attribute "ROOM" "CPU1"
					( Origin gFrontEnd )
				)
				( attribute "ROT" "0"
					( Origin gFrontEnd )
				)
				( attribute "SEC" "1"
					( Origin gFrontEnd )
				)
				( attribute "SEC_TYPE" "0402"
					( Origin gFrontEnd )
				)
				( attribute "TOLERANCE" "1%"
					( Origin gFrontEnd )
				)
				( attribute "VALUE" "1.00K"
					( Origin gFrontEnd )
				)
				( attribute "VER" "1"
					( Origin gFrontEnd )
				)
				( attribute "WATTAGE" "1/16W"
					( Origin gFrontEnd )
				)
				( attribute "XY" "(-1900,575)"
					( Origin gFrontEnd )
				)
				( attribute "CHIPS_PART_NAME" "RES"
					( Origin gPackager )
				)
				( attribute "CDS_PART_NAME" "RES_0402-1.00K,1%,1/16W,CHIP,GA"
					( Origin gPackager )
				)
				( objectStatus "R1C32" )
			)
			( gate "@baseboard_fab2_lib.baseboard_fab2(sch_1):page156_i313"
				( attribute "CDS_LIB" "mstr_discrete"
					( Origin gPackager )
				)
				( attribute "CDS_LOCATION" "R1C33"
					( Origin gPackager )
				)
				( attribute "CDS_SEC" "1"
					( Origin gPackager )
				)
				( attribute "LOCATION" "R1C33"
					( Origin gFrontEnd )
				)
				( attribute "MATERIAL" "CHIP"
					( Origin gFrontEnd )
				)
				( attribute "PACK_TYPE" "0402"
					( Origin gFrontEnd )
				)
				( attribute "PART_NUMBER" "G21796-026"
					( Origin gFrontEnd )
				)
				( attribute "PHYS_PAGE" "156"
					( Origin gFrontEnd )
				)
				( attribute "ROOM" "CPU1"
					( Origin gFrontEnd )
				)
				( attribute "ROT" "0"
					( Origin gFrontEnd )
				)
				( attribute "SEC" "1"
					( Origin gFrontEnd )
				)
				( attribute "SEC_TYPE" "0402"
					( Origin gFrontEnd )
				)
				( attribute "TOLERANCE" "1%"
					( Origin gFrontEnd )
				)
				( attribute "VALUE" "1.00K"
					( Origin gFrontEnd )
				)
				( attribute "VER" "1"
					( Origin gFrontEnd )
				)
				( attribute "WATTAGE" "1/16W"
					( Origin gFrontEnd )
				)
				( attribute "XY" "(-1900,775)"
					( Origin gFrontEnd )
				)
				( attribute "CHIPS_PART_NAME" "RES"
					( Origin gPackager )
				)
				( attribute "CDS_PART_NAME" "RES_0402-1.00K,1%,1/16W,CHIP,GA"
					( Origin gPackager )
				)
				( objectStatus "R1C33" )
			)
			( gate "@baseboard_fab2_lib.baseboard_fab2(sch_1):page156_i320"
				( attribute "CDS_LIB" "mstr_discrete"
					( Origin gPackager )
				)
				( attribute "CDS_LOCATION" "R1C34"
					( Origin gPackager )
				)
				( attribute "CDS_SEC" "1"
					( Origin gPackager )
				)
				( attribute "LOCATION" "R1C34"
					( Origin gFrontEnd )
				)
				( attribute "MATERIAL" "CHIP"
					( Origin gFrontEnd )
				)
				( attribute "PACK_TYPE" "0402"
					( Origin gFrontEnd )
				)
				( attribute "PART_NUMBER" "G21796-016"
					( Origin gFrontEnd )
				)
				( attribute "PHYS_PAGE" "156"
					( Origin gFrontEnd )
				)
				( attribute "ROOM" "CPU1"
					( Origin gFrontEnd )
				)
				( attribute "ROT" "0"
					( Origin gFrontEnd )
				)
				( attribute "SEC" "1"
					( Origin gFrontEnd )
				)
				( attribute "SEC_TYPE" "0402"
					( Origin gFrontEnd )
				)
				( attribute "TOLERANCE" "1%"
					( Origin gFrontEnd )
				)
				( attribute "VALUE" "10.0K"
					( Origin gFrontEnd )
				)
				( attribute "VER" "1"
					( Origin gFrontEnd )
				)
				( attribute "WATTAGE" "1/16W"
					( Origin gFrontEnd )
				)
				( attribute "XY" "(-1900,975)"
					( Origin gFrontEnd )
				)
				( attribute "CHIPS_PART_NAME" "RES"
					( Origin gPackager )
				)
				( attribute "CDS_PART_NAME" "RES_0402-10.0K,1%,1/16W,CHIP,GA"
					( Origin gPackager )
				)
				( objectStatus "R1C34" )
			)
			( gate "@baseboard_fab2_lib.baseboard_fab2(sch_1):page156_i321"
				( attribute "CDS_LIB" "mstr_discrete"
					( Origin gPackager )
				)
				( attribute "CDS_LOCATION" "R9M21"
					( Origin gPackager )
				)
				( attribute "CDS_SEC" "1"
					( Origin gPackager )
				)
				( attribute "LOCATION" "R9M21"
					( Origin gFrontEnd )
				)
				( attribute "MATERIAL" "CHIP"
					( Origin gFrontEnd )
				)
				( attribute "PACK_TYPE" "0402"
					( Origin gFrontEnd )
				)
				( attribute "PART_NUMBER" "G21497-005"
					( Origin gFrontEnd )
				)
				( attribute "PHYS_PAGE" "156"
					( Origin gFrontEnd )
				)
				( attribute "ROOM" "CPU1"
					( Origin gFrontEnd )
				)
				( attribute "ROT" "0"
					( Origin gFrontEnd )
				)
				( attribute "SEC" "1"
					( Origin gFrontEnd )
				)
				( attribute "SEC_TYPE" "0402"
					( Origin gFrontEnd )
				)
				( attribute "TOLERANCE" "5%"
					( Origin gFrontEnd )
				)
				( attribute "VALUE" "0.0"
					( Origin gFrontEnd )
				)
				( attribute "VER" "1"
					( Origin gFrontEnd )
				)
				( attribute "WATTAGE" "1/16W"
					( Origin gFrontEnd )
				)
				( attribute "XY" "(-6425,850)"
					( Origin gFrontEnd )
				)
				( attribute "CHIPS_PART_NAME" "RES"
					( Origin gPackager )
				)
				( attribute "CDS_PART_NAME" "RES_0402-0.0,5%,1/16W,CHIP,G21A"
					( Origin gPackager )
				)
				( objectStatus "R9M21" )
			)
			( gate "@baseboard_fab2_lib.baseboard_fab2(sch_1):page156_i322"
				( attribute "CDS_LIB" "mstr_discrete"
					( Origin gPackager )
				)
				( attribute "CDS_LOCATION" "R4A8"
					( Origin gPackager )
				)
				( attribute "CDS_SEC" "1"
					( Origin gPackager )
				)
				( attribute "LOCATION" "R4A8"
					( Origin gFrontEnd )
				)
				( attribute "MATERIAL" "CHIP"
					( Origin gFrontEnd )
				)
				( attribute "PACK_TYPE" "0402"
					( Origin gFrontEnd )
				)
				( attribute "PART_NUMBER" "G21497-005"
					( Origin gFrontEnd )
				)
				( attribute "PHYS_PAGE" "156"
					( Origin gFrontEnd )
				)
				( attribute "ROOM" "CPU0"
					( Origin gFrontEnd )
				)
				( attribute "ROT" "0"
					( Origin gFrontEnd )
				)
				( attribute "SEC" "1"
					( Origin gFrontEnd )
				)
				( attribute "SEC_TYPE" "0402"
					( Origin gFrontEnd )
				)
				( attribute "TOLERANCE" "5%"
					( Origin gFrontEnd )
				)
				( attribute "VALUE" "0.0"
					( Origin gFrontEnd )
				)
				( attribute "VER" "1"
					( Origin gFrontEnd )
				)
				( attribute "WATTAGE" "1/16W"
					( Origin gFrontEnd )
				)
				( attribute "XY" "(-6425,700)"
					( Origin gFrontEnd )
				)
				( attribute "CHIPS_PART_NAME" "RES"
					( Origin gPackager )
				)
				( attribute "CDS_PART_NAME" "RES_0402-0.0,5%,1/16W,CHIP,G21A"
					( Origin gPackager )
				)
				( objectStatus "R4A8" )
			)
			( gate "@baseboard_fab2_lib.baseboard_fab2(sch_1):page156_i323"
				( attribute "CDS_LIB" "mstr_discrete"
					( Origin gPackager )
				)
				( attribute "CDS_LOCATION" "R9M20"
					( Origin gPackager )
				)
				( attribute "CDS_SEC" "1"
					( Origin gPackager )
				)
				( attribute "LOCATION" "R9M20"
					( Origin gFrontEnd )
				)
				( attribute "MATERIAL" "CHIP"
					( Origin gFrontEnd )
				)
				( attribute "PACK_TYPE" "0402"
					( Origin gFrontEnd )
				)
				( attribute "PART_NUMBER" "G21497-005"
					( Origin gFrontEnd )
				)
				( attribute "PHYS_PAGE" "156"
					( Origin gFrontEnd )
				)
				( attribute "ROOM" "CPU1"
					( Origin gFrontEnd )
				)
				( attribute "ROT" "0"
					( Origin gFrontEnd )
				)
				( attribute "SEC" "1"
					( Origin gFrontEnd )
				)
				( attribute "SEC_TYPE" "0402"
					( Origin gFrontEnd )
				)
				( attribute "TOLERANCE" "5%"
					( Origin gFrontEnd )
				)
				( attribute "VALUE" "0.0"
					( Origin gFrontEnd )
				)
				( attribute "VER" "1"
					( Origin gFrontEnd )
				)
				( attribute "WATTAGE" "1/16W"
					( Origin gFrontEnd )
				)
				( attribute "XY" "(-6425,550)"
					( Origin gFrontEnd )
				)
				( attribute "CHIPS_PART_NAME" "RES"
					( Origin gPackager )
				)
				( attribute "CDS_PART_NAME" "RES_0402-0.0,5%,1/16W,CHIP,G21A"
					( Origin gPackager )
				)
				( objectStatus "R9M20" )
			)
			( gate "@baseboard_fab2_lib.baseboard_fab2(sch_1):page156_i324"
				( attribute "CDS_LIB" "mstr_discrete"
					( Origin gPackager )
				)
				( attribute "CDS_LOCATION" "R4A9"
					( Origin gPackager )
				)
				( attribute "CDS_SEC" "1"
					( Origin gPackager )
				)
				( attribute "LOCATION" "R4A9"
					( Origin gFrontEnd )
				)
				( attribute "MATERIAL" "CHIP"
					( Origin gFrontEnd )
				)
				( attribute "PACK_TYPE" "0402"
					( Origin gFrontEnd )
				)
				( attribute "PART_NUMBER" "G21497-005"
					( Origin gFrontEnd )
				)
				( attribute "PHYS_PAGE" "156"
					( Origin gFrontEnd )
				)
				( attribute "ROOM" "CPU0"
					( Origin gFrontEnd )
				)
				( attribute "ROT" "0"
					( Origin gFrontEnd )
				)
				( attribute "SEC" "1"
					( Origin gFrontEnd )
				)
				( attribute "SEC_TYPE" "0402"
					( Origin gFrontEnd )
				)
				( attribute "TOLERANCE" "5%"
					( Origin gFrontEnd )
				)
				( attribute "VALUE" "0.0"
					( Origin gFrontEnd )
				)
				( attribute "VER" "1"
					( Origin gFrontEnd )
				)
				( attribute "WATTAGE" "1/16W"
					( Origin gFrontEnd )
				)
				( attribute "XY" "(-6425,400)"
					( Origin gFrontEnd )
				)
				( attribute "CHIPS_PART_NAME" "RES"
					( Origin gPackager )
				)
				( attribute "CDS_PART_NAME" "RES_0402-0.0,5%,1/16W,CHIP,G21A"
					( Origin gPackager )
				)
				( objectStatus "R4A9" )
			)
			( gate "@baseboard_fab2_lib.baseboard_fab2(sch_1):page156_i331"
				( attribute "CDS_LIB" "mstr_discrete"
					( Origin gPackager )
				)
				( attribute "CDS_LOCATION" "R3P54"
					( Origin gPackager )
				)
				( attribute "CDS_SEC" "1"
					( Origin gPackager )
				)
				( attribute "LOCATION" "R3P54"
					( Origin gFrontEnd )
				)
				( attribute "MATERIAL" "EMPTY"
					( Origin gFrontEnd )
				)
				( attribute "PACK_TYPE" "0402"
					( Origin gFrontEnd )
				)
				( attribute "PART_NUMBER" "G21796-027"
					( Origin gFrontEnd )
				)
				( attribute "PHYS_PAGE" "156"
					( Origin gFrontEnd )
				)
				( attribute "ROOM" "CPU0"
					( Origin gFrontEnd )
				)
				( attribute "ROT" "0"
					( Origin gFrontEnd )
				)
				( attribute "SEC" "1"
					( Origin gFrontEnd )
				)
				( attribute "SEC_TYPE" "0402"
					( Origin gFrontEnd )
				)
				( attribute "TOLERANCE" "1%"
					( Origin gFrontEnd )
				)
				( attribute "VALUE" "3.32K"
					( Origin gFrontEnd )
				)
				( attribute "VER" "2"
					( Origin gFrontEnd )
				)
				( attribute "WATTAGE" "1/16W"
					( Origin gFrontEnd )
				)
				( attribute "XY" "(-7650,1700)"
					( Origin gFrontEnd )
				)
				( attribute "CHIPS_PART_NAME" "RES"
					( Origin gPackager )
				)
				( attribute "CDS_PART_NAME" "RES_0402-3.32K,1%,1/16W,EMPTY,A"
					( Origin gPackager )
				)
				( objectStatus "R3P54" )
			)
			( gate "@baseboard_fab2_lib.baseboard_fab2(sch_1):page156_i333"
				( attribute "CDS_LIB" "mstr_discrete"
					( Origin gPackager )
				)
				( attribute "CDS_LOCATION" "R3P56"
					( Origin gPackager )
				)
				( attribute "CDS_SEC" "1"
					( Origin gPackager )
				)
				( attribute "LOCATION" "R3P56"
					( Origin gFrontEnd )
				)
				( attribute "MATERIAL" "CHIP"
					( Origin gFrontEnd )
				)
				( attribute "PACK_TYPE" "0402"
					( Origin gFrontEnd )
				)
				( attribute "PART_NUMBER" "G21796-026"
					( Origin gFrontEnd )
				)
				( attribute "PHYS_PAGE" "156"
					( Origin gFrontEnd )
				)
				( attribute "ROOM" "CPU0"
					( Origin gFrontEnd )
				)
				( attribute "ROT" "0"
					( Origin gFrontEnd )
				)
				( attribute "SEC" "1"
					( Origin gFrontEnd )
				)
				( attribute "SEC_TYPE" "0402"
					( Origin gFrontEnd )
				)
				( attribute "TOLERANCE" "1%"
					( Origin gFrontEnd )
				)
				( attribute "VALUE" "1.00K"
					( Origin gFrontEnd )
				)
				( attribute "VER" "2"
					( Origin gFrontEnd )
				)
				( attribute "WATTAGE" "1/16W"
					( Origin gFrontEnd )
				)
				( attribute "XY" "(-7650,1325)"
					( Origin gFrontEnd )
				)
				( attribute "CHIPS_PART_NAME" "RES"
					( Origin gPackager )
				)
				( attribute "CDS_PART_NAME" "RES_0402-1.00K,1%,1/16W,CHIP,GA"
					( Origin gPackager )
				)
				( objectStatus "R3P56" )
			)
			( gate "@baseboard_fab2_lib.baseboard_fab2(sch_1):page156_i336"
				( attribute "CDS_LIB" "mstr_discrete"
					( Origin gPackager )
				)
				( attribute "CDS_LOCATION" "R1C35"
					( Origin gPackager )
				)
				( attribute "CDS_SEC" "1"
					( Origin gPackager )
				)
				( attribute "LOCATION" "R1C35"
					( Origin gFrontEnd )
				)
				( attribute "MATERIAL" "EMPTY"
					( Origin gFrontEnd )
				)
				( attribute "PACK_TYPE" "0402"
					( Origin gFrontEnd )
				)
				( attribute "PART_NUMBER" "G21796-027"
					( Origin gFrontEnd )
				)
				( attribute "PHYS_PAGE" "156"
					( Origin gFrontEnd )
				)
				( attribute "ROOM" "CPU1"
					( Origin gFrontEnd )
				)
				( attribute "ROT" "0"
					( Origin gFrontEnd )
				)
				( attribute "SEC" "1"
					( Origin gFrontEnd )
				)
				( attribute "SEC_TYPE" "0402"
					( Origin gFrontEnd )
				)
				( attribute "TOLERANCE" "1%"
					( Origin gFrontEnd )
				)
				( attribute "VALUE" "3.32K"
					( Origin gFrontEnd )
				)
				( attribute "VER" "2"
					( Origin gFrontEnd )
				)
				( attribute "WATTAGE" "1/16W"
					( Origin gFrontEnd )
				)
				( attribute "XY" "(-6025,1725)"
					( Origin gFrontEnd )
				)
				( attribute "CHIPS_PART_NAME" "RES"
					( Origin gPackager )
				)
				( attribute "CDS_PART_NAME" "RES_0402-3.32K,1%,1/16W,EMPTY,A"
					( Origin gPackager )
				)
				( objectStatus "R1C35" )
			)
			( gate "@baseboard_fab2_lib.baseboard_fab2(sch_1):page156_i337"
				( attribute "CDS_LIB" "mstr_discrete"
					( Origin gPackager )
				)
				( attribute "CDS_LOCATION" "R1C36"
					( Origin gPackager )
				)
				( attribute "CDS_SEC" "1"
					( Origin gPackager )
				)
				( attribute "LOCATION" "R1C36"
					( Origin gFrontEnd )
				)
				( attribute "MATERIAL" "CHIP"
					( Origin gFrontEnd )
				)
				( attribute "PACK_TYPE" "0402"
					( Origin gFrontEnd )
				)
				( attribute "PART_NUMBER" "G21796-026"
					( Origin gFrontEnd )
				)
				( attribute "PHYS_PAGE" "156"
					( Origin gFrontEnd )
				)
				( attribute "ROOM" "CPU1"
					( Origin gFrontEnd )
				)
				( attribute "ROT" "0"
					( Origin gFrontEnd )
				)
				( attribute "SEC" "1"
					( Origin gFrontEnd )
				)
				( attribute "SEC_TYPE" "0402"
					( Origin gFrontEnd )
				)
				( attribute "TOLERANCE" "1%"
					( Origin gFrontEnd )
				)
				( attribute "VALUE" "1.00K"
					( Origin gFrontEnd )
				)
				( attribute "VER" "2"
					( Origin gFrontEnd )
				)
				( attribute "WATTAGE" "1/16W"
					( Origin gFrontEnd )
				)
				( attribute "XY" "(-6025,1350)"
					( Origin gFrontEnd )
				)
				( attribute "CHIPS_PART_NAME" "RES"
					( Origin gPackager )
				)
				( attribute "CDS_PART_NAME" "RES_0402-1.00K,1%,1/16W,CHIP,GA"
					( Origin gPackager )
				)
				( objectStatus "R1C36" )
			)
			( gate "@baseboard_fab2_lib.baseboard_fab2(sch_1):page157_i97"
				( attribute "BOM_COST" "SM_CONTROLLER"
					( Origin gFrontEnd )
				)
				( attribute "CDS_LIB" "mstr_discrete"
					( Origin gPackager )
				)
				( attribute "CDS_LOCATION" "R2N27"
					( Origin gPackager )
				)
				( attribute "CDS_SEC" "1"
					( Origin gPackager )
				)
				( attribute "LOCATION" "R2N27"
					( Origin gFrontEnd )
				)
				( attribute "MATERIAL" "CHIP"
					( Origin gFrontEnd )
				)
				( attribute "PACK_TYPE" "0402"
					( Origin gFrontEnd )
				)
				( attribute "PART_NUMBER" "G21796-072"
					( Origin gFrontEnd )
				)
				( attribute "PHYS_PAGE" "157"
					( Origin gFrontEnd )
				)
				( attribute "ROOM" "BMC_MISC"
					( Origin gFrontEnd )
				)
				( attribute "ROT" "0"
					( Origin gFrontEnd )
				)
				( attribute "SEC" "1"
					( Origin gFrontEnd )
				)
				( attribute "SEC_TYPE" "0402"
					( Origin gFrontEnd )
				)
				( attribute "TOLERANCE" "1%"
					( Origin gFrontEnd )
				)
				( attribute "VALUE" "4.75K"
					( Origin gFrontEnd )
				)
				( attribute "VER" "2"
					( Origin gFrontEnd )
				)
				( attribute "WATTAGE" "1/16W"
					( Origin gFrontEnd )
				)
				( attribute "XY" "(-1850,4025)"
					( Origin gFrontEnd )
				)
				( attribute "CHIPS_PART_NAME" "RES"
					( Origin gPackager )
				)
				( attribute "CDS_PART_NAME" "RES_0402-4.75K,1%,1/16W,CHIP,GA"
					( Origin gPackager )
				)
				( objectStatus "R2N27" )
			)
			( gate "@baseboard_fab2_lib.baseboard_fab2(sch_1):page157_i296"
				( attribute "BOM_COST" "SM_CONTROLLER"
					( Origin gFrontEnd )
				)
				( attribute "CDS_LIB" "mstr_discrete"
					( Origin gPackager )
				)
				( attribute "CDS_LOCATION" "R8F23"
					( Origin gPackager )
				)
				( attribute "CDS_SEC" "1"
					( Origin gPackager )
				)
				( attribute "LOCATION" "R8F23"
					( Origin gFrontEnd )
				)
				( attribute "MATERIAL" "CHIP"
					( Origin gFrontEnd )
				)
				( attribute "PACK_TYPE" "0402"
					( Origin gFrontEnd )
				)
				( attribute "PART_NUMBER" "G21796-112"
					( Origin gFrontEnd )
				)
				( attribute "PHYS_PAGE" "157"
					( Origin gFrontEnd )
				)
				( attribute "ROOM" "BMC_MISC"
					( Origin gFrontEnd )
				)
				( attribute "ROT" "0"
					( Origin gFrontEnd )
				)
				( attribute "SEC" "1"
					( Origin gFrontEnd )
				)
				( attribute "SEC_TYPE" "0402"
					( Origin gFrontEnd )
				)
				( attribute "TOLERANCE" "1%"
					( Origin gFrontEnd )
				)
				( attribute "VALUE" "2.21K"
					( Origin gFrontEnd )
				)
				( attribute "VER" "1"
					( Origin gFrontEnd )
				)
				( attribute "WATTAGE" "1/16W"
					( Origin gFrontEnd )
				)
				( attribute "XY" "(-7200,4225)"
					( Origin gFrontEnd )
				)
				( attribute "CHIPS_PART_NAME" "RES"
					( Origin gPackager )
				)
				( attribute "CDS_PART_NAME" "RES_0402-2.21K,1%,1/16W,CHIP,GA"
					( Origin gPackager )
				)
				( objectStatus "R8F23" )
			)
			( gate "@baseboard_fab2_lib.baseboard_fab2(sch_1):page157_i298"
				( attribute "BOM_COST" "SM_CONTROLLER"
					( Origin gFrontEnd )
				)
				( attribute "CDS_LIB" "mstr_discrete"
					( Origin gPackager )
				)
				( attribute "CDS_LOCATION" "R2T29"
					( Origin gPackager )
				)
				( attribute "CDS_SEC" "1"
					( Origin gPackager )
				)
				( attribute "LOCATION" "R2T29"
					( Origin gFrontEnd )
				)
				( attribute "MATERIAL" "CHIP"
					( Origin gFrontEnd )
				)
				( attribute "PACK_TYPE" "0402"
					( Origin gFrontEnd )
				)
				( attribute "PART_NUMBER" "G21796-112"
					( Origin gFrontEnd )
				)
				( attribute "PHYS_PAGE" "157"
					( Origin gFrontEnd )
				)
				( attribute "ROOM" "BMC_MISC"
					( Origin gFrontEnd )
				)
				( attribute "ROT" "0"
					( Origin gFrontEnd )
				)
				( attribute "SEC" "1"
					( Origin gFrontEnd )
				)
				( attribute "SEC_TYPE" "0402"
					( Origin gFrontEnd )
				)
				( attribute "TOLERANCE" "1%"
					( Origin gFrontEnd )
				)
				( attribute "VALUE" "2.21K"
					( Origin gFrontEnd )
				)
				( attribute "VER" "1"
					( Origin gFrontEnd )
				)
				( attribute "WATTAGE" "1/16W"
					( Origin gFrontEnd )
				)
				( attribute "XY" "(-7175,3975)"
					( Origin gFrontEnd )
				)
				( attribute "CHIPS_PART_NAME" "RES"
					( Origin gPackager )
				)
				( attribute "CDS_PART_NAME" "RES_0402-2.21K,1%,1/16W,CHIP,GA"
					( Origin gPackager )
				)
				( objectStatus "R2T29" )
			)
			( gate "@baseboard_fab2_lib.baseboard_fab2(sch_1):page157_i302"
				( attribute "BOM_COST" "SM_CONTROLLER"
					( Origin gFrontEnd )
				)
				( attribute "CDS_LIB" "mstr_discrete"
					( Origin gPackager )
				)
				( attribute "CDS_LOCATION" "R2N25"
					( Origin gPackager )
				)
				( attribute "CDS_SEC" "1"
					( Origin gPackager )
				)
				( attribute "LOCATION" "R2N25"
					( Origin gFrontEnd )
				)
				( attribute "MATERIAL" "CHIP"
					( Origin gFrontEnd )
				)
				( attribute "PACK_TYPE" "0402"
					( Origin gFrontEnd )
				)
				( attribute "PART_NUMBER" "G21796-208"
					( Origin gFrontEnd )
				)
				( attribute "PHYS_PAGE" "157"
					( Origin gFrontEnd )
				)
				( attribute "ROOM" "BMC_MISC"
					( Origin gFrontEnd )
				)
				( attribute "ROT" "0"
					( Origin gFrontEnd )
				)
				( attribute "SEC" "1"
					( Origin gFrontEnd )
				)
				( attribute "SEC_TYPE" "0402"
					( Origin gFrontEnd )
				)
				( attribute "TOLERANCE" "1.0%"
					( Origin gFrontEnd )
				)
				( attribute "VALUE" "51.1"
					( Origin gFrontEnd )
				)
				( attribute "VER" "1"
					( Origin gFrontEnd )
				)
				( attribute "WATTAGE" "1/16W"
					( Origin gFrontEnd )
				)
				( attribute "XY" "(-2050,3825)"
					( Origin gFrontEnd )
				)
				( attribute "CHIPS_PART_NAME" "RES"
					( Origin gPackager )
				)
				( attribute "CDS_PART_NAME" "RES_0402-51.1,1.0%,1/16W,CHIP,A"
					( Origin gPackager )
				)
				( objectStatus "R2N25" )
			)
			( gate "@baseboard_fab2_lib.baseboard_fab2(sch_1):page157_i316"
				( attribute "BOM_COST" "SM_CONTROLLER"
					( Origin gFrontEnd )
				)
				( attribute "CDS_LIB" "mstr_discrete"
					( Origin gPackager )
				)
				( attribute "CDS_LOCATION" "R8F24"
					( Origin gPackager )
				)
				( attribute "CDS_SEC" "1"
					( Origin gPackager )
				)
				( attribute "LOCATION" "R8F24"
					( Origin gFrontEnd )
				)
				( attribute "MATERIAL" "CHIP"
					( Origin gFrontEnd )
				)
				( attribute "PACK_TYPE" "0402"
					( Origin gFrontEnd )
				)
				( attribute "PART_NUMBER" "G21796-072"
					( Origin gFrontEnd )
				)
				( attribute "PHYS_PAGE" "157"
					( Origin gFrontEnd )
				)
				( attribute "ROOM" "BMC_MISC"
					( Origin gFrontEnd )
				)
				( attribute "ROT" "0"
					( Origin gFrontEnd )
				)
				( attribute "SEC" "1"
					( Origin gFrontEnd )
				)
				( attribute "SEC_TYPE" "0402"
					( Origin gFrontEnd )
				)
				( attribute "TOLERANCE" "1%"
					( Origin gFrontEnd )
				)
				( attribute "VALUE" "4.75K"
					( Origin gFrontEnd )
				)
				( attribute "VER" "1"
					( Origin gFrontEnd )
				)
				( attribute "WATTAGE" "1/16W"
					( Origin gFrontEnd )
				)
				( attribute "XY" "(-7175,3725)"
					( Origin gFrontEnd )
				)
				( attribute "CHIPS_PART_NAME" "RES"
					( Origin gPackager )
				)
				( attribute "CDS_PART_NAME" "RES_0402-4.75K,1%,1/16W,CHIP,GA"
					( Origin gPackager )
				)
				( objectStatus "R8F24" )
			)
			( gate "@baseboard_fab2_lib.baseboard_fab2(sch_1):page157_i326"
				( attribute "BOM_COST" "PROC_SIDEBAND"
					( Origin gFrontEnd )
				)
				( attribute "CDS_LIB" "mstr_discrete"
					( Origin gPackager )
				)
				( attribute "CDS_LOCATION" "R2T5"
					( Origin gPackager )
				)
				( attribute "CDS_SEC" "1"
					( Origin gPackager )
				)
				( attribute "LOCATION" "R2T5"
					( Origin gFrontEnd )
				)
				( attribute "MATERIAL" "CHIP"
					( Origin gFrontEnd )
				)
				( attribute "PACK_TYPE" "0402"
					( Origin gFrontEnd )
				)
				( attribute "PART_NUMBER" "G21796-026"
					( Origin gFrontEnd )
				)
				( attribute "PHYS_PAGE" "157"
					( Origin gFrontEnd )
				)
				( attribute "ROOM" "PROC_SIDEBAND"
					( Origin gFrontEnd )
				)
				( attribute "ROT" "0"
					( Origin gFrontEnd )
				)
				( attribute "SEC" "1"
					( Origin gFrontEnd )
				)
				( attribute "SEC_TYPE" "0402"
					( Origin gFrontEnd )
				)
				( attribute "TOLERANCE" "1%"
					( Origin gFrontEnd )
				)
				( attribute "VALUE" "1.00K"
					( Origin gFrontEnd )
				)
				( attribute "VER" "2"
					( Origin gFrontEnd )
				)
				( attribute "WATTAGE" "1/16W"
					( Origin gFrontEnd )
				)
				( attribute "XY" "(-6150,1250)"
					( Origin gFrontEnd )
				)
				( attribute "CHIPS_PART_NAME" "RES"
					( Origin gPackager )
				)
				( attribute "CDS_PART_NAME" "RES_0402-1.00K,1%,1/16W,CHIP,GA"
					( Origin gPackager )
				)
				( objectStatus "R2T5" )
			)
			( gate "@baseboard_fab2_lib.baseboard_fab2(sch_1):page157_i327"
				( attribute "BOM_COST" "PROC_SIDEBAND"
					( Origin gFrontEnd )
				)
				( attribute "CDS_LIB" "mstr_discrete"
					( Origin gPackager )
				)
				( attribute "CDS_LOCATION" "R2T7"
					( Origin gPackager )
				)
				( attribute "CDS_SEC" "1"
					( Origin gPackager )
				)
				( attribute "LOCATION" "R2T7"
					( Origin gFrontEnd )
				)
				( attribute "MATERIAL" "CHIP"
					( Origin gFrontEnd )
				)
				( attribute "PACK_TYPE" "0402"
					( Origin gFrontEnd )
				)
				( attribute "PART_NUMBER" "G21796-026"
					( Origin gFrontEnd )
				)
				( attribute "PHYS_PAGE" "157"
					( Origin gFrontEnd )
				)
				( attribute "ROOM" "PROC_SIDEBAND"
					( Origin gFrontEnd )
				)
				( attribute "ROT" "0"
					( Origin gFrontEnd )
				)
				( attribute "SEC" "1"
					( Origin gFrontEnd )
				)
				( attribute "SEC_TYPE" "0402"
					( Origin gFrontEnd )
				)
				( attribute "TOLERANCE" "1%"
					( Origin gFrontEnd )
				)
				( attribute "VALUE" "1.00K"
					( Origin gFrontEnd )
				)
				( attribute "VER" "2"
					( Origin gFrontEnd )
				)
				( attribute "WATTAGE" "1/16W"
					( Origin gFrontEnd )
				)
				( attribute "XY" "(-5500,1650)"
					( Origin gFrontEnd )
				)
				( attribute "CHIPS_PART_NAME" "RES"
					( Origin gPackager )
				)
				( attribute "CDS_PART_NAME" "RES_0402-1.00K,1%,1/16W,CHIP,GA"
					( Origin gPackager )
				)
				( objectStatus "R2T7" )
			)
			( gate "@baseboard_fab2_lib.baseboard_fab2(sch_1):page157_i330"
				( attribute "BOM_COST" "PROC_SIDEBAND"
					( Origin gFrontEnd )
				)
				( attribute "CDS_LIB" "mstr_discrete"
					( Origin gPackager )
				)
				( attribute "CDS_LOCATION" "Q2T1"
					( Origin gPackager )
				)
				( attribute "CDS_SEC" "1"
					( Origin gPackager )
				)
				( attribute "LOCATION" "Q2T1"
					( Origin gFrontEnd )
				)
				( attribute "MATERIAL" "IC"
					( Origin gFrontEnd )
				)
				( attribute "PACK_TYPE" "SM"
					( Origin gFrontEnd )
				)
				( attribute "PART_NUMBER" "C52245-001"
					( Origin gFrontEnd )
				)
				( attribute "PHYS_PAGE" "157"
					( Origin gFrontEnd )
				)
				( attribute "ROOM" "PROC_SIDEBAND"
					( Origin gFrontEnd )
				)
				( attribute "ROT" "0"
					( Origin gFrontEnd )
				)
				( attribute "SEC" "1"
					( Origin gFrontEnd )
				)
				( attribute "SEC_TYPE" "SM"
					( Origin gFrontEnd )
				)
				( attribute "VALUE" "MMBT3904"
					( Origin gFrontEnd )
				)
				( attribute "VER" "1"
					( Origin gFrontEnd )
				)
				( attribute "XY" "(-6200,775)"
					( Origin gFrontEnd )
				)
				( attribute "CHIPS_PART_NAME" "NPN"
					( Origin gPackager )
				)
				( attribute "CDS_PART_NAME" "NPN_SM-MMBT3904,IC,C52245-001"
					( Origin gPackager )
				)
				( objectStatus "Q2T1" )
			)
			( gate "@baseboard_fab2_lib.baseboard_fab2(sch_1):page157_i335"
				( attribute "BOM_COST" "SM_CONTROLLER"
					( Origin gFrontEnd )
				)
				( attribute "CDS_LIB" "mstr_discrete"
					( Origin gPackager )
				)
				( attribute "CDS_LOCATION" "R8D25"
					( Origin gPackager )
				)
				( attribute "CDS_SEC" "1"
					( Origin gPackager )
				)
				( attribute "LOCATION" "R8D25"
					( Origin gFrontEnd )
				)
				( attribute "MATERIAL" "CHIP"
					( Origin gFrontEnd )
				)
				( attribute "PACK_TYPE" "0402"
					( Origin gFrontEnd )
				)
				( attribute "PART_NUMBER" "G21796-072"
					( Origin gFrontEnd )
				)
				( attribute "PHYS_PAGE" "157"
					( Origin gFrontEnd )
				)
				( attribute "ROOM" "BMC_MISC"
					( Origin gFrontEnd )
				)
				( attribute "ROT" "0"
					( Origin gFrontEnd )
				)
				( attribute "SEC" "1"
					( Origin gFrontEnd )
				)
				( attribute "SEC_TYPE" "0402"
					( Origin gFrontEnd )
				)
				( attribute "TOLERANCE" "1%"
					( Origin gFrontEnd )
				)
				( attribute "VALUE" "4.75K"
					( Origin gFrontEnd )
				)
				( attribute "VER" "2"
					( Origin gFrontEnd )
				)
				( attribute "WATTAGE" "1/16W"
					( Origin gFrontEnd )
				)
				( attribute "XY" "(-2275,1525)"
					( Origin gFrontEnd )
				)
				( attribute "CHIPS_PART_NAME" "RES"
					( Origin gPackager )
				)
				( attribute "CDS_PART_NAME" "RES_0402-4.75K,1%,1/16W,CHIP,GA"
					( Origin gPackager )
				)
				( objectStatus "R8D25" )
			)
			( gate "@baseboard_fab2_lib.baseboard_fab2(sch_1):page157_i340"
				( attribute "BOM_COST" "PROC_SIDEBAND"
					( Origin gFrontEnd )
				)
				( attribute "CDS_LIB" "mstr_discrete"
					( Origin gPackager )
				)
				( attribute "CDS_LOCATION" "Q2T2"
					( Origin gPackager )
				)
				( attribute "CDS_SEC" "1"
					( Origin gPackager )
				)
				( attribute "LOCATION" "Q2T2"
					( Origin gFrontEnd )
				)
				( attribute "MATERIAL" "FET"
					( Origin gFrontEnd )
				)
				( attribute "PACK_TYPE" "SOT23LF"
					( Origin gFrontEnd )
				)
				( attribute "PART_NUMBER" "C79254-001"
					( Origin gFrontEnd )
				)
				( attribute "PHYS_PAGE" "157"
					( Origin gFrontEnd )
				)
				( attribute "ROOM" "PROC_SIDEBAND"
					( Origin gFrontEnd )
				)
				( attribute "ROT" "0"
					( Origin gFrontEnd )
				)
				( attribute "SEC" "1"
					( Origin gFrontEnd )
				)
				( attribute "SEC_TYPE" "SOT23LF"
					( Origin gFrontEnd )
				)
				( attribute "VALUE" "2N7002"
					( Origin gFrontEnd )
				)
				( attribute "VER" "8"
					( Origin gFrontEnd )
				)
				( attribute "XY" "(-5500,1100)"
					( Origin gFrontEnd )
				)
				( attribute "CHIPS_PART_NAME" "FET_N"
					( Origin gPackager )
				)
				( attribute "CDS_PART_NAME" "FET_N_SOT23LF-2N7002,FET,C7925A"
					( Origin gPackager )
				)
				( objectStatus "Q2T2" )
			)
			( gate "@baseboard_fab2_lib.baseboard_fab2(sch_1):page157_i342"
				( attribute "BOM_COST" "SM_CONTROLLER"
					( Origin gFrontEnd )
				)
				( attribute "CDS_LIB" "mstr_discrete"
					( Origin gPackager )
				)
				( attribute "CDS_LOCATION" "R3N12"
					( Origin gPackager )
				)
				( attribute "CDS_SEC" "1"
					( Origin gPackager )
				)
				( attribute "LOCATION" "R3N12"
					( Origin gFrontEnd )
				)
				( attribute "MATERIAL" "CHIP"
					( Origin gFrontEnd )
				)
				( attribute "PACK_TYPE" "0402"
					( Origin gFrontEnd )
				)
				( attribute "PART_NUMBER" "G21796-072"
					( Origin gFrontEnd )
				)
				( attribute "PHYS_PAGE" "157"
					( Origin gFrontEnd )
				)
				( attribute "ROOM" "BMC_MISC"
					( Origin gFrontEnd )
				)
				( attribute "ROT" "0"
					( Origin gFrontEnd )
				)
				( attribute "SEC" "1"
					( Origin gFrontEnd )
				)
				( attribute "SEC_TYPE" "0402"
					( Origin gFrontEnd )
				)
				( attribute "TOLERANCE" "1%"
					( Origin gFrontEnd )
				)
				( attribute "VALUE" "4.75K"
					( Origin gFrontEnd )
				)
				( attribute "VER" "1"
					( Origin gFrontEnd )
				)
				( attribute "WATTAGE" "1/16W"
					( Origin gFrontEnd )
				)
				( attribute "XY" "(-7175,3100)"
					( Origin gFrontEnd )
				)
				( attribute "CHIPS_PART_NAME" "RES"
					( Origin gPackager )
				)
				( attribute "CDS_PART_NAME" "RES_0402-4.75K,1%,1/16W,CHIP,GA"
					( Origin gPackager )
				)
				( objectStatus "R3N12" )
			)
			( gate "@baseboard_fab2_lib.baseboard_fab2(sch_1):page157_i344"
				( attribute "BOM_COST" "SM_CONTROLLER"
					( Origin gFrontEnd )
				)
				( attribute "CDS_LIB" "mstr_discrete"
					( Origin gPackager )
				)
				( attribute "CDS_LOCATION" "R3N11"
					( Origin gPackager )
				)
				( attribute "CDS_SEC" "1"
					( Origin gPackager )
				)
				( attribute "LOCATION" "R3N11"
					( Origin gFrontEnd )
				)
				( attribute "MATERIAL" "CHIP"
					( Origin gFrontEnd )
				)
				( attribute "PACK_TYPE" "0402"
					( Origin gFrontEnd )
				)
				( attribute "PART_NUMBER" "G21796-072"
					( Origin gFrontEnd )
				)
				( attribute "PHYS_PAGE" "157"
					( Origin gFrontEnd )
				)
				( attribute "ROOM" "BMC_MISC"
					( Origin gFrontEnd )
				)
				( attribute "ROT" "0"
					( Origin gFrontEnd )
				)
				( attribute "SEC" "1"
					( Origin gFrontEnd )
				)
				( attribute "SEC_TYPE" "0402"
					( Origin gFrontEnd )
				)
				( attribute "TOLERANCE" "1%"
					( Origin gFrontEnd )
				)
				( attribute "VALUE" "4.75K"
					( Origin gFrontEnd )
				)
				( attribute "VER" "1"
					( Origin gFrontEnd )
				)
				( attribute "WATTAGE" "1/16W"
					( Origin gFrontEnd )
				)
				( attribute "XY" "(-7175,2875)"
					( Origin gFrontEnd )
				)
				( attribute "CHIPS_PART_NAME" "RES"
					( Origin gPackager )
				)
				( attribute "CDS_PART_NAME" "RES_0402-4.75K,1%,1/16W,CHIP,GA"
					( Origin gPackager )
				)
				( objectStatus "R3N11" )
			)
			( gate "@baseboard_fab2_lib.baseboard_fab2(sch_1):page157_i346"
				( attribute "BOM_COST" "SM_CONTROLLER"
					( Origin gFrontEnd )
				)
				( attribute "CDS_LIB" "mstr_discrete"
					( Origin gPackager )
				)
				( attribute "CDS_LOCATION" "R2M2"
					( Origin gPackager )
				)
				( attribute "CDS_SEC" "1"
					( Origin gPackager )
				)
				( attribute "LOCATION" "R2M2"
					( Origin gFrontEnd )
				)
				( attribute "MATERIAL" "CHIP"
					( Origin gFrontEnd )
				)
				( attribute "PACK_TYPE" "0402"
					( Origin gFrontEnd )
				)
				( attribute "PART_NUMBER" "G21796-072"
					( Origin gFrontEnd )
				)
				( attribute "PHYS_PAGE" "157"
					( Origin gFrontEnd )
				)
				( attribute "ROOM" "BMC_MISC"
					( Origin gFrontEnd )
				)
				( attribute "ROT" "0"
					( Origin gFrontEnd )
				)
				( attribute "SEC" "1"
					( Origin gFrontEnd )
				)
				( attribute "SEC_TYPE" "0402"
					( Origin gFrontEnd )
				)
				( attribute "TOLERANCE" "1%"
					( Origin gFrontEnd )
				)
				( attribute "VALUE" "4.75K"
					( Origin gFrontEnd )
				)
				( attribute "VER" "1"
					( Origin gFrontEnd )
				)
				( attribute "WATTAGE" "1/16W"
					( Origin gFrontEnd )
				)
				( attribute "XY" "(-7175,2650)"
					( Origin gFrontEnd )
				)
				( attribute "CHIPS_PART_NAME" "RES"
					( Origin gPackager )
				)
				( attribute "CDS_PART_NAME" "RES_0402-4.75K,1%,1/16W,CHIP,GA"
					( Origin gPackager )
				)
				( objectStatus "R2M2" )
			)
			( gate "@baseboard_fab2_lib.baseboard_fab2(sch_1):page157_i348"
				( attribute "BOM_COST" "SM_CONTROLLER"
					( Origin gFrontEnd )
				)
				( attribute "CDS_LIB" "mstr_discrete"
					( Origin gPackager )
				)
				( attribute "CDS_LOCATION" "R2M5"
					( Origin gPackager )
				)
				( attribute "CDS_SEC" "1"
					( Origin gPackager )
				)
				( attribute "LOCATION" "R2M5"
					( Origin gFrontEnd )
				)
				( attribute "MATERIAL" "CHIP"
					( Origin gFrontEnd )
				)
				( attribute "PACK_TYPE" "0402"
					( Origin gFrontEnd )
				)
				( attribute "PART_NUMBER" "G21796-072"
					( Origin gFrontEnd )
				)
				( attribute "PHYS_PAGE" "157"
					( Origin gFrontEnd )
				)
				( attribute "ROOM" "BMC_MISC"
					( Origin gFrontEnd )
				)
				( attribute "ROT" "0"
					( Origin gFrontEnd )
				)
				( attribute "SEC" "1"
					( Origin gFrontEnd )
				)
				( attribute "SEC_TYPE" "0402"
					( Origin gFrontEnd )
				)
				( attribute "TOLERANCE" "1%"
					( Origin gFrontEnd )
				)
				( attribute "VALUE" "4.75K"
					( Origin gFrontEnd )
				)
				( attribute "VER" "1"
					( Origin gFrontEnd )
				)
				( attribute "WATTAGE" "1/16W"
					( Origin gFrontEnd )
				)
				( attribute "XY" "(-7175,2425)"
					( Origin gFrontEnd )
				)
				( attribute "CHIPS_PART_NAME" "RES"
					( Origin gPackager )
				)
				( attribute "CDS_PART_NAME" "RES_0402-4.75K,1%,1/16W,CHIP,GA"
					( Origin gPackager )
				)
				( objectStatus "R2M5" )
			)
			( gate "@baseboard_fab2_lib.baseboard_fab2(sch_1):page157_i351"
				( attribute "BOM_COST" "MIO_CHASSIS"
					( Origin gFrontEnd )
				)
				( attribute "CDS_LIB" "mstr_misc"
					( Origin gPackager )
				)
				( attribute "CDS_LOCATION" "S8E1"
					( Origin gPackager )
				)
				( attribute "CDS_SEC" "1"
					( Origin gPackager )
				)
				( attribute "LOCATION" "S8E1"
					( Origin gFrontEnd )
				)
				( attribute "MATERIAL" "IC"
					( Origin gFrontEnd )
				)
				( attribute "PACK_TYPE" "SMLF"
					( Origin gFrontEnd )
				)
				( attribute "PART_NAME" "SWITCH_D90553001"
					( Origin gFrontEnd )
				)
				( attribute "PART_NUMBER" "D90553-001"
					( Origin gFrontEnd )
				)
				( attribute "PHYS_PAGE" "157"
					( Origin gFrontEnd )
				)
				( attribute "ROOM" "MIO_CHASSIS"
					( Origin gFrontEnd )
				)
				( attribute "ROT" "0"
					( Origin gFrontEnd )
				)
				( attribute "SEC" "1"
					( Origin gFrontEnd )
				)
				( attribute "SEC_TYPE" "SMLF"
					( Origin gFrontEnd )
				)
				( attribute "VER" "1"
					( Origin gFrontEnd )
				)
				( attribute "XY" "(-4525,2675)"
					( Origin gFrontEnd )
				)
				( attribute "CHIPS_PART_NAME" "SWITCH_D90553001"
					( Origin gPackager )
				)
				( attribute "CDS_PART_NAME" "SWITCH_D90553001_SMLF-IC,D9055A"
					( Origin gPackager )
				)
				( objectStatus "S8E1" )
			)
			( gate "@baseboard_fab2_lib.baseboard_fab2(sch_1):page157_i352"
				( attribute "BOM_COST" "MIO_CHASSIS"
					( Origin gFrontEnd )
				)
				( attribute "CDS_LIB" "mstr_discrete"
					( Origin gPackager )
				)
				( attribute "CDS_LOCATION" "R2R9"
					( Origin gPackager )
				)
				( attribute "CDS_SEC" "1"
					( Origin gPackager )
				)
				( attribute "LOCATION" "R2R9"
					( Origin gFrontEnd )
				)
				( attribute "MATERIAL" "CHIP"
					( Origin gFrontEnd )
				)
				( attribute "PACK_TYPE" "0402"
					( Origin gFrontEnd )
				)
				( attribute "PART_NUMBER" "G21796-004"
					( Origin gFrontEnd )
				)
				( attribute "PHYS_PAGE" "157"
					( Origin gFrontEnd )
				)
				( attribute "ROOM" "MIO_CHASSIS"
					( Origin gFrontEnd )
				)
				( attribute "ROT" "0"
					( Origin gFrontEnd )
				)
				( attribute "SEC" "1"
					( Origin gFrontEnd )
				)
				( attribute "SEC_TYPE" "0402"
					( Origin gFrontEnd )
				)
				( attribute "TOLERANCE" "1%"
					( Origin gFrontEnd )
				)
				( attribute "VALUE" "200.0"
					( Origin gFrontEnd )
				)
				( attribute "VER" "1"
					( Origin gFrontEnd )
				)
				( attribute "WATTAGE" "1/16W"
					( Origin gFrontEnd )
				)
				( attribute "XY" "(-3675,2675)"
					( Origin gFrontEnd )
				)
				( attribute "CHIPS_PART_NAME" "RES"
					( Origin gPackager )
				)
				( attribute "CDS_PART_NAME" "RES_0402-200.0,1%,1/16W,CHIP,GA"
					( Origin gPackager )
				)
				( objectStatus "R2R9" )
			)
			( gate "@baseboard_fab2_lib.baseboard_fab2(sch_1):page157_i353"
				( attribute "BOM_COST" "MIO_CHASSIS"
					( Origin gFrontEnd )
				)
				( attribute "CDS_LIB" "dev_discrete"
					( Origin gPackager )
				)
				( attribute "CDS_LOCATION" "C2R12"
					( Origin gPackager )
				)
				( attribute "CDS_SEC" "1"
					( Origin gPackager )
				)
				( attribute "LOCATION" "C2R12"
					( Origin gFrontEnd )
				)
				( attribute "MATERIAL" "X6S"
					( Origin gFrontEnd )
				)
				( attribute "PACK_TYPE" "0402V"
					( Origin gFrontEnd )
				)
				( attribute "PART_NUMBER" "D97712-004"
					( Origin gFrontEnd )
				)
				( attribute "PHYS_PAGE" "157"
					( Origin gFrontEnd )
				)
				( attribute "ROOM" "MIO_CHASSIS"
					( Origin gFrontEnd )
				)
				( attribute "ROT" "0"
					( Origin gFrontEnd )
				)
				( attribute "SEC" "1"
					( Origin gFrontEnd )
				)
				( attribute "SEC_TYPE" "0402V"
					( Origin gFrontEnd )
				)
				( attribute "TOLERANCE" "10%"
					( Origin gFrontEnd )
				)
				( attribute "VALUE" "1.0UF"
					( Origin gFrontEnd )
				)
				( attribute "VER" "1"
					( Origin gFrontEnd )
				)
				( attribute "VOLTAGE" "6.3V"
					( Units "uVoltage" "V" 1.000000)
					( Origin gFrontEnd )
				)
				( attribute "XY" "(-3225,2450)"
					( Origin gFrontEnd )
				)
				( attribute "CHIPS_PART_NAME" "CAP_A"
					( Origin gPackager )
				)
				( attribute "CDS_PART_NAME" "CAP_A_0402V-1.0UF,6.3V,10%,X6SA"
					( Origin gPackager )
				)
				( objectStatus "C2R12" )
			)
			( gate "@baseboard_fab2_lib.baseboard_fab2(sch_1):page175_i93"
				( attribute "CDS_LIB" "w_hdl"
					( Origin gPackager )
				)
				( attribute "CDS_LMAN_SYM_OUTLINE" "-200,150,200,-150"
					( Origin gPackager )
				)
				( attribute "LOCATION" "U9A3"
					( Origin gFrontEnd )
				)
				( attribute "PACK_TYPE" "DISCRET-GA1"
					( Origin gFrontEnd )
				)
				( attribute "PART_NUMBER" "073.7PZ14.0007"
					( Origin gFrontEnd )
				)
				( attribute "PHYS_PAGE" "175"
					( Origin gFrontEnd )
				)
				( attribute "ROT" "0"
					( Origin gFrontEnd )
				)
				( attribute "SEC" "1"
					( Origin gFrontEnd )
				)
				( attribute "SEC_TYPE" "DISCRET-GA1"
					( Origin gFrontEnd )
				)
				( attribute "VALUE" "TC7PZ14FU-GP"
					( Origin gFrontEnd )
				)
				( attribute "VER" "1"
					( Origin gFrontEnd )
				)
				( attribute "XY" "(-3725,2725)"
					( Origin gFrontEnd )
				)
				( attribute "CHIPS_PART_NAME" "TC7PZ14FU-GP"
					( Origin gPackager )
				)
				( attribute "CDS_PART_NAME" "TC7PZ14FU-GP_DISCRET-GA1-TC7PZA"
					( Origin gPackager )
				)
				( attribute "CDS_LOCATION" "U9A3"
					( Origin gPackager )
				)
				( attribute "CDS_SEC" "1"
					( Origin gPackager )
				)
				( objectStatus "U9A3" )
			)
			( gate "@baseboard_fab2_lib.baseboard_fab2(sch_1):page157_i357"
				( attribute "CHIPS_PART_NAME" "TTL2G14"
					( Origin gPackager )
				)
			)
			( gate "@baseboard_fab2_lib.baseboard_fab2(sch_1):page157_i356"
				( attribute "CHIPS_PART_NAME" "TTL2G14"
					( Origin gPackager )
				)
			)
			( gate "@baseboard_fab2_lib.baseboard_fab2(sch_1):page157_i361"
				( attribute "BOM_COST" "SM_CONTROLLER"
					( Origin gFrontEnd )
				)
				( attribute "CDS_LIB" "mstr_discrete"
					( Origin gPackager )
				)
				( attribute "CDS_LOCATION" "R8E19"
					( Origin gPackager )
				)
				( attribute "CDS_SEC" "1"
					( Origin gPackager )
				)
				( attribute "LOCATION" "R8E19"
					( Origin gFrontEnd )
				)
				( attribute "MATERIAL" "EMPTY"
					( Origin gFrontEnd )
				)
				( attribute "PACK_TYPE" "0402"
					( Origin gFrontEnd )
				)
				( attribute "PART_NUMBER" "G21796-072"
					( Origin gFrontEnd )
				)
				( attribute "PHYS_PAGE" "157"
					( Origin gFrontEnd )
				)
				( attribute "ROOM" "BMC_MISC"
					( Origin gFrontEnd )
				)
				( attribute "ROT" "0"
					( Origin gFrontEnd )
				)
				( attribute "SEC" "1"
					( Origin gFrontEnd )
				)
				( attribute "SEC_TYPE" "0402"
					( Origin gFrontEnd )
				)
				( attribute "TOLERANCE" "1%"
					( Origin gFrontEnd )
				)
				( attribute "VALUE" "4.75K"
					( Origin gFrontEnd )
				)
				( attribute "VER" "1"
					( Origin gFrontEnd )
				)
				( attribute "WATTAGE" "1/16W"
					( Origin gFrontEnd )
				)
				( attribute "XY" "(-7175,2200)"
					( Origin gFrontEnd )
				)
				( attribute "CHIPS_PART_NAME" "RES"
					( Origin gPackager )
				)
				( attribute "CDS_PART_NAME" "RES_0402-4.75K,1%,1/16W,EMPTY,A"
					( Origin gPackager )
				)
				( objectStatus "R8E19" )
			)
			( gate "@baseboard_fab2_lib.baseboard_fab2(sch_1):page157_i367"
				( attribute "BOM_COST" "SM_CONTROLLER"
					( Origin gFrontEnd )
				)
				( attribute "CDS_LIB" "mstr_discrete"
					( Origin gPackager )
				)
				( attribute "CDS_LOCATION" "R2U4"
					( Origin gPackager )
				)
				( attribute "CDS_SEC" "1"
					( Origin gPackager )
				)
				( attribute "LOCATION" "R2U4"
					( Origin gFrontEnd )
				)
				( attribute "MATERIAL" "CHIP"
					( Origin gFrontEnd )
				)
				( attribute "PACK_TYPE" "0402"
					( Origin gFrontEnd )
				)
				( attribute "PART_NUMBER" "G21796-072"
					( Origin gFrontEnd )
				)
				( attribute "PHYS_PAGE" "157"
					( Origin gFrontEnd )
				)
				( attribute "ROOM" "BMC_MISC"
					( Origin gFrontEnd )
				)
				( attribute "ROT" "0"
					( Origin gFrontEnd )
				)
				( attribute "SEC" "1"
					( Origin gFrontEnd )
				)
				( attribute "SEC_TYPE" "0402"
					( Origin gFrontEnd )
				)
				( attribute "TOLERANCE" "1%"
					( Origin gFrontEnd )
				)
				( attribute "VALUE" "4.75K"
					( Origin gFrontEnd )
				)
				( attribute "VER" "1"
					( Origin gFrontEnd )
				)
				( attribute "WATTAGE" "1/16W"
					( Origin gFrontEnd )
				)
				( attribute "XY" "(-4925,4025)"
					( Origin gFrontEnd )
				)
				( attribute "CHIPS_PART_NAME" "RES"
					( Origin gPackager )
				)
				( attribute "CDS_PART_NAME" "RES_0402-4.75K,1%,1/16W,CHIP,GA"
					( Origin gPackager )
				)
				( objectStatus "R2U4" )
			)
			( gate "@baseboard_fab2_lib.baseboard_fab2(sch_1):page157_i368"
				( attribute "BOM_COST" "MIO_CHASSIS"
					( Origin gFrontEnd )
				)
				( attribute "CDS_LIB" "mstr_discrete"
					( Origin gPackager )
				)
				( attribute "CDS_LOCATION" "R4R1"
					( Origin gPackager )
				)
				( attribute "CDS_SEC" "1"
					( Origin gPackager )
				)
				( attribute "LOCATION" "R4R1"
					( Origin gFrontEnd )
				)
				( attribute "MATERIAL" "CHIP"
					( Origin gFrontEnd )
				)
				( attribute "PACK_TYPE" "0402"
					( Origin gFrontEnd )
				)
				( attribute "PART_NUMBER" "G21796-026"
					( Origin gFrontEnd )
				)
				( attribute "PHYS_PAGE" "157"
					( Origin gFrontEnd )
				)
				( attribute "ROOM" "MIO_CHASSIS"
					( Origin gFrontEnd )
				)
				( attribute "ROT" "0"
					( Origin gFrontEnd )
				)
				( attribute "SEC" "1"
					( Origin gFrontEnd )
				)
				( attribute "SEC_TYPE" "0402"
					( Origin gFrontEnd )
				)
				( attribute "TOLERANCE" "1%"
					( Origin gFrontEnd )
				)
				( attribute "VALUE" "1.00K"
					( Origin gFrontEnd )
				)
				( attribute "VER" "1"
					( Origin gFrontEnd )
				)
				( attribute "WATTAGE" "1/16W"
					( Origin gFrontEnd )
				)
				( attribute "XY" "(-6975,775)"
					( Origin gFrontEnd )
				)
				( attribute "CHIPS_PART_NAME" "RES"
					( Origin gPackager )
				)
				( attribute "CDS_PART_NAME" "RES_0402-1.00K,1%,1/16W,CHIP,GA"
					( Origin gPackager )
				)
				( objectStatus "R4R1" )
			)
			( gate "@baseboard_fab2_lib.baseboard_fab2(sch_1):page157_i370"
				( attribute "BOM_COST" "MIO_CHASSIS"
					( Origin gFrontEnd )
				)
				( attribute "CDS_LIB" "dev_discrete"
					( Origin gPackager )
				)
				( attribute "CDS_LOCATION" "C2T3"
					( Origin gPackager )
				)
				( attribute "CDS_SEC" "1"
					( Origin gPackager )
				)
				( attribute "LOCATION" "C2T3"
					( Origin gFrontEnd )
				)
				( attribute "MATERIAL" "X7R"
					( Origin gFrontEnd )
				)
				( attribute "PACK_TYPE" "0402V"
					( Origin gFrontEnd )
				)
				( attribute "PART_NUMBER" "A36096-030"
					( Origin gFrontEnd )
				)
				( attribute "PHYS_PAGE" "157"
					( Origin gFrontEnd )
				)
				( attribute "ROOM" "MIO_CHASSIS"
					( Origin gFrontEnd )
				)
				( attribute "ROT" "0"
					( Origin gFrontEnd )
				)
				( attribute "SEC" "1"
					( Origin gFrontEnd )
				)
				( attribute "SEC_TYPE" "0402V"
					( Origin gFrontEnd )
				)
				( attribute "TOLERANCE" "10%"
					( Origin gFrontEnd )
				)
				( attribute "VALUE" "0.1UF"
					( Origin gFrontEnd )
				)
				( attribute "VER" "1"
					( Origin gFrontEnd )
				)
				( attribute "VOLTAGE" "16V"
					( Units "uVoltage" "V" 1.000000)
					( Origin gFrontEnd )
				)
				( attribute "XY" "(-1700,2575)"
					( Origin gFrontEnd )
				)
				( attribute "CHIPS_PART_NAME" "CAP_A"
					( Origin gPackager )
				)
				( attribute "CDS_PART_NAME" "CAP_A_0402V-0.1UF,16V,10%,X7R,A"
					( Origin gPackager )
				)
				( objectStatus "C2T3" )
			)
			( gate "@baseboard_fab2_lib.baseboard_fab2(sch_1):page157_i374"
				( attribute "CDS_LIB" "mstr_ttl"
					( Origin gPackager )
				)
				( attribute "CDS_LOCATION" "U8D2"
					( Origin gPackager )
				)
				( attribute "CDS_SEC" "1"
					( Origin gPackager )
				)
				( attribute "LOCATION" "U8D2"
					( Origin gFrontEnd )
				)
				( attribute "MATERIAL" "IC"
					( Origin gFrontEnd )
				)
				( attribute "PACK_TYPE" "SOP"
					( Origin gFrontEnd )
				)
				( attribute "PART_NUMBER" "C88419-001"
					( Origin gFrontEnd )
				)
				( attribute "PHYS_PAGE" "157"
					( Origin gFrontEnd )
				)
				( attribute "ROT" "0"
					( Origin gFrontEnd )
				)
				( attribute "SEC" "1"
					( Origin gFrontEnd )
				)
				( attribute "SEC_TYPE" "SOP"
					( Origin gFrontEnd )
				)
				( attribute "VALUE" "74LVC1G07"
					( Origin gFrontEnd )
				)
				( attribute "VER" "1"
					( Origin gFrontEnd )
				)
				( attribute "XY" "(-2800,1150)"
					( Origin gFrontEnd )
				)
				( attribute "CHIPS_PART_NAME" "TTL1G07_A"
					( Origin gPackager )
				)
				( attribute "CDS_PART_NAME" "TTL1G07_A_SOP-74LVC1G07,IC,C88B"
					( Origin gPackager )
				)
				( objectStatus "U8D2" )
			)
			( gate "@baseboard_fab2_lib.baseboard_fab2(sch_1):page157_i376"
				( attribute "CDS_LIB" "dev_discrete"
					( Origin gPackager )
				)
				( attribute "CDS_LOCATION" "C8D1"
					( Origin gPackager )
				)
				( attribute "CDS_SEC" "1"
					( Origin gPackager )
				)
				( attribute "LOCATION" "C8D1"
					( Origin gFrontEnd )
				)
				( attribute "MATERIAL" "X7R"
					( Origin gFrontEnd )
				)
				( attribute "PACK_TYPE" "0402V"
					( Origin gFrontEnd )
				)
				( attribute "PART_NUMBER" "A36096-030"
					( Origin gFrontEnd )
				)
				( attribute "PHYS_PAGE" "157"
					( Origin gFrontEnd )
				)
				( attribute "ROT" "0"
					( Origin gFrontEnd )
				)
				( attribute "SEC" "1"
					( Origin gFrontEnd )
				)
				( attribute "SEC_TYPE" "0402V"
					( Origin gFrontEnd )
				)
				( attribute "TOLERANCE" "10%"
					( Origin gFrontEnd )
				)
				( attribute "VALUE" "0.1UF"
					( Origin gFrontEnd )
				)
				( attribute "VER" "1"
					( Origin gFrontEnd )
				)
				( attribute "VOLTAGE" "16V"
					( Units "uVoltage" "V" 1.000000)
					( Origin gFrontEnd )
				)
				( attribute "XY" "(-500,1750)"
					( Origin gFrontEnd )
				)
				( attribute "CHIPS_PART_NAME" "CAP_A"
					( Origin gPackager )
				)
				( attribute "CDS_PART_NAME" "CAP_A_0402V-0.1UF,16V,10%,X7R,A"
					( Origin gPackager )
				)
				( objectStatus "C8D1" )
			)
			( gate "@baseboard_fab2_lib.baseboard_fab2(sch_1):page157_i382"
				( attribute "BOM_COST" "SM_CONTROLLER"
					( Origin gFrontEnd )
				)
				( attribute "CDS_LIB" "mstr_discrete"
					( Origin gPackager )
				)
				( attribute "CDS_LOCATION" "R1L7"
					( Origin gPackager )
				)
				( attribute "CDS_SEC" "1"
					( Origin gPackager )
				)
				( attribute "LOCATION" "R1L7"
					( Origin gFrontEnd )
				)
				( attribute "MATERIAL" "CHIP"
					( Origin gFrontEnd )
				)
				( attribute "PACK_TYPE" "0402"
					( Origin gFrontEnd )
				)
				( attribute "PART_NUMBER" "G21796-072"
					( Origin gFrontEnd )
				)
				( attribute "PHYS_PAGE" "157"
					( Origin gFrontEnd )
				)
				( attribute "ROOM" "BMC_MISC"
					( Origin gFrontEnd )
				)
				( attribute "ROT" "0"
					( Origin gFrontEnd )
				)
				( attribute "SEC" "1"
					( Origin gFrontEnd )
				)
				( attribute "SEC_TYPE" "0402"
					( Origin gFrontEnd )
				)
				( attribute "TOLERANCE" "1%"
					( Origin gFrontEnd )
				)
				( attribute "VALUE" "4.75K"
					( Origin gFrontEnd )
				)
				( attribute "VER" "1"
					( Origin gFrontEnd )
				)
				( attribute "WATTAGE" "1/16W"
					( Origin gFrontEnd )
				)
				( attribute "XY" "(-7175,3425)"
					( Origin gFrontEnd )
				)
				( attribute "CHIPS_PART_NAME" "RES"
					( Origin gPackager )
				)
				( attribute "CDS_PART_NAME" "RES_0402-4.75K,1%,1/16W,CHIP,GA"
					( Origin gPackager )
				)
				( objectStatus "R1L7" )
			)
			( gate "@baseboard_fab2_lib.baseboard_fab2(sch_1):page157_i385"
				( attribute "BOM_COST" "MIO_CHASSIS"
					( Origin gFrontEnd )
				)
				( attribute "CDS_LIB" "mstr_discrete"
					( Origin gPackager )
				)
				( attribute "CDS_LOCATION" "R8E32"
					( Origin gPackager )
				)
				( attribute "CDS_SEC" "1"
					( Origin gPackager )
				)
				( attribute "LOCATION" "R8E32"
					( Origin gFrontEnd )
				)
				( attribute "MATERIAL" "CHIP"
					( Origin gFrontEnd )
				)
				( attribute "PACK_TYPE" "0402"
					( Origin gFrontEnd )
				)
				( attribute "PART_NUMBER" "G21796-072"
					( Origin gFrontEnd )
				)
				( attribute "PHYS_PAGE" "157"
					( Origin gFrontEnd )
				)
				( attribute "ROOM" "MIO_CHASSIS"
					( Origin gFrontEnd )
				)
				( attribute "ROT" "0"
					( Origin gFrontEnd )
				)
				( attribute "SEC" "1"
					( Origin gFrontEnd )
				)
				( attribute "SEC_TYPE" "0402"
					( Origin gFrontEnd )
				)
				( attribute "TOLERANCE" "1%"
					( Origin gFrontEnd )
				)
				( attribute "VALUE" "4.75K"
					( Origin gFrontEnd )
				)
				( attribute "VER" "2"
					( Origin gFrontEnd )
				)
				( attribute "WATTAGE" "1/16W"
					( Origin gFrontEnd )
				)
				( attribute "XY" "(-3975,2950)"
					( Origin gFrontEnd )
				)
				( attribute "CHIPS_PART_NAME" "RES"
					( Origin gPackager )
				)
				( attribute "CDS_PART_NAME" "RES_0402-4.75K,1%,1/16W,CHIP,GA"
					( Origin gPackager )
				)
				( objectStatus "R8E32" )
			)
			( gate "@baseboard_fab2_lib.baseboard_fab2(sch_1):page157_i386"
				( attribute "BOM_COST" "SM"
					( Origin gFrontEnd )
				)
				( attribute "CDS_LIB" "mstr_discrete"
					( Origin gPackager )
				)
				( attribute "CDS_LOCATION" "R8D22"
					( Origin gPackager )
				)
				( attribute "CDS_SEC" "1"
					( Origin gPackager )
				)
				( attribute "LOCATION" "R8D22"
					( Origin gFrontEnd )
				)
				( attribute "MATERIAL" "CHIP"
					( Origin gFrontEnd )
				)
				( attribute "PACK_TYPE" "0402"
					( Origin gFrontEnd )
				)
				( attribute "PART_NUMBER" "G21796-074"
					( Origin gFrontEnd )
				)
				( attribute "PHYS_PAGE" "157"
					( Origin gFrontEnd )
				)
				( attribute "ROOM" "BMC_MISC"
					( Origin gFrontEnd )
				)
				( attribute "ROT" "0"
					( Origin gFrontEnd )
				)
				( attribute "SEC" "1"
					( Origin gFrontEnd )
				)
				( attribute "SEC_TYPE" "0402"
					( Origin gFrontEnd )
				)
				( attribute "TOLERANCE" "1%"
					( Origin gFrontEnd )
				)
				( attribute "VALUE" "33.2"
					( Origin gFrontEnd )
				)
				( attribute "VER" "1"
					( Origin gFrontEnd )
				)
				( attribute "WATTAGE" "1/16W"
					( Origin gFrontEnd )
				)
				( attribute "XY" "(-1925,1150)"
					( Origin gFrontEnd )
				)
				( attribute "CHIPS_PART_NAME" "RES"
					( Origin gPackager )
				)
				( attribute "CDS_PART_NAME" "RES_0402-33.2,1%,1/16W,CHIP,G2A"
					( Origin gPackager )
				)
				( objectStatus "R8D22" )
			)
			( gate "@baseboard_fab2_lib.baseboard_fab2(sch_1):page157_i388"
				( attribute "BOM_COST" "SM"
					( Origin gFrontEnd )
				)
				( attribute "CDS_LIB" "mstr_discrete"
					( Origin gPackager )
				)
				( attribute "CDS_LOCATION" "R8D36"
					( Origin gPackager )
				)
				( attribute "CDS_SEC" "1"
					( Origin gPackager )
				)
				( attribute "LOCATION" "R8D36"
					( Origin gFrontEnd )
				)
				( attribute "MATERIAL" "CHIP"
					( Origin gFrontEnd )
				)
				( attribute "PACK_TYPE" "0402"
					( Origin gFrontEnd )
				)
				( attribute "PART_NUMBER" "G21796-074"
					( Origin gFrontEnd )
				)
				( attribute "PHYS_PAGE" "157"
					( Origin gFrontEnd )
				)
				( attribute "ROOM" "BMC_MISC"
					( Origin gFrontEnd )
				)
				( attribute "ROT" "0"
					( Origin gFrontEnd )
				)
				( attribute "SEC" "1"
					( Origin gFrontEnd )
				)
				( attribute "SEC_TYPE" "0402"
					( Origin gFrontEnd )
				)
				( attribute "TOLERANCE" "1%"
					( Origin gFrontEnd )
				)
				( attribute "VALUE" "33.2"
					( Origin gFrontEnd )
				)
				( attribute "VER" "1"
					( Origin gFrontEnd )
				)
				( attribute "WATTAGE" "1/16W"
					( Origin gFrontEnd )
				)
				( attribute "XY" "(-1425,1375)"
					( Origin gFrontEnd )
				)
				( attribute "CHIPS_PART_NAME" "RES"
					( Origin gPackager )
				)
				( attribute "CDS_PART_NAME" "RES_0402-33.2,1%,1/16W,CHIP,G2A"
					( Origin gPackager )
				)
				( attribute "POP" "NOPOP"
					( Origin gFrontEnd )
				)
				( objectStatus "R8D36" )
			)
			( gate "@baseboard_fab2_lib.baseboard_fab2(sch_1):page158_i70"
				( attribute "BOM_COST" "DEBUG"
					( Origin gFrontEnd )
				)
				( attribute "CDS_LIB" "dev_discrete"
					( Origin gPackager )
				)
				( attribute "CDS_LOCATION" "C1T10"
					( Origin gPackager )
				)
				( attribute "CDS_SEC" "1"
					( Origin gPackager )
				)
				( attribute "LOCATION" "C1T10"
					( Origin gFrontEnd )
				)
				( attribute "MATERIAL" "X7R"
					( Origin gFrontEnd )
				)
				( attribute "PACK_TYPE" "0402V"
					( Origin gFrontEnd )
				)
				( attribute "PART_NUMBER" "A36096-030"
					( Origin gFrontEnd )
				)
				( attribute "PHYS_PAGE" "158"
					( Origin gFrontEnd )
				)
				( attribute "ROOM" "UART_MUX"
					( Origin gFrontEnd )
				)
				( attribute "ROT" "0"
					( Origin gFrontEnd )
				)
				( attribute "SEC" "1"
					( Origin gFrontEnd )
				)
				( attribute "SEC_TYPE" "0402V"
					( Origin gFrontEnd )
				)
				( attribute "TOLERANCE" "10%"
					( Origin gFrontEnd )
				)
				( attribute "VALUE" "0.1UF"
					( Origin gFrontEnd )
				)
				( attribute "VER" "1"
					( Origin gFrontEnd )
				)
				( attribute "VOLTAGE" "16V"
					( Units "uVoltage" "V" 1.000000)
					( Origin gFrontEnd )
				)
				( attribute "XY" "(-1675,2950)"
					( Origin gFrontEnd )
				)
				( attribute "CHIPS_PART_NAME" "CAP_A"
					( Origin gPackager )
				)
				( attribute "CDS_PART_NAME" "CAP_A_0402V-0.1UF,16V,10%,X7R,A"
					( Origin gPackager )
				)
				( objectStatus "C1T10" )
			)
			( gate "@baseboard_fab2_lib.baseboard_fab2(sch_1):page158_i74"
				( attribute "BOM_COST" "DEBUG"
					( Origin gFrontEnd )
				)
				( attribute "CDS_LIB" "mstr_analog"
					( Origin gPackager )
				)
				( attribute "CDS_LOCATION" "U9F2"
					( Origin gPackager )
				)
				( attribute "CDS_SEC" "1"
					( Origin gPackager )
				)
				( attribute "LOCATION" "U9F2"
					( Origin gFrontEnd )
				)
				( attribute "MATERIAL" "IC"
					( Origin gFrontEnd )
				)
				( attribute "PACK_TYPE" "SM"
					( Origin gFrontEnd )
				)
				( attribute "PART_NUMBER" "C63273-001"
					( Origin gFrontEnd )
				)
				( attribute "PHYS_PAGE" "158"
					( Origin gFrontEnd )
				)
				( attribute "ROOM" "UART_MUX"
					( Origin gFrontEnd )
				)
				( attribute "ROT" "2"
					( Origin gFrontEnd )
				)
				( attribute "SEC" "1"
					( Origin gFrontEnd )
				)
				( attribute "SEC_TYPE" "SM"
					( Origin gFrontEnd )
				)
				( attribute "VER" "1"
					( Origin gFrontEnd )
				)
				( attribute "XY" "(-2175,2575)"
					( Origin gFrontEnd )
				)
				( attribute "CHIPS_PART_NAME" "FSA3357"
					( Origin gPackager )
				)
				( attribute "CDS_PART_NAME" "FSA3357_SM-IC,C63273-001"
					( Origin gPackager )
				)
				( objectStatus "U9F2" )
			)
			( gate "@baseboard_fab2_lib.baseboard_fab2(sch_1):page158_i75"
				( attribute "BOM_COST" "DEBUG"
					( Origin gFrontEnd )
				)
				( attribute "CDS_LIB" "mstr_analog"
					( Origin gPackager )
				)
				( attribute "CDS_LOCATION" "U9F1"
					( Origin gPackager )
				)
				( attribute "CDS_SEC" "1"
					( Origin gPackager )
				)
				( attribute "LOCATION" "U9F1"
					( Origin gFrontEnd )
				)
				( attribute "MATERIAL" "IC"
					( Origin gFrontEnd )
				)
				( attribute "PACK_TYPE" "SM"
					( Origin gFrontEnd )
				)
				( attribute "PART_NUMBER" "C63273-001"
					( Origin gFrontEnd )
				)
				( attribute "PHYS_PAGE" "158"
					( Origin gFrontEnd )
				)
				( attribute "ROOM" "UART_MUX"
					( Origin gFrontEnd )
				)
				( attribute "ROT" "0"
					( Origin gFrontEnd )
				)
				( attribute "SEC" "1"
					( Origin gFrontEnd )
				)
				( attribute "SEC_TYPE" "SM"
					( Origin gFrontEnd )
				)
				( attribute "VER" "1"
					( Origin gFrontEnd )
				)
				( attribute "XY" "(-2650,850)"
					( Origin gFrontEnd )
				)
				( attribute "CHIPS_PART_NAME" "FSA3357"
					( Origin gPackager )
				)
				( attribute "CDS_PART_NAME" "FSA3357_SM-IC,C63273-001"
					( Origin gPackager )
				)
				( objectStatus "U9F1" )
			)
			( gate "@baseboard_fab2_lib.baseboard_fab2(sch_1):page158_i86"
				( attribute "BOM_COST" "DEBUG"
					( Origin gFrontEnd )
				)
				( attribute "CDS_LIB" "mstr_discrete"
					( Origin gPackager )
				)
				( attribute "CDS_LOCATION" "R9F25"
					( Origin gPackager )
				)
				( attribute "CDS_SEC" "1"
					( Origin gPackager )
				)
				( attribute "LOCATION" "R9F25"
					( Origin gFrontEnd )
				)
				( attribute "MATERIAL" "CHIP"
					( Origin gFrontEnd )
				)
				( attribute "PACK_TYPE" "0402"
					( Origin gFrontEnd )
				)
				( attribute "PART_NUMBER" "G21796-017"
					( Origin gFrontEnd )
				)
				( attribute "PHYS_PAGE" "158"
					( Origin gFrontEnd )
				)
				( attribute "ROOM" "UART_MUX"
					( Origin gFrontEnd )
				)
				( attribute "ROT" "0"
					( Origin gFrontEnd )
				)
				( attribute "SEC" "1"
					( Origin gFrontEnd )
				)
				( attribute "SEC_TYPE" "0402"
					( Origin gFrontEnd )
				)
				( attribute "TOLERANCE" "1%"
					( Origin gFrontEnd )
				)
				( attribute "VALUE" "100.0"
					( Origin gFrontEnd )
				)
				( attribute "VER" "1"
					( Origin gFrontEnd )
				)
				( attribute "WATTAGE" "1/16W"
					( Origin gFrontEnd )
				)
				( attribute "XY" "(-3625,900)"
					( Origin gFrontEnd )
				)
				( attribute "CHIPS_PART_NAME" "RES"
					( Origin gPackager )
				)
				( attribute "CDS_PART_NAME" "RES_0402-100.0,1%,1/16W,CHIP,GA"
					( Origin gPackager )
				)
				( objectStatus "R9F25" )
			)
			( gate "@baseboard_fab2_lib.baseboard_fab2(sch_1):page158_i91"
				( attribute "BOM_COST" "DEBUG"
					( Origin gFrontEnd )
				)
				( attribute "CDS_LIB" "mstr_discrete"
					( Origin gPackager )
				)
				( attribute "CDS_LOCATION" "R9F27"
					( Origin gPackager )
				)
				( attribute "CDS_SEC" "1"
					( Origin gPackager )
				)
				( attribute "LOCATION" "R9F27"
					( Origin gFrontEnd )
				)
				( attribute "MATERIAL" "CHIP"
					( Origin gFrontEnd )
				)
				( attribute "PACK_TYPE" "0402"
					( Origin gFrontEnd )
				)
				( attribute "PART_NUMBER" "G21497-005"
					( Origin gFrontEnd )
				)
				( attribute "PHYS_PAGE" "158"
					( Origin gFrontEnd )
				)
				( attribute "ROOM" "UART_MUX"
					( Origin gFrontEnd )
				)
				( attribute "ROT" "0"
					( Origin gFrontEnd )
				)
				( attribute "SEC" "1"
					( Origin gFrontEnd )
				)
				( attribute "SEC_TYPE" "0402"
					( Origin gFrontEnd )
				)
				( attribute "TOLERANCE" "5%"
					( Origin gFrontEnd )
				)
				( attribute "VALUE" "0.0"
					( Origin gFrontEnd )
				)
				( attribute "VER" "1"
					( Origin gFrontEnd )
				)
				( attribute "WATTAGE" "1/16W"
					( Origin gFrontEnd )
				)
				( attribute "XY" "(-1325,2625)"
					( Origin gFrontEnd )
				)
				( attribute "CHIPS_PART_NAME" "RES"
					( Origin gPackager )
				)
				( attribute "CDS_PART_NAME" "RES_0402-0.0,5%,1/16W,CHIP,G21A"
					( Origin gPackager )
				)
				( objectStatus "R9F27" )
			)
			( gate "@baseboard_fab2_lib.baseboard_fab2(sch_1):page158_i97"
				( attribute "BOM_COST" "DEBUG"
					( Origin gFrontEnd )
				)
				( attribute "CDS_LIB" "dev_discrete"
					( Origin gPackager )
				)
				( attribute "CDS_LOCATION" "C1T11"
					( Origin gPackager )
				)
				( attribute "CDS_SEC" "1"
					( Origin gPackager )
				)
				( attribute "LOCATION" "C1T11"
					( Origin gFrontEnd )
				)
				( attribute "MATERIAL" "X7R"
					( Origin gFrontEnd )
				)
				( attribute "PACK_TYPE" "0402V"
					( Origin gFrontEnd )
				)
				( attribute "PART_NUMBER" "A36096-030"
					( Origin gFrontEnd )
				)
				( attribute "PHYS_PAGE" "158"
					( Origin gFrontEnd )
				)
				( attribute "ROOM" "UART_MUX"
					( Origin gFrontEnd )
				)
				( attribute "ROT" "0"
					( Origin gFrontEnd )
				)
				( attribute "SEC" "1"
					( Origin gFrontEnd )
				)
				( attribute "SEC_TYPE" "0402V"
					( Origin gFrontEnd )
				)
				( attribute "TOLERANCE" "10%"
					( Origin gFrontEnd )
				)
				( attribute "VALUE" "0.1UF"
					( Origin gFrontEnd )
				)
				( attribute "VER" "1"
					( Origin gFrontEnd )
				)
				( attribute "VOLTAGE" "16V"
					( Units "uVoltage" "V" 1.000000)
					( Origin gFrontEnd )
				)
				( attribute "XY" "(-3475,1200)"
					( Origin gFrontEnd )
				)
				( attribute "CHIPS_PART_NAME" "CAP_A"
					( Origin gPackager )
				)
				( attribute "CDS_PART_NAME" "CAP_A_0402V-0.1UF,16V,10%,X7R,A"
					( Origin gPackager )
				)
				( objectStatus "C1T11" )
			)
			( gate "@baseboard_fab2_lib.baseboard_fab2(sch_1):page158_i99"
				( attribute "BOM_COST" "DEBUG"
					( Origin gFrontEnd )
				)
				( attribute "CDS_LIB" "mstr_discrete"
					( Origin gPackager )
				)
				( attribute "CDS_LOCATION" "R9F26"
					( Origin gPackager )
				)
				( attribute "CDS_SEC" "1"
					( Origin gPackager )
				)
				( attribute "LOCATION" "R9F26"
					( Origin gFrontEnd )
				)
				( attribute "MATERIAL" "EMPTY"
					( Origin gFrontEnd )
				)
				( attribute "PACK_TYPE" "0402"
					( Origin gFrontEnd )
				)
				( attribute "PART_NUMBER" "G21497-005"
					( Origin gFrontEnd )
				)
				( attribute "PHYS_PAGE" "158"
					( Origin gFrontEnd )
				)
				( attribute "ROOM" "UART_MUX"
					( Origin gFrontEnd )
				)
				( attribute "ROT" "0"
					( Origin gFrontEnd )
				)
				( attribute "SEC" "1"
					( Origin gFrontEnd )
				)
				( attribute "SEC_TYPE" "0402"
					( Origin gFrontEnd )
				)
				( attribute "TOLERANCE" "5%"
					( Origin gFrontEnd )
				)
				( attribute "VALUE" "0.0"
					( Origin gFrontEnd )
				)
				( attribute "VER" "1"
					( Origin gFrontEnd )
				)
				( attribute "WATTAGE" "1/16W"
					( Origin gFrontEnd )
				)
				( attribute "XY" "(-1900,3450)"
					( Origin gFrontEnd )
				)
				( attribute "CHIPS_PART_NAME" "RES"
					( Origin gPackager )
				)
				( attribute "CDS_PART_NAME" "RES_0402-0.0,5%,1/16W,EMPTY,G2A"
					( Origin gPackager )
				)
				( objectStatus "R9F26" )
			)
			( gate "@baseboard_fab2_lib.baseboard_fab2(sch_1):page158_i100"
				( attribute "BOM_COST" "DEBUG"
					( Origin gFrontEnd )
				)
				( attribute "CDS_LIB" "mstr_discrete"
					( Origin gPackager )
				)
				( attribute "CDS_LOCATION" "R9F24"
					( Origin gPackager )
				)
				( attribute "CDS_SEC" "1"
					( Origin gPackager )
				)
				( attribute "LOCATION" "R9F24"
					( Origin gFrontEnd )
				)
				( attribute "MATERIAL" "EMPTY"
					( Origin gFrontEnd )
				)
				( attribute "PACK_TYPE" "0402"
					( Origin gFrontEnd )
				)
				( attribute "PART_NUMBER" "G21497-005"
					( Origin gFrontEnd )
				)
				( attribute "PHYS_PAGE" "158"
					( Origin gFrontEnd )
				)
				( attribute "ROOM" "UART_MUX"
					( Origin gFrontEnd )
				)
				( attribute "ROT" "0"
					( Origin gFrontEnd )
				)
				( attribute "SEC" "1"
					( Origin gFrontEnd )
				)
				( attribute "SEC_TYPE" "0402"
					( Origin gFrontEnd )
				)
				( attribute "TOLERANCE" "5%"
					( Origin gFrontEnd )
				)
				( attribute "VALUE" "0.0"
					( Origin gFrontEnd )
				)
				( attribute "VER" "1"
					( Origin gFrontEnd )
				)
				( attribute "WATTAGE" "1/16W"
					( Origin gFrontEnd )
				)
				( attribute "XY" "(-2650,1525)"
					( Origin gFrontEnd )
				)
				( attribute "CHIPS_PART_NAME" "RES"
					( Origin gPackager )
				)
				( attribute "CDS_PART_NAME" "RES_0402-0.0,5%,1/16W,EMPTY,G2A"
					( Origin gPackager )
				)
				( objectStatus "R9F24" )
			)
			( gate "@baseboard_fab2_lib.baseboard_fab2(sch_1):page158_i130"
				( attribute "BOM_COST" "DEBUG"
					( Origin gFrontEnd )
				)
				( attribute "CDS_LIB" "mstr_discrete"
					( Origin gPackager )
				)
				( attribute "CDS_LOCATION" "DS9A4"
					( Origin gPackager )
				)
				( attribute "CDS_SEC" "1"
					( Origin gPackager )
				)
				( attribute "COLOR" "GREEN"
					( Origin gFrontEnd )
				)
				( attribute "LOCATION" "DS9A4"
					( Origin gFrontEnd )
				)
				( attribute "MATERIAL" "IC"
					( Origin gFrontEnd )
				)
				( attribute "PACK_TYPE" "A1LF"
					( Origin gFrontEnd )
				)
				( attribute "PART_NUMBER" "D14725-022"
					( Origin gFrontEnd )
				)
				( attribute "PHYS_PAGE" "158"
					( Origin gFrontEnd )
				)
				( attribute "ROOM" "UART_MUX"
					( Origin gFrontEnd )
				)
				( attribute "ROT" "0"
					( Origin gFrontEnd )
				)
				( attribute "SEC" "1"
					( Origin gFrontEnd )
				)
				( attribute "SEC_TYPE" "A1LF"
					( Origin gFrontEnd )
				)
				( attribute "VER" "3"
					( Origin gFrontEnd )
				)
				( attribute "XY" "(-5725,3200)"
					( Origin gFrontEnd )
				)
				( attribute "CHIPS_PART_NAME" "LED"
					( Origin gPackager )
				)
				( attribute "CDS_PART_NAME" "LED_A1LF-GREEN,IC,D14725-022"
					( Origin gPackager )
				)
				( objectStatus "DS9A4" )
			)
			( gate "@baseboard_fab2_lib.baseboard_fab2(sch_1):page158_i131"
				( attribute "BOM_COST" "DEBUG"
					( Origin gFrontEnd )
				)
				( attribute "CDS_LIB" "mstr_discrete"
					( Origin gPackager )
				)
				( attribute "CDS_LOCATION" "R1L43"
					( Origin gPackager )
				)
				( attribute "CDS_SEC" "1"
					( Origin gPackager )
				)
				( attribute "LOCATION" "R1L43"
					( Origin gFrontEnd )
				)
				( attribute "MATERIAL" "CHIP"
					( Origin gFrontEnd )
				)
				( attribute "PACK_TYPE" "0402"
					( Origin gFrontEnd )
				)
				( attribute "PART_NUMBER" "G21497-028"
					( Origin gFrontEnd )
				)
				( attribute "PHYS_PAGE" "158"
					( Origin gFrontEnd )
				)
				( attribute "ROOM" "UART_MUX"
					( Origin gFrontEnd )
				)
				( attribute "ROT" "0"
					( Origin gFrontEnd )
				)
				( attribute "SEC" "1"
					( Origin gFrontEnd )
				)
				( attribute "SEC_TYPE" "0402"
					( Origin gFrontEnd )
				)
				( attribute "TOLERANCE" "5%"
					( Origin gFrontEnd )
				)
				( attribute "VALUE" "330"
					( Origin gFrontEnd )
				)
				( attribute "VER" "1"
					( Origin gFrontEnd )
				)
				( attribute "WATTAGE" "1/16W"
					( Origin gFrontEnd )
				)
				( attribute "XY" "(-4875,3200)"
					( Origin gFrontEnd )
				)
				( attribute "CHIPS_PART_NAME" "RES"
					( Origin gPackager )
				)
				( attribute "CDS_PART_NAME" "RES_0402-330,5%,1/16W,CHIP,G21A"
					( Origin gPackager )
				)
				( objectStatus "R1L43" )
			)
			( gate "@baseboard_fab2_lib.baseboard_fab2(sch_1):page158_i134"
				( attribute "BOM_COST" "DEBUG"
					( Origin gFrontEnd )
				)
				( attribute "CDS_LIB" "mstr_discrete"
					( Origin gPackager )
				)
				( attribute "CDS_LOCATION" "DS9A7"
					( Origin gPackager )
				)
				( attribute "CDS_SEC" "1"
					( Origin gPackager )
				)
				( attribute "COLOR" "GREEN"
					( Origin gFrontEnd )
				)
				( attribute "LOCATION" "DS9A7"
					( Origin gFrontEnd )
				)
				( attribute "MATERIAL" "IC"
					( Origin gFrontEnd )
				)
				( attribute "PACK_TYPE" "A1LF"
					( Origin gFrontEnd )
				)
				( attribute "PART_NUMBER" "D14725-022"
					( Origin gFrontEnd )
				)
				( attribute "PHYS_PAGE" "158"
					( Origin gFrontEnd )
				)
				( attribute "ROOM" "UART_MUX"
					( Origin gFrontEnd )
				)
				( attribute "ROT" "0"
					( Origin gFrontEnd )
				)
				( attribute "SEC" "1"
					( Origin gFrontEnd )
				)
				( attribute "SEC_TYPE" "A1LF"
					( Origin gFrontEnd )
				)
				( attribute "VER" "3"
					( Origin gFrontEnd )
				)
				( attribute "XY" "(-5725,3600)"
					( Origin gFrontEnd )
				)
				( attribute "CHIPS_PART_NAME" "LED"
					( Origin gPackager )
				)
				( attribute "CDS_PART_NAME" "LED_A1LF-GREEN,IC,D14725-022"
					( Origin gPackager )
				)
				( objectStatus "DS9A7" )
			)
			( gate "@baseboard_fab2_lib.baseboard_fab2(sch_1):page158_i136"
				( attribute "BOM_COST" "DEBUG"
					( Origin gFrontEnd )
				)
				( attribute "CDS_LIB" "mstr_discrete"
					( Origin gPackager )
				)
				( attribute "CDS_LOCATION" "R1L44"
					( Origin gPackager )
				)
				( attribute "CDS_SEC" "1"
					( Origin gPackager )
				)
				( attribute "LOCATION" "R1L44"
					( Origin gFrontEnd )
				)
				( attribute "MATERIAL" "CHIP"
					( Origin gFrontEnd )
				)
				( attribute "PACK_TYPE" "0402"
					( Origin gFrontEnd )
				)
				( attribute "PART_NUMBER" "G21497-028"
					( Origin gFrontEnd )
				)
				( attribute "PHYS_PAGE" "158"
					( Origin gFrontEnd )
				)
				( attribute "ROOM" "UART_MUX"
					( Origin gFrontEnd )
				)
				( attribute "ROT" "0"
					( Origin gFrontEnd )
				)
				( attribute "SEC" "1"
					( Origin gFrontEnd )
				)
				( attribute "SEC_TYPE" "0402"
					( Origin gFrontEnd )
				)
				( attribute "TOLERANCE" "5%"
					( Origin gFrontEnd )
				)
				( attribute "VALUE" "330"
					( Origin gFrontEnd )
				)
				( attribute "VER" "1"
					( Origin gFrontEnd )
				)
				( attribute "WATTAGE" "1/16W"
					( Origin gFrontEnd )
				)
				( attribute "XY" "(-4875,3600)"
					( Origin gFrontEnd )
				)
				( attribute "CHIPS_PART_NAME" "RES"
					( Origin gPackager )
				)
				( attribute "CDS_PART_NAME" "RES_0402-330,5%,1/16W,CHIP,G21A"
					( Origin gPackager )
				)
				( objectStatus "R1L44" )
			)
			( gate "@baseboard_fab2_lib.baseboard_fab2(sch_1):page239_i98"
				( attribute "CDS_LIB" "w_hdl"
					( Origin gPackager )
				)
				( attribute "CDS_LMAN_SYM_OUTLINE" "-50,75,50,-75"
					( Origin gPackager )
				)
				( attribute "LOCATION" "R9F31"
					( Origin gFrontEnd )
				)
				( attribute "PACK_TYPE" "SMD-RG"
					( Origin gFrontEnd )
				)
				( attribute "PART_NUMBER" "64.51015.6DL"
					( Origin gFrontEnd )
				)
				( attribute "PHYS_PAGE" "239"
					( Origin gFrontEnd )
				)
				( attribute "ROT" "0"
					( Origin gFrontEnd )
				)
				( attribute "VALUE" "5K1R2F-2-GP"
					( Origin gFrontEnd )
				)
				( attribute "VER" "1"
					( Origin gFrontEnd )
				)
				( attribute "XY" "(10350,3525)"
					( Origin gFrontEnd )
				)
				( attribute "CHIPS_PART_NAME" "5K1R2F-2-GP"
					( Origin gPackager )
				)
				( attribute "CDS_PART_NAME" "5K1R2F-2-GP_SMD-RG-5K1R2F-2-GPA"
					( Origin gPackager )
				)
				( attribute "CDS_LOCATION" "R9F31"
					( Origin gPackager )
				)
				( attribute "CDS_SEC" "1"
					( Origin gPackager )
				)
				( attribute "SEC" "1"
					( Origin gPackager )
				)
				( attribute "ATTRIBUTE" "5.1KOHM"
					( Origin gFrontEnd )
				)
				( attribute "RATED" "1/16W"
					( Origin gFrontEnd )
				)
				( attribute "TOLERANCE" "1%"
					( Origin gFrontEnd )
				)
				( attribute "PACK_SIZE" "0402"
					( Origin gFrontEnd )
				)
				( objectStatus "R9F31" )
			)
			( gate "@baseboard_fab2_lib.baseboard_fab2(sch_1):page159_i210"
				( attribute "BOM_COST" "SM_CONTROLLER"
					( Origin gFrontEnd )
				)
				( attribute "CDS_LIB" "mstr_discrete"
					( Origin gPackager )
				)
				( attribute "CDS_LOCATION" "R8G3"
					( Origin gPackager )
				)
				( attribute "LOCATION" "R8G3"
					( Origin gFrontEnd )
				)
				( attribute "MATERIAL" "EMPTY"
					( Origin gFrontEnd )
				)
				( attribute "PACK_TYPE" "0402"
					( Origin gFrontEnd )
				)
				( attribute "PART_NUMBER" "G21796-311"
					( Origin gFrontEnd )
				)
				( attribute "PHYS_PAGE" "159"
					( Origin gFrontEnd )
				)
				( attribute "ROOM" "SMBUS"
					( Origin gFrontEnd )
				)
				( attribute "ROT" "0"
					( Origin gFrontEnd )
				)
				( attribute "SEC" "1"
					( Origin gFrontEnd )
				)
				( attribute "SKU" "B"
					( Origin gFrontEnd )
				)
				( attribute "TOLERANCE" "1.0%"
					( Origin gFrontEnd )
				)
				( attribute "VALUE" "2.26K"
					( Origin gFrontEnd )
				)
				( attribute "VER" "2"
					( Origin gFrontEnd )
				)
				( attribute "WATTAGE" "1/16W"
					( Origin gFrontEnd )
				)
				( attribute "XY" "(-3375,2900)"
					( Origin gFrontEnd )
				)
				( attribute "CHIPS_PART_NAME" "RES"
					( Origin gPackager )
				)
				( attribute "CDS_PART_NAME" "RES_0402-2.26K,1.0%,1/16W,EMPTA"
					( Origin gPackager )
				)
				( attribute "SEC_TYPE" "0402"
					( Origin gFrontEnd )
				)
				( attribute "CDS_SEC" "1"
					( Origin gPackager )
				)
				( objectStatus "R8G3" )
			)
			( gate "@baseboard_fab2_lib.baseboard_fab2(sch_1):page159_i212"
				( attribute "BOM_COST" "SM_CONTROLLER"
					( Origin gFrontEnd )
				)
				( attribute "CDS_LIB" "mstr_discrete"
					( Origin gPackager )
				)
				( attribute "CDS_LOCATION" "R8G6"
					( Origin gPackager )
				)
				( attribute "LOCATION" "R8G6"
					( Origin gFrontEnd )
				)
				( attribute "MATERIAL" "EMPTY"
					( Origin gFrontEnd )
				)
				( attribute "PACK_TYPE" "0402"
					( Origin gFrontEnd )
				)
				( attribute "PART_NUMBER" "G21796-311"
					( Origin gFrontEnd )
				)
				( attribute "PHYS_PAGE" "159"
					( Origin gFrontEnd )
				)
				( attribute "ROOM" "SMBUS"
					( Origin gFrontEnd )
				)
				( attribute "ROT" "0"
					( Origin gFrontEnd )
				)
				( attribute "SEC" "1"
					( Origin gFrontEnd )
				)
				( attribute "SKU" "B"
					( Origin gFrontEnd )
				)
				( attribute "TOLERANCE" "1.0%"
					( Origin gFrontEnd )
				)
				( attribute "VALUE" "2.26K"
					( Origin gFrontEnd )
				)
				( attribute "VER" "2"
					( Origin gFrontEnd )
				)
				( attribute "WATTAGE" "1/16W"
					( Origin gFrontEnd )
				)
				( attribute "XY" "(-3725,2900)"
					( Origin gFrontEnd )
				)
				( attribute "CHIPS_PART_NAME" "RES"
					( Origin gPackager )
				)
				( attribute "CDS_PART_NAME" "RES_0402-2.26K,1.0%,1/16W,EMPTA"
					( Origin gPackager )
				)
				( attribute "SEC_TYPE" "0402"
					( Origin gFrontEnd )
				)
				( attribute "CDS_SEC" "1"
					( Origin gPackager )
				)
				( objectStatus "R8G6" )
			)
			( gate "@baseboard_fab2_lib.baseboard_fab2(sch_1):page159_i214"
				( attribute "BOM_COST" "SM_CONTROLLER"
					( Origin gFrontEnd )
				)
				( attribute "CDS_LIB" "mstr_discrete"
					( Origin gPackager )
				)
				( attribute "CDS_LOCATION" "R2U5"
					( Origin gPackager )
				)
				( attribute "LOCATION" "R2U5"
					( Origin gFrontEnd )
				)
				( attribute "MATERIAL" "CHIP"
					( Origin gFrontEnd )
				)
				( attribute "PACK_TYPE" "0402"
					( Origin gFrontEnd )
				)
				( attribute "PART_NUMBER" "G21796-311"
					( Origin gFrontEnd )
				)
				( attribute "PHYS_PAGE" "159"
					( Origin gFrontEnd )
				)
				( attribute "ROOM" "SMBUS"
					( Origin gFrontEnd )
				)
				( attribute "ROT" "0"
					( Origin gFrontEnd )
				)
				( attribute "SEC" "1"
					( Origin gFrontEnd )
				)
				( attribute "SKU" "B"
					( Origin gFrontEnd )
				)
				( attribute "TOLERANCE" "1.0%"
					( Origin gFrontEnd )
				)
				( attribute "VALUE" "2.26K"
					( Origin gFrontEnd )
				)
				( attribute "VER" "2"
					( Origin gFrontEnd )
				)
				( attribute "WATTAGE" "1/16W"
					( Origin gFrontEnd )
				)
				( attribute "XY" "(550,4825)"
					( Origin gFrontEnd )
				)
				( attribute "CHIPS_PART_NAME" "RES"
					( Origin gPackager )
				)
				( attribute "CDS_PART_NAME" "RES_0402-2.26K,1.0%,1/16W,CHIPA"
					( Origin gPackager )
				)
				( attribute "SEC_TYPE" "0402"
					( Origin gFrontEnd )
				)
				( attribute "CDS_SEC" "1"
					( Origin gPackager )
				)
				( objectStatus "R2U5" )
			)
			( gate "@baseboard_fab2_lib.baseboard_fab2(sch_1):page159_i216"
				( attribute "BOM_COST" "SM_CONTROLLER"
					( Origin gFrontEnd )
				)
				( attribute "CDS_LIB" "mstr_discrete"
					( Origin gPackager )
				)
				( attribute "CDS_LOCATION" "R2U13"
					( Origin gPackager )
				)
				( attribute "LOCATION" "R2U13"
					( Origin gFrontEnd )
				)
				( attribute "MATERIAL" "CHIP"
					( Origin gFrontEnd )
				)
				( attribute "PACK_TYPE" "0402"
					( Origin gFrontEnd )
				)
				( attribute "PART_NUMBER" "G21796-311"
					( Origin gFrontEnd )
				)
				( attribute "PHYS_PAGE" "159"
					( Origin gFrontEnd )
				)
				( attribute "ROOM" "SMBUS"
					( Origin gFrontEnd )
				)
				( attribute "ROT" "0"
					( Origin gFrontEnd )
				)
				( attribute "SEC" "1"
					( Origin gFrontEnd )
				)
				( attribute "SKU" "B"
					( Origin gFrontEnd )
				)
				( attribute "TOLERANCE" "1.0%"
					( Origin gFrontEnd )
				)
				( attribute "VALUE" "2.26K"
					( Origin gFrontEnd )
				)
				( attribute "VER" "2"
					( Origin gFrontEnd )
				)
				( attribute "WATTAGE" "1/16W"
					( Origin gFrontEnd )
				)
				( attribute "XY" "(200,4825)"
					( Origin gFrontEnd )
				)
				( attribute "CHIPS_PART_NAME" "RES"
					( Origin gPackager )
				)
				( attribute "CDS_PART_NAME" "RES_0402-2.26K,1.0%,1/16W,CHIPA"
					( Origin gPackager )
				)
				( attribute "SEC_TYPE" "0402"
					( Origin gFrontEnd )
				)
				( attribute "CDS_SEC" "1"
					( Origin gPackager )
				)
				( objectStatus "R2U13" )
			)
			( gate "@baseboard_fab2_lib.baseboard_fab2(sch_1):page159_i218"
				( attribute "BOM_COST" "SM_CONTROLLER"
					( Origin gFrontEnd )
				)
				( attribute "CDS_LIB" "mstr_discrete"
					( Origin gPackager )
				)
				( attribute "CDS_LOCATION" "R2U1"
					( Origin gPackager )
				)
				( attribute "CDS_SEC" "1"
					( Origin gPackager )
				)
				( attribute "LOCATION" "R2U1"
					( Origin gFrontEnd )
				)
				( attribute "MATERIAL" "CHIP"
					( Origin gFrontEnd )
				)
				( attribute "PACK_TYPE" "0402"
					( Origin gFrontEnd )
				)
				( attribute "PART_NUMBER" "G21796-173"
					( Origin gFrontEnd )
				)
				( attribute "PHYS_PAGE" "159"
					( Origin gFrontEnd )
				)
				( attribute "ROOM" "SMBUS"
					( Origin gFrontEnd )
				)
				( attribute "ROT" "0"
					( Origin gFrontEnd )
				)
				( attribute "SEC" "1"
					( Origin gPackager )
				)
				( attribute "TOLERANCE" "1%"
					( Origin gFrontEnd )
				)
				( attribute "VALUE" "20.0"
					( Origin gFrontEnd )
				)
				( attribute "VER" "1"
					( Origin gFrontEnd )
				)
				( attribute "WATTAGE" "1/16W"
					( Origin gFrontEnd )
				)
				( attribute "XY" "(700,3375)"
					( Origin gFrontEnd )
				)
				( attribute "CHIPS_PART_NAME" "RES"
					( Origin gPackager )
				)
				( attribute "CDS_PART_NAME" "RES_0402-20.0,1%,1/16W,CHIP,G2A"
					( Origin gPackager )
				)
				( objectStatus "R2U1" )
			)
			( gate "@baseboard_fab2_lib.baseboard_fab2(sch_1):page159_i219"
				( attribute "BOM_COST" "SM_CONTROLLER"
					( Origin gFrontEnd )
				)
				( attribute "CDS_LIB" "mstr_discrete"
					( Origin gPackager )
				)
				( attribute "CDS_LOCATION" "R2T49"
					( Origin gPackager )
				)
				( attribute "CDS_SEC" "1"
					( Origin gPackager )
				)
				( attribute "LOCATION" "R2T49"
					( Origin gFrontEnd )
				)
				( attribute "MATERIAL" "CHIP"
					( Origin gFrontEnd )
				)
				( attribute "PACK_TYPE" "0402"
					( Origin gFrontEnd )
				)
				( attribute "PART_NUMBER" "G21796-173"
					( Origin gFrontEnd )
				)
				( attribute "PHYS_PAGE" "159"
					( Origin gFrontEnd )
				)
				( attribute "ROOM" "SMBUS"
					( Origin gFrontEnd )
				)
				( attribute "ROT" "0"
					( Origin gFrontEnd )
				)
				( attribute "SEC" "1"
					( Origin gPackager )
				)
				( attribute "TOLERANCE" "1%"
					( Origin gFrontEnd )
				)
				( attribute "VALUE" "20.0"
					( Origin gFrontEnd )
				)
				( attribute "VER" "1"
					( Origin gFrontEnd )
				)
				( attribute "WATTAGE" "1/16W"
					( Origin gFrontEnd )
				)
				( attribute "XY" "(700,3550)"
					( Origin gFrontEnd )
				)
				( attribute "CHIPS_PART_NAME" "RES"
					( Origin gPackager )
				)
				( attribute "CDS_PART_NAME" "RES_0402-20.0,1%,1/16W,CHIP,G2A"
					( Origin gPackager )
				)
				( objectStatus "R2T49" )
			)
			( gate "@baseboard_fab2_lib.baseboard_fab2(sch_1):page159_i220"
				( attribute "BOM_COST" "SM_CONTROLLER"
					( Origin gFrontEnd )
				)
				( attribute "CDS_LIB" "mstr_discrete"
					( Origin gPackager )
				)
				( attribute "CDS_LOCATION" "R2U7"
					( Origin gPackager )
				)
				( attribute "CDS_SEC" "1"
					( Origin gPackager )
				)
				( attribute "LOCATION" "R2U7"
					( Origin gFrontEnd )
				)
				( attribute "MATERIAL" "CHIP"
					( Origin gFrontEnd )
				)
				( attribute "PACK_TYPE" "0402"
					( Origin gFrontEnd )
				)
				( attribute "PART_NUMBER" "G21796-173"
					( Origin gFrontEnd )
				)
				( attribute "PHYS_PAGE" "159"
					( Origin gFrontEnd )
				)
				( attribute "ROOM" "SMBUS"
					( Origin gFrontEnd )
				)
				( attribute "ROT" "0"
					( Origin gFrontEnd )
				)
				( attribute "SEC" "1"
					( Origin gPackager )
				)
				( attribute "TOLERANCE" "1%"
					( Origin gFrontEnd )
				)
				( attribute "VALUE" "20.0"
					( Origin gFrontEnd )
				)
				( attribute "VER" "1"
					( Origin gFrontEnd )
				)
				( attribute "WATTAGE" "1/16W"
					( Origin gFrontEnd )
				)
				( attribute "XY" "(800,4275)"
					( Origin gFrontEnd )
				)
				( attribute "CHIPS_PART_NAME" "RES"
					( Origin gPackager )
				)
				( attribute "CDS_PART_NAME" "RES_0402-20.0,1%,1/16W,CHIP,G2A"
					( Origin gPackager )
				)
				( objectStatus "R2U7" )
			)
			( gate "@baseboard_fab2_lib.baseboard_fab2(sch_1):page159_i221"
				( attribute "BOM_COST" "SM_CONTROLLER"
					( Origin gFrontEnd )
				)
				( attribute "CDS_LIB" "mstr_discrete"
					( Origin gPackager )
				)
				( attribute "CDS_LOCATION" "R2U10"
					( Origin gPackager )
				)
				( attribute "CDS_SEC" "1"
					( Origin gPackager )
				)
				( attribute "LOCATION" "R2U10"
					( Origin gFrontEnd )
				)
				( attribute "MATERIAL" "CHIP"
					( Origin gFrontEnd )
				)
				( attribute "PACK_TYPE" "0402"
					( Origin gFrontEnd )
				)
				( attribute "PART_NUMBER" "G21796-173"
					( Origin gFrontEnd )
				)
				( attribute "PHYS_PAGE" "159"
					( Origin gFrontEnd )
				)
				( attribute "ROOM" "SMBUS"
					( Origin gFrontEnd )
				)
				( attribute "ROT" "0"
					( Origin gFrontEnd )
				)
				( attribute "SEC" "1"
					( Origin gPackager )
				)
				( attribute "TOLERANCE" "1%"
					( Origin gFrontEnd )
				)
				( attribute "VALUE" "20.0"
					( Origin gFrontEnd )
				)
				( attribute "VER" "1"
					( Origin gFrontEnd )
				)
				( attribute "WATTAGE" "1/16W"
					( Origin gFrontEnd )
				)
				( attribute "XY" "(800,4450)"
					( Origin gFrontEnd )
				)
				( attribute "CHIPS_PART_NAME" "RES"
					( Origin gPackager )
				)
				( attribute "CDS_PART_NAME" "RES_0402-20.0,1%,1/16W,CHIP,G2A"
					( Origin gPackager )
				)
				( objectStatus "R2U10" )
			)
			( gate "@baseboard_fab2_lib.baseboard_fab2(sch_1):page159_i222"
				( attribute "BOM_COST" "SM_CONTROLLER"
					( Origin gFrontEnd )
				)
				( attribute "CDS_LIB" "mstr_discrete"
					( Origin gPackager )
				)
				( attribute "CDS_LOCATION" "R1U11"
					( Origin gPackager )
				)
				( attribute "CDS_SEC" "1"
					( Origin gPackager )
				)
				( attribute "LOCATION" "R1U11"
					( Origin gFrontEnd )
				)
				( attribute "MATERIAL" "CHIP"
					( Origin gFrontEnd )
				)
				( attribute "PACK_TYPE" "0402"
					( Origin gFrontEnd )
				)
				( attribute "PART_NUMBER" "G21497-005"
					( Origin gFrontEnd )
				)
				( attribute "PHYS_PAGE" "159"
					( Origin gFrontEnd )
				)
				( attribute "ROOM" "SMBUS"
					( Origin gFrontEnd )
				)
				( attribute "ROT" "0"
					( Origin gFrontEnd )
				)
				( attribute "SEC" "1"
					( Origin gPackager )
				)
				( attribute "TOLERANCE" "5%"
					( Origin gFrontEnd )
				)
				( attribute "VALUE" "0.0"
					( Origin gFrontEnd )
				)
				( attribute "VER" "1"
					( Origin gFrontEnd )
				)
				( attribute "WATTAGE" "1/16W"
					( Origin gFrontEnd )
				)
				( attribute "XY" "(700,1600)"
					( Origin gFrontEnd )
				)
				( attribute "CHIPS_PART_NAME" "RES"
					( Origin gPackager )
				)
				( attribute "CDS_PART_NAME" "RES_0402-0.0,5%,1/16W,CHIP,G21A"
					( Origin gPackager )
				)
				( objectStatus "R1U11" )
			)
			( gate "@baseboard_fab2_lib.baseboard_fab2(sch_1):page159_i223"
				( attribute "BOM_COST" "SM_CONTROLLER"
					( Origin gFrontEnd )
				)
				( attribute "CDS_LIB" "mstr_discrete"
					( Origin gPackager )
				)
				( attribute "CDS_LOCATION" "R1U8"
					( Origin gPackager )
				)
				( attribute "CDS_SEC" "1"
					( Origin gPackager )
				)
				( attribute "LOCATION" "R1U8"
					( Origin gFrontEnd )
				)
				( attribute "MATERIAL" "CHIP"
					( Origin gFrontEnd )
				)
				( attribute "PACK_TYPE" "0402"
					( Origin gFrontEnd )
				)
				( attribute "PART_NUMBER" "G21497-005"
					( Origin gFrontEnd )
				)
				( attribute "PHYS_PAGE" "159"
					( Origin gFrontEnd )
				)
				( attribute "ROOM" "SMBUS"
					( Origin gFrontEnd )
				)
				( attribute "ROT" "0"
					( Origin gFrontEnd )
				)
				( attribute "SEC" "1"
					( Origin gPackager )
				)
				( attribute "TOLERANCE" "5%"
					( Origin gFrontEnd )
				)
				( attribute "VALUE" "0.0"
					( Origin gFrontEnd )
				)
				( attribute "VER" "1"
					( Origin gFrontEnd )
				)
				( attribute "WATTAGE" "1/16W"
					( Origin gFrontEnd )
				)
				( attribute "XY" "(700,1775)"
					( Origin gFrontEnd )
				)
				( attribute "CHIPS_PART_NAME" "RES"
					( Origin gPackager )
				)
				( attribute "CDS_PART_NAME" "RES_0402-0.0,5%,1/16W,CHIP,G21A"
					( Origin gPackager )
				)
				( objectStatus "R1U8" )
			)
			( gate "@baseboard_fab2_lib.baseboard_fab2(sch_1):page159_i224"
				( attribute "BOM_COST" "SM_CONTROLLER"
					( Origin gFrontEnd )
				)
				( attribute "CDS_LIB" "mstr_discrete"
					( Origin gPackager )
				)
				( attribute "CDS_LOCATION" "R9G12"
					( Origin gPackager )
				)
				( attribute "CDS_SEC" "1"
					( Origin gPackager )
				)
				( attribute "LOCATION" "R9G12"
					( Origin gFrontEnd )
				)
				( attribute "MATERIAL" "CHIP"
					( Origin gFrontEnd )
				)
				( attribute "PACK_TYPE" "0402"
					( Origin gFrontEnd )
				)
				( attribute "PART_NUMBER" "G21796-173"
					( Origin gFrontEnd )
				)
				( attribute "PHYS_PAGE" "159"
					( Origin gFrontEnd )
				)
				( attribute "ROOM" "SMBUS"
					( Origin gFrontEnd )
				)
				( attribute "ROT" "0"
					( Origin gFrontEnd )
				)
				( attribute "SEC" "1"
					( Origin gPackager )
				)
				( attribute "TOLERANCE" "1%"
					( Origin gFrontEnd )
				)
				( attribute "VALUE" "20.0"
					( Origin gFrontEnd )
				)
				( attribute "VER" "1"
					( Origin gFrontEnd )
				)
				( attribute "WATTAGE" "1/16W"
					( Origin gFrontEnd )
				)
				( attribute "XY" "(-3625,1575)"
					( Origin gFrontEnd )
				)
				( attribute "CHIPS_PART_NAME" "RES"
					( Origin gPackager )
				)
				( attribute "CDS_PART_NAME" "RES_0402-20.0,1%,1/16W,CHIP,G2A"
					( Origin gPackager )
				)
				( objectStatus "R9G12" )
			)
			( gate "@baseboard_fab2_lib.baseboard_fab2(sch_1):page159_i225"
				( attribute "BOM_COST" "SM_CONTROLLER"
					( Origin gFrontEnd )
				)
				( attribute "CDS_LIB" "mstr_discrete"
					( Origin gPackager )
				)
				( attribute "CDS_LOCATION" "R1U20"
					( Origin gPackager )
				)
				( attribute "CDS_SEC" "1"
					( Origin gPackager )
				)
				( attribute "LOCATION" "R1U20"
					( Origin gFrontEnd )
				)
				( attribute "MATERIAL" "CHIP"
					( Origin gFrontEnd )
				)
				( attribute "PACK_TYPE" "0402"
					( Origin gFrontEnd )
				)
				( attribute "PART_NUMBER" "G21796-173"
					( Origin gFrontEnd )
				)
				( attribute "PHYS_PAGE" "159"
					( Origin gFrontEnd )
				)
				( attribute "ROOM" "SMBUS"
					( Origin gFrontEnd )
				)
				( attribute "ROT" "0"
					( Origin gFrontEnd )
				)
				( attribute "SEC" "1"
					( Origin gPackager )
				)
				( attribute "TOLERANCE" "1%"
					( Origin gFrontEnd )
				)
				( attribute "VALUE" "20.0"
					( Origin gFrontEnd )
				)
				( attribute "VER" "1"
					( Origin gFrontEnd )
				)
				( attribute "WATTAGE" "1/16W"
					( Origin gFrontEnd )
				)
				( attribute "XY" "(-3625,1450)"
					( Origin gFrontEnd )
				)
				( attribute "CHIPS_PART_NAME" "RES"
					( Origin gPackager )
				)
				( attribute "CDS_PART_NAME" "RES_0402-20.0,1%,1/16W,CHIP,G2A"
					( Origin gPackager )
				)
				( objectStatus "R1U20" )
			)
			( gate "@baseboard_fab2_lib.baseboard_fab2(sch_1):page159_i226"
				( attribute "BOM_COST" "SM_CONTROLLER"
					( Origin gFrontEnd )
				)
				( attribute "CDS_LIB" "mstr_discrete"
					( Origin gPackager )
				)
				( attribute "CDS_LOCATION" "R1U19"
					( Origin gPackager )
				)
				( attribute "CDS_SEC" "1"
					( Origin gPackager )
				)
				( attribute "LOCATION" "R1U19"
					( Origin gFrontEnd )
				)
				( attribute "MATERIAL" "CHIP"
					( Origin gFrontEnd )
				)
				( attribute "PACK_TYPE" "0402"
					( Origin gFrontEnd )
				)
				( attribute "PART_NUMBER" "G21796-173"
					( Origin gFrontEnd )
				)
				( attribute "PHYS_PAGE" "159"
					( Origin gFrontEnd )
				)
				( attribute "ROOM" "SMBUS"
					( Origin gFrontEnd )
				)
				( attribute "ROT" "0"
					( Origin gFrontEnd )
				)
				( attribute "SEC" "1"
					( Origin gPackager )
				)
				( attribute "TOLERANCE" "1%"
					( Origin gFrontEnd )
				)
				( attribute "VALUE" "20.0"
					( Origin gFrontEnd )
				)
				( attribute "VER" "1"
					( Origin gFrontEnd )
				)
				( attribute "WATTAGE" "1/16W"
					( Origin gFrontEnd )
				)
				( attribute "XY" "(-3625,1325)"
					( Origin gFrontEnd )
				)
				( attribute "CHIPS_PART_NAME" "RES"
					( Origin gPackager )
				)
				( attribute "CDS_PART_NAME" "RES_0402-20.0,1%,1/16W,CHIP,G2A"
					( Origin gPackager )
				)
				( objectStatus "R1U19" )
			)
			( gate "@baseboard_fab2_lib.baseboard_fab2(sch_1):page159_i227"
				( attribute "BOM_COST" "SM_CONTROLLER"
					( Origin gFrontEnd )
				)
				( attribute "CDS_LIB" "mstr_discrete"
					( Origin gPackager )
				)
				( attribute "CDS_LOCATION" "R9G13"
					( Origin gPackager )
				)
				( attribute "CDS_SEC" "1"
					( Origin gPackager )
				)
				( attribute "LOCATION" "R9G13"
					( Origin gFrontEnd )
				)
				( attribute "MATERIAL" "CHIP"
					( Origin gFrontEnd )
				)
				( attribute "PACK_TYPE" "0402"
					( Origin gFrontEnd )
				)
				( attribute "PART_NUMBER" "G21796-173"
					( Origin gFrontEnd )
				)
				( attribute "PHYS_PAGE" "159"
					( Origin gFrontEnd )
				)
				( attribute "ROOM" "SMBUS"
					( Origin gFrontEnd )
				)
				( attribute "ROT" "0"
					( Origin gFrontEnd )
				)
				( attribute "SEC" "1"
					( Origin gPackager )
				)
				( attribute "TOLERANCE" "1%"
					( Origin gFrontEnd )
				)
				( attribute "VALUE" "20.0"
					( Origin gFrontEnd )
				)
				( attribute "VER" "1"
					( Origin gFrontEnd )
				)
				( attribute "WATTAGE" "1/16W"
					( Origin gFrontEnd )
				)
				( attribute "XY" "(-3625,1200)"
					( Origin gFrontEnd )
				)
				( attribute "CHIPS_PART_NAME" "RES"
					( Origin gPackager )
				)
				( attribute "CDS_PART_NAME" "RES_0402-20.0,1%,1/16W,CHIP,G2A"
					( Origin gPackager )
				)
				( objectStatus "R9G13" )
			)
			( gate "@baseboard_fab2_lib.baseboard_fab2(sch_1):page159_i228"
				( attribute "BOM_COST" "SM_CONTROLLER"
					( Origin gFrontEnd )
				)
				( attribute "CDS_LIB" "mstr_discrete"
					( Origin gPackager )
				)
				( attribute "CDS_LOCATION" "R8G5"
					( Origin gPackager )
				)
				( attribute "CDS_SEC" "1"
					( Origin gPackager )
				)
				( attribute "LOCATION" "R8G5"
					( Origin gFrontEnd )
				)
				( attribute "MATERIAL" "CHIP"
					( Origin gFrontEnd )
				)
				( attribute "PACK_TYPE" "0402"
					( Origin gFrontEnd )
				)
				( attribute "PART_NUMBER" "G21796-173"
					( Origin gFrontEnd )
				)
				( attribute "PHYS_PAGE" "159"
					( Origin gFrontEnd )
				)
				( attribute "ROOM" "SMBUS"
					( Origin gFrontEnd )
				)
				( attribute "ROT" "0"
					( Origin gFrontEnd )
				)
				( attribute "SEC" "1"
					( Origin gPackager )
				)
				( attribute "TOLERANCE" "1%"
					( Origin gFrontEnd )
				)
				( attribute "VALUE" "20.0"
					( Origin gFrontEnd )
				)
				( attribute "VER" "1"
					( Origin gFrontEnd )
				)
				( attribute "WATTAGE" "1/16W"
					( Origin gFrontEnd )
				)
				( attribute "XY" "(-2875,2525)"
					( Origin gFrontEnd )
				)
				( attribute "CHIPS_PART_NAME" "RES"
					( Origin gPackager )
				)
				( attribute "CDS_PART_NAME" "RES_0402-20.0,1%,1/16W,CHIP,G2A"
					( Origin gPackager )
				)
				( objectStatus "R8G5" )
			)
			( gate "@baseboard_fab2_lib.baseboard_fab2(sch_1):page159_i229"
				( attribute "BOM_COST" "SM_CONTROLLER"
					( Origin gFrontEnd )
				)
				( attribute "CDS_LIB" "mstr_discrete"
					( Origin gPackager )
				)
				( attribute "CDS_LOCATION" "R8G4"
					( Origin gPackager )
				)
				( attribute "CDS_SEC" "1"
					( Origin gPackager )
				)
				( attribute "LOCATION" "R8G4"
					( Origin gFrontEnd )
				)
				( attribute "MATERIAL" "CHIP"
					( Origin gFrontEnd )
				)
				( attribute "PACK_TYPE" "0402"
					( Origin gFrontEnd )
				)
				( attribute "PART_NUMBER" "G21796-173"
					( Origin gFrontEnd )
				)
				( attribute "PHYS_PAGE" "159"
					( Origin gFrontEnd )
				)
				( attribute "ROOM" "SMBUS"
					( Origin gFrontEnd )
				)
				( attribute "ROT" "0"
					( Origin gFrontEnd )
				)
				( attribute "SEC" "1"
					( Origin gPackager )
				)
				( attribute "TOLERANCE" "1%"
					( Origin gFrontEnd )
				)
				( attribute "VALUE" "20.0"
					( Origin gFrontEnd )
				)
				( attribute "VER" "1"
					( Origin gFrontEnd )
				)
				( attribute "WATTAGE" "1/16W"
					( Origin gFrontEnd )
				)
				( attribute "XY" "(-2875,2350)"
					( Origin gFrontEnd )
				)
				( attribute "CHIPS_PART_NAME" "RES"
					( Origin gPackager )
				)
				( attribute "CDS_PART_NAME" "RES_0402-20.0,1%,1/16W,CHIP,G2A"
					( Origin gPackager )
				)
				( objectStatus "R8G4" )
			)
			( gate "@baseboard_fab2_lib.baseboard_fab2(sch_1):page159_i230"
				( attribute "BOM_COST" "SM_CONTROLLER"
					( Origin gFrontEnd )
				)
				( attribute "CDS_LIB" "mstr_discrete"
					( Origin gPackager )
				)
				( attribute "CDS_LOCATION" "R2U34"
					( Origin gPackager )
				)
				( attribute "CDS_SEC" "1"
					( Origin gPackager )
				)
				( attribute "LOCATION" "R2U34"
					( Origin gFrontEnd )
				)
				( attribute "MATERIAL" "CHIP"
					( Origin gFrontEnd )
				)
				( attribute "PACK_TYPE" "0402"
					( Origin gFrontEnd )
				)
				( attribute "PART_NUMBER" "G21796-173"
					( Origin gFrontEnd )
				)
				( attribute "PHYS_PAGE" "159"
					( Origin gFrontEnd )
				)
				( attribute "ROOM" "SMBUS"
					( Origin gFrontEnd )
				)
				( attribute "ROT" "0"
					( Origin gFrontEnd )
				)
				( attribute "SEC" "1"
					( Origin gPackager )
				)
				( attribute "TOLERANCE" "1%"
					( Origin gFrontEnd )
				)
				( attribute "VALUE" "20.0"
					( Origin gFrontEnd )
				)
				( attribute "VER" "1"
					( Origin gFrontEnd )
				)
				( attribute "WATTAGE" "1/16W"
					( Origin gFrontEnd )
				)
				( attribute "XY" "(-3175,3600)"
					( Origin gFrontEnd )
				)
				( attribute "CHIPS_PART_NAME" "RES"
					( Origin gPackager )
				)
				( attribute "CDS_PART_NAME" "RES_0402-20.0,1%,1/16W,CHIP,G2A"
					( Origin gPackager )
				)
				( objectStatus "R2U34" )
			)
			( gate "@baseboard_fab2_lib.baseboard_fab2(sch_1):page159_i231"
				( attribute "BOM_COST" "SM_CONTROLLER"
					( Origin gFrontEnd )
				)
				( attribute "CDS_LIB" "mstr_discrete"
					( Origin gPackager )
				)
				( attribute "CDS_LOCATION" "R2U33"
					( Origin gPackager )
				)
				( attribute "CDS_SEC" "1"
					( Origin gPackager )
				)
				( attribute "LOCATION" "R2U33"
					( Origin gFrontEnd )
				)
				( attribute "MATERIAL" "CHIP"
					( Origin gFrontEnd )
				)
				( attribute "PACK_TYPE" "0402"
					( Origin gFrontEnd )
				)
				( attribute "PART_NUMBER" "G21796-173"
					( Origin gFrontEnd )
				)
				( attribute "PHYS_PAGE" "159"
					( Origin gFrontEnd )
				)
				( attribute "ROOM" "SMBUS"
					( Origin gFrontEnd )
				)
				( attribute "ROT" "0"
					( Origin gFrontEnd )
				)
				( attribute "SEC" "1"
					( Origin gPackager )
				)
				( attribute "TOLERANCE" "1%"
					( Origin gFrontEnd )
				)
				( attribute "VALUE" "20.0"
					( Origin gFrontEnd )
				)
				( attribute "VER" "1"
					( Origin gFrontEnd )
				)
				( attribute "WATTAGE" "1/16W"
					( Origin gFrontEnd )
				)
				( attribute "XY" "(-3175,3775)"
					( Origin gFrontEnd )
				)
				( attribute "CHIPS_PART_NAME" "RES"
					( Origin gPackager )
				)
				( attribute "CDS_PART_NAME" "RES_0402-20.0,1%,1/16W,CHIP,G2A"
					( Origin gPackager )
				)
				( objectStatus "R2U33" )
			)
			( gate "@baseboard_fab2_lib.baseboard_fab2(sch_1):page159_i232"
				( attribute "BOM_COST" "SM_CONTROLLER"
					( Origin gFrontEnd )
				)
				( attribute "CDS_LIB" "mstr_discrete"
					( Origin gPackager )
				)
				( attribute "CDS_LOCATION" "R1U9"
					( Origin gPackager )
				)
				( attribute "CDS_SEC" "1"
					( Origin gPackager )
				)
				( attribute "LOCATION" "R1U9"
					( Origin gFrontEnd )
				)
				( attribute "MATERIAL" "CHIP"
					( Origin gFrontEnd )
				)
				( attribute "PACK_TYPE" "0402"
					( Origin gFrontEnd )
				)
				( attribute "PART_NUMBER" "G21796-173"
					( Origin gFrontEnd )
				)
				( attribute "PHYS_PAGE" "159"
					( Origin gFrontEnd )
				)
				( attribute "ROOM" "SMBUS"
					( Origin gFrontEnd )
				)
				( attribute "ROT" "0"
					( Origin gFrontEnd )
				)
				( attribute "SEC" "1"
					( Origin gPackager )
				)
				( attribute "TOLERANCE" "1%"
					( Origin gFrontEnd )
				)
				( attribute "VALUE" "20.0"
					( Origin gFrontEnd )
				)
				( attribute "VER" "1"
					( Origin gFrontEnd )
				)
				( attribute "WATTAGE" "1/16W"
					( Origin gFrontEnd )
				)
				( attribute "XY" "(-3175,4775)"
					( Origin gFrontEnd )
				)
				( attribute "CHIPS_PART_NAME" "RES"
					( Origin gPackager )
				)
				( attribute "CDS_PART_NAME" "RES_0402-20.0,1%,1/16W,CHIP,G2A"
					( Origin gPackager )
				)
				( objectStatus "R1U9" )
			)
			( gate "@baseboard_fab2_lib.baseboard_fab2(sch_1):page159_i233"
				( attribute "BOM_COST" "SM_CONTROLLER"
					( Origin gFrontEnd )
				)
				( attribute "CDS_LIB" "mstr_discrete"
					( Origin gPackager )
				)
				( attribute "CDS_LOCATION" "R1U10"
					( Origin gPackager )
				)
				( attribute "CDS_SEC" "1"
					( Origin gPackager )
				)
				( attribute "LOCATION" "R1U10"
					( Origin gFrontEnd )
				)
				( attribute "MATERIAL" "CHIP"
					( Origin gFrontEnd )
				)
				( attribute "PACK_TYPE" "0402"
					( Origin gFrontEnd )
				)
				( attribute "PART_NUMBER" "G21796-173"
					( Origin gFrontEnd )
				)
				( attribute "PHYS_PAGE" "159"
					( Origin gFrontEnd )
				)
				( attribute "ROOM" "SMBUS"
					( Origin gFrontEnd )
				)
				( attribute "ROT" "0"
					( Origin gFrontEnd )
				)
				( attribute "SEC" "1"
					( Origin gPackager )
				)
				( attribute "TOLERANCE" "1%"
					( Origin gFrontEnd )
				)
				( attribute "VALUE" "20.0"
					( Origin gFrontEnd )
				)
				( attribute "VER" "1"
					( Origin gFrontEnd )
				)
				( attribute "WATTAGE" "1/16W"
					( Origin gFrontEnd )
				)
				( attribute "XY" "(-3175,4950)"
					( Origin gFrontEnd )
				)
				( attribute "CHIPS_PART_NAME" "RES"
					( Origin gPackager )
				)
				( attribute "CDS_PART_NAME" "RES_0402-20.0,1%,1/16W,CHIP,G2A"
					( Origin gPackager )
				)
				( objectStatus "R1U10" )
			)
			( gate "@baseboard_fab2_lib.baseboard_fab2(sch_1):page160_i4"
				( attribute "BOM_COST" "SM_CONTROLLER"
					( Origin gFrontEnd )
				)
				( attribute "CDS_LIB" "mstr_discrete"
					( Origin gPackager )
				)
				( attribute "CDS_LOCATION" "R1T8"
					( Origin gPackager )
				)
				( attribute "CDS_SEC" "1"
					( Origin gPackager )
				)
				( attribute "LOCATION" "R1T8"
					( Origin gFrontEnd )
				)
				( attribute "MATERIAL" "CHIP"
					( Origin gFrontEnd )
				)
				( attribute "PACK_TYPE" "0402"
					( Origin gFrontEnd )
				)
				( attribute "PART_NUMBER" "G21796-173"
					( Origin gFrontEnd )
				)
				( attribute "PHYS_PAGE" "160"
					( Origin gFrontEnd )
				)
				( attribute "ROOM" "SMBUS"
					( Origin gFrontEnd )
				)
				( attribute "ROT" "0"
					( Origin gFrontEnd )
				)
				( attribute "SEC" "1"
					( Origin gPackager )
				)
				( attribute "TOLERANCE" "1%"
					( Origin gFrontEnd )
				)
				( attribute "VALUE" "20.0"
					( Origin gFrontEnd )
				)
				( attribute "VER" "1"
					( Origin gFrontEnd )
				)
				( attribute "WATTAGE" "1/16W"
					( Origin gFrontEnd )
				)
				( attribute "XY" "(-3350,4600)"
					( Origin gFrontEnd )
				)
				( attribute "CHIPS_PART_NAME" "RES"
					( Origin gPackager )
				)
				( attribute "CDS_PART_NAME" "RES_0402-20.0,1%,1/16W,CHIP,G2A"
					( Origin gPackager )
				)
				( objectStatus "R1T8" )
			)
			( gate "@baseboard_fab2_lib.baseboard_fab2(sch_1):page160_i46"
				( attribute "BOM_COST" "SM_CONTROLLER"
					( Origin gFrontEnd )
				)
				( attribute "CDS_LIB" "mstr_discrete"
					( Origin gPackager )
				)
				( attribute "CDS_LOCATION" "R1T3"
					( Origin gPackager )
				)
				( attribute "LOCATION" "R1T3"
					( Origin gFrontEnd )
				)
				( attribute "MATERIAL" "CHIP"
					( Origin gFrontEnd )
				)
				( attribute "PACK_TYPE" "0402"
					( Origin gFrontEnd )
				)
				( attribute "PART_NUMBER" "G21796-235"
					( Origin gFrontEnd )
				)
				( attribute "PHYS_PAGE" "160"
					( Origin gFrontEnd )
				)
				( attribute "ROOM" "SMBUS"
					( Origin gFrontEnd )
				)
				( attribute "ROT" "0"
					( Origin gFrontEnd )
				)
				( attribute "SEC" "1"
					( Origin gFrontEnd )
				)
				( attribute "SKU" "B"
					( Origin gFrontEnd )
				)
				( attribute "TOLERANCE" "1.0%"
					( Origin gFrontEnd )
				)
				( attribute "VALUE" "665"
					( Origin gFrontEnd )
				)
				( attribute "VER" "2"
					( Origin gFrontEnd )
				)
				( attribute "WATTAGE" "1/16W"
					( Origin gFrontEnd )
				)
				( attribute "XY" "(-4000,4975)"
					( Origin gFrontEnd )
				)
				( attribute "CHIPS_PART_NAME" "RES"
					( Origin gPackager )
				)
				( attribute "CDS_PART_NAME" "RES_0402-665,1.0%,1/16W,CHIP,GA"
					( Origin gPackager )
				)
				( attribute "SEC_TYPE" "0402"
					( Origin gFrontEnd )
				)
				( attribute "CDS_SEC" "1"
					( Origin gPackager )
				)
				( objectStatus "R1T3" )
			)
			( gate "@baseboard_fab2_lib.baseboard_fab2(sch_1):page160_i49"
				( attribute "BOM_COST" "SM_CONTROLLER"
					( Origin gFrontEnd )
				)
				( attribute "CDS_LIB" "mstr_discrete"
					( Origin gPackager )
				)
				( attribute "CDS_LOCATION" "R1T2"
					( Origin gPackager )
				)
				( attribute "LOCATION" "R1T2"
					( Origin gFrontEnd )
				)
				( attribute "MATERIAL" "CHIP"
					( Origin gFrontEnd )
				)
				( attribute "PACK_TYPE" "0402"
					( Origin gFrontEnd )
				)
				( attribute "PART_NUMBER" "G21796-235"
					( Origin gFrontEnd )
				)
				( attribute "PHYS_PAGE" "160"
					( Origin gFrontEnd )
				)
				( attribute "ROOM" "SMBUS"
					( Origin gFrontEnd )
				)
				( attribute "ROT" "0"
					( Origin gFrontEnd )
				)
				( attribute "SEC" "1"
					( Origin gFrontEnd )
				)
				( attribute "SKU" "B"
					( Origin gFrontEnd )
				)
				( attribute "TOLERANCE" "1.0%"
					( Origin gFrontEnd )
				)
				( attribute "VALUE" "665"
					( Origin gFrontEnd )
				)
				( attribute "VER" "2"
					( Origin gFrontEnd )
				)
				( attribute "WATTAGE" "1/16W"
					( Origin gFrontEnd )
				)
				( attribute "XY" "(-3650,4975)"
					( Origin gFrontEnd )
				)
				( attribute "CHIPS_PART_NAME" "RES"
					( Origin gPackager )
				)
				( attribute "CDS_PART_NAME" "RES_0402-665,1.0%,1/16W,CHIP,GA"
					( Origin gPackager )
				)
				( attribute "SEC_TYPE" "0402"
					( Origin gFrontEnd )
				)
				( attribute "CDS_SEC" "1"
					( Origin gPackager )
				)
				( objectStatus "R1T2" )
			)
			( gate "@baseboard_fab2_lib.baseboard_fab2(sch_1):page160_i50"
				( attribute "BOM_COST" "SM_CONTROLLER"
					( Origin gFrontEnd )
				)
				( attribute "CDS_LIB" "mstr_discrete"
					( Origin gPackager )
				)
				( attribute "CDS_LOCATION" "R1T7"
					( Origin gPackager )
				)
				( attribute "CDS_SEC" "1"
					( Origin gPackager )
				)
				( attribute "LOCATION" "R1T7"
					( Origin gFrontEnd )
				)
				( attribute "MATERIAL" "CHIP"
					( Origin gFrontEnd )
				)
				( attribute "PACK_TYPE" "0402"
					( Origin gFrontEnd )
				)
				( attribute "PART_NUMBER" "G21796-173"
					( Origin gFrontEnd )
				)
				( attribute "PHYS_PAGE" "160"
					( Origin gFrontEnd )
				)
				( attribute "ROOM" "SMBUS"
					( Origin gFrontEnd )
				)
				( attribute "ROT" "0"
					( Origin gFrontEnd )
				)
				( attribute "SEC" "1"
					( Origin gPackager )
				)
				( attribute "TOLERANCE" "1%"
					( Origin gFrontEnd )
				)
				( attribute "VALUE" "20.0"
					( Origin gFrontEnd )
				)
				( attribute "VER" "1"
					( Origin gFrontEnd )
				)
				( attribute "WATTAGE" "1/16W"
					( Origin gFrontEnd )
				)
				( attribute "XY" "(-3350,4425)"
					( Origin gFrontEnd )
				)
				( attribute "CHIPS_PART_NAME" "RES"
					( Origin gPackager )
				)
				( attribute "CDS_PART_NAME" "RES_0402-20.0,1%,1/16W,CHIP,G2A"
					( Origin gPackager )
				)
				( objectStatus "R1T7" )
			)
			( gate "@baseboard_fab2_lib.baseboard_fab2(sch_1):page160_i51"
				( attribute "BOM_COST" "SM_CONTROLLER"
					( Origin gFrontEnd )
				)
				( attribute "CDS_LIB" "mstr_discrete"
					( Origin gPackager )
				)
				( attribute "CDS_LOCATION" "R9F23"
					( Origin gPackager )
				)
				( attribute "CDS_SEC" "1"
					( Origin gPackager )
				)
				( attribute "LOCATION" "R9F23"
					( Origin gFrontEnd )
				)
				( attribute "MATERIAL" "CHIP"
					( Origin gFrontEnd )
				)
				( attribute "PACK_TYPE" "0402"
					( Origin gFrontEnd )
				)
				( attribute "PART_NUMBER" "G21796-173"
					( Origin gFrontEnd )
				)
				( attribute "PHYS_PAGE" "160"
					( Origin gFrontEnd )
				)
				( attribute "ROOM" "SMBUS"
					( Origin gFrontEnd )
				)
				( attribute "ROT" "0"
					( Origin gFrontEnd )
				)
				( attribute "SEC" "1"
					( Origin gPackager )
				)
				( attribute "TOLERANCE" "1%"
					( Origin gFrontEnd )
				)
				( attribute "VALUE" "20.0"
					( Origin gFrontEnd )
				)
				( attribute "VER" "1"
					( Origin gFrontEnd )
				)
				( attribute "WATTAGE" "1/16W"
					( Origin gFrontEnd )
				)
				( attribute "XY" "(-3350,3700)"
					( Origin gFrontEnd )
				)
				( attribute "CHIPS_PART_NAME" "RES"
					( Origin gPackager )
				)
				( attribute "CDS_PART_NAME" "RES_0402-20.0,1%,1/16W,CHIP,G2A"
					( Origin gPackager )
				)
				( objectStatus "R9F23" )
			)
			( gate "@baseboard_fab2_lib.baseboard_fab2(sch_1):page160_i52"
				( attribute "BOM_COST" "SM_CONTROLLER"
					( Origin gFrontEnd )
				)
				( attribute "CDS_LIB" "mstr_discrete"
					( Origin gPackager )
				)
				( attribute "CDS_LOCATION" "R9F22"
					( Origin gPackager )
				)
				( attribute "CDS_SEC" "1"
					( Origin gPackager )
				)
				( attribute "LOCATION" "R9F22"
					( Origin gFrontEnd )
				)
				( attribute "MATERIAL" "CHIP"
					( Origin gFrontEnd )
				)
				( attribute "PACK_TYPE" "0402"
					( Origin gFrontEnd )
				)
				( attribute "PART_NUMBER" "G21796-173"
					( Origin gFrontEnd )
				)
				( attribute "PHYS_PAGE" "160"
					( Origin gFrontEnd )
				)
				( attribute "ROOM" "SMBUS"
					( Origin gFrontEnd )
				)
				( attribute "ROT" "0"
					( Origin gFrontEnd )
				)
				( attribute "SEC" "1"
					( Origin gPackager )
				)
				( attribute "TOLERANCE" "1%"
					( Origin gFrontEnd )
				)
				( attribute "VALUE" "20.0"
					( Origin gFrontEnd )
				)
				( attribute "VER" "1"
					( Origin gFrontEnd )
				)
				( attribute "WATTAGE" "1/16W"
					( Origin gFrontEnd )
				)
				( attribute "XY" "(-3350,3525)"
					( Origin gFrontEnd )
				)
				( attribute "CHIPS_PART_NAME" "RES"
					( Origin gPackager )
				)
				( attribute "CDS_PART_NAME" "RES_0402-20.0,1%,1/16W,CHIP,G2A"
					( Origin gPackager )
				)
				( objectStatus "R9F22" )
			)
			( gate "@baseboard_fab2_lib.baseboard_fab2(sch_1):page161_i140"
				( attribute "CDS_LIB" "w_hdl"
					( Origin gPackager )
				)
				( attribute "CDS_LMAN_SYM_OUTLINE" "-75,150,75,-150"
					( Origin gPackager )
				)
				( attribute "CDS_LOCATION" "J10W1"
					( Origin gPackager )
				)
				( attribute "CDS_SEC" "1"
					( Origin gPackager )
				)
				( attribute "LOCATION" "J10W1"
					( Origin gFrontEnd )
				)
				( attribute "PACK_TYPE" "CONN-G7"
					( Origin gFrontEnd )
				)
				( attribute "PART_NUMBER" "021.60521.0104"
					( Origin gFrontEnd )
				)
				( attribute "PHYS_PAGE" "161"
					( Origin gFrontEnd )
				)
				( attribute "ROT" "0"
					( Origin gFrontEnd )
				)
				( attribute "SEC" "1"
					( Origin gFrontEnd )
				)
				( attribute "SEC_TYPE" "CONN-G7"
					( Origin gFrontEnd )
				)
				( attribute "VALUE" "LOTES-CON4-S1-GP"
					( Origin gFrontEnd )
				)
				( attribute "VER" "1"
					( Origin gFrontEnd )
				)
				( attribute "XY" "(-650,1800)"
					( Origin gFrontEnd )
				)
				( attribute "CHIPS_PART_NAME" "LOTES-CON4-S1-GP"
					( Origin gPackager )
				)
				( attribute "CDS_PART_NAME" "LOTES-CON4-S1-GP_CONN-G7-LOTESA"
					( Origin gPackager )
				)
				( objectStatus "J10W1" )
			)
			( gate "@baseboard_fab2_lib.baseboard_fab2(sch_1):page161_i3"
				( attribute "BOM_COST" "SM_THERM"
					( Origin gFrontEnd )
				)
				( attribute "CDS_LIB" "mstr_discrete"
					( Origin gPackager )
				)
				( attribute "CDS_LOCATION" "C1E21"
					( Origin gPackager )
				)
				( attribute "CDS_SEC" "1"
					( Origin gPackager )
				)
				( attribute "LOCATION" "C1E21"
					( Origin gFrontEnd )
				)
				( attribute "MATERIAL" "X6S"
					( Origin gFrontEnd )
				)
				( attribute "PACK_TYPE" "0805"
					( Origin gFrontEnd )
				)
				( attribute "PART_NUMBER" "C95333-007"
					( Origin gFrontEnd )
				)
				( attribute "PHYS_PAGE" "161"
					( Origin gFrontEnd )
				)
				( attribute "ROOM" "CPU_FANS"
					( Origin gFrontEnd )
				)
				( attribute "ROT" "0"
					( Origin gFrontEnd )
				)
				( attribute "SEC" "1"
					( Origin gFrontEnd )
				)
				( attribute "SEC_TYPE" "0805"
					( Origin gFrontEnd )
				)
				( attribute "TOLERANCE" "10%"
					( Origin gFrontEnd )
				)
				( attribute "VALUE" "10UF"
					( Origin gFrontEnd )
				)
				( attribute "VER" "1"
					( Origin gFrontEnd )
				)
				( attribute "VOLTAGE" "16V"
					( Units "uVoltage" "V" 1.000000)
					( Origin gFrontEnd )
				)
				( attribute "XY" "(-1400,4350)"
					( Origin gFrontEnd )
				)
				( attribute "CHIPS_PART_NAME" "CAP"
					( Origin gPackager )
				)
				( attribute "CDS_PART_NAME" "CAP_0805-10UF,16V,10%,X6S,C953A"
					( Origin gPackager )
				)
				( objectStatus "C1E21" )
			)
			( gate "@baseboard_fab2_lib.baseboard_fab2(sch_1):page161_i4"
				( attribute "BOM_COST" "SM_THERM"
					( Origin gFrontEnd )
				)
				( attribute "CDS_LIB" "dev_discrete"
					( Origin gPackager )
				)
				( attribute "CDS_LOCATION" "C1E20"
					( Origin gPackager )
				)
				( attribute "CDS_SEC" "1"
					( Origin gPackager )
				)
				( attribute "LOCATION" "C1E20"
					( Origin gFrontEnd )
				)
				( attribute "MATERIAL" "X7R"
					( Origin gFrontEnd )
				)
				( attribute "PACK_TYPE" "0402V"
					( Origin gFrontEnd )
				)
				( attribute "PART_NUMBER" "A36096-030"
					( Origin gFrontEnd )
				)
				( attribute "PHYS_PAGE" "161"
					( Origin gFrontEnd )
				)
				( attribute "ROOM" "CPU_FANS"
					( Origin gFrontEnd )
				)
				( attribute "ROT" "0"
					( Origin gFrontEnd )
				)
				( attribute "SEC" "1"
					( Origin gFrontEnd )
				)
				( attribute "SEC_TYPE" "0402V"
					( Origin gFrontEnd )
				)
				( attribute "TOLERANCE" "10%"
					( Origin gFrontEnd )
				)
				( attribute "VALUE" "0.1UF"
					( Origin gFrontEnd )
				)
				( attribute "VER" "1"
					( Origin gFrontEnd )
				)
				( attribute "VOLTAGE" "16V"
					( Units "uVoltage" "V" 1.000000)
					( Origin gFrontEnd )
				)
				( attribute "XY" "(-1125,4325)"
					( Origin gFrontEnd )
				)
				( attribute "CHIPS_PART_NAME" "CAP_A"
					( Origin gPackager )
				)
				( attribute "CDS_PART_NAME" "CAP_A_0402V-0.1UF,16V,10%,X7R,A"
					( Origin gPackager )
				)
				( objectStatus "C1E20" )
			)
			( gate "@baseboard_fab2_lib.baseboard_fab2(sch_1):page161_i26"
				( attribute "BOM_COST" "SM_THERM"
					( Origin gFrontEnd )
				)
				( attribute "CDS_LIB" "dev_discrete"
					( Origin gPackager )
				)
				( attribute "CDS_LOCATION" "C9M5"
					( Origin gPackager )
				)
				( attribute "CDS_SEC" "1"
					( Origin gPackager )
				)
				( attribute "LOCATION" "C9M5"
					( Origin gFrontEnd )
				)
				( attribute "MATERIAL" "X7R"
					( Origin gFrontEnd )
				)
				( attribute "PACK_TYPE" "0402V"
					( Origin gFrontEnd )
				)
				( attribute "PART_NUMBER" "A36096-030"
					( Origin gFrontEnd )
				)
				( attribute "PHYS_PAGE" "161"
					( Origin gFrontEnd )
				)
				( attribute "ROOM" "CPU_FANS"
					( Origin gFrontEnd )
				)
				( attribute "ROT" "0"
					( Origin gFrontEnd )
				)
				( attribute "SEC" "1"
					( Origin gFrontEnd )
				)
				( attribute "SEC_TYPE" "0402V"
					( Origin gFrontEnd )
				)
				( attribute "TOLERANCE" "10%"
					( Origin gFrontEnd )
				)
				( attribute "VALUE" "0.1UF"
					( Origin gFrontEnd )
				)
				( attribute "VER" "1"
					( Origin gFrontEnd )
				)
				( attribute "VOLTAGE" "16V"
					( Units "uVoltage" "V" 1.000000)
					( Origin gFrontEnd )
				)
				( attribute "XY" "(-1000,2275)"
					( Origin gFrontEnd )
				)
				( attribute "CHIPS_PART_NAME" "CAP_A"
					( Origin gPackager )
				)
				( attribute "CDS_PART_NAME" "CAP_A_0402V-0.1UF,16V,10%,X7R,A"
					( Origin gPackager )
				)
				( objectStatus "C9M5" )
			)
			( gate "@baseboard_fab2_lib.baseboard_fab2(sch_1):page161_i27"
				( attribute "BOM_COST" "SM_THERM"
					( Origin gFrontEnd )
				)
				( attribute "CDS_LIB" "mstr_discrete"
					( Origin gPackager )
				)
				( attribute "CDS_LOCATION" "C9M4"
					( Origin gPackager )
				)
				( attribute "CDS_SEC" "1"
					( Origin gPackager )
				)
				( attribute "LOCATION" "C9M4"
					( Origin gFrontEnd )
				)
				( attribute "MATERIAL" "X6S"
					( Origin gFrontEnd )
				)
				( attribute "PACK_TYPE" "0805"
					( Origin gFrontEnd )
				)
				( attribute "PART_NUMBER" "C95333-007"
					( Origin gFrontEnd )
				)
				( attribute "PHYS_PAGE" "161"
					( Origin gFrontEnd )
				)
				( attribute "ROOM" "CPU_FANS"
					( Origin gFrontEnd )
				)
				( attribute "ROT" "0"
					( Origin gFrontEnd )
				)
				( attribute "SEC" "1"
					( Origin gFrontEnd )
				)
				( attribute "SEC_TYPE" "0805"
					( Origin gFrontEnd )
				)
				( attribute "TOLERANCE" "10%"
					( Origin gFrontEnd )
				)
				( attribute "VALUE" "10UF"
					( Origin gFrontEnd )
				)
				( attribute "VER" "1"
					( Origin gFrontEnd )
				)
				( attribute "VOLTAGE" "16V"
					( Units "uVoltage" "V" 1.000000)
					( Origin gFrontEnd )
				)
				( attribute "XY" "(-1300,2275)"
					( Origin gFrontEnd )
				)
				( attribute "CHIPS_PART_NAME" "CAP"
					( Origin gPackager )
				)
				( attribute "CDS_PART_NAME" "CAP_0805-10UF,16V,10%,X6S,C953A"
					( Origin gPackager )
				)
				( objectStatus "C9M4" )
			)
			( gate "@baseboard_fab2_lib.baseboard_fab2(sch_1):page161_i42"
				( attribute "BOM_COST" "SM_THERM"
					( Origin gFrontEnd )
				)
				( attribute "CDS_LIB" "mstr_discrete"
					( Origin gPackager )
				)
				( attribute "CDS_LOCATION" "CR1F1"
					( Origin gPackager )
				)
				( attribute "CDS_SEC" "1"
					( Origin gPackager )
				)
				( attribute "LOCATION" "CR1F1"
					( Origin gFrontEnd )
				)
				( attribute "MATERIAL" "IC"
					( Origin gFrontEnd )
				)
				( attribute "PACK_TYPE" "SM"
					( Origin gFrontEnd )
				)
				( attribute "PART_NUMBER" "H71799-001"
					( Origin gFrontEnd )
				)
				( attribute "PHYS_PAGE" "161"
					( Origin gFrontEnd )
				)
				( attribute "ROOM" "CPU_FANS"
					( Origin gFrontEnd )
				)
				( attribute "ROT" "0"
					( Origin gFrontEnd )
				)
				( attribute "SEC" "1"
					( Origin gFrontEnd )
				)
				( attribute "SEC_TYPE" "SM"
					( Origin gFrontEnd )
				)
				( attribute "VALUE" "SDMK0340L"
					( Origin gFrontEnd )
				)
				( attribute "VER" "1"
					( Origin gFrontEnd )
				)
				( attribute "XY" "(-1675,3825)"
					( Origin gFrontEnd )
				)
				( attribute "CHIPS_PART_NAME" "DIODE"
					( Origin gPackager )
				)
				( attribute "CDS_PART_NAME" "DIODE_SM-SDMK0340L,IC,H71799-0A"
					( Origin gPackager )
				)
				( objectStatus "CR1F1" )
			)
			( gate "@baseboard_fab2_lib.baseboard_fab2(sch_1):page161_i43"
				( attribute "BOM_COST" "SM_THERM"
					( Origin gFrontEnd )
				)
				( attribute "CDS_LIB" "mstr_discrete"
					( Origin gPackager )
				)
				( attribute "CDS_LOCATION" "R1F2"
					( Origin gPackager )
				)
				( attribute "CDS_SEC" "1"
					( Origin gPackager )
				)
				( attribute "LOCATION" "R1F2"
					( Origin gFrontEnd )
				)
				( attribute "MATERIAL" "CHIP"
					( Origin gFrontEnd )
				)
				( attribute "NO_XNET_CONNECTION" "1"
					( Origin gFrontEnd )
				)
				( attribute "PACK_TYPE" "0402"
					( Origin gFrontEnd )
				)
				( attribute "PART_NUMBER" "G21796-017"
					( Origin gFrontEnd )
				)
				( attribute "PHYS_PAGE" "161"
					( Origin gFrontEnd )
				)
				( attribute "ROOM" "CPU_FANS"
					( Origin gFrontEnd )
				)
				( attribute "ROT" "0"
					( Origin gFrontEnd )
				)
				( attribute "SEC" "1"
					( Origin gFrontEnd )
				)
				( attribute "SEC_TYPE" "0402"
					( Origin gFrontEnd )
				)
				( attribute "TOLERANCE" "1%"
					( Origin gFrontEnd )
				)
				( attribute "VALUE" "100.0"
					( Origin gFrontEnd )
				)
				( attribute "VER" "1"
					( Origin gFrontEnd )
				)
				( attribute "WATTAGE" "1/16W"
					( Origin gFrontEnd )
				)
				( attribute "XY" "(-2525,3825)"
					( Origin gFrontEnd )
				)
				( attribute "CHIPS_PART_NAME" "RES"
					( Origin gPackager )
				)
				( attribute "CDS_PART_NAME" "RES_0402-100.0,1%,1/16W,CHIP,GA"
					( Origin gPackager )
				)
				( objectStatus "R1F2" )
			)
			( gate "@baseboard_fab2_lib.baseboard_fab2(sch_1):page161_i45"
				( attribute "BOM_COST" "SM_THERM"
					( Origin gFrontEnd )
				)
				( attribute "CDS_LIB" "mstr_discrete"
					( Origin gPackager )
				)
				( attribute "CDS_LOCATION" "R1F1"
					( Origin gPackager )
				)
				( attribute "CDS_SEC" "1"
					( Origin gPackager )
				)
				( attribute "LOCATION" "R1F1"
					( Origin gFrontEnd )
				)
				( attribute "MATERIAL" "CHIP"
					( Origin gFrontEnd )
				)
				( attribute "PACK_TYPE" "0402"
					( Origin gFrontEnd )
				)
				( attribute "PART_NUMBER" "G21796-072"
					( Origin gFrontEnd )
				)
				( attribute "PHYS_PAGE" "161"
					( Origin gFrontEnd )
				)
				( attribute "ROOM" "CPU_FANS"
					( Origin gFrontEnd )
				)
				( attribute "ROT" "0"
					( Origin gFrontEnd )
				)
				( attribute "SEC" "1"
					( Origin gFrontEnd )
				)
				( attribute "SEC_TYPE" "0402"
					( Origin gFrontEnd )
				)
				( attribute "TOLERANCE" "1%"
					( Origin gFrontEnd )
				)
				( attribute "VALUE" "4.75K"
					( Origin gFrontEnd )
				)
				( attribute "VER" "2"
					( Origin gFrontEnd )
				)
				( attribute "WATTAGE" "1/16W"
					( Origin gFrontEnd )
				)
				( attribute "XY" "(-2900,4025)"
					( Origin gFrontEnd )
				)
				( attribute "CHIPS_PART_NAME" "RES"
					( Origin gPackager )
				)
				( attribute "CDS_PART_NAME" "RES_0402-4.75K,1%,1/16W,CHIP,GA"
					( Origin gPackager )
				)
				( objectStatus "R1F1" )
			)
			( gate "@baseboard_fab2_lib.baseboard_fab2(sch_1):page161_i46"
				( attribute "BOM_COST" "SM_THERM"
					( Origin gFrontEnd )
				)
				( attribute "CDS_LIB" "dev_discrete"
					( Origin gPackager )
				)
				( attribute "CDS_LOCATION" "C1F9"
					( Origin gPackager )
				)
				( attribute "CDS_SEC" "1"
					( Origin gPackager )
				)
				( attribute "LOCATION" "C1F9"
					( Origin gFrontEnd )
				)
				( attribute "MATERIAL" "X7R"
					( Origin gFrontEnd )
				)
				( attribute "PACK_TYPE" "0402V"
					( Origin gFrontEnd )
				)
				( attribute "PART_NUMBER" "A36096-045"
					( Origin gFrontEnd )
				)
				( attribute "PHYS_PAGE" "161"
					( Origin gFrontEnd )
				)
				( attribute "ROOM" "CPU_FANS"
					( Origin gFrontEnd )
				)
				( attribute "ROT" "2"
					( Origin gFrontEnd )
				)
				( attribute "SEC" "1"
					( Origin gFrontEnd )
				)
				( attribute "SEC_TYPE" "0402V"
					( Origin gFrontEnd )
				)
				( attribute "TOLERANCE" "10%"
					( Origin gFrontEnd )
				)
				( attribute "VALUE" "0.01UF"
					( Origin gFrontEnd )
				)
				( attribute "VER" "1"
					( Origin gFrontEnd )
				)
				( attribute "VOLTAGE" "25V"
					( Units "uVoltage" "V" 1.000000)
					( Origin gFrontEnd )
				)
				( attribute "XY" "(-2775,3625)"
					( Origin gFrontEnd )
				)
				( attribute "CHIPS_PART_NAME" "CAP_A"
					( Origin gPackager )
				)
				( attribute "CDS_PART_NAME" "CAP_A_0402V-0.01UF,25V,10%,X7RA"
					( Origin gPackager )
				)
				( objectStatus "C1F9" )
			)
			( gate "@baseboard_fab2_lib.baseboard_fab2(sch_1):page161_i50"
				( attribute "BOM_COST" "SM_THERM"
					( Origin gFrontEnd )
				)
				( attribute "CDS_LIB" "mstr_discrete"
					( Origin gPackager )
				)
				( attribute "CDS_LOCATION" "CR1E1"
					( Origin gPackager )
				)
				( attribute "CDS_SEC" "1"
					( Origin gPackager )
				)
				( attribute "LOCATION" "CR1E1"
					( Origin gFrontEnd )
				)
				( attribute "MATERIAL" "EMPTY"
					( Origin gFrontEnd )
				)
				( attribute "PACK_TYPE" "SM"
					( Origin gFrontEnd )
				)
				( attribute "PART_NUMBER" "H71799-001"
					( Origin gFrontEnd )
				)
				( attribute "PHYS_PAGE" "161"
					( Origin gFrontEnd )
				)
				( attribute "ROOM" "CPU_FANS"
					( Origin gFrontEnd )
				)
				( attribute "ROT" "0"
					( Origin gFrontEnd )
				)
				( attribute "SEC" "1"
					( Origin gFrontEnd )
				)
				( attribute "SEC_TYPE" "SM"
					( Origin gFrontEnd )
				)
				( attribute "VALUE" "SDMK0340L"
					( Origin gFrontEnd )
				)
				( attribute "VER" "4"
					( Origin gFrontEnd )
				)
				( attribute "XY" "(-1950,3325)"
					( Origin gFrontEnd )
				)
				( attribute "CHIPS_PART_NAME" "DIODE"
					( Origin gPackager )
				)
				( attribute "CDS_PART_NAME" "DIODE_SM-SDMK0340L,EMPTY,H7179A"
					( Origin gPackager )
				)
				( objectStatus "CR1E1" )
			)
			( gate "@baseboard_fab2_lib.baseboard_fab2(sch_1):page161_i51"
				( attribute "BOM_COST" "SM_THERM"
					( Origin gFrontEnd )
				)
				( attribute "CDS_LIB" "mstr_discrete"
					( Origin gPackager )
				)
				( attribute "CDS_LOCATION" "R1E12"
					( Origin gPackager )
				)
				( attribute "CDS_SEC" "1"
					( Origin gPackager )
				)
				( attribute "LOCATION" "R1E12"
					( Origin gFrontEnd )
				)
				( attribute "MATERIAL" "CHIP"
					( Origin gFrontEnd )
				)
				( attribute "PACK_TYPE" "0402"
					( Origin gFrontEnd )
				)
				( attribute "PART_NUMBER" "G21796-072"
					( Origin gFrontEnd )
				)
				( attribute "PHYS_PAGE" "161"
					( Origin gFrontEnd )
				)
				( attribute "ROOM" "CPU_FANS"
					( Origin gFrontEnd )
				)
				( attribute "ROT" "2"
					( Origin gFrontEnd )
				)
				( attribute "SEC" "1"
					( Origin gFrontEnd )
				)
				( attribute "SEC_TYPE" "0402"
					( Origin gFrontEnd )
				)
				( attribute "TOLERANCE" "1%"
					( Origin gFrontEnd )
				)
				( attribute "VALUE" "4.75K"
					( Origin gFrontEnd )
				)
				( attribute "VER" "2"
					( Origin gFrontEnd )
				)
				( attribute "WATTAGE" "1/16W"
					( Origin gFrontEnd )
				)
				( attribute "XY" "(-2175,3400)"
					( Origin gFrontEnd )
				)
				( attribute "CHIPS_PART_NAME" "RES"
					( Origin gPackager )
				)
				( attribute "CDS_PART_NAME" "RES_0402-4.75K,1%,1/16W,CHIP,GA"
					( Origin gPackager )
				)
				( objectStatus "R1E12" )
			)
			( gate "@baseboard_fab2_lib.baseboard_fab2(sch_1):page161_i62"
				( attribute "BOM_COST" "SM_THERM"
					( Origin gFrontEnd )
				)
				( attribute "CDS_LIB" "mstr_discrete"
					( Origin gPackager )
				)
				( attribute "CDS_LOCATION" "CR1B2"
					( Origin gPackager )
				)
				( attribute "CDS_SEC" "1"
					( Origin gPackager )
				)
				( attribute "LOCATION" "CR1B2"
					( Origin gFrontEnd )
				)
				( attribute "MATERIAL" "IC"
					( Origin gFrontEnd )
				)
				( attribute "PACK_TYPE" "SM"
					( Origin gFrontEnd )
				)
				( attribute "PART_NUMBER" "H71799-001"
					( Origin gFrontEnd )
				)
				( attribute "PHYS_PAGE" "161"
					( Origin gFrontEnd )
				)
				( attribute "ROOM" "CPU_FANS"
					( Origin gFrontEnd )
				)
				( attribute "ROT" "0"
					( Origin gFrontEnd )
				)
				( attribute "SEC" "1"
					( Origin gFrontEnd )
				)
				( attribute "SEC_TYPE" "SM"
					( Origin gFrontEnd )
				)
				( attribute "VALUE" "SDMK0340L"
					( Origin gFrontEnd )
				)
				( attribute "VER" "1"
					( Origin gFrontEnd )
				)
				( attribute "XY" "(-1825,1750)"
					( Origin gFrontEnd )
				)
				( attribute "CHIPS_PART_NAME" "DIODE"
					( Origin gPackager )
				)
				( attribute "CDS_PART_NAME" "DIODE_SM-SDMK0340L,IC,H71799-0A"
					( Origin gPackager )
				)
				( objectStatus "CR1B2" )
			)
			( gate "@baseboard_fab2_lib.baseboard_fab2(sch_1):page161_i64"
				( attribute "BOM_COST" "SM_THERM"
					( Origin gFrontEnd )
				)
				( attribute "CDS_LIB" "mstr_discrete"
					( Origin gPackager )
				)
				( attribute "CDS_LOCATION" "CR1B1"
					( Origin gPackager )
				)
				( attribute "CDS_SEC" "1"
					( Origin gPackager )
				)
				( attribute "LOCATION" "CR1B1"
					( Origin gFrontEnd )
				)
				( attribute "MATERIAL" "EMPTY"
					( Origin gFrontEnd )
				)
				( attribute "PACK_TYPE" "SM"
					( Origin gFrontEnd )
				)
				( attribute "PART_NUMBER" "H71799-001"
					( Origin gFrontEnd )
				)
				( attribute "PHYS_PAGE" "161"
					( Origin gFrontEnd )
				)
				( attribute "ROOM" "CPU_FANS"
					( Origin gFrontEnd )
				)
				( attribute "ROT" "0"
					( Origin gFrontEnd )
				)
				( attribute "SEC" "1"
					( Origin gFrontEnd )
				)
				( attribute "SEC_TYPE" "SM"
					( Origin gFrontEnd )
				)
				( attribute "VALUE" "SDMK0340L"
					( Origin gFrontEnd )
				)
				( attribute "VER" "4"
					( Origin gFrontEnd )
				)
				( attribute "XY" "(-2100,1250)"
					( Origin gFrontEnd )
				)
				( attribute "CHIPS_PART_NAME" "DIODE"
					( Origin gPackager )
				)
				( attribute "CDS_PART_NAME" "DIODE_SM-SDMK0340L,EMPTY,H7179A"
					( Origin gPackager )
				)
				( objectStatus "CR1B1" )
			)
			( gate "@baseboard_fab2_lib.baseboard_fab2(sch_1):page161_i65"
				( attribute "BOM_COST" "SM_THERM"
					( Origin gFrontEnd )
				)
				( attribute "CDS_LIB" "mstr_discrete"
					( Origin gPackager )
				)
				( attribute "CDS_LOCATION" "R7F33"
					( Origin gPackager )
				)
				( attribute "CDS_SEC" "1"
					( Origin gPackager )
				)
				( attribute "LOCATION" "R7F33"
					( Origin gFrontEnd )
				)
				( attribute "MATERIAL" "CHIP"
					( Origin gFrontEnd )
				)
				( attribute "PACK_TYPE" "0402"
					( Origin gFrontEnd )
				)
				( attribute "PART_NUMBER" "G21796-072"
					( Origin gFrontEnd )
				)
				( attribute "PHYS_PAGE" "161"
					( Origin gFrontEnd )
				)
				( attribute "ROOM" "CPU_FANS"
					( Origin gFrontEnd )
				)
				( attribute "ROT" "2"
					( Origin gFrontEnd )
				)
				( attribute "SEC" "1"
					( Origin gFrontEnd )
				)
				( attribute "SEC_TYPE" "0402"
					( Origin gFrontEnd )
				)
				( attribute "TOLERANCE" "1%"
					( Origin gFrontEnd )
				)
				( attribute "VALUE" "4.75K"
					( Origin gFrontEnd )
				)
				( attribute "VER" "2"
					( Origin gFrontEnd )
				)
				( attribute "WATTAGE" "1/16W"
					( Origin gFrontEnd )
				)
				( attribute "XY" "(-2325,1300)"
					( Origin gFrontEnd )
				)
				( attribute "CHIPS_PART_NAME" "RES"
					( Origin gPackager )
				)
				( attribute "CDS_PART_NAME" "RES_0402-4.75K,1%,1/16W,CHIP,GA"
					( Origin gPackager )
				)
				( objectStatus "R7F33" )
			)
			( gate "@baseboard_fab2_lib.baseboard_fab2(sch_1):page161_i67"
				( attribute "BOM_COST" "SM_THERM"
					( Origin gFrontEnd )
				)
				( attribute "CDS_LIB" "mstr_discrete"
					( Origin gPackager )
				)
				( attribute "CDS_LOCATION" "R1B22"
					( Origin gPackager )
				)
				( attribute "CDS_SEC" "1"
					( Origin gPackager )
				)
				( attribute "LOCATION" "R1B22"
					( Origin gFrontEnd )
				)
				( attribute "MATERIAL" "CHIP"
					( Origin gFrontEnd )
				)
				( attribute "NO_XNET_CONNECTION" "1"
					( Origin gFrontEnd )
				)
				( attribute "PACK_TYPE" "0402"
					( Origin gFrontEnd )
				)
				( attribute "PART_NUMBER" "G21796-017"
					( Origin gFrontEnd )
				)
				( attribute "PHYS_PAGE" "161"
					( Origin gFrontEnd )
				)
				( attribute "ROOM" "CPU_FANS"
					( Origin gFrontEnd )
				)
				( attribute "ROT" "0"
					( Origin gFrontEnd )
				)
				( attribute "SEC" "1"
					( Origin gFrontEnd )
				)
				( attribute "SEC_TYPE" "0402"
					( Origin gFrontEnd )
				)
				( attribute "TOLERANCE" "1%"
					( Origin gFrontEnd )
				)
				( attribute "VALUE" "100.0"
					( Origin gFrontEnd )
				)
				( attribute "VER" "1"
					( Origin gFrontEnd )
				)
				( attribute "WATTAGE" "1/16W"
					( Origin gFrontEnd )
				)
				( attribute "XY" "(-2675,1750)"
					( Origin gFrontEnd )
				)
				( attribute "CHIPS_PART_NAME" "RES"
					( Origin gPackager )
				)
				( attribute "CDS_PART_NAME" "RES_0402-100.0,1%,1/16W,CHIP,GA"
					( Origin gPackager )
				)
				( objectStatus "R1B22" )
			)
			( gate "@baseboard_fab2_lib.baseboard_fab2(sch_1):page161_i68"
				( attribute "BOM_COST" "SM_THERM"
					( Origin gFrontEnd )
				)
				( attribute "CDS_LIB" "dev_discrete"
					( Origin gPackager )
				)
				( attribute "CDS_LOCATION" "C1B15"
					( Origin gPackager )
				)
				( attribute "CDS_SEC" "1"
					( Origin gPackager )
				)
				( attribute "LOCATION" "C1B15"
					( Origin gFrontEnd )
				)
				( attribute "MATERIAL" "X7R"
					( Origin gFrontEnd )
				)
				( attribute "PACK_TYPE" "0402V"
					( Origin gFrontEnd )
				)
				( attribute "PART_NUMBER" "A36096-045"
					( Origin gFrontEnd )
				)
				( attribute "PHYS_PAGE" "161"
					( Origin gFrontEnd )
				)
				( attribute "ROOM" "CPU_FANS"
					( Origin gFrontEnd )
				)
				( attribute "ROT" "2"
					( Origin gFrontEnd )
				)
				( attribute "SEC" "1"
					( Origin gFrontEnd )
				)
				( attribute "SEC_TYPE" "0402V"
					( Origin gFrontEnd )
				)
				( attribute "TOLERANCE" "10%"
					( Origin gFrontEnd )
				)
				( attribute "VALUE" "0.01UF"
					( Origin gFrontEnd )
				)
				( attribute "VER" "1"
					( Origin gFrontEnd )
				)
				( attribute "VOLTAGE" "25V"
					( Units "uVoltage" "V" 1.000000)
					( Origin gFrontEnd )
				)
				( attribute "XY" "(-2925,1550)"
					( Origin gFrontEnd )
				)
				( attribute "CHIPS_PART_NAME" "CAP_A"
					( Origin gPackager )
				)
				( attribute "CDS_PART_NAME" "CAP_A_0402V-0.01UF,25V,10%,X7RA"
					( Origin gPackager )
				)
				( objectStatus "C1B15" )
			)
			( gate "@baseboard_fab2_lib.baseboard_fab2(sch_1):page161_i70"
				( attribute "BOM_COST" "SM_THERM"
					( Origin gFrontEnd )
				)
				( attribute "CDS_LIB" "mstr_discrete"
					( Origin gPackager )
				)
				( attribute "CDS_LOCATION" "R1B21"
					( Origin gPackager )
				)
				( attribute "CDS_SEC" "1"
					( Origin gPackager )
				)
				( attribute "LOCATION" "R1B21"
					( Origin gFrontEnd )
				)
				( attribute "MATERIAL" "CHIP"
					( Origin gFrontEnd )
				)
				( attribute "PACK_TYPE" "0402"
					( Origin gFrontEnd )
				)
				( attribute "PART_NUMBER" "G21796-072"
					( Origin gFrontEnd )
				)
				( attribute "PHYS_PAGE" "161"
					( Origin gFrontEnd )
				)
				( attribute "ROOM" "CPU_FANS"
					( Origin gFrontEnd )
				)
				( attribute "ROT" "0"
					( Origin gFrontEnd )
				)
				( attribute "SEC" "1"
					( Origin gFrontEnd )
				)
				( attribute "SEC_TYPE" "0402"
					( Origin gFrontEnd )
				)
				( attribute "TOLERANCE" "1%"
					( Origin gFrontEnd )
				)
				( attribute "VALUE" "4.75K"
					( Origin gFrontEnd )
				)
				( attribute "VER" "2"
					( Origin gFrontEnd )
				)
				( attribute "WATTAGE" "1/16W"
					( Origin gFrontEnd )
				)
				( attribute "XY" "(-3050,1950)"
					( Origin gFrontEnd )
				)
				( attribute "CHIPS_PART_NAME" "RES"
					( Origin gPackager )
				)
				( attribute "CDS_PART_NAME" "RES_0402-4.75K,1%,1/16W,CHIP,GA"
					( Origin gPackager )
				)
				( objectStatus "R1B21" )
			)
			( gate "@baseboard_fab2_lib.baseboard_fab2(sch_1):page161_i88"
				( attribute "BOM_COST" "SM_THERM"
					( Origin gFrontEnd )
				)
				( attribute "CDS_LIB" "mstr_ttl"
					( Origin gPackager )
				)
				( attribute "CDS_LOCATION" "U8G2"
					( Origin gPackager )
				)
				( attribute "CDS_SEC" "1"
					( Origin gPackager )
				)
				( attribute "LOCATION" "U8G2"
					( Origin gFrontEnd )
				)
				( attribute "MATERIAL" "IC"
					( Origin gFrontEnd )
				)
				( attribute "PACK_TYPE" "SOP"
					( Origin gFrontEnd )
				)
				( attribute "PART_NUMBER" "C88419-001"
					( Origin gFrontEnd )
				)
				( attribute "PHYS_PAGE" "161"
					( Origin gFrontEnd )
				)
				( attribute "ROOM" "CPU_FANS"
					( Origin gFrontEnd )
				)
				( attribute "ROT" "0"
					( Origin gFrontEnd )
				)
				( attribute "SEC" "1"
					( Origin gFrontEnd )
				)
				( attribute "SEC_TYPE" "SOP"
					( Origin gFrontEnd )
				)
				( attribute "VALUE" "74LVC1G07"
					( Origin gFrontEnd )
				)
				( attribute "VER" "1"
					( Origin gFrontEnd )
				)
				( attribute "XY" "(-6350,3850)"
					( Origin gFrontEnd )
				)
				( attribute "CHIPS_PART_NAME" "TTL1G07_A"
					( Origin gPackager )
				)
				( attribute "CDS_PART_NAME" "TTL1G07_A_SOP-74LVC1G07,IC,C88B"
					( Origin gPackager )
				)
				( objectStatus "U8G2" )
			)
			( gate "@baseboard_fab2_lib.baseboard_fab2(sch_1):page161_i90"
				( attribute "BOM_COST" "SM_THERM"
					( Origin gFrontEnd )
				)
				( attribute "CDS_LIB" "dev_discrete"
					( Origin gPackager )
				)
				( attribute "CDS_LOCATION" "C2U27"
					( Origin gPackager )
				)
				( attribute "CDS_SEC" "1"
					( Origin gPackager )
				)
				( attribute "LOCATION" "C2U27"
					( Origin gFrontEnd )
				)
				( attribute "MATERIAL" "X7R"
					( Origin gFrontEnd )
				)
				( attribute "PACK_TYPE" "0402V"
					( Origin gFrontEnd )
				)
				( attribute "PART_NUMBER" "A36096-030"
					( Origin gFrontEnd )
				)
				( attribute "PHYS_PAGE" "161"
					( Origin gFrontEnd )
				)
				( attribute "ROOM" "CPU_FANS"
					( Origin gFrontEnd )
				)
				( attribute "ROT" "0"
					( Origin gFrontEnd )
				)
				( attribute "SEC" "1"
					( Origin gFrontEnd )
				)
				( attribute "SEC_TYPE" "0402V"
					( Origin gFrontEnd )
				)
				( attribute "TOLERANCE" "10%"
					( Origin gFrontEnd )
				)
				( attribute "VALUE" "0.1UF"
					( Origin gFrontEnd )
				)
				( attribute "VER" "1"
					( Origin gFrontEnd )
				)
				( attribute "VOLTAGE" "16V"
					( Units "uVoltage" "V" 1.000000)
					( Origin gFrontEnd )
				)
				( attribute "XY" "(-6300,4450)"
					( Origin gFrontEnd )
				)
				( attribute "CHIPS_PART_NAME" "CAP_A"
					( Origin gPackager )
				)
				( attribute "CDS_PART_NAME" "CAP_A_0402V-0.1UF,16V,10%,X7R,A"
					( Origin gPackager )
				)
				( objectStatus "C2U27" )
			)
			( gate "@baseboard_fab2_lib.baseboard_fab2(sch_1):page161_i92"
				( attribute "BOM_COST" "SM_THERM"
					( Origin gFrontEnd )
				)
				( attribute "CDS_LIB" "mstr_ttl"
					( Origin gPackager )
				)
				( attribute "CDS_LOCATION" "U8G3"
					( Origin gPackager )
				)
				( attribute "CDS_SEC" "1"
					( Origin gPackager )
				)
				( attribute "LOCATION" "U8G3"
					( Origin gFrontEnd )
				)
				( attribute "MATERIAL" "IC"
					( Origin gFrontEnd )
				)
				( attribute "PACK_TYPE" "SOP"
					( Origin gFrontEnd )
				)
				( attribute "PART_NUMBER" "C88419-001"
					( Origin gFrontEnd )
				)
				( attribute "PHYS_PAGE" "161"
					( Origin gFrontEnd )
				)
				( attribute "ROOM" "CPU_FANS"
					( Origin gFrontEnd )
				)
				( attribute "ROT" "0"
					( Origin gFrontEnd )
				)
				( attribute "SEC" "1"
					( Origin gFrontEnd )
				)
				( attribute "SEC_TYPE" "SOP"
					( Origin gFrontEnd )
				)
				( attribute "VALUE" "74LVC1G07"
					( Origin gFrontEnd )
				)
				( attribute "VER" "1"
					( Origin gFrontEnd )
				)
				( attribute "XY" "(-6425,1100)"
					( Origin gFrontEnd )
				)
				( attribute "CHIPS_PART_NAME" "TTL1G07_A"
					( Origin gPackager )
				)
				( attribute "CDS_PART_NAME" "TTL1G07_A_SOP-74LVC1G07,IC,C88B"
					( Origin gPackager )
				)
				( objectStatus "U8G3" )
			)
			( gate "@baseboard_fab2_lib.baseboard_fab2(sch_1):page161_i93"
				( attribute "BOM_COST" "SM_THERM"
					( Origin gFrontEnd )
				)
				( attribute "CDS_LIB" "dev_discrete"
					( Origin gPackager )
				)
				( attribute "CDS_LOCATION" "C2U28"
					( Origin gPackager )
				)
				( attribute "CDS_SEC" "1"
					( Origin gPackager )
				)
				( attribute "LOCATION" "C2U28"
					( Origin gFrontEnd )
				)
				( attribute "MATERIAL" "X7R"
					( Origin gFrontEnd )
				)
				( attribute "PACK_TYPE" "0402V"
					( Origin gFrontEnd )
				)
				( attribute "PART_NUMBER" "A36096-030"
					( Origin gFrontEnd )
				)
				( attribute "PHYS_PAGE" "161"
					( Origin gFrontEnd )
				)
				( attribute "ROOM" "CPU_FANS"
					( Origin gFrontEnd )
				)
				( attribute "ROT" "0"
					( Origin gFrontEnd )
				)
				( attribute "SEC" "1"
					( Origin gFrontEnd )
				)
				( attribute "SEC_TYPE" "0402V"
					( Origin gFrontEnd )
				)
				( attribute "TOLERANCE" "10%"
					( Origin gFrontEnd )
				)
				( attribute "VALUE" "0.1UF"
					( Origin gFrontEnd )
				)
				( attribute "VER" "1"
					( Origin gFrontEnd )
				)
				( attribute "VOLTAGE" "16V"
					( Units "uVoltage" "V" 1.000000)
					( Origin gFrontEnd )
				)
				( attribute "XY" "(-6200,675)"
					( Origin gFrontEnd )
				)
				( attribute "CHIPS_PART_NAME" "CAP_A"
					( Origin gPackager )
				)
				( attribute "CDS_PART_NAME" "CAP_A_0402V-0.1UF,16V,10%,X7R,A"
					( Origin gPackager )
				)
				( objectStatus "C2U28" )
			)
			( gate "@baseboard_fab2_lib.baseboard_fab2(sch_1):page161_i99"
				( attribute "BOM_COST" "SM_THERM"
					( Origin gFrontEnd )
				)
				( attribute "CDS_LIB" "mstr_discrete"
					( Origin gPackager )
				)
				( attribute "CDS_LOCATION" "R2U42"
					( Origin gPackager )
				)
				( attribute "CDS_SEC" "1"
					( Origin gPackager )
				)
				( attribute "LOCATION" "R2U42"
					( Origin gFrontEnd )
				)
				( attribute "MATERIAL" "CHIP"
					( Origin gFrontEnd )
				)
				( attribute "PACK_TYPE" "0402"
					( Origin gFrontEnd )
				)
				( attribute "PART_NUMBER" "G21796-271"
					( Origin gFrontEnd )
				)
				( attribute "PHYS_PAGE" "161"
					( Origin gFrontEnd )
				)
				( attribute "ROOM" "CPU_FANS"
					( Origin gFrontEnd )
				)
				( attribute "ROT" "0"
					( Origin gFrontEnd )
				)
				( attribute "SEC" "1"
					( Origin gFrontEnd )
				)
				( attribute "SEC_TYPE" "0402"
					( Origin gFrontEnd )
				)
				( attribute "TOLERANCE" "1.0%"
					( Origin gFrontEnd )
				)
				( attribute "VALUE" "221"
					( Origin gFrontEnd )
				)
				( attribute "VER" "1"
					( Origin gFrontEnd )
				)
				( attribute "WATTAGE" "1/16W"
					( Origin gFrontEnd )
				)
				( attribute "XY" "(-5450,3850)"
					( Origin gFrontEnd )
				)
				( attribute "CHIPS_PART_NAME" "RES"
					( Origin gPackager )
				)
				( attribute "CDS_PART_NAME" "RES_0402-221,1.0%,1/16W,CHIP,GA"
					( Origin gPackager )
				)
				( objectStatus "R2U42" )
			)
			( gate "@baseboard_fab2_lib.baseboard_fab2(sch_1):page161_i102"
				( attribute "BOM_COST" "SM_THERM"
					( Origin gFrontEnd )
				)
				( attribute "CDS_LIB" "mstr_discrete"
					( Origin gPackager )
				)
				( attribute "CDS_LOCATION" "R2U44"
					( Origin gPackager )
				)
				( attribute "CDS_SEC" "1"
					( Origin gPackager )
				)
				( attribute "LOCATION" "R2U44"
					( Origin gFrontEnd )
				)
				( attribute "MATERIAL" "CHIP"
					( Origin gFrontEnd )
				)
				( attribute "PACK_TYPE" "0402"
					( Origin gFrontEnd )
				)
				( attribute "PART_NUMBER" "G21796-271"
					( Origin gFrontEnd )
				)
				( attribute "PHYS_PAGE" "161"
					( Origin gFrontEnd )
				)
				( attribute "ROOM" "CPU_FANS"
					( Origin gFrontEnd )
				)
				( attribute "ROT" "0"
					( Origin gFrontEnd )
				)
				( attribute "SEC" "1"
					( Origin gFrontEnd )
				)
				( attribute "SEC_TYPE" "0402"
					( Origin gFrontEnd )
				)
				( attribute "TOLERANCE" "1.0%"
					( Origin gFrontEnd )
				)
				( attribute "VALUE" "221"
					( Origin gFrontEnd )
				)
				( attribute "VER" "1"
					( Origin gFrontEnd )
				)
				( attribute "WATTAGE" "1/16W"
					( Origin gFrontEnd )
				)
				( attribute "XY" "(-5600,1100)"
					( Origin gFrontEnd )
				)
				( attribute "CHIPS_PART_NAME" "RES"
					( Origin gPackager )
				)
				( attribute "CDS_PART_NAME" "RES_0402-221,1.0%,1/16W,CHIP,GA"
					( Origin gPackager )
				)
				( objectStatus "R2U44" )
			)
			( gate "@baseboard_fab2_lib.baseboard_fab2(sch_1):page161_i113"
				( attribute "BOM_COST" "SM_THERM"
					( Origin gFrontEnd )
				)
				( attribute "CDS_LIB" "dev_discrete"
					( Origin gPackager )
				)
				( attribute "CDS_LOCATION" "C1E22"
					( Origin gPackager )
				)
				( attribute "CDS_SEC" "1"
					( Origin gPackager )
				)
				( attribute "LOCATION" "C1E22"
					( Origin gFrontEnd )
				)
				( attribute "MATERIAL" "X7R"
					( Origin gFrontEnd )
				)
				( attribute "PACK_TYPE" "0402V"
					( Origin gFrontEnd )
				)
				( attribute "PART_NUMBER" "A36096-030"
					( Origin gFrontEnd )
				)
				( attribute "PHYS_PAGE" "161"
					( Origin gFrontEnd )
				)
				( attribute "ROOM" "CPUFANS"
					( Origin gFrontEnd )
				)
				( attribute "ROT" "0"
					( Origin gFrontEnd )
				)
				( attribute "SEC" "1"
					( Origin gFrontEnd )
				)
				( attribute "SEC_TYPE" "0402V"
					( Origin gFrontEnd )
				)
				( attribute "TOLERANCE" "10%"
					( Origin gFrontEnd )
				)
				( attribute "VALUE" "0.1UF"
					( Origin gFrontEnd )
				)
				( attribute "VER" "1"
					( Origin gFrontEnd )
				)
				( attribute "VOLTAGE" "16V"
					( Units "uVoltage" "V" 1.000000)
					( Origin gFrontEnd )
				)
				( attribute "XY" "(-5775,2150)"
					( Origin gFrontEnd )
				)
				( attribute "CHIPS_PART_NAME" "CAP_A"
					( Origin gPackager )
				)
				( attribute "CDS_PART_NAME" "CAP_A_0402V-0.1UF,16V,10%,X7R,A"
					( Origin gPackager )
				)
				( objectStatus "C1E22" )
			)
			( gate "@baseboard_fab2_lib.baseboard_fab2(sch_1):page161_i120"
				( attribute "BOM_COST" "SM_THERM"
					( Origin gFrontEnd )
				)
				( attribute "CDS_LIB" "mstr_discrete"
					( Origin gPackager )
				)
				( attribute "CDS_LOCATION" "R1E11"
					( Origin gPackager )
				)
				( attribute "CDS_SEC" "1"
					( Origin gPackager )
				)
				( attribute "LOCATION" "R1E11"
					( Origin gFrontEnd )
				)
				( attribute "MATERIAL" "EMPTY"
					( Origin gFrontEnd )
				)
				( attribute "PACK_TYPE" "0402"
					( Origin gFrontEnd )
				)
				( attribute "PART_NUMBER" "G21796-016"
					( Origin gFrontEnd )
				)
				( attribute "PHYS_PAGE" "161"
					( Origin gFrontEnd )
				)
				( attribute "ROOM" "CPU_FANS"
					( Origin gFrontEnd )
				)
				( attribute "ROT" "0"
					( Origin gFrontEnd )
				)
				( attribute "SEC" "1"
					( Origin gFrontEnd )
				)
				( attribute "SEC_TYPE" "0402"
					( Origin gFrontEnd )
				)
				( attribute "TOLERANCE" "1%"
					( Origin gFrontEnd )
				)
				( attribute "VALUE" "10.0K"
					( Origin gFrontEnd )
				)
				( attribute "VER" "2"
					( Origin gFrontEnd )
				)
				( attribute "WATTAGE" "1/16W"
					( Origin gFrontEnd )
				)
				( attribute "XY" "(-5950,2800)"
					( Origin gFrontEnd )
				)
				( attribute "CHIPS_PART_NAME" "RES"
					( Origin gPackager )
				)
				( attribute "CDS_PART_NAME" "RES_0402-10.0K,1%,1/16W,EMPTY,A"
					( Origin gPackager )
				)
				( objectStatus "R1E11" )
			)
			( gate "@baseboard_fab2_lib.baseboard_fab2(sch_1):page161_i121"
				( attribute "BOM_COST" "SM_THERM"
					( Origin gFrontEnd )
				)
				( attribute "CDS_LIB" "mstr_ttl"
					( Origin gPackager )
				)
				( attribute "CDS_LOCATION" "U1E2"
					( Origin gPackager )
				)
				( attribute "CDS_SEC" "1"
					( Origin gPackager )
				)
				( attribute "LOCATION" "U1E2"
					( Origin gFrontEnd )
				)
				( attribute "MATERIAL" "IC"
					( Origin gFrontEnd )
				)
				( attribute "PACK_TYPE" "SOTLF"
					( Origin gFrontEnd )
				)
				( attribute "PART_NUMBER" "D10321-001"
					( Origin gFrontEnd )
				)
				( attribute "PHYS_PAGE" "161"
					( Origin gFrontEnd )
				)
				( attribute "ROOM" "CPU_FANS"
					( Origin gFrontEnd )
				)
				( attribute "ROT" "0"
					( Origin gFrontEnd )
				)
				( attribute "SEC" "1"
					( Origin gFrontEnd )
				)
				( attribute "SEC_TYPE" "SOTLF"
					( Origin gFrontEnd )
				)
				( attribute "VALUE" "NC7SZ08"
					( Origin gFrontEnd )
				)
				( attribute "VER" "1"
					( Origin gFrontEnd )
				)
				( attribute "XY" "(-6250,2575)"
					( Origin gFrontEnd )
				)
				( attribute "CHIPS_PART_NAME" "TTL1G08"
					( Origin gPackager )
				)
				( attribute "CDS_PART_NAME" "TTL1G08_SOTLF-NC7SZ08,IC,D1032B"
					( Origin gPackager )
				)
				( objectStatus "U1E2" )
			)
			( gate "@baseboard_fab2_lib.baseboard_fab2(sch_1):page162_i8"
				( attribute "BOM_COST" "SM_MEM"
					( Origin gFrontEnd )
				)
				( attribute "CDS_LIB" "mstr_discrete"
					( Origin gPackager )
				)
				( attribute "CDS_LOCATION" "R8F16"
					( Origin gPackager )
				)
				( attribute "CDS_SEC" "1"
					( Origin gPackager )
				)
				( attribute "LOCATION" "R8F16"
					( Origin gFrontEnd )
				)
				( attribute "MATERIAL" "EMPTY"
					( Origin gFrontEnd )
				)
				( attribute "PACK_TYPE" "0402"
					( Origin gFrontEnd )
				)
				( attribute "PART_NUMBER" "G21796-072"
					( Origin gFrontEnd )
				)
				( attribute "PHYS_PAGE" "162"
					( Origin gFrontEnd )
				)
				( attribute "ROOM" "BMC_BOOT_SPI"
					( Origin gFrontEnd )
				)
				( attribute "ROT" "0"
					( Origin gFrontEnd )
				)
				( attribute "SEC" "1"
					( Origin gFrontEnd )
				)
				( attribute "SEC_TYPE" "0402"
					( Origin gFrontEnd )
				)
				( attribute "TOLERANCE" "1%"
					( Origin gFrontEnd )
				)
				( attribute "VALUE" "4.75K"
					( Origin gFrontEnd )
				)
				( attribute "VER" "2"
					( Origin gFrontEnd )
				)
				( attribute "WATTAGE" "1/16W"
					( Origin gFrontEnd )
				)
				( attribute "XY" "(5300,3300)"
					( Origin gFrontEnd )
				)
				( attribute "CHIPS_PART_NAME" "RES"
					( Origin gPackager )
				)
				( attribute "CDS_PART_NAME" "RES_0402-4.75K,1%,1/16W,EMPTY,A"
					( Origin gPackager )
				)
				( objectStatus "R8F16" )
			)
			( gate "@baseboard_fab2_lib.baseboard_fab2(sch_1):page162_i9"
				( attribute "BOM_COST" "SM_MEM"
					( Origin gFrontEnd )
				)
				( attribute "CDS_LIB" "mstr_discrete"
					( Origin gPackager )
				)
				( attribute "CDS_LOCATION" "R8F14"
					( Origin gPackager )
				)
				( attribute "CDS_SEC" "1"
					( Origin gPackager )
				)
				( attribute "LOCATION" "R8F14"
					( Origin gFrontEnd )
				)
				( attribute "MATERIAL" "CHIP"
					( Origin gFrontEnd )
				)
				( attribute "PACK_TYPE" "0402"
					( Origin gFrontEnd )
				)
				( attribute "PART_NUMBER" "G21796-072"
					( Origin gFrontEnd )
				)
				( attribute "PHYS_PAGE" "162"
					( Origin gFrontEnd )
				)
				( attribute "ROOM" "BMC_BOOT_SPI"
					( Origin gFrontEnd )
				)
				( attribute "ROT" "2"
					( Origin gFrontEnd )
				)
				( attribute "SEC" "1"
					( Origin gFrontEnd )
				)
				( attribute "SEC_TYPE" "0402"
					( Origin gFrontEnd )
				)
				( attribute "TOLERANCE" "1%"
					( Origin gFrontEnd )
				)
				( attribute "VALUE" "4.75K"
					( Origin gFrontEnd )
				)
				( attribute "VER" "2"
					( Origin gFrontEnd )
				)
				( attribute "WATTAGE" "1/16W"
					( Origin gFrontEnd )
				)
				( attribute "XY" "(5100,3325)"
					( Origin gFrontEnd )
				)
				( attribute "CHIPS_PART_NAME" "RES"
					( Origin gPackager )
				)
				( attribute "CDS_PART_NAME" "RES_0402-4.75K,1%,1/16W,CHIP,GA"
					( Origin gPackager )
				)
				( objectStatus "R8F14" )
			)
			( gate "@baseboard_fab2_lib.baseboard_fab2(sch_1):page162_i13"
				( attribute "BOM_COST" "SM_MEM"
					( Origin gFrontEnd )
				)
				( attribute "CDS_LIB" "mstr_discrete"
					( Origin gPackager )
				)
				( attribute "CDS_LOCATION" "R8F12"
					( Origin gPackager )
				)
				( attribute "CDS_SEC" "1"
					( Origin gPackager )
				)
				( attribute "LOCATION" "R8F12"
					( Origin gFrontEnd )
				)
				( attribute "MATERIAL" "CHIP"
					( Origin gFrontEnd )
				)
				( attribute "PACK_TYPE" "0402"
					( Origin gFrontEnd )
				)
				( attribute "PART_NUMBER" "G21796-074"
					( Origin gFrontEnd )
				)
				( attribute "PHYS_PAGE" "162"
					( Origin gFrontEnd )
				)
				( attribute "ROOM" "BMC_BOOT_SPI"
					( Origin gFrontEnd )
				)
				( attribute "ROT" "0"
					( Origin gFrontEnd )
				)
				( attribute "SEC" "1"
					( Origin gFrontEnd )
				)
				( attribute "SEC_TYPE" "0402"
					( Origin gFrontEnd )
				)
				( attribute "TOLERANCE" "1%"
					( Origin gFrontEnd )
				)
				( attribute "VALUE" "33.2"
					( Origin gFrontEnd )
				)
				( attribute "VER" "1"
					( Origin gFrontEnd )
				)
				( attribute "WATTAGE" "1/16W"
					( Origin gFrontEnd )
				)
				( attribute "XY" "(5075,2550)"
					( Origin gFrontEnd )
				)
				( attribute "CHIPS_PART_NAME" "RES"
					( Origin gPackager )
				)
				( attribute "CDS_PART_NAME" "RES_0402-33.2,1%,1/16W,CHIP,G2A"
					( Origin gPackager )
				)
				( objectStatus "R8F12" )
			)
			( gate "@baseboard_fab2_lib.baseboard_fab2(sch_1):page162_i22"
				( attribute "BOM_COST" "SM_MEM"
					( Origin gFrontEnd )
				)
				( attribute "CDS_LIB" "mstr_discrete"
					( Origin gPackager )
				)
				( attribute "CDS_LOCATION" "R8F34"
					( Origin gPackager )
				)
				( attribute "LOCATION" "R8F34"
					( Origin gFrontEnd )
				)
				( attribute "MATERIAL" "CHIP"
					( Origin gFrontEnd )
				)
				( attribute "PACK_TYPE" "0402"
					( Origin gFrontEnd )
				)
				( attribute "PART_NUMBER" "G21796-072"
					( Origin gFrontEnd )
				)
				( attribute "PHYS_PAGE" "162"
					( Origin gFrontEnd )
				)
				( attribute "ROOM" "BMC_BOOT_SPI"
					( Origin gFrontEnd )
				)
				( attribute "ROT" "2"
					( Origin gFrontEnd )
				)
				( attribute "SEC" "1"
					( Origin gFrontEnd )
				)
				( attribute "TOLERANCE" "1%"
					( Origin gFrontEnd )
				)
				( attribute "VALUE" "4.75K"
					( Origin gFrontEnd )
				)
				( attribute "VER" "2"
					( Origin gFrontEnd )
				)
				( attribute "WATTAGE" "1/16W"
					( Origin gFrontEnd )
				)
				( attribute "XY" "(4825,3325)"
					( Origin gFrontEnd )
				)
				( attribute "CHIPS_PART_NAME" "RES"
					( Origin gPackager )
				)
				( attribute "CDS_PART_NAME" "RES_0402-4.75K,1%,1/16W,CHIP,GA"
					( Origin gPackager )
				)
				( attribute "SEC_TYPE" "0402"
					( Origin gFrontEnd )
				)
				( attribute "CDS_SEC" "1"
					( Origin gPackager )
				)
				( objectStatus "R8F34" )
			)
			( gate "@baseboard_fab2_lib.baseboard_fab2(sch_1):page246_i20"
				( attribute "BOM_COST" "SM_MEM"
					( Origin gFrontEnd )
				)
				( attribute "CDS_LIB" "mstr_discrete"
					( Origin gPackager )
				)
				( attribute "LOCATION" "RN8F2"
					( Origin gFrontEnd )
				)
				( attribute "MATERIAL" "EMPTY"
					( Origin gFrontEnd )
				)
				( attribute "PACK_TYPE" "0402"
					( Origin gFrontEnd )
				)
				( attribute "PART_NUMBER" "G21796-072"
					( Origin gFrontEnd )
				)
				( attribute "PHYS_PAGE" "246"
					( Origin gFrontEnd )
				)
				( attribute "ROOM" "BMC_BOOT_SPI"
					( Origin gFrontEnd )
				)
				( attribute "ROT" "2"
					( Origin gFrontEnd )
				)
				( attribute "SEC" "1"
					( Origin gFrontEnd )
				)
				( attribute "SEC_TYPE" "0402"
					( Origin gFrontEnd )
				)
				( attribute "TOLERANCE" "1%"
					( Origin gFrontEnd )
				)
				( attribute "VALUE" "4.75K"
					( Origin gFrontEnd )
				)
				( attribute "VER" "2"
					( Origin gFrontEnd )
				)
				( attribute "WATTAGE" "1/16W"
					( Origin gFrontEnd )
				)
				( attribute "XY" "(-6225,3225)"
					( Origin gFrontEnd )
				)
				( attribute "CHIPS_PART_NAME" "RES"
					( Origin gPackager )
				)
				( attribute "CDS_PART_NAME" "RES_0402-4.75K,1%,1/16W,EMPTY,A"
					( Origin gPackager )
				)
				( attribute "CDS_LOCATION" "RN8F2"
					( Origin gPackager )
				)
				( attribute "CDS_SEC" "1"
					( Origin gPackager )
				)
				( objectStatus "RN8F2" )
			)
			( gate "@baseboard_fab2_lib.baseboard_fab2(sch_1):page162_i24"
				( attribute "BOM_COST" "SM_MEM"
					( Origin gFrontEnd )
				)
				( attribute "CDS_LIB" "mstr_discrete"
					( Origin gPackager )
				)
				( attribute "CDS_LOCATION" "R8F35"
					( Origin gPackager )
				)
				( attribute "LOCATION" "R8F35"
					( Origin gFrontEnd )
				)
				( attribute "MATERIAL" "EMPTY"
					( Origin gFrontEnd )
				)
				( attribute "PACK_TYPE" "0402"
					( Origin gFrontEnd )
				)
				( attribute "PART_NUMBER" "G21796-026"
					( Origin gFrontEnd )
				)
				( attribute "PHYS_PAGE" "162"
					( Origin gFrontEnd )
				)
				( attribute "ROOM" "BMC_BOOT_SPI"
					( Origin gFrontEnd )
				)
				( attribute "ROT" "0"
					( Origin gFrontEnd )
				)
				( attribute "SEC" "1"
					( Origin gFrontEnd )
				)
				( attribute "TOLERANCE" "1%"
					( Origin gFrontEnd )
				)
				( attribute "VALUE" "1.00K"
					( Origin gFrontEnd )
				)
				( attribute "VER" "2"
					( Origin gFrontEnd )
				)
				( attribute "WATTAGE" "1/16W"
					( Origin gFrontEnd )
				)
				( attribute "XY" "(4875,2050)"
					( Origin gFrontEnd )
				)
				( attribute "CHIPS_PART_NAME" "RES"
					( Origin gPackager )
				)
				( attribute "CDS_PART_NAME" "RES_0402-1.00K,1%,1/16W,EMPTY,A"
					( Origin gPackager )
				)
				( attribute "SEC_TYPE" "0402"
					( Origin gFrontEnd )
				)
				( attribute "CDS_SEC" "1"
					( Origin gPackager )
				)
				( objectStatus "R8F35" )
			)
			( gate "@baseboard_fab2_lib.baseboard_fab2(sch_1):page162_i28"
				( attribute "BOM_COST" "SM_MEM"
					( Origin gFrontEnd )
				)
				( attribute "CDS_LIB" "dev_discrete"
					( Origin gPackager )
				)
				( attribute "CDS_LOCATION" "C8F5"
					( Origin gPackager )
				)
				( attribute "LOCATION" "C8F5"
					( Origin gFrontEnd )
				)
				( attribute "MATERIAL" "X7R"
					( Origin gFrontEnd )
				)
				( attribute "PACK_TYPE" "0402V"
					( Origin gFrontEnd )
				)
				( attribute "PART_NUMBER" "A36096-045"
					( Origin gFrontEnd )
				)
				( attribute "PHYS_PAGE" "162"
					( Origin gFrontEnd )
				)
				( attribute "ROOM" "BMC_BOOT_SPI"
					( Origin gFrontEnd )
				)
				( attribute "ROT" "0"
					( Origin gFrontEnd )
				)
				( attribute "SEC" "1"
					( Origin gFrontEnd )
				)
				( attribute "TOLERANCE" "10%"
					( Origin gFrontEnd )
				)
				( attribute "VALUE" "0.01UF"
					( Origin gFrontEnd )
				)
				( attribute "VER" "1"
					( Origin gFrontEnd )
				)
				( attribute "VOLTAGE" "25V"
					( Units "uVoltage" "V" 1.000000)
					( Origin gFrontEnd )
				)
				( attribute "XY" "(7650,3400)"
					( Origin gFrontEnd )
				)
				( attribute "CHIPS_PART_NAME" "CAP_A"
					( Origin gPackager )
				)
				( attribute "CDS_PART_NAME" "CAP_A_0402V-0.01UF,25V,10%,X7RA"
					( Origin gPackager )
				)
				( attribute "SEC_TYPE" "0402V"
					( Origin gFrontEnd )
				)
				( attribute "CDS_SEC" "1"
					( Origin gPackager )
				)
				( objectStatus "C8F5" )
			)
			( gate "@baseboard_fab2_lib.baseboard_fab2(sch_1):page162_i30"
				( attribute "BOM_COST" "SM_MEM"
					( Origin gFrontEnd )
				)
				( attribute "CDS_LIB" "dev_discrete"
					( Origin gPackager )
				)
				( attribute "CDS_LOCATION" "C8F4"
					( Origin gPackager )
				)
				( attribute "LOCATION" "C8F4"
					( Origin gFrontEnd )
				)
				( attribute "MATERIAL" "X6S"
					( Origin gFrontEnd )
				)
				( attribute "PACK_TYPE" "0402V"
					( Origin gFrontEnd )
				)
				( attribute "PART_NUMBER" "D97712-004"
					( Origin gFrontEnd )
				)
				( attribute "PHYS_PAGE" "162"
					( Origin gFrontEnd )
				)
				( attribute "ROOM" "BMC_BOOT_SPI"
					( Origin gFrontEnd )
				)
				( attribute "ROT" "0"
					( Origin gFrontEnd )
				)
				( attribute "SEC" "1"
					( Origin gFrontEnd )
				)
				( attribute "TOLERANCE" "10%"
					( Origin gFrontEnd )
				)
				( attribute "VALUE" "1.0UF"
					( Origin gFrontEnd )
				)
				( attribute "VER" "1"
					( Origin gFrontEnd )
				)
				( attribute "VOLTAGE" "6.3V"
					( Units "uVoltage" "V" 1.000000)
					( Origin gFrontEnd )
				)
				( attribute "XY" "(7350,3400)"
					( Origin gFrontEnd )
				)
				( attribute "CHIPS_PART_NAME" "CAP_A"
					( Origin gPackager )
				)
				( attribute "CDS_PART_NAME" "CAP_A_0402V-1.0UF,6.3V,10%,X6SA"
					( Origin gPackager )
				)
				( attribute "SEC_TYPE" "0402V"
					( Origin gFrontEnd )
				)
				( attribute "CDS_SEC" "1"
					( Origin gPackager )
				)
				( objectStatus "C8F4" )
			)
			( gate "@baseboard_fab2_lib.baseboard_fab2(sch_1):page162_i32"
				( attribute "BOM_COST" "SM_MEM"
					( Origin gFrontEnd )
				)
				( attribute "CDS_LIB" "mstr_memory"
					( Origin gPackager )
				)
				( attribute "CDS_LMAN_SYM_OUTLINE" "-500,325,500,-325"
					( Origin gPackager )
				)
				( attribute "CDS_LOCATION" "U8F2"
					( Origin gPackager )
				)
				( attribute "CDS_SEC" "1"
					( Origin gPackager )
				)
				( attribute "LOCATION" "U8F2"
					( Origin gFrontEnd )
				)
				( attribute "MATERIAL" "IC"
					( Origin gFrontEnd )
				)
				( attribute "PACK_TYPE" "SKT16"
					( Origin gFrontEnd )
				)
				( attribute "PART_NUMBER" "H12709-001"
					( Origin gFrontEnd )
				)
				( attribute "PHYS_PAGE" "162"
					( Origin gFrontEnd )
				)
				( attribute "ROOM" "BMC_BOOT_SPI"
					( Origin gFrontEnd )
				)
				( attribute "ROT" "0"
					( Origin gFrontEnd )
				)
				( attribute "SEC" "1"
					( Origin gFrontEnd )
				)
				( attribute "SEC_TYPE" "SKT16"
					( Origin gFrontEnd )
				)
				( attribute "VER" "3"
					( Origin gFrontEnd )
				)
				( attribute "XY" "(6450,2800)"
					( Origin gFrontEnd )
				)
				( attribute "CHIPS_PART_NAME" "W25Q128"
					( Origin gPackager )
				)
				( attribute "CDS_PART_NAME" "W25Q128_SKT16-IC,H12709-001"
					( Origin gPackager )
				)
				( objectStatus "U8F2" )
			)
			( gate "@baseboard_fab2_lib.baseboard_fab2(sch_1):page163_i1"
				( attribute "CHIPS_PART_NAME" "PCA9517"
					( Origin gPackager )
				)
			)
			( gate "@baseboard_fab2_lib.baseboard_fab2(sch_1):page163_i2"
				( attribute "CDS_LIB" "mstr_discrete"
					( Origin gPackager )
				)
				( attribute "CDS_LOCATION" "R6N8"
					( Origin gPackager )
				)
				( attribute "CDS_SEC" "1"
					( Origin gPackager )
				)
				( attribute "LOCATION" "R6N8"
					( Origin gFrontEnd )
				)
				( attribute "MATERIAL" "CHIP"
					( Origin gFrontEnd )
				)
				( attribute "PACK_TYPE" "0402"
					( Origin gFrontEnd )
				)
				( attribute "PART_NUMBER" "G21796-066"
					( Origin gFrontEnd )
				)
				( attribute "PHYS_PAGE" "163"
					( Origin gFrontEnd )
				)
				( attribute "ROOM" "CPU1"
					( Origin gFrontEnd )
				)
				( attribute "ROT" "0"
					( Origin gFrontEnd )
				)
				( attribute "SEC" "1"
					( Origin gFrontEnd )
				)
				( attribute "SEC_TYPE" "0402"
					( Origin gFrontEnd )
				)
				( attribute "TOLERANCE" "1%"
					( Origin gFrontEnd )
				)
				( attribute "VALUE" "10.0"
					( Origin gFrontEnd )
				)
				( attribute "VER" "1"
					( Origin gFrontEnd )
				)
				( attribute "WATTAGE" "1/16W"
					( Origin gFrontEnd )
				)
				( attribute "XY" "(-3800,3300)"
					( Origin gFrontEnd )
				)
				( attribute "CHIPS_PART_NAME" "RES"
					( Origin gPackager )
				)
				( attribute "CDS_PART_NAME" "RES_0402-10.0,1%,1/16W,CHIP,G2A"
					( Origin gPackager )
				)
				( objectStatus "R6N8" )
			)
			( gate "@baseboard_fab2_lib.baseboard_fab2(sch_1):page163_i3"
				( attribute "CDS_LIB" "mstr_discrete"
					( Origin gPackager )
				)
				( attribute "CDS_LOCATION" "R6N9"
					( Origin gPackager )
				)
				( attribute "CDS_SEC" "1"
					( Origin gPackager )
				)
				( attribute "LOCATION" "R6N9"
					( Origin gFrontEnd )
				)
				( attribute "MATERIAL" "CHIP"
					( Origin gFrontEnd )
				)
				( attribute "PACK_TYPE" "0402"
					( Origin gFrontEnd )
				)
				( attribute "PART_NUMBER" "G21796-066"
					( Origin gFrontEnd )
				)
				( attribute "PHYS_PAGE" "163"
					( Origin gFrontEnd )
				)
				( attribute "ROOM" "CPU1"
					( Origin gFrontEnd )
				)
				( attribute "ROT" "0"
					( Origin gFrontEnd )
				)
				( attribute "SEC" "1"
					( Origin gFrontEnd )
				)
				( attribute "SEC_TYPE" "0402"
					( Origin gFrontEnd )
				)
				( attribute "TOLERANCE" "1%"
					( Origin gFrontEnd )
				)
				( attribute "VALUE" "10.0"
					( Origin gFrontEnd )
				)
				( attribute "VER" "1"
					( Origin gFrontEnd )
				)
				( attribute "WATTAGE" "1/16W"
					( Origin gFrontEnd )
				)
				( attribute "XY" "(-3275,3250)"
					( Origin gFrontEnd )
				)
				( attribute "CHIPS_PART_NAME" "RES"
					( Origin gPackager )
				)
				( attribute "CDS_PART_NAME" "RES_0402-10.0,1%,1/16W,CHIP,G2A"
					( Origin gPackager )
				)
				( objectStatus "R6N9" )
			)
			( gate "@baseboard_fab2_lib.baseboard_fab2(sch_1):page163_i6"
				( attribute "CDS_LIB" "mstr_discrete"
					( Origin gPackager )
				)
				( attribute "CDS_LOCATION" "R9M18"
					( Origin gPackager )
				)
				( attribute "CDS_SEC" "1"
					( Origin gPackager )
				)
				( attribute "LOCATION" "R9M18"
					( Origin gFrontEnd )
				)
				( attribute "MATERIAL" "CHIP"
					( Origin gFrontEnd )
				)
				( attribute "PACK_TYPE" "0402"
					( Origin gFrontEnd )
				)
				( attribute "PART_NUMBER" "G21796-294"
					( Origin gFrontEnd )
				)
				( attribute "PHYS_PAGE" "163"
					( Origin gFrontEnd )
				)
				( attribute "ROOM" "SMB_PE_HP_CPU1"
					( Origin gFrontEnd )
				)
				( attribute "ROT" "0"
					( Origin gFrontEnd )
				)
				( attribute "SEC" "1"
					( Origin gFrontEnd )
				)
				( attribute "SEC_TYPE" "0402"
					( Origin gFrontEnd )
				)
				( attribute "TOLERANCE" "1.0%"
					( Origin gFrontEnd )
				)
				( attribute "VALUE" "240"
					( Origin gFrontEnd )
				)
				( attribute "VER" "2"
					( Origin gFrontEnd )
				)
				( attribute "WATTAGE" "1/16W"
					( Origin gFrontEnd )
				)
				( attribute "XY" "(-2200,3650)"
					( Origin gFrontEnd )
				)
				( attribute "CHIPS_PART_NAME" "RES"
					( Origin gPackager )
				)
				( attribute "CDS_PART_NAME" "RES_0402-240,1.0%,1/16W,CHIP,GA"
					( Origin gPackager )
				)
				( objectStatus "R9M18" )
			)
			( gate "@baseboard_fab2_lib.baseboard_fab2(sch_1):page163_i7"
				( attribute "CDS_LIB" "mstr_discrete"
					( Origin gPackager )
				)
				( attribute "CDS_LOCATION" "R9M19"
					( Origin gPackager )
				)
				( attribute "CDS_SEC" "1"
					( Origin gPackager )
				)
				( attribute "LOCATION" "R9M19"
					( Origin gFrontEnd )
				)
				( attribute "MATERIAL" "CHIP"
					( Origin gFrontEnd )
				)
				( attribute "PACK_TYPE" "0402"
					( Origin gFrontEnd )
				)
				( attribute "PART_NUMBER" "G21796-294"
					( Origin gFrontEnd )
				)
				( attribute "PHYS_PAGE" "163"
					( Origin gFrontEnd )
				)
				( attribute "ROOM" "SMB_PE_HP_CPU1"
					( Origin gFrontEnd )
				)
				( attribute "ROT" "2"
					( Origin gFrontEnd )
				)
				( attribute "SEC" "1"
					( Origin gFrontEnd )
				)
				( attribute "SEC_TYPE" "0402"
					( Origin gFrontEnd )
				)
				( attribute "TOLERANCE" "1.0%"
					( Origin gFrontEnd )
				)
				( attribute "VALUE" "240"
					( Origin gFrontEnd )
				)
				( attribute "VER" "2"
					( Origin gFrontEnd )
				)
				( attribute "WATTAGE" "1/16W"
					( Origin gFrontEnd )
				)
				( attribute "XY" "(-2325,3650)"
					( Origin gFrontEnd )
				)
				( attribute "CHIPS_PART_NAME" "RES"
					( Origin gPackager )
				)
				( attribute "CDS_PART_NAME" "RES_0402-240,1.0%,1/16W,CHIP,GA"
					( Origin gPackager )
				)
				( objectStatus "R9M19" )
			)
			( gate "@baseboard_fab2_lib.baseboard_fab2(sch_1):page163_i10"
				( attribute "CDS_LIB" "dev_discrete"
					( Origin gPackager )
				)
				( attribute "CDS_LOCATION" "C9M8"
					( Origin gPackager )
				)
				( attribute "CDS_SEC" "1"
					( Origin gPackager )
				)
				( attribute "LOCATION" "C9M8"
					( Origin gFrontEnd )
				)
				( attribute "MATERIAL" "X7R"
					( Origin gFrontEnd )
				)
				( attribute "PACK_TYPE" "0402V"
					( Origin gFrontEnd )
				)
				( attribute "PART_NUMBER" "A36096-030"
					( Origin gFrontEnd )
				)
				( attribute "PHYS_PAGE" "163"
					( Origin gFrontEnd )
				)
				( attribute "ROOM" "SMB_PE_HP_CPU1"
					( Origin gFrontEnd )
				)
				( attribute "ROT" "0"
					( Origin gFrontEnd )
				)
				( attribute "SEC" "1"
					( Origin gFrontEnd )
				)
				( attribute "SEC_TYPE" "0402V"
					( Origin gFrontEnd )
				)
				( attribute "TOLERANCE" "10%"
					( Origin gFrontEnd )
				)
				( attribute "VALUE" "0.1UF"
					( Origin gFrontEnd )
				)
				( attribute "VER" "1"
					( Origin gFrontEnd )
				)
				( attribute "VOLTAGE" "16V"
					( Units "uVoltage" "V" 1.000000)
					( Origin gFrontEnd )
				)
				( attribute "XY" "(-1800,3850)"
					( Origin gFrontEnd )
				)
				( attribute "CHIPS_PART_NAME" "CAP_A"
					( Origin gPackager )
				)
				( attribute "CDS_PART_NAME" "CAP_A_0402V-0.1UF,16V,10%,X7R,A"
					( Origin gPackager )
				)
				( objectStatus "C9M8" )
			)
			( gate "@baseboard_fab2_lib.baseboard_fab2(sch_1):page163_i12"
				( attribute "CDS_LIB" "dev_discrete"
					( Origin gPackager )
				)
				( attribute "CDS_LOCATION" "C9M7"
					( Origin gPackager )
				)
				( attribute "CDS_SEC" "1"
					( Origin gPackager )
				)
				( attribute "LOCATION" "C9M7"
					( Origin gFrontEnd )
				)
				( attribute "MATERIAL" "X7R"
					( Origin gFrontEnd )
				)
				( attribute "PACK_TYPE" "0402V"
					( Origin gFrontEnd )
				)
				( attribute "PART_NUMBER" "A36096-030"
					( Origin gFrontEnd )
				)
				( attribute "PHYS_PAGE" "163"
					( Origin gFrontEnd )
				)
				( attribute "ROOM" "SMB_PE_HP_CPU1"
					( Origin gFrontEnd )
				)
				( attribute "ROT" "2"
					( Origin gFrontEnd )
				)
				( attribute "SEC" "1"
					( Origin gFrontEnd )
				)
				( attribute "SEC_TYPE" "0402V"
					( Origin gFrontEnd )
				)
				( attribute "TOLERANCE" "10%"
					( Origin gFrontEnd )
				)
				( attribute "VALUE" "0.1UF"
					( Origin gFrontEnd )
				)
				( attribute "VER" "1"
					( Origin gFrontEnd )
				)
				( attribute "VOLTAGE" "16V"
					( Units "uVoltage" "V" 1.000000)
					( Origin gFrontEnd )
				)
				( attribute "XY" "(-1150,3850)"
					( Origin gFrontEnd )
				)
				( attribute "CHIPS_PART_NAME" "CAP_A"
					( Origin gPackager )
				)
				( attribute "CDS_PART_NAME" "CAP_A_0402V-0.1UF,16V,10%,X7R,A"
					( Origin gPackager )
				)
				( objectStatus "C9M7" )
			)
			( gate "@baseboard_fab2_lib.baseboard_fab2(sch_1):page163_i15"
				( attribute "CDS_LIB" "mstr_discrete"
					( Origin gPackager )
				)
				( attribute "CDS_LOCATION" "R9M17"
					( Origin gPackager )
				)
				( attribute "CDS_SEC" "1"
					( Origin gPackager )
				)
				( attribute "LOCATION" "R9M17"
					( Origin gFrontEnd )
				)
				( attribute "MATERIAL" "CHIP"
					( Origin gFrontEnd )
				)
				( attribute "PACK_TYPE" "0402"
					( Origin gFrontEnd )
				)
				( attribute "PART_NUMBER" "G21796-001"
					( Origin gFrontEnd )
				)
				( attribute "PHYS_PAGE" "163"
					( Origin gFrontEnd )
				)
				( attribute "ROOM" "SMB_PE_HP_CPU1"
					( Origin gFrontEnd )
				)
				( attribute "ROT" "2"
					( Origin gFrontEnd )
				)
				( attribute "SEC" "1"
					( Origin gFrontEnd )
				)
				( attribute "SEC_TYPE" "0402"
					( Origin gFrontEnd )
				)
				( attribute "TOLERANCE" "1%"
					( Origin gFrontEnd )
				)
				( attribute "VALUE" "2.0K"
					( Origin gFrontEnd )
				)
				( attribute "VER" "2"
					( Origin gFrontEnd )
				)
				( attribute "WATTAGE" "1/16W"
					( Origin gFrontEnd )
				)
				( attribute "XY" "(-600,3650)"
					( Origin gFrontEnd )
				)
				( attribute "CHIPS_PART_NAME" "RES"
					( Origin gPackager )
				)
				( attribute "CDS_PART_NAME" "RES_0402-2.0K,1%,1/16W,CHIP,G2A"
					( Origin gPackager )
				)
				( objectStatus "R9M17" )
			)
			( gate "@baseboard_fab2_lib.baseboard_fab2(sch_1):page163_i16"
				( attribute "CDS_LIB" "mstr_discrete"
					( Origin gPackager )
				)
				( attribute "CDS_LOCATION" "R9M16"
					( Origin gPackager )
				)
				( attribute "CDS_SEC" "1"
					( Origin gPackager )
				)
				( attribute "LOCATION" "R9M16"
					( Origin gFrontEnd )
				)
				( attribute "MATERIAL" "CHIP"
					( Origin gFrontEnd )
				)
				( attribute "PACK_TYPE" "0402"
					( Origin gFrontEnd )
				)
				( attribute "PART_NUMBER" "G21796-001"
					( Origin gFrontEnd )
				)
				( attribute "PHYS_PAGE" "163"
					( Origin gFrontEnd )
				)
				( attribute "ROOM" "SMB_PE_HP_CPU1"
					( Origin gFrontEnd )
				)
				( attribute "ROT" "0"
					( Origin gFrontEnd )
				)
				( attribute "SEC" "1"
					( Origin gFrontEnd )
				)
				( attribute "SEC_TYPE" "0402"
					( Origin gFrontEnd )
				)
				( attribute "TOLERANCE" "1%"
					( Origin gFrontEnd )
				)
				( attribute "VALUE" "2.0K"
					( Origin gFrontEnd )
				)
				( attribute "VER" "2"
					( Origin gFrontEnd )
				)
				( attribute "WATTAGE" "1/16W"
					( Origin gFrontEnd )
				)
				( attribute "XY" "(-450,3650)"
					( Origin gFrontEnd )
				)
				( attribute "CHIPS_PART_NAME" "RES"
					( Origin gPackager )
				)
				( attribute "CDS_PART_NAME" "RES_0402-2.0K,1%,1/16W,CHIP,G2A"
					( Origin gPackager )
				)
				( objectStatus "R9M16" )
			)
			( gate "@baseboard_fab2_lib.baseboard_fab2(sch_1):page163_i20"
				( attribute "CDS_LIB" "mstr_discrete"
					( Origin gPackager )
				)
				( attribute "CDS_LOCATION" "R9M14"
					( Origin gPackager )
				)
				( attribute "LOCATION" "R9M14"
					( Origin gFrontEnd )
				)
				( attribute "MATERIAL" "CHIP"
					( Origin gFrontEnd )
				)
				( attribute "PACK_TYPE" "0402"
					( Origin gFrontEnd )
				)
				( attribute "PART_NUMBER" "G21796-173"
					( Origin gFrontEnd )
				)
				( attribute "PHYS_PAGE" "163"
					( Origin gFrontEnd )
				)
				( attribute "ROOM" "SMB_PE_HP_CPU1"
					( Origin gFrontEnd )
				)
				( attribute "ROT" "0"
					( Origin gFrontEnd )
				)
				( attribute "SEC" "1"
					( Origin gFrontEnd )
				)
				( attribute "TOLERANCE" "1%"
					( Origin gFrontEnd )
				)
				( attribute "VALUE" "20.0"
					( Origin gFrontEnd )
				)
				( attribute "VER" "1"
					( Origin gFrontEnd )
				)
				( attribute "WATTAGE" "1/16W"
					( Origin gFrontEnd )
				)
				( attribute "XY" "(-50,3300)"
					( Origin gFrontEnd )
				)
				( attribute "CHIPS_PART_NAME" "RES"
					( Origin gPackager )
				)
				( attribute "CDS_PART_NAME" "RES_0402-20.0,1%,1/16W,CHIP,G2A"
					( Origin gPackager )
				)
				( attribute "SEC_TYPE" "0402"
					( Origin gFrontEnd )
				)
				( attribute "CDS_SEC" "1"
					( Origin gPackager )
				)
				( objectStatus "R9M14" )
			)
			( gate "@baseboard_fab2_lib.baseboard_fab2(sch_1):page163_i21"
				( attribute "CDS_LIB" "mstr_discrete"
					( Origin gPackager )
				)
				( attribute "CDS_LOCATION" "R9M13"
					( Origin gPackager )
				)
				( attribute "LOCATION" "R9M13"
					( Origin gFrontEnd )
				)
				( attribute "MATERIAL" "CHIP"
					( Origin gFrontEnd )
				)
				( attribute "PACK_TYPE" "0402"
					( Origin gFrontEnd )
				)
				( attribute "PART_NUMBER" "G21796-173"
					( Origin gFrontEnd )
				)
				( attribute "PHYS_PAGE" "163"
					( Origin gFrontEnd )
				)
				( attribute "ROOM" "SMB_PE_HP_CPU1"
					( Origin gFrontEnd )
				)
				( attribute "ROT" "0"
					( Origin gFrontEnd )
				)
				( attribute "SEC" "1"
					( Origin gFrontEnd )
				)
				( attribute "TOLERANCE" "1%"
					( Origin gFrontEnd )
				)
				( attribute "VALUE" "20.0"
					( Origin gFrontEnd )
				)
				( attribute "VER" "1"
					( Origin gFrontEnd )
				)
				( attribute "WATTAGE" "1/16W"
					( Origin gFrontEnd )
				)
				( attribute "XY" "(200,3250)"
					( Origin gFrontEnd )
				)
				( attribute "CHIPS_PART_NAME" "RES"
					( Origin gPackager )
				)
				( attribute "CDS_PART_NAME" "RES_0402-20.0,1%,1/16W,CHIP,G2A"
					( Origin gPackager )
				)
				( attribute "SEC_TYPE" "0402"
					( Origin gFrontEnd )
				)
				( attribute "CDS_SEC" "1"
					( Origin gPackager )
				)
				( objectStatus "R9M13" )
			)
			( gate "@baseboard_fab2_lib.baseboard_fab2(sch_1):page246_i19"
				( attribute "CDS_LIB" "w_hdl"
					( Origin gPackager )
				)
				( attribute "CDS_LMAN_SYM_OUTLINE" "-50,75,50,-75"
					( Origin gPackager )
				)
				( attribute "LOCATION" "RN8F6"
					( Origin gFrontEnd )
				)
				( attribute "PACK_TYPE" "SMD-RG"
					( Origin gFrontEnd )
				)
				( attribute "PART_NUMBER" "64.82025.6DL"
					( Origin gFrontEnd )
				)
				( attribute "PHYS_PAGE" "246"
					( Origin gFrontEnd )
				)
				( attribute "ROT" "0"
					( Origin gFrontEnd )
				)
				( attribute "VALUE" "82KR2F-1-GP"
					( Origin gFrontEnd )
				)
				( attribute "VER" "1"
					( Origin gFrontEnd )
				)
				( attribute "XY" "(-6225,2300)"
					( Origin gFrontEnd )
				)
				( attribute "CHIPS_PART_NAME" "82KR2F-1-GP"
					( Origin gPackager )
				)
				( attribute "CDS_PART_NAME" "82KR2F-1-GP_SMD-RG-82KR2F-1-GPA"
					( Origin gPackager )
				)
				( attribute "CDS_LOCATION" "RN8F6"
					( Origin gPackager )
				)
				( attribute "CDS_SEC" "1"
					( Origin gPackager )
				)
				( attribute "SEC" "1"
					( Origin gPackager )
				)
				( attribute "ATTRIBUTE" "82KOHM"
					( Origin gFrontEnd )
				)
				( attribute "RATED" "1/16W"
					( Origin gFrontEnd )
				)
				( attribute "TOLERANCE" "1%"
					( Origin gFrontEnd )
				)
				( attribute "PACK_SIZE" "0402"
					( Origin gFrontEnd )
				)
				( objectStatus "RN8F6" )
			)
			( gate "@baseboard_fab2_lib.baseboard_fab2(sch_1):page164_i47"
				( attribute "BOM_COST" "SM_CONTROLLER"
					( Origin gFrontEnd )
				)
				( attribute "CDS_LIB" "mstr_discrete"
					( Origin gPackager )
				)
				( attribute "CDS_LOCATION" "R1U24"
					( Origin gPackager )
				)
				( attribute "CDS_SEC" "1"
					( Origin gPackager )
				)
				( attribute "LOCATION" "R1U24"
					( Origin gFrontEnd )
				)
				( attribute "MATERIAL" "CHIP"
					( Origin gFrontEnd )
				)
				( attribute "PACK_TYPE" "0402"
					( Origin gFrontEnd )
				)
				( attribute "PART_NUMBER" "G21796-344"
					( Origin gFrontEnd )
				)
				( attribute "PHYS_PAGE" "164"
					( Origin gFrontEnd )
				)
				( attribute "ROOM" "BMC_MISC"
					( Origin gFrontEnd )
				)
				( attribute "ROT" "0"
					( Origin gFrontEnd )
				)
				( attribute "SEC" "1"
					( Origin gFrontEnd )
				)
				( attribute "SEC_TYPE" "0402"
					( Origin gFrontEnd )
				)
				( attribute "TOLERANCE" "1%"
					( Origin gFrontEnd )
				)
				( attribute "VALUE" "2.7K"
					( Origin gFrontEnd )
				)
				( attribute "VER" "1"
					( Origin gFrontEnd )
				)
				( attribute "WATTAGE" "1/16W"
					( Origin gFrontEnd )
				)
				( attribute "XY" "(-7175,4075)"
					( Origin gFrontEnd )
				)
				( attribute "CHIPS_PART_NAME" "RES"
					( Origin gPackager )
				)
				( attribute "CDS_PART_NAME" "RES_0402-2.7K,1%,1/16W,CHIP,G2A"
					( Origin gPackager )
				)
				( attribute "POP" "NOPOP"
					( Origin gFrontEnd )
				)
				( objectStatus "R1U24" )
			)
			( gate "@baseboard_fab2_lib.baseboard_fab2(sch_1):page164_i7"
				( attribute "BOM_COST" "SM_CONTROLLER"
					( Origin gFrontEnd )
				)
				( attribute "CDS_LIB" "mstr_discrete"
					( Origin gPackager )
				)
				( attribute "CDS_LOCATION" "R1T11"
					( Origin gPackager )
				)
				( attribute "CDS_SEC" "1"
					( Origin gPackager )
				)
				( attribute "LOCATION" "R1T11"
					( Origin gFrontEnd )
				)
				( attribute "MATERIAL" "CHIP"
					( Origin gFrontEnd )
				)
				( attribute "PACK_TYPE" "0402"
					( Origin gFrontEnd )
				)
				( attribute "PART_NUMBER" "G21796-026"
					( Origin gFrontEnd )
				)
				( attribute "PHYS_PAGE" "164"
					( Origin gFrontEnd )
				)
				( attribute "ROOM" "BMC_MISC"
					( Origin gFrontEnd )
				)
				( attribute "ROT" "0"
					( Origin gFrontEnd )
				)
				( attribute "SEC" "1"
					( Origin gFrontEnd )
				)
				( attribute "SEC_TYPE" "0402"
					( Origin gFrontEnd )
				)
				( attribute "TOLERANCE" "1%"
					( Origin gFrontEnd )
				)
				( attribute "VALUE" "1.00K"
					( Origin gFrontEnd )
				)
				( attribute "VER" "2"
					( Origin gFrontEnd )
				)
				( attribute "WATTAGE" "1/16W"
					( Origin gFrontEnd )
				)
				( attribute "XY" "(-6850,925)"
					( Origin gFrontEnd )
				)
				( attribute "CHIPS_PART_NAME" "RES"
					( Origin gPackager )
				)
				( attribute "CDS_PART_NAME" "RES_0402-1.00K,1%,1/16W,CHIP,GA"
					( Origin gPackager )
				)
				( objectStatus "R1T11" )
			)
			( gate "@baseboard_fab2_lib.baseboard_fab2(sch_1):page164_i11"
				( attribute "BOM_COST" "SM_CONTROLLER"
					( Origin gFrontEnd )
				)
				( attribute "CDS_LIB" "mstr_discrete"
					( Origin gPackager )
				)
				( attribute "CDS_LOCATION" "R1T5"
					( Origin gPackager )
				)
				( attribute "CDS_SEC" "1"
					( Origin gPackager )
				)
				( attribute "LOCATION" "R1T5"
					( Origin gFrontEnd )
				)
				( attribute "MATERIAL" "EMPTY"
					( Origin gFrontEnd )
				)
				( attribute "PACK_TYPE" "0402"
					( Origin gFrontEnd )
				)
				( attribute "PART_NUMBER" "G21796-344"
					( Origin gFrontEnd )
				)
				( attribute "PHYS_PAGE" "164"
					( Origin gFrontEnd )
				)
				( attribute "ROOM" "BMC_MISC"
					( Origin gFrontEnd )
				)
				( attribute "ROT" "0"
					( Origin gFrontEnd )
				)
				( attribute "SEC" "1"
					( Origin gFrontEnd )
				)
				( attribute "SEC_TYPE" "0402"
					( Origin gFrontEnd )
				)
				( attribute "TOLERANCE" "1%"
					( Origin gFrontEnd )
				)
				( attribute "VALUE" "2.7K"
					( Origin gFrontEnd )
				)
				( attribute "VER" "1"
					( Origin gFrontEnd )
				)
				( attribute "WATTAGE" "1/16W"
					( Origin gFrontEnd )
				)
				( attribute "XY" "(-7400,1600)"
					( Origin gFrontEnd )
				)
				( attribute "CHIPS_PART_NAME" "RES"
					( Origin gPackager )
				)
				( attribute "CDS_PART_NAME" "RES_0402-2.7K,1%,1/16W,EMPTY,GA"
					( Origin gPackager )
				)
				( objectStatus "R1T5" )
			)
			( gate "@baseboard_fab2_lib.baseboard_fab2(sch_1):page164_i46"
				( attribute "BOM_COST" "SM_CONTROLLER"
					( Origin gFrontEnd )
				)
				( attribute "CDS_LIB" "mstr_discrete"
					( Origin gPackager )
				)
				( attribute "CDS_LOCATION" "R2N17"
					( Origin gPackager )
				)
				( attribute "CDS_SEC" "1"
					( Origin gPackager )
				)
				( attribute "LOCATION" "R2N17"
					( Origin gFrontEnd )
				)
				( attribute "MATERIAL" "CHIP"
					( Origin gFrontEnd )
				)
				( attribute "PACK_TYPE" "0402"
					( Origin gFrontEnd )
				)
				( attribute "PART_NUMBER" "G21796-344"
					( Origin gFrontEnd )
				)
				( attribute "PHYS_PAGE" "164"
					( Origin gFrontEnd )
				)
				( attribute "ROOM" "BMC_MISC"
					( Origin gFrontEnd )
				)
				( attribute "ROT" "0"
					( Origin gFrontEnd )
				)
				( attribute "SEC" "1"
					( Origin gFrontEnd )
				)
				( attribute "SEC_TYPE" "0402"
					( Origin gFrontEnd )
				)
				( attribute "TOLERANCE" "1%"
					( Origin gFrontEnd )
				)
				( attribute "VALUE" "2.7K"
					( Origin gFrontEnd )
				)
				( attribute "VER" "1"
					( Origin gFrontEnd )
				)
				( attribute "WATTAGE" "1/16W"
					( Origin gFrontEnd )
				)
				( attribute "XY" "(-7175,4475)"
					( Origin gFrontEnd )
				)
				( attribute "CHIPS_PART_NAME" "RES"
					( Origin gPackager )
				)
				( attribute "CDS_PART_NAME" "RES_0402-2.7K,1%,1/16W,CHIP,G2A"
					( Origin gPackager )
				)
				( attribute "GROUP" "PU_SKU_ID4"
					( Origin gFrontEnd )
				)
				( objectStatus "R2N17" )
			)
			( gate "@baseboard_fab2_lib.baseboard_fab2(sch_1):page164_i21"
				( attribute "BOM_COST" "SM_CONTROLLER"
					( Origin gFrontEnd )
				)
				( attribute "CDS_LIB" "mstr_discrete"
					( Origin gPackager )
				)
				( attribute "CDS_LOCATION" "R1U17"
					( Origin gPackager )
				)
				( attribute "CDS_SEC" "1"
					( Origin gPackager )
				)
				( attribute "LOCATION" "R1U17"
					( Origin gFrontEnd )
				)
				( attribute "MATERIAL" "CHIP"
					( Origin gFrontEnd )
				)
				( attribute "PACK_TYPE" "0402"
					( Origin gFrontEnd )
				)
				( attribute "PART_NUMBER" "G21796-026"
					( Origin gFrontEnd )
				)
				( attribute "PHYS_PAGE" "164"
					( Origin gFrontEnd )
				)
				( attribute "ROOM" "BMC_MISC"
					( Origin gFrontEnd )
				)
				( attribute "ROT" "0"
					( Origin gFrontEnd )
				)
				( attribute "SEC" "1"
					( Origin gFrontEnd )
				)
				( attribute "SEC_TYPE" "0402"
					( Origin gFrontEnd )
				)
				( attribute "TOLERANCE" "1%"
					( Origin gFrontEnd )
				)
				( attribute "VALUE" "1.00K"
					( Origin gFrontEnd )
				)
				( attribute "VER" "2"
					( Origin gFrontEnd )
				)
				( attribute "WATTAGE" "1/16W"
					( Origin gFrontEnd )
				)
				( attribute "XY" "(-6025,3350)"
					( Origin gFrontEnd )
				)
				( attribute "CHIPS_PART_NAME" "RES"
					( Origin gPackager )
				)
				( attribute "CDS_PART_NAME" "RES_0402-1.00K,1%,1/16W,CHIP,GA"
					( Origin gPackager )
				)
				( objectStatus "R1U17" )
			)
			( gate "@baseboard_fab2_lib.baseboard_fab2(sch_1):page164_i32"
				( attribute "BOM_COST" "SM_CONTROLLER"
					( Origin gFrontEnd )
				)
				( attribute "CDS_LIB" "mstr_discrete"
					( Origin gPackager )
				)
				( attribute "CDS_LOCATION" "R2N18"
					( Origin gPackager )
				)
				( attribute "LOCATION" "R2N18"
					( Origin gFrontEnd )
				)
				( attribute "MATERIAL" "CHIP"
					( Origin gFrontEnd )
				)
				( attribute "PACK_TYPE" "0402"
					( Origin gFrontEnd )
				)
				( attribute "PART_NUMBER" "G21796-026"
					( Origin gFrontEnd )
				)
				( attribute "PHYS_PAGE" "164"
					( Origin gFrontEnd )
				)
				( attribute "ROOM" "BMC_MISC"
					( Origin gFrontEnd )
				)
				( attribute "ROT" "0"
					( Origin gFrontEnd )
				)
				( attribute "SEC" "1"
					( Origin gFrontEnd )
				)
				( attribute "TOLERANCE" "1%"
					( Origin gFrontEnd )
				)
				( attribute "VALUE" "1.00K"
					( Origin gFrontEnd )
				)
				( attribute "VER" "2"
					( Origin gFrontEnd )
				)
				( attribute "WATTAGE" "1/16W"
					( Origin gFrontEnd )
				)
				( attribute "XY" "(-6625,3350)"
					( Origin gFrontEnd )
				)
				( attribute "CHIPS_PART_NAME" "RES"
					( Origin gPackager )
				)
				( attribute "CDS_PART_NAME" "RES_0402-1.00K,1%,1/16W,CHIP,GA"
					( Origin gPackager )
				)
				( attribute "SEC_TYPE" "0402"
					( Origin gFrontEnd )
				)
				( attribute "CDS_SEC" "1"
					( Origin gPackager )
				)
				( attribute "GROUP" "PD_SKU_ID4"
					( Origin gFrontEnd )
				)
				( objectStatus "R2N18" )
			)
			( gate "@baseboard_fab2_lib.baseboard_fab2(sch_1):page166_i46"
				( attribute "BOM_COST" "SYS_CLOCK"
					( Origin gFrontEnd )
				)
				( attribute "CDS_LIB" "mstr_discrete"
					( Origin gPackager )
				)
				( attribute "CDS_LOCATION" "R7W3"
					( Origin gPackager )
				)
				( attribute "CDS_SEC" "1"
					( Origin gPackager )
				)
				( attribute "LOCATION" "R7W3"
					( Origin gFrontEnd )
				)
				( attribute "MATERIAL" "EMPTY"
					( Origin gFrontEnd )
				)
				( attribute "PACK_TYPE" "0402"
					( Origin gFrontEnd )
				)
				( attribute "PART_NUMBER" "G21796-016"
					( Origin gFrontEnd )
				)
				( attribute "PHYS_PAGE" "166"
					( Origin gFrontEnd )
				)
				( attribute "ROOM" "DB1200ZL"
					( Origin gFrontEnd )
				)
				( attribute "ROT" "0"
					( Origin gFrontEnd )
				)
				( attribute "SEC" "1"
					( Origin gFrontEnd )
				)
				( attribute "SEC_TYPE" "0402"
					( Origin gFrontEnd )
				)
				( attribute "TOLERANCE" "1%"
					( Origin gFrontEnd )
				)
				( attribute "VALUE" "10.0K"
					( Origin gFrontEnd )
				)
				( attribute "VER" "2"
					( Origin gFrontEnd )
				)
				( attribute "WATTAGE" "1/16W"
					( Origin gFrontEnd )
				)
				( attribute "XY" "(-2400,3150)"
					( Origin gFrontEnd )
				)
				( attribute "CHIPS_PART_NAME" "RES"
					( Origin gPackager )
				)
				( attribute "CDS_PART_NAME" "RES_0402-10.0K,1%,1/16W,EMPTY,A"
					( Origin gPackager )
				)
				( objectStatus "R7W3" )
			)
			( gate "@baseboard_fab2_lib.baseboard_fab2(sch_1):page166_i42"
				( attribute "BOM_COST" "SYS_CLOCK"
					( Origin gFrontEnd )
				)
				( attribute "CDS_LIB" "mstr_discrete"
					( Origin gPackager )
				)
				( attribute "CDS_LOCATION" "R7W2"
					( Origin gPackager )
				)
				( attribute "CDS_SEC" "1"
					( Origin gPackager )
				)
				( attribute "LOCATION" "R7W2"
					( Origin gFrontEnd )
				)
				( attribute "MATERIAL" "EMPTY"
					( Origin gFrontEnd )
				)
				( attribute "PACK_TYPE" "0402"
					( Origin gFrontEnd )
				)
				( attribute "PART_NUMBER" "G21796-016"
					( Origin gFrontEnd )
				)
				( attribute "PHYS_PAGE" "166"
					( Origin gFrontEnd )
				)
				( attribute "ROOM" "DB1200ZL"
					( Origin gFrontEnd )
				)
				( attribute "ROT" "0"
					( Origin gFrontEnd )
				)
				( attribute "SEC" "1"
					( Origin gFrontEnd )
				)
				( attribute "SEC_TYPE" "0402"
					( Origin gFrontEnd )
				)
				( attribute "TOLERANCE" "1%"
					( Origin gFrontEnd )
				)
				( attribute "VALUE" "10.0K"
					( Origin gFrontEnd )
				)
				( attribute "VER" "2"
					( Origin gFrontEnd )
				)
				( attribute "WATTAGE" "1/16W"
					( Origin gFrontEnd )
				)
				( attribute "XY" "(-2400,2500)"
					( Origin gFrontEnd )
				)
				( attribute "CHIPS_PART_NAME" "RES"
					( Origin gPackager )
				)
				( attribute "CDS_PART_NAME" "RES_0402-10.0K,1%,1/16W,EMPTY,A"
					( Origin gPackager )
				)
				( objectStatus "R7W2" )
			)
			( gate "@baseboard_fab2_lib.baseboard_fab2(sch_1):page166_i28"
				( attribute "BOM_COST" "DEBUG"
					( Origin gFrontEnd )
				)
				( attribute "CDS_LIB" "mstr_discrete"
					( Origin gPackager )
				)
				( attribute "CDS_LOCATION" "R7C17"
					( Origin gPackager )
				)
				( attribute "CDS_SEC" "1"
					( Origin gPackager )
				)
				( attribute "LOCATION" "R7C17"
					( Origin gFrontEnd )
				)
				( attribute "MATERIAL" "CHIP"
					( Origin gFrontEnd )
				)
				( attribute "PACK_TYPE" "0402"
					( Origin gFrontEnd )
				)
				( attribute "PART_NUMBER" "G21796-072"
					( Origin gFrontEnd )
				)
				( attribute "PHYS_PAGE" "166"
					( Origin gFrontEnd )
				)
				( attribute "ROOM" "PECI"
					( Origin gFrontEnd )
				)
				( attribute "ROT" "2"
					( Origin gFrontEnd )
				)
				( attribute "SEC" "1"
					( Origin gFrontEnd )
				)
				( attribute "SEC_TYPE" "0402"
					( Origin gFrontEnd )
				)
				( attribute "TOLERANCE" "1%"
					( Origin gFrontEnd )
				)
				( attribute "VALUE" "4.75K"
					( Origin gFrontEnd )
				)
				( attribute "VER" "2"
					( Origin gFrontEnd )
				)
				( attribute "WATTAGE" "1/16W"
					( Origin gFrontEnd )
				)
				( attribute "XY" "(-5050,3500)"
					( Origin gFrontEnd )
				)
				( attribute "CHIPS_PART_NAME" "RES"
					( Origin gPackager )
				)
				( attribute "CDS_PART_NAME" "RES_0402-4.75K,1%,1/16W,CHIP,GA"
					( Origin gPackager )
				)
				( objectStatus "R7C17" )
			)
			( gate "@baseboard_fab2_lib.baseboard_fab2(sch_1):page166_i32"
				( attribute "BOM_COST" "DEBUG"
					( Origin gFrontEnd )
				)
				( attribute "CDS_LIB" "mstr_discrete"
					( Origin gPackager )
				)
				( attribute "CDS_LOCATION" "R7D15"
					( Origin gPackager )
				)
				( attribute "CDS_SEC" "1"
					( Origin gPackager )
				)
				( attribute "LOCATION" "R7D15"
					( Origin gFrontEnd )
				)
				( attribute "MATERIAL" "CHIP"
					( Origin gFrontEnd )
				)
				( attribute "PACK_TYPE" "0402"
					( Origin gFrontEnd )
				)
				( attribute "PART_NUMBER" "G21796-340"
					( Origin gFrontEnd )
				)
				( attribute "PHYS_PAGE" "166"
					( Origin gFrontEnd )
				)
				( attribute "ROOM" "PECI"
					( Origin gFrontEnd )
				)
				( attribute "ROT" "0"
					( Origin gFrontEnd )
				)
				( attribute "SEC" "1"
					( Origin gFrontEnd )
				)
				( attribute "SEC_TYPE" "0402"
					( Origin gFrontEnd )
				)
				( attribute "TOLERANCE" "1%"
					( Origin gFrontEnd )
				)
				( attribute "VALUE" "348"
					( Origin gFrontEnd )
				)
				( attribute "VER" "2"
					( Origin gFrontEnd )
				)
				( attribute "WATTAGE" "1/16W"
					( Origin gFrontEnd )
				)
				( attribute "XY" "(-4475,2150)"
					( Origin gFrontEnd )
				)
				( attribute "CHIPS_PART_NAME" "RES"
					( Origin gPackager )
				)
				( attribute "CDS_PART_NAME" "RES_0402-348,1%,1/16W,CHIP,G21A"
					( Origin gPackager )
				)
				( objectStatus "R7D15" )
			)
			( gate "@baseboard_fab2_lib.baseboard_fab2(sch_1):page167_i1"
				( attribute "BOM_COST" "SM_THERM"
					( Origin gFrontEnd )
				)
				( attribute "CDS_LIB" "mstr_analog"
					( Origin gPackager )
				)
				( attribute "CDS_LOCATION" "U9B4"
					( Origin gPackager )
				)
				( attribute "CDS_SEC" "1"
					( Origin gPackager )
				)
				( attribute "LOCATION" "U9B4"
					( Origin gFrontEnd )
				)
				( attribute "MATERIAL" "IC"
					( Origin gFrontEnd )
				)
				( attribute "PACK_TYPE" "TSSOP"
					( Origin gFrontEnd )
				)
				( attribute "PART_NUMBER" "G62962-001"
					( Origin gFrontEnd )
				)
				( attribute "PHYS_PAGE" "167"
					( Origin gFrontEnd )
				)
				( attribute "ROOM" "TEMP_SENSORS"
					( Origin gFrontEnd )
				)
				( attribute "ROT" "0"
					( Origin gFrontEnd )
				)
				( attribute "SEC" "1"
					( Origin gFrontEnd )
				)
				( attribute "SEC_TYPE" "TSSOP"
					( Origin gFrontEnd )
				)
				( attribute "VER" "1"
					( Origin gFrontEnd )
				)
				( attribute "XY" "(-4000,4450)"
					( Origin gFrontEnd )
				)
				( attribute "CHIPS_PART_NAME" "TMP421"
					( Origin gPackager )
				)
				( attribute "CDS_PART_NAME" "TMP421_TSSOP-IC,G62962-001"
					( Origin gPackager )
				)
				( objectStatus "U9B4" )
			)
			( gate "@baseboard_fab2_lib.baseboard_fab2(sch_1):page167_i5"
				( attribute "BOM_COST" "SM_THERM"
					( Origin gFrontEnd )
				)
				( attribute "CDS_LIB" "mstr_discrete"
					( Origin gPackager )
				)
				( attribute "CDS_LOCATION" "R9B5"
					( Origin gPackager )
				)
				( attribute "CDS_SEC" "1"
					( Origin gPackager )
				)
				( attribute "LOCATION" "R9B5"
					( Origin gFrontEnd )
				)
				( attribute "MATERIAL" "CHIP"
					( Origin gFrontEnd )
				)
				( attribute "PACK_TYPE" "0402"
					( Origin gFrontEnd )
				)
				( attribute "PART_NUMBER" "G21796-047"
					( Origin gFrontEnd )
				)
				( attribute "PHYS_PAGE" "167"
					( Origin gFrontEnd )
				)
				( attribute "ROOM" "TEMP_SENSORS"
					( Origin gFrontEnd )
				)
				( attribute "ROT" "0"
					( Origin gFrontEnd )
				)
				( attribute "SEC" "1"
					( Origin gFrontEnd )
				)
				( attribute "SEC_TYPE" "0402"
					( Origin gFrontEnd )
				)
				( attribute "TOLERANCE" "1%"
					( Origin gFrontEnd )
				)
				( attribute "VALUE" "49.9"
					( Origin gFrontEnd )
				)
				( attribute "VER" "1"
					( Origin gFrontEnd )
				)
				( attribute "WATTAGE" "1/16W"
					( Origin gFrontEnd )
				)
				( attribute "XY" "(-5150,4450)"
					( Origin gFrontEnd )
				)
				( attribute "CHIPS_PART_NAME" "RES"
					( Origin gPackager )
				)
				( attribute "CDS_PART_NAME" "RES_0402-49.9,1%,1/16W,CHIP,G2A"
					( Origin gPackager )
				)
				( objectStatus "R9B5" )
			)
			( gate "@baseboard_fab2_lib.baseboard_fab2(sch_1):page167_i6"
				( attribute "BOM_COST" "SM_THERM"
					( Origin gFrontEnd )
				)
				( attribute "CDS_LIB" "mstr_discrete"
					( Origin gPackager )
				)
				( attribute "CDS_LOCATION" "R9B4"
					( Origin gPackager )
				)
				( attribute "CDS_SEC" "1"
					( Origin gPackager )
				)
				( attribute "LOCATION" "R9B4"
					( Origin gFrontEnd )
				)
				( attribute "MATERIAL" "CHIP"
					( Origin gFrontEnd )
				)
				( attribute "PACK_TYPE" "0402"
					( Origin gFrontEnd )
				)
				( attribute "PART_NUMBER" "G21796-047"
					( Origin gFrontEnd )
				)
				( attribute "PHYS_PAGE" "167"
					( Origin gFrontEnd )
				)
				( attribute "ROOM" "TEMP_SENSORS"
					( Origin gFrontEnd )
				)
				( attribute "ROT" "0"
					( Origin gFrontEnd )
				)
				( attribute "SEC" "1"
					( Origin gFrontEnd )
				)
				( attribute "SEC_TYPE" "0402"
					( Origin gFrontEnd )
				)
				( attribute "TOLERANCE" "1%"
					( Origin gFrontEnd )
				)
				( attribute "VALUE" "49.9"
					( Origin gFrontEnd )
				)
				( attribute "VER" "1"
					( Origin gFrontEnd )
				)
				( attribute "WATTAGE" "1/16W"
					( Origin gFrontEnd )
				)
				( attribute "XY" "(-5150,4775)"
					( Origin gFrontEnd )
				)
				( attribute "CHIPS_PART_NAME" "RES"
					( Origin gPackager )
				)
				( attribute "CDS_PART_NAME" "RES_0402-49.9,1%,1/16W,CHIP,G2A"
					( Origin gPackager )
				)
				( objectStatus "R9B4" )
			)
			( gate "@baseboard_fab2_lib.baseboard_fab2(sch_1):page167_i7"
				( attribute "BOM_COST" "SM_THERM"
					( Origin gFrontEnd )
				)
				( attribute "CDS_LIB" "mstr_discrete"
					( Origin gPackager )
				)
				( attribute "CDS_LOCATION" "C1M4"
					( Origin gPackager )
				)
				( attribute "CDS_SEC" "1"
					( Origin gPackager )
				)
				( attribute "LOCATION" "C1M4"
					( Origin gFrontEnd )
				)
				( attribute "MATERIAL" "EMPTY"
					( Origin gFrontEnd )
				)
				( attribute "PACK_TYPE" "0402LF"
					( Origin gFrontEnd )
				)
				( attribute "PART_NUMBER" "A36095-025"
					( Origin gFrontEnd )
				)
				( attribute "PHYS_PAGE" "167"
					( Origin gFrontEnd )
				)
				( attribute "ROOM" "TEMP_SENSORS"
					( Origin gFrontEnd )
				)
				( attribute "ROT" "0"
					( Origin gFrontEnd )
				)
				( attribute "SEC" "1"
					( Origin gFrontEnd )
				)
				( attribute "SEC_TYPE" "0402LF"
					( Origin gFrontEnd )
				)
				( attribute "TOLERANCE" "5%"
					( Origin gFrontEnd )
				)
				( attribute "VALUE" "47.0PF"
					( Origin gFrontEnd )
				)
				( attribute "VER" "1"
					( Origin gFrontEnd )
				)
				( attribute "VOLTAGE" "50V"
					( Units "uVoltage" "V" 1.000000)
					( Origin gFrontEnd )
				)
				( attribute "XY" "(-4850,4625)"
					( Origin gFrontEnd )
				)
				( attribute "CHIPS_PART_NAME" "CAP"
					( Origin gPackager )
				)
				( attribute "CDS_PART_NAME" "CAP_0402LF-47.0PF,50V,5%,EMPTYA"
					( Origin gPackager )
				)
				( objectStatus "C1M4" )
			)
			( gate "@baseboard_fab2_lib.baseboard_fab2(sch_1):page167_i8"
				( attribute "BOM_COST" "SM_THERM"
					( Origin gFrontEnd )
				)
				( attribute "CDS_LIB" "mstr_discrete"
					( Origin gPackager )
				)
				( attribute "CDS_LOCATION" "R1M9"
					( Origin gPackager )
				)
				( attribute "CDS_SEC" "1"
					( Origin gPackager )
				)
				( attribute "LOCATION" "R1M9"
					( Origin gFrontEnd )
				)
				( attribute "MATERIAL" "CHIP"
					( Origin gFrontEnd )
				)
				( attribute "PACK_TYPE" "0402"
					( Origin gFrontEnd )
				)
				( attribute "PART_NUMBER" "G21796-173"
					( Origin gFrontEnd )
				)
				( attribute "PHYS_PAGE" "167"
					( Origin gFrontEnd )
				)
				( attribute "ROOM" "TEMP_SENSORS"
					( Origin gFrontEnd )
				)
				( attribute "ROT" "0"
					( Origin gFrontEnd )
				)
				( attribute "SEC" "1"
					( Origin gFrontEnd )
				)
				( attribute "SEC_TYPE" "0402"
					( Origin gFrontEnd )
				)
				( attribute "TOLERANCE" "1%"
					( Origin gFrontEnd )
				)
				( attribute "VALUE" "20.0"
					( Origin gFrontEnd )
				)
				( attribute "VER" "1"
					( Origin gFrontEnd )
				)
				( attribute "WATTAGE" "1/16W"
					( Origin gFrontEnd )
				)
				( attribute "XY" "(-2950,4500)"
					( Origin gFrontEnd )
				)
				( attribute "CHIPS_PART_NAME" "RES"
					( Origin gPackager )
				)
				( attribute "CDS_PART_NAME" "RES_0402-20.0,1%,1/16W,CHIP,G2A"
					( Origin gPackager )
				)
				( objectStatus "R1M9" )
			)
			( gate "@baseboard_fab2_lib.baseboard_fab2(sch_1):page167_i10"
				( attribute "BOM_COST" "SM_THERM"
					( Origin gFrontEnd )
				)
				( attribute "CDS_LIB" "mstr_discrete"
					( Origin gPackager )
				)
				( attribute "CDS_LOCATION" "R9B8"
					( Origin gPackager )
				)
				( attribute "CDS_SEC" "1"
					( Origin gPackager )
				)
				( attribute "LOCATION" "R9B8"
					( Origin gFrontEnd )
				)
				( attribute "MATERIAL" "CHIP"
					( Origin gFrontEnd )
				)
				( attribute "PACK_TYPE" "0402"
					( Origin gFrontEnd )
				)
				( attribute "PART_NUMBER" "G21796-026"
					( Origin gFrontEnd )
				)
				( attribute "PHYS_PAGE" "167"
					( Origin gFrontEnd )
				)
				( attribute "ROOM" "TEMP_SENSORS"
					( Origin gFrontEnd )
				)
				( attribute "ROT" "0"
					( Origin gFrontEnd )
				)
				( attribute "SEC" "1"
					( Origin gFrontEnd )
				)
				( attribute "SEC_TYPE" "0402"
					( Origin gFrontEnd )
				)
				( attribute "TOLERANCE" "1%"
					( Origin gFrontEnd )
				)
				( attribute "VALUE" "1.00K"
					( Origin gFrontEnd )
				)
				( attribute "VER" "2"
					( Origin gFrontEnd )
				)
				( attribute "WATTAGE" "1/16W"
					( Origin gFrontEnd )
				)
				( attribute "XY" "(-4775,4075)"
					( Origin gFrontEnd )
				)
				( attribute "CHIPS_PART_NAME" "RES"
					( Origin gPackager )
				)
				( attribute "CDS_PART_NAME" "RES_0402-1.00K,1%,1/16W,CHIP,GA"
					( Origin gPackager )
				)
				( objectStatus "R9B8" )
			)
			( gate "@baseboard_fab2_lib.baseboard_fab2(sch_1):page167_i24"
				( attribute "BOM_COST" "SM_THERM"
					( Origin gFrontEnd )
				)
				( attribute "CDS_LIB" "mstr_discrete"
					( Origin gPackager )
				)
				( attribute "CDS_LOCATION" "C1E19"
					( Origin gPackager )
				)
				( attribute "CDS_SEC" "1"
					( Origin gPackager )
				)
				( attribute "LOCATION" "C1E19"
					( Origin gFrontEnd )
				)
				( attribute "MATERIAL" "EMPTY"
					( Origin gFrontEnd )
				)
				( attribute "PACK_TYPE" "0402LF"
					( Origin gFrontEnd )
				)
				( attribute "PART_NUMBER" "A36095-025"
					( Origin gFrontEnd )
				)
				( attribute "PHYS_PAGE" "167"
					( Origin gFrontEnd )
				)
				( attribute "ROOM" "TEMP_SENSORS"
					( Origin gFrontEnd )
				)
				( attribute "ROT" "0"
					( Origin gFrontEnd )
				)
				( attribute "SEC" "1"
					( Origin gFrontEnd )
				)
				( attribute "SEC_TYPE" "0402LF"
					( Origin gFrontEnd )
				)
				( attribute "TOLERANCE" "5%"
					( Origin gFrontEnd )
				)
				( attribute "VALUE" "47.0PF"
					( Origin gFrontEnd )
				)
				( attribute "VER" "1"
					( Origin gFrontEnd )
				)
				( attribute "VOLTAGE" "50V"
					( Units "uVoltage" "V" 1.000000)
					( Origin gFrontEnd )
				)
				( attribute "XY" "(-4675,3175)"
					( Origin gFrontEnd )
				)
				( attribute "CHIPS_PART_NAME" "CAP"
					( Origin gPackager )
				)
				( attribute "CDS_PART_NAME" "CAP_0402LF-47.0PF,50V,5%,EMPTYA"
					( Origin gPackager )
				)
				( objectStatus "C1E19" )
			)
			( gate "@baseboard_fab2_lib.baseboard_fab2(sch_1):page167_i25"
				( attribute "BOM_COST" "SM_THERM"
					( Origin gFrontEnd )
				)
				( attribute "CDS_LIB" "mstr_discrete"
					( Origin gPackager )
				)
				( attribute "CDS_LOCATION" "R9R5"
					( Origin gPackager )
				)
				( attribute "CDS_SEC" "1"
					( Origin gPackager )
				)
				( attribute "LOCATION" "R9R5"
					( Origin gFrontEnd )
				)
				( attribute "MATERIAL" "CHIP"
					( Origin gFrontEnd )
				)
				( attribute "PACK_TYPE" "0402"
					( Origin gFrontEnd )
				)
				( attribute "PART_NUMBER" "G21796-047"
					( Origin gFrontEnd )
				)
				( attribute "PHYS_PAGE" "167"
					( Origin gFrontEnd )
				)
				( attribute "ROOM" "TEMP_SENSORS"
					( Origin gFrontEnd )
				)
				( attribute "ROT" "0"
					( Origin gFrontEnd )
				)
				( attribute "SEC" "1"
					( Origin gFrontEnd )
				)
				( attribute "SEC_TYPE" "0402"
					( Origin gFrontEnd )
				)
				( attribute "TOLERANCE" "1%"
					( Origin gFrontEnd )
				)
				( attribute "VALUE" "49.9"
					( Origin gFrontEnd )
				)
				( attribute "VER" "1"
					( Origin gFrontEnd )
				)
				( attribute "WATTAGE" "1/16W"
					( Origin gFrontEnd )
				)
				( attribute "XY" "(-5000,3325)"
					( Origin gFrontEnd )
				)
				( attribute "CHIPS_PART_NAME" "RES"
					( Origin gPackager )
				)
				( attribute "CDS_PART_NAME" "RES_0402-49.9,1%,1/16W,CHIP,G2A"
					( Origin gPackager )
				)
				( objectStatus "R9R5" )
			)
			( gate "@baseboard_fab2_lib.baseboard_fab2(sch_1):page167_i26"
				( attribute "BOM_COST" "SM_THERM"
					( Origin gFrontEnd )
				)
				( attribute "CDS_LIB" "mstr_discrete"
					( Origin gPackager )
				)
				( attribute "CDS_LOCATION" "R9R6"
					( Origin gPackager )
				)
				( attribute "CDS_SEC" "1"
					( Origin gPackager )
				)
				( attribute "LOCATION" "R9R6"
					( Origin gFrontEnd )
				)
				( attribute "MATERIAL" "CHIP"
					( Origin gFrontEnd )
				)
				( attribute "PACK_TYPE" "0402"
					( Origin gFrontEnd )
				)
				( attribute "PART_NUMBER" "G21796-047"
					( Origin gFrontEnd )
				)
				( attribute "PHYS_PAGE" "167"
					( Origin gFrontEnd )
				)
				( attribute "ROOM" "TEMP_SENSORS"
					( Origin gFrontEnd )
				)
				( attribute "ROT" "0"
					( Origin gFrontEnd )
				)
				( attribute "SEC" "1"
					( Origin gFrontEnd )
				)
				( attribute "SEC_TYPE" "0402"
					( Origin gFrontEnd )
				)
				( attribute "TOLERANCE" "1%"
					( Origin gFrontEnd )
				)
				( attribute "VALUE" "49.9"
					( Origin gFrontEnd )
				)
				( attribute "VER" "1"
					( Origin gFrontEnd )
				)
				( attribute "WATTAGE" "1/16W"
					( Origin gFrontEnd )
				)
				( attribute "XY" "(-4975,3000)"
					( Origin gFrontEnd )
				)
				( attribute "CHIPS_PART_NAME" "RES"
					( Origin gPackager )
				)
				( attribute "CDS_PART_NAME" "RES_0402-49.9,1%,1/16W,CHIP,G2A"
					( Origin gPackager )
				)
				( objectStatus "R9R6" )
			)
			( gate "@baseboard_fab2_lib.baseboard_fab2(sch_1):page167_i30"
				( attribute "BOM_COST" "SM_THERM"
					( Origin gFrontEnd )
				)
				( attribute "CDS_LIB" "mstr_analog"
					( Origin gPackager )
				)
				( attribute "CDS_LOCATION" "U1E1"
					( Origin gPackager )
				)
				( attribute "CDS_SEC" "1"
					( Origin gPackager )
				)
				( attribute "LOCATION" "U1E1"
					( Origin gFrontEnd )
				)
				( attribute "MATERIAL" "IC"
					( Origin gFrontEnd )
				)
				( attribute "PACK_TYPE" "TSSOP"
					( Origin gFrontEnd )
				)
				( attribute "PART_NUMBER" "G62962-001"
					( Origin gFrontEnd )
				)
				( attribute "PHYS_PAGE" "167"
					( Origin gFrontEnd )
				)
				( attribute "ROOM" "TEMP_SENSORS"
					( Origin gFrontEnd )
				)
				( attribute "ROT" "0"
					( Origin gFrontEnd )
				)
				( attribute "SEC" "1"
					( Origin gFrontEnd )
				)
				( attribute "SEC_TYPE" "TSSOP"
					( Origin gFrontEnd )
				)
				( attribute "VER" "1"
					( Origin gFrontEnd )
				)
				( attribute "XY" "(-3825,3000)"
					( Origin gFrontEnd )
				)
				( attribute "CHIPS_PART_NAME" "TMP421"
					( Origin gPackager )
				)
				( attribute "CDS_PART_NAME" "TMP421_TSSOP-IC,G62962-001"
					( Origin gPackager )
				)
				( objectStatus "U1E1" )
			)
			( gate "@baseboard_fab2_lib.baseboard_fab2(sch_1):page167_i34"
				( attribute "BOM_COST" "SM_THERM"
					( Origin gFrontEnd )
				)
				( attribute "CDS_LIB" "mstr_discrete"
					( Origin gPackager )
				)
				( attribute "CDS_LOCATION" "R1E9"
					( Origin gPackager )
				)
				( attribute "CDS_SEC" "1"
					( Origin gPackager )
				)
				( attribute "LOCATION" "R1E9"
					( Origin gFrontEnd )
				)
				( attribute "MATERIAL" "CHIP"
					( Origin gFrontEnd )
				)
				( attribute "PACK_TYPE" "0402"
					( Origin gFrontEnd )
				)
				( attribute "PART_NUMBER" "G21796-026"
					( Origin gFrontEnd )
				)
				( attribute "PHYS_PAGE" "167"
					( Origin gFrontEnd )
				)
				( attribute "ROOM" "TEMP_SENSORS"
					( Origin gFrontEnd )
				)
				( attribute "ROT" "0"
					( Origin gFrontEnd )
				)
				( attribute "SEC" "1"
					( Origin gFrontEnd )
				)
				( attribute "SEC_TYPE" "0402"
					( Origin gFrontEnd )
				)
				( attribute "TOLERANCE" "1%"
					( Origin gFrontEnd )
				)
				( attribute "VALUE" "1.00K"
					( Origin gFrontEnd )
				)
				( attribute "VER" "1"
					( Origin gFrontEnd )
				)
				( attribute "WATTAGE" "1/16W"
					( Origin gFrontEnd )
				)
				( attribute "XY" "(-5050,2850)"
					( Origin gFrontEnd )
				)
				( attribute "CHIPS_PART_NAME" "RES"
					( Origin gPackager )
				)
				( attribute "CDS_PART_NAME" "RES_0402-1.00K,1%,1/16W,CHIP,GA"
					( Origin gPackager )
				)
				( objectStatus "R1E9" )
			)
			( gate "@baseboard_fab2_lib.baseboard_fab2(sch_1):page167_i35"
				( attribute "BOM_COST" "SM_THERM"
					( Origin gFrontEnd )
				)
				( attribute "CDS_LIB" "mstr_discrete"
					( Origin gPackager )
				)
				( attribute "CDS_LOCATION" "R9B6"
					( Origin gPackager )
				)
				( attribute "CDS_SEC" "1"
					( Origin gPackager )
				)
				( attribute "LOCATION" "R9B6"
					( Origin gFrontEnd )
				)
				( attribute "MATERIAL" "CHIP"
					( Origin gFrontEnd )
				)
				( attribute "PACK_TYPE" "0402"
					( Origin gFrontEnd )
				)
				( attribute "PART_NUMBER" "G21796-026"
					( Origin gFrontEnd )
				)
				( attribute "PHYS_PAGE" "167"
					( Origin gFrontEnd )
				)
				( attribute "ROOM" "TEMP_SENSORS"
					( Origin gFrontEnd )
				)
				( attribute "ROT" "0"
					( Origin gFrontEnd )
				)
				( attribute "SEC" "1"
					( Origin gFrontEnd )
				)
				( attribute "SEC_TYPE" "0402"
					( Origin gFrontEnd )
				)
				( attribute "TOLERANCE" "1%"
					( Origin gFrontEnd )
				)
				( attribute "VALUE" "1.00K"
					( Origin gFrontEnd )
				)
				( attribute "VER" "1"
					( Origin gFrontEnd )
				)
				( attribute "WATTAGE" "1/16W"
					( Origin gFrontEnd )
				)
				( attribute "XY" "(-5475,4150)"
					( Origin gFrontEnd )
				)
				( attribute "CHIPS_PART_NAME" "RES"
					( Origin gPackager )
				)
				( attribute "CDS_PART_NAME" "RES_0402-1.00K,1%,1/16W,CHIP,GA"
					( Origin gPackager )
				)
				( objectStatus "R9B6" )
			)
			( gate "@baseboard_fab2_lib.baseboard_fab2(sch_1):page167_i38"
				( attribute "BOM_COST" "SM_THERM"
					( Origin gFrontEnd )
				)
				( attribute "CDS_LIB" "mstr_discrete"
					( Origin gPackager )
				)
				( attribute "CDS_LOCATION" "R1E10"
					( Origin gPackager )
				)
				( attribute "CDS_SEC" "1"
					( Origin gPackager )
				)
				( attribute "LOCATION" "R1E10"
					( Origin gFrontEnd )
				)
				( attribute "MATERIAL" "CHIP"
					( Origin gFrontEnd )
				)
				( attribute "PACK_TYPE" "0402"
					( Origin gFrontEnd )
				)
				( attribute "PART_NUMBER" "G21796-026"
					( Origin gFrontEnd )
				)
				( attribute "PHYS_PAGE" "167"
					( Origin gFrontEnd )
				)
				( attribute "ROOM" "TEMP_SENSORS"
					( Origin gFrontEnd )
				)
				( attribute "ROT" "0"
					( Origin gFrontEnd )
				)
				( attribute "SEC" "1"
					( Origin gFrontEnd )
				)
				( attribute "SEC_TYPE" "0402"
					( Origin gFrontEnd )
				)
				( attribute "TOLERANCE" "1%"
					( Origin gFrontEnd )
				)
				( attribute "VALUE" "1.00K"
					( Origin gFrontEnd )
				)
				( attribute "VER" "1"
					( Origin gFrontEnd )
				)
				( attribute "WATTAGE" "1/16W"
					( Origin gFrontEnd )
				)
				( attribute "XY" "(-4650,2900)"
					( Origin gFrontEnd )
				)
				( attribute "CHIPS_PART_NAME" "RES"
					( Origin gPackager )
				)
				( attribute "CDS_PART_NAME" "RES_0402-1.00K,1%,1/16W,CHIP,GA"
					( Origin gPackager )
				)
				( objectStatus "R1E10" )
			)
			( gate "@baseboard_fab2_lib.baseboard_fab2(sch_1):page167_i39"
				( attribute "BOM_COST" "SM_THERM"
					( Origin gFrontEnd )
				)
				( attribute "CDS_LIB" "dev_discrete"
					( Origin gPackager )
				)
				( attribute "CDS_LOCATION" "C9B7"
					( Origin gPackager )
				)
				( attribute "CDS_SEC" "1"
					( Origin gPackager )
				)
				( attribute "LOCATION" "C9B7"
					( Origin gFrontEnd )
				)
				( attribute "MATERIAL" "X7R"
					( Origin gFrontEnd )
				)
				( attribute "PACK_TYPE" "0402V"
					( Origin gFrontEnd )
				)
				( attribute "PART_NUMBER" "A36096-030"
					( Origin gFrontEnd )
				)
				( attribute "PHYS_PAGE" "167"
					( Origin gFrontEnd )
				)
				( attribute "ROOM" "TEMP_SENSORS"
					( Origin gFrontEnd )
				)
				( attribute "ROT" "0"
					( Origin gFrontEnd )
				)
				( attribute "SEC" "1"
					( Origin gFrontEnd )
				)
				( attribute "SEC_TYPE" "0402V"
					( Origin gFrontEnd )
				)
				( attribute "TOLERANCE" "10%"
					( Origin gFrontEnd )
				)
				( attribute "VALUE" "0.1UF"
					( Origin gFrontEnd )
				)
				( attribute "VER" "1"
					( Origin gFrontEnd )
				)
				( attribute "VOLTAGE" "16V"
					( Units "uVoltage" "V" 1.000000)
					( Origin gFrontEnd )
				)
				( attribute "XY" "(-7700,4350)"
					( Origin gFrontEnd )
				)
				( attribute "CHIPS_PART_NAME" "CAP_A"
					( Origin gPackager )
				)
				( attribute "CDS_PART_NAME" "CAP_A_0402V-0.1UF,16V,10%,X7R,A"
					( Origin gPackager )
				)
				( objectStatus "C9B7" )
			)
			( gate "@baseboard_fab2_lib.baseboard_fab2(sch_1):page167_i41"
				( attribute "BOM_COST" "SM_THERM"
					( Origin gFrontEnd )
				)
				( attribute "CDS_LIB" "dev_discrete"
					( Origin gPackager )
				)
				( attribute "CDS_LOCATION" "C9R14"
					( Origin gPackager )
				)
				( attribute "CDS_SEC" "1"
					( Origin gPackager )
				)
				( attribute "LOCATION" "C9R14"
					( Origin gFrontEnd )
				)
				( attribute "MATERIAL" "X7R"
					( Origin gFrontEnd )
				)
				( attribute "PACK_TYPE" "0402V"
					( Origin gFrontEnd )
				)
				( attribute "PART_NUMBER" "A36096-030"
					( Origin gFrontEnd )
				)
				( attribute "PHYS_PAGE" "167"
					( Origin gFrontEnd )
				)
				( attribute "ROOM" "TEMP_SENSORS"
					( Origin gFrontEnd )
				)
				( attribute "ROT" "0"
					( Origin gFrontEnd )
				)
				( attribute "SEC" "1"
					( Origin gFrontEnd )
				)
				( attribute "SEC_TYPE" "0402V"
					( Origin gFrontEnd )
				)
				( attribute "TOLERANCE" "10%"
					( Origin gFrontEnd )
				)
				( attribute "VALUE" "0.1UF"
					( Origin gFrontEnd )
				)
				( attribute "VER" "1"
					( Origin gFrontEnd )
				)
				( attribute "VOLTAGE" "16V"
					( Units "uVoltage" "V" 1.000000)
					( Origin gFrontEnd )
				)
				( attribute "XY" "(-7700,3675)"
					( Origin gFrontEnd )
				)
				( attribute "CHIPS_PART_NAME" "CAP_A"
					( Origin gPackager )
				)
				( attribute "CDS_PART_NAME" "CAP_A_0402V-0.1UF,16V,10%,X7R,A"
					( Origin gPackager )
				)
				( objectStatus "C9R14" )
			)
			( gate "@baseboard_fab2_lib.baseboard_fab2(sch_1):page167_i42"
				( attribute "BOM_COST" "SM_THERM"
					( Origin gFrontEnd )
				)
				( attribute "CDS_LIB" "dev_discrete"
					( Origin gPackager )
				)
				( attribute "CDS_LOCATION" "C9R13"
					( Origin gPackager )
				)
				( attribute "CDS_SEC" "1"
					( Origin gPackager )
				)
				( attribute "LOCATION" "C9R13"
					( Origin gFrontEnd )
				)
				( attribute "MATERIAL" "X7R"
					( Origin gFrontEnd )
				)
				( attribute "PACK_TYPE" "0402V"
					( Origin gFrontEnd )
				)
				( attribute "PART_NUMBER" "A36096-030"
					( Origin gFrontEnd )
				)
				( attribute "PHYS_PAGE" "167"
					( Origin gFrontEnd )
				)
				( attribute "ROOM" "TEMP_SENSORS"
					( Origin gFrontEnd )
				)
				( attribute "ROT" "0"
					( Origin gFrontEnd )
				)
				( attribute "SEC" "1"
					( Origin gFrontEnd )
				)
				( attribute "SEC_TYPE" "0402V"
					( Origin gFrontEnd )
				)
				( attribute "TOLERANCE" "10%"
					( Origin gFrontEnd )
				)
				( attribute "VALUE" "0.1UF"
					( Origin gFrontEnd )
				)
				( attribute "VER" "1"
					( Origin gFrontEnd )
				)
				( attribute "VOLTAGE" "16V"
					( Units "uVoltage" "V" 1.000000)
					( Origin gFrontEnd )
				)
				( attribute "XY" "(-1425,2150)"
					( Origin gFrontEnd )
				)
				( attribute "CHIPS_PART_NAME" "CAP_A"
					( Origin gPackager )
				)
				( attribute "CDS_PART_NAME" "CAP_A_0402V-0.1UF,16V,10%,X7R,A"
					( Origin gPackager )
				)
				( objectStatus "C9R13" )
			)
			( gate "@baseboard_fab2_lib.baseboard_fab2(sch_1):page167_i49"
				( attribute "BOM_COST" "SM_THERM"
					( Origin gFrontEnd )
				)
				( attribute "CDS_LIB" "mstr_memory"
					( Origin gPackager )
				)
				( attribute "CDS_LOCATION" "U8D4"
					( Origin gPackager )
				)
				( attribute "CDS_SEC" "1"
					( Origin gPackager )
				)
				( attribute "LOCATION" "U8D4"
					( Origin gFrontEnd )
				)
				( attribute "MATERIAL" "IC"
					( Origin gFrontEnd )
				)
				( attribute "PACK_TYPE" "SOICLF"
					( Origin gFrontEnd )
				)
				( attribute "PART_NUMBER" "C47049-001"
					( Origin gFrontEnd )
				)
				( attribute "PHYS_PAGE" "167"
					( Origin gFrontEnd )
				)
				( attribute "ROOM" "TEMP_SENSORS"
					( Origin gFrontEnd )
				)
				( attribute "ROT" "0"
					( Origin gFrontEnd )
				)
				( attribute "SEC" "1"
					( Origin gFrontEnd )
				)
				( attribute "SEC_TYPE" "SOICLF"
					( Origin gFrontEnd )
				)
				( attribute "VER" "1"
					( Origin gFrontEnd )
				)
				( attribute "XY" "(-2700,1650)"
					( Origin gFrontEnd )
				)
				( attribute "CHIPS_PART_NAME" "AT24C64"
					( Origin gPackager )
				)
				( attribute "CDS_PART_NAME" "AT24C64_SOICLF-IC,C47049-001-VA"
					( Origin gPackager )
				)
				( objectStatus "U8D4" )
			)
			( gate "@baseboard_fab2_lib.baseboard_fab2(sch_1):page167_i50"
				( attribute "BOM_COST" "SM_THERM"
					( Origin gFrontEnd )
				)
				( attribute "CDS_LIB" "mstr_discrete"
					( Origin gPackager )
				)
				( attribute "CDS_LOCATION" "R8D27"
					( Origin gPackager )
				)
				( attribute "CDS_SEC" "1"
					( Origin gPackager )
				)
				( attribute "LOCATION" "R8D27"
					( Origin gFrontEnd )
				)
				( attribute "MATERIAL" "CHIP"
					( Origin gFrontEnd )
				)
				( attribute "PACK_TYPE" "0402"
					( Origin gFrontEnd )
				)
				( attribute "PART_NUMBER" "G21796-026"
					( Origin gFrontEnd )
				)
				( attribute "PHYS_PAGE" "167"
					( Origin gFrontEnd )
				)
				( attribute "ROOM" "TEMP_SENSORS"
					( Origin gFrontEnd )
				)
				( attribute "ROT" "0"
					( Origin gFrontEnd )
				)
				( attribute "SEC" "1"
					( Origin gFrontEnd )
				)
				( attribute "SEC_TYPE" "0402"
					( Origin gFrontEnd )
				)
				( attribute "TOLERANCE" "1%"
					( Origin gFrontEnd )
				)
				( attribute "VALUE" "1.00K"
					( Origin gFrontEnd )
				)
				( attribute "VER" "2"
					( Origin gFrontEnd )
				)
				( attribute "WATTAGE" "1/16W"
					( Origin gFrontEnd )
				)
				( attribute "XY" "(-3500,1300)"
					( Origin gFrontEnd )
				)
				( attribute "CHIPS_PART_NAME" "RES"
					( Origin gPackager )
				)
				( attribute "CDS_PART_NAME" "RES_0402-1.00K,1%,1/16W,CHIP,GA"
					( Origin gPackager )
				)
				( objectStatus "R8D27" )
			)
			( gate "@baseboard_fab2_lib.baseboard_fab2(sch_1):page167_i58"
				( attribute "BOM_COST" "SM_CONTROLLER"
					( Origin gFrontEnd )
				)
				( attribute "CDS_LIB" "mstr_discrete"
					( Origin gPackager )
				)
				( attribute "CDS_LOCATION" "R9G15"
					( Origin gPackager )
				)
				( attribute "CDS_SEC" "1"
					( Origin gPackager )
				)
				( attribute "LOCATION" "R9G15"
					( Origin gFrontEnd )
				)
				( attribute "MATERIAL" "CHIP"
					( Origin gFrontEnd )
				)
				( attribute "PACK_TYPE" "0402"
					( Origin gFrontEnd )
				)
				( attribute "PART_NUMBER" "G21796-173"
					( Origin gFrontEnd )
				)
				( attribute "PHYS_PAGE" "167"
					( Origin gFrontEnd )
				)
				( attribute "ROOM" "SMBUS"
					( Origin gFrontEnd )
				)
				( attribute "ROT" "0"
					( Origin gFrontEnd )
				)
				( attribute "SEC" "1"
					( Origin gPackager )
				)
				( attribute "SKU" "B"
					( Origin gFrontEnd )
				)
				( attribute "TOLERANCE" "1%"
					( Origin gFrontEnd )
				)
				( attribute "VALUE" "20.0"
					( Origin gFrontEnd )
				)
				( attribute "VER" "1"
					( Origin gFrontEnd )
				)
				( attribute "WATTAGE" "1/16W"
					( Origin gFrontEnd )
				)
				( attribute "XY" "(-6725,1450)"
					( Origin gFrontEnd )
				)
				( attribute "CHIPS_PART_NAME" "RES"
					( Origin gPackager )
				)
				( attribute "CDS_PART_NAME" "RES_0402-20.0,1%,1/16W,CHIP,G2A"
					( Origin gPackager )
				)
				( objectStatus "R9G15" )
			)
			( gate "@baseboard_fab2_lib.baseboard_fab2(sch_1):page167_i70"
				( attribute "BOM_COST" "SM_THERM"
					( Origin gFrontEnd )
				)
				( attribute "CDS_LIB" "mstr_discrete"
					( Origin gPackager )
				)
				( attribute "CDS_LOCATION" "R8D28"
					( Origin gPackager )
				)
				( attribute "CDS_SEC" "1"
					( Origin gPackager )
				)
				( attribute "LOCATION" "R8D28"
					( Origin gFrontEnd )
				)
				( attribute "MATERIAL" "CHIP"
					( Origin gFrontEnd )
				)
				( attribute "PACK_TYPE" "0402"
					( Origin gFrontEnd )
				)
				( attribute "PART_NUMBER" "G21796-026"
					( Origin gFrontEnd )
				)
				( attribute "PHYS_PAGE" "167"
					( Origin gFrontEnd )
				)
				( attribute "ROOM" "TEMP_SENSORS"
					( Origin gFrontEnd )
				)
				( attribute "ROT" "0"
					( Origin gFrontEnd )
				)
				( attribute "SEC" "1"
					( Origin gFrontEnd )
				)
				( attribute "SEC_TYPE" "0402"
					( Origin gFrontEnd )
				)
				( attribute "TOLERANCE" "1%"
					( Origin gFrontEnd )
				)
				( attribute "VALUE" "1.00K"
					( Origin gFrontEnd )
				)
				( attribute "VER" "2"
					( Origin gFrontEnd )
				)
				( attribute "WATTAGE" "1/16W"
					( Origin gFrontEnd )
				)
				( attribute "XY" "(-3550,1975)"
					( Origin gFrontEnd )
				)
				( attribute "CHIPS_PART_NAME" "RES"
					( Origin gPackager )
				)
				( attribute "CDS_PART_NAME" "RES_0402-1.00K,1%,1/16W,CHIP,GA"
					( Origin gPackager )
				)
				( objectStatus "R8D28" )
			)
			( gate "@baseboard_fab2_lib.baseboard_fab2(sch_1):page167_i74"
				( attribute "BOM_COST" "SM_THERM"
					( Origin gFrontEnd )
				)
				( attribute "CDS_LIB" "mstr_discrete"
					( Origin gPackager )
				)
				( attribute "CDS_LOCATION" "R1M8"
					( Origin gPackager )
				)
				( attribute "CDS_SEC" "1"
					( Origin gPackager )
				)
				( attribute "LOCATION" "R1M8"
					( Origin gFrontEnd )
				)
				( attribute "MATERIAL" "CHIP"
					( Origin gFrontEnd )
				)
				( attribute "PACK_TYPE" "0402"
					( Origin gFrontEnd )
				)
				( attribute "PART_NUMBER" "G21796-173"
					( Origin gFrontEnd )
				)
				( attribute "PHYS_PAGE" "167"
					( Origin gFrontEnd )
				)
				( attribute "ROOM" "TEMP_SENSORS"
					( Origin gFrontEnd )
				)
				( attribute "ROT" "0"
					( Origin gFrontEnd )
				)
				( attribute "SEC" "1"
					( Origin gFrontEnd )
				)
				( attribute "SEC_TYPE" "0402"
					( Origin gFrontEnd )
				)
				( attribute "TOLERANCE" "1%"
					( Origin gFrontEnd )
				)
				( attribute "VALUE" "20.0"
					( Origin gFrontEnd )
				)
				( attribute "VER" "1"
					( Origin gFrontEnd )
				)
				( attribute "WATTAGE" "1/16W"
					( Origin gFrontEnd )
				)
				( attribute "XY" "(-2650,4450)"
					( Origin gFrontEnd )
				)
				( attribute "CHIPS_PART_NAME" "RES"
					( Origin gPackager )
				)
				( attribute "CDS_PART_NAME" "RES_0402-20.0,1%,1/16W,CHIP,G2A"
					( Origin gPackager )
				)
				( objectStatus "R1M8" )
			)
			( gate "@baseboard_fab2_lib.baseboard_fab2(sch_1):page167_i75"
				( attribute "BOM_COST" "SM_THERM"
					( Origin gFrontEnd )
				)
				( attribute "CDS_LIB" "mstr_discrete"
					( Origin gPackager )
				)
				( attribute "CDS_LOCATION" "R9R7"
					( Origin gPackager )
				)
				( attribute "CDS_SEC" "1"
					( Origin gPackager )
				)
				( attribute "LOCATION" "R9R7"
					( Origin gFrontEnd )
				)
				( attribute "MATERIAL" "CHIP"
					( Origin gFrontEnd )
				)
				( attribute "PACK_TYPE" "0402"
					( Origin gFrontEnd )
				)
				( attribute "PART_NUMBER" "G21796-173"
					( Origin gFrontEnd )
				)
				( attribute "PHYS_PAGE" "167"
					( Origin gFrontEnd )
				)
				( attribute "ROOM" "TEMP_SENSORS"
					( Origin gFrontEnd )
				)
				( attribute "ROT" "0"
					( Origin gFrontEnd )
				)
				( attribute "SEC" "1"
					( Origin gFrontEnd )
				)
				( attribute "SEC_TYPE" "0402"
					( Origin gFrontEnd )
				)
				( attribute "TOLERANCE" "1%"
					( Origin gFrontEnd )
				)
				( attribute "VALUE" "20.0"
					( Origin gFrontEnd )
				)
				( attribute "VER" "1"
					( Origin gFrontEnd )
				)
				( attribute "WATTAGE" "1/16W"
					( Origin gFrontEnd )
				)
				( attribute "XY" "(-2300,3000)"
					( Origin gFrontEnd )
				)
				( attribute "CHIPS_PART_NAME" "RES"
					( Origin gPackager )
				)
				( attribute "CDS_PART_NAME" "RES_0402-20.0,1%,1/16W,CHIP,G2A"
					( Origin gPackager )
				)
				( objectStatus "R9R7" )
			)
			( gate "@baseboard_fab2_lib.baseboard_fab2(sch_1):page167_i76"
				( attribute "BOM_COST" "SM_THERM"
					( Origin gFrontEnd )
				)
				( attribute "CDS_LIB" "mstr_discrete"
					( Origin gPackager )
				)
				( attribute "CDS_LOCATION" "R9R8"
					( Origin gPackager )
				)
				( attribute "CDS_SEC" "1"
					( Origin gPackager )
				)
				( attribute "LOCATION" "R9R8"
					( Origin gFrontEnd )
				)
				( attribute "MATERIAL" "CHIP"
					( Origin gFrontEnd )
				)
				( attribute "PACK_TYPE" "0402"
					( Origin gFrontEnd )
				)
				( attribute "PART_NUMBER" "G21796-173"
					( Origin gFrontEnd )
				)
				( attribute "PHYS_PAGE" "167"
					( Origin gFrontEnd )
				)
				( attribute "ROOM" "TEMP_SENSORS"
					( Origin gFrontEnd )
				)
				( attribute "ROT" "0"
					( Origin gFrontEnd )
				)
				( attribute "SEC" "1"
					( Origin gFrontEnd )
				)
				( attribute "SEC_TYPE" "0402"
					( Origin gFrontEnd )
				)
				( attribute "TOLERANCE" "1%"
					( Origin gFrontEnd )
				)
				( attribute "VALUE" "20.0"
					( Origin gFrontEnd )
				)
				( attribute "VER" "1"
					( Origin gFrontEnd )
				)
				( attribute "WATTAGE" "1/16W"
					( Origin gFrontEnd )
				)
				( attribute "XY" "(-2625,3050)"
					( Origin gFrontEnd )
				)
				( attribute "CHIPS_PART_NAME" "RES"
					( Origin gPackager )
				)
				( attribute "CDS_PART_NAME" "RES_0402-20.0,1%,1/16W,CHIP,G2A"
					( Origin gPackager )
				)
				( objectStatus "R9R8" )
			)
			( gate "@baseboard_fab2_lib.baseboard_fab2(sch_1):page167_i77"
				( attribute "BOM_COST" "SM_CONTROLLER"
					( Origin gFrontEnd )
				)
				( attribute "CDS_LIB" "mstr_discrete"
					( Origin gPackager )
				)
				( attribute "CDS_LOCATION" "R9G14"
					( Origin gPackager )
				)
				( attribute "CDS_SEC" "1"
					( Origin gPackager )
				)
				( attribute "LOCATION" "R9G14"
					( Origin gFrontEnd )
				)
				( attribute "MATERIAL" "CHIP"
					( Origin gFrontEnd )
				)
				( attribute "PACK_TYPE" "0402"
					( Origin gFrontEnd )
				)
				( attribute "PART_NUMBER" "G21796-173"
					( Origin gFrontEnd )
				)
				( attribute "PHYS_PAGE" "167"
					( Origin gFrontEnd )
				)
				( attribute "ROOM" "SMBUS"
					( Origin gFrontEnd )
				)
				( attribute "ROT" "0"
					( Origin gFrontEnd )
				)
				( attribute "SEC" "1"
					( Origin gPackager )
				)
				( attribute "SKU" "B"
					( Origin gFrontEnd )
				)
				( attribute "TOLERANCE" "1%"
					( Origin gFrontEnd )
				)
				( attribute "VALUE" "20.0"
					( Origin gFrontEnd )
				)
				( attribute "VER" "1"
					( Origin gFrontEnd )
				)
				( attribute "WATTAGE" "1/16W"
					( Origin gFrontEnd )
				)
				( attribute "XY" "(-6725,1325)"
					( Origin gFrontEnd )
				)
				( attribute "CHIPS_PART_NAME" "RES"
					( Origin gPackager )
				)
				( attribute "CDS_PART_NAME" "RES_0402-20.0,1%,1/16W,CHIP,G2A"
					( Origin gPackager )
				)
				( objectStatus "R9G14" )
			)
			( gate "@baseboard_fab2_lib.baseboard_fab2(sch_1):page167_i80"
				( attribute "BOM_COST" "SM_CONTROLLER"
					( Origin gFrontEnd )
				)
				( attribute "CDS_LIB" "mstr_discrete"
					( Origin gPackager )
				)
				( attribute "CDS_LOCATION" "R2U38"
					( Origin gPackager )
				)
				( attribute "CDS_SEC" "1"
					( Origin gPackager )
				)
				( attribute "LOCATION" "R2U38"
					( Origin gFrontEnd )
				)
				( attribute "MATERIAL" "CHIP"
					( Origin gFrontEnd )
				)
				( attribute "PACK_TYPE" "0402"
					( Origin gFrontEnd )
				)
				( attribute "PART_NUMBER" "G21796-235"
					( Origin gFrontEnd )
				)
				( attribute "PHYS_PAGE" "167"
					( Origin gFrontEnd )
				)
				( attribute "ROOM" "SMBUS"
					( Origin gFrontEnd )
				)
				( attribute "ROT" "0"
					( Origin gFrontEnd )
				)
				( attribute "SEC" "1"
					( Origin gFrontEnd )
				)
				( attribute "SEC_TYPE" "0402"
					( Origin gFrontEnd )
				)
				( attribute "TOLERANCE" "1.0%"
					( Origin gFrontEnd )
				)
				( attribute "VALUE" "665"
					( Origin gFrontEnd )
				)
				( attribute "VER" "2"
					( Origin gFrontEnd )
				)
				( attribute "WATTAGE" "1/16W"
					( Origin gFrontEnd )
				)
				( attribute "XY" "(-6075,1950)"
					( Origin gFrontEnd )
				)
				( attribute "CHIPS_PART_NAME" "RES"
					( Origin gPackager )
				)
				( attribute "CDS_PART_NAME" "RES_0402-665,1.0%,1/16W,CHIP,GA"
					( Origin gPackager )
				)
				( objectStatus "R2U38" )
			)
			( gate "@baseboard_fab2_lib.baseboard_fab2(sch_1):page167_i83"
				( attribute "BOM_COST" "SM_CONTROLLER"
					( Origin gFrontEnd )
				)
				( attribute "CDS_LIB" "mstr_discrete"
					( Origin gPackager )
				)
				( attribute "CDS_LOCATION" "R2U39"
					( Origin gPackager )
				)
				( attribute "CDS_SEC" "1"
					( Origin gPackager )
				)
				( attribute "LOCATION" "R2U39"
					( Origin gFrontEnd )
				)
				( attribute "MATERIAL" "CHIP"
					( Origin gFrontEnd )
				)
				( attribute "PACK_TYPE" "0402"
					( Origin gFrontEnd )
				)
				( attribute "PART_NUMBER" "G21796-235"
					( Origin gFrontEnd )
				)
				( attribute "PHYS_PAGE" "167"
					( Origin gFrontEnd )
				)
				( attribute "ROOM" "SMBUS"
					( Origin gFrontEnd )
				)
				( attribute "ROT" "0"
					( Origin gFrontEnd )
				)
				( attribute "SEC" "1"
					( Origin gFrontEnd )
				)
				( attribute "SEC_TYPE" "0402"
					( Origin gFrontEnd )
				)
				( attribute "TOLERANCE" "1.0%"
					( Origin gFrontEnd )
				)
				( attribute "VALUE" "665"
					( Origin gFrontEnd )
				)
				( attribute "VER" "2"
					( Origin gFrontEnd )
				)
				( attribute "WATTAGE" "1/16W"
					( Origin gFrontEnd )
				)
				( attribute "XY" "(-6425,1950)"
					( Origin gFrontEnd )
				)
				( attribute "CHIPS_PART_NAME" "RES"
					( Origin gPackager )
				)
				( attribute "CDS_PART_NAME" "RES_0402-665,1.0%,1/16W,CHIP,GA"
					( Origin gPackager )
				)
				( objectStatus "R2U39" )
			)
			( gate "@baseboard_fab2_lib.baseboard_fab2(sch_1):page167_i84"
				( attribute "BOM_COST" "SM_THERM"
					( Origin gFrontEnd )
				)
				( attribute "CDS_LIB" "mstr_discrete"
					( Origin gPackager )
				)
				( attribute "CDS_LOCATION" "R8D24"
					( Origin gPackager )
				)
				( attribute "CDS_SEC" "1"
					( Origin gPackager )
				)
				( attribute "LOCATION" "R8D24"
					( Origin gFrontEnd )
				)
				( attribute "MATERIAL" "CHIP"
					( Origin gFrontEnd )
				)
				( attribute "PACK_TYPE" "0402"
					( Origin gFrontEnd )
				)
				( attribute "PART_NUMBER" "G21796-173"
					( Origin gFrontEnd )
				)
				( attribute "PHYS_PAGE" "167"
					( Origin gFrontEnd )
				)
				( attribute "ROOM" "TEMP_SENSORS"
					( Origin gFrontEnd )
				)
				( attribute "ROT" "0"
					( Origin gFrontEnd )
				)
				( attribute "SEC" "1"
					( Origin gFrontEnd )
				)
				( attribute "SEC_TYPE" "0402"
					( Origin gFrontEnd )
				)
				( attribute "TOLERANCE" "1%"
					( Origin gFrontEnd )
				)
				( attribute "VALUE" "20.0"
					( Origin gFrontEnd )
				)
				( attribute "VER" "1"
					( Origin gFrontEnd )
				)
				( attribute "WATTAGE" "1/16W"
					( Origin gFrontEnd )
				)
				( attribute "XY" "(-4000,1550)"
					( Origin gFrontEnd )
				)
				( attribute "CHIPS_PART_NAME" "RES"
					( Origin gPackager )
				)
				( attribute "CDS_PART_NAME" "RES_0402-20.0,1%,1/16W,CHIP,G2A"
					( Origin gPackager )
				)
				( objectStatus "R8D24" )
			)
			( gate "@baseboard_fab2_lib.baseboard_fab2(sch_1):page167_i85"
				( attribute "BOM_COST" "SM_THERM"
					( Origin gFrontEnd )
				)
				( attribute "CDS_LIB" "mstr_discrete"
					( Origin gPackager )
				)
				( attribute "CDS_LOCATION" "R8D23"
					( Origin gPackager )
				)
				( attribute "LOCATION" "R8D23"
					( Origin gFrontEnd )
				)
				( attribute "MATERIAL" "CHIP"
					( Origin gFrontEnd )
				)
				( attribute "PACK_TYPE" "0402"
					( Origin gFrontEnd )
				)
				( attribute "PART_NUMBER" "G21796-173"
					( Origin gFrontEnd )
				)
				( attribute "PHYS_PAGE" "167"
					( Origin gFrontEnd )
				)
				( attribute "ROOM" "TEMP_SENSORS"
					( Origin gFrontEnd )
				)
				( attribute "ROT" "0"
					( Origin gFrontEnd )
				)
				( attribute "SEC" "1"
					( Origin gFrontEnd )
				)
				( attribute "TOLERANCE" "1%"
					( Origin gFrontEnd )
				)
				( attribute "VALUE" "20.0"
					( Origin gFrontEnd )
				)
				( attribute "VER" "1"
					( Origin gFrontEnd )
				)
				( attribute "WATTAGE" "1/16W"
					( Origin gFrontEnd )
				)
				( attribute "XY" "(-1475,1550)"
					( Origin gFrontEnd )
				)
				( attribute "CHIPS_PART_NAME" "RES"
					( Origin gPackager )
				)
				( attribute "CDS_PART_NAME" "RES_0402-20.0,1%,1/16W,CHIP,G2A"
					( Origin gPackager )
				)
				( attribute "SEC_TYPE" "0402"
					( Origin gFrontEnd )
				)
				( attribute "CDS_SEC" "1"
					( Origin gPackager )
				)
				( objectStatus "R8D23" )
			)
			( gate "@baseboard_fab2_lib.baseboard_fab2(sch_1):page168_i2"
				( attribute "BOM_COST" "DEBUG"
					( Origin gFrontEnd )
				)
				( attribute "CDS_LIB" "mstr_discrete"
					( Origin gPackager )
				)
				( attribute "CDS_LOCATION" "CR1L1"
					( Origin gPackager )
				)
				( attribute "CDS_SEC" "1"
					( Origin gPackager )
				)
				( attribute "LOCATION" "CR1L1"
					( Origin gFrontEnd )
				)
				( attribute "MATERIAL" "IC"
					( Origin gFrontEnd )
				)
				( attribute "PACK_TYPE" "SM"
					( Origin gFrontEnd )
				)
				( attribute "PART_NUMBER" "D89194-001"
					( Origin gFrontEnd )
				)
				( attribute "PHYS_PAGE" "168"
					( Origin gFrontEnd )
				)
				( attribute "ROOM" "UART_MUX"
					( Origin gFrontEnd )
				)
				( attribute "ROT" "0"
					( Origin gFrontEnd )
				)
				( attribute "SEC" "1"
					( Origin gFrontEnd )
				)
				( attribute "SEC_TYPE" "SM"
					( Origin gFrontEnd )
				)
				( attribute "VALUE" "1N4148W"
					( Origin gFrontEnd )
				)
				( attribute "VER" "1"
					( Origin gFrontEnd )
				)
				( attribute "XY" "(-6325,2750)"
					( Origin gFrontEnd )
				)
				( attribute "CHIPS_PART_NAME" "DIODE"
					( Origin gPackager )
				)
				( attribute "CDS_PART_NAME" "DIODE_SM-1N4148W,IC,D89194-001"
					( Origin gPackager )
				)
				( objectStatus "CR1L1" )
			)
			( gate "@baseboard_fab2_lib.baseboard_fab2(sch_1):page168_i3"
				( attribute "BOM_COST" "DEBUG"
					( Origin gFrontEnd )
				)
				( attribute "CDS_LIB" "mstr_discrete"
					( Origin gPackager )
				)
				( attribute "CDS_LOCATION" "CR1L2"
					( Origin gPackager )
				)
				( attribute "CDS_SEC" "1"
					( Origin gPackager )
				)
				( attribute "LOCATION" "CR1L2"
					( Origin gFrontEnd )
				)
				( attribute "MATERIAL" "IC"
					( Origin gFrontEnd )
				)
				( attribute "PACK_TYPE" "SM"
					( Origin gFrontEnd )
				)
				( attribute "PART_NUMBER" "D89194-001"
					( Origin gFrontEnd )
				)
				( attribute "PHYS_PAGE" "168"
					( Origin gFrontEnd )
				)
				( attribute "ROOM" "UART_MUX"
					( Origin gFrontEnd )
				)
				( attribute "ROT" "0"
					( Origin gFrontEnd )
				)
				( attribute "SEC" "1"
					( Origin gFrontEnd )
				)
				( attribute "SEC_TYPE" "SM"
					( Origin gFrontEnd )
				)
				( attribute "VALUE" "1N4148W"
					( Origin gFrontEnd )
				)
				( attribute "VER" "1"
					( Origin gFrontEnd )
				)
				( attribute "XY" "(-5675,2750)"
					( Origin gFrontEnd )
				)
				( attribute "CHIPS_PART_NAME" "DIODE"
					( Origin gPackager )
				)
				( attribute "CDS_PART_NAME" "DIODE_SM-1N4148W,IC,D89194-001"
					( Origin gPackager )
				)
				( objectStatus "CR1L2" )
			)
			( gate "@baseboard_fab2_lib.baseboard_fab2(sch_1):page168_i4"
				( attribute "BOM_COST" "DEBUG"
					( Origin gFrontEnd )
				)
				( attribute "CDS_LIB" "mstr_discrete"
					( Origin gPackager )
				)
				( attribute "CDS_LOCATION" "CR1L3"
					( Origin gPackager )
				)
				( attribute "CDS_SEC" "1"
					( Origin gPackager )
				)
				( attribute "LOCATION" "CR1L3"
					( Origin gFrontEnd )
				)
				( attribute "MATERIAL" "IC"
					( Origin gFrontEnd )
				)
				( attribute "PACK_TYPE" "SM"
					( Origin gFrontEnd )
				)
				( attribute "PART_NUMBER" "D89194-001"
					( Origin gFrontEnd )
				)
				( attribute "PHYS_PAGE" "168"
					( Origin gFrontEnd )
				)
				( attribute "ROOM" "UART_MUX"
					( Origin gFrontEnd )
				)
				( attribute "ROT" "0"
					( Origin gFrontEnd )
				)
				( attribute "SEC" "1"
					( Origin gFrontEnd )
				)
				( attribute "SEC_TYPE" "SM"
					( Origin gFrontEnd )
				)
				( attribute "VALUE" "1N4148W"
					( Origin gFrontEnd )
				)
				( attribute "VER" "1"
					( Origin gFrontEnd )
				)
				( attribute "XY" "(-4975,2750)"
					( Origin gFrontEnd )
				)
				( attribute "CHIPS_PART_NAME" "DIODE"
					( Origin gPackager )
				)
				( attribute "CDS_PART_NAME" "DIODE_SM-1N4148W,IC,D89194-001"
					( Origin gPackager )
				)
				( objectStatus "CR1L3" )
			)
			( gate "@baseboard_fab2_lib.baseboard_fab2(sch_1):page168_i5"
				( attribute "BOM_COST" "DEBUG"
					( Origin gFrontEnd )
				)
				( attribute "CDS_LIB" "mstr_discrete"
					( Origin gPackager )
				)
				( attribute "CDS_LOCATION" "CR1L4"
					( Origin gPackager )
				)
				( attribute "CDS_SEC" "1"
					( Origin gPackager )
				)
				( attribute "LOCATION" "CR1L4"
					( Origin gFrontEnd )
				)
				( attribute "MATERIAL" "IC"
					( Origin gFrontEnd )
				)
				( attribute "PACK_TYPE" "SM"
					( Origin gFrontEnd )
				)
				( attribute "PART_NUMBER" "D89194-001"
					( Origin gFrontEnd )
				)
				( attribute "PHYS_PAGE" "168"
					( Origin gFrontEnd )
				)
				( attribute "ROOM" "UART_MUX"
					( Origin gFrontEnd )
				)
				( attribute "ROT" "0"
					( Origin gFrontEnd )
				)
				( attribute "SEC" "1"
					( Origin gFrontEnd )
				)
				( attribute "SEC_TYPE" "SM"
					( Origin gFrontEnd )
				)
				( attribute "VALUE" "1N4148W"
					( Origin gFrontEnd )
				)
				( attribute "VER" "1"
					( Origin gFrontEnd )
				)
				( attribute "XY" "(-4225,2750)"
					( Origin gFrontEnd )
				)
				( attribute "CHIPS_PART_NAME" "DIODE"
					( Origin gPackager )
				)
				( attribute "CDS_PART_NAME" "DIODE_SM-1N4148W,IC,D89194-001"
					( Origin gPackager )
				)
				( objectStatus "CR1L4" )
			)
			( gate "@baseboard_fab2_lib.baseboard_fab2(sch_1):page168_i6"
				( attribute "BOM_COST" "DEBUG"
					( Origin gFrontEnd )
				)
				( attribute "CDS_LIB" "mstr_discrete"
					( Origin gPackager )
				)
				( attribute "CDS_LOCATION" "R1L6"
					( Origin gPackager )
				)
				( attribute "CDS_SEC" "1"
					( Origin gPackager )
				)
				( attribute "LOCATION" "R1L6"
					( Origin gFrontEnd )
				)
				( attribute "MATERIAL" "CHIP"
					( Origin gFrontEnd )
				)
				( attribute "PACK_TYPE" "0402"
					( Origin gFrontEnd )
				)
				( attribute "PART_NUMBER" "G21497-005"
					( Origin gFrontEnd )
				)
				( attribute "PHYS_PAGE" "168"
					( Origin gFrontEnd )
				)
				( attribute "ROOM" "UART_MUX"
					( Origin gFrontEnd )
				)
				( attribute "ROT" "0"
					( Origin gFrontEnd )
				)
				( attribute "SEC" "1"
					( Origin gFrontEnd )
				)
				( attribute "SEC_TYPE" "0402"
					( Origin gFrontEnd )
				)
				( attribute "TOLERANCE" "5%"
					( Origin gFrontEnd )
				)
				( attribute "VALUE" "0.0"
					( Origin gFrontEnd )
				)
				( attribute "VER" "1"
					( Origin gFrontEnd )
				)
				( attribute "WATTAGE" "1/16W"
					( Origin gFrontEnd )
				)
				( attribute "XY" "(-6975,2750)"
					( Origin gFrontEnd )
				)
				( attribute "CHIPS_PART_NAME" "RES"
					( Origin gPackager )
				)
				( attribute "CDS_PART_NAME" "RES_0402-0.0,5%,1/16W,CHIP,G21A"
					( Origin gPackager )
				)
				( objectStatus "R1L6" )
			)
			( gate "@baseboard_fab2_lib.baseboard_fab2(sch_1):page168_i8"
				( attribute "BOM_COST" "DEBUG"
					( Origin gFrontEnd )
				)
				( attribute "CDS_LIB" "mstr_discrete"
					( Origin gPackager )
				)
				( attribute "CDS_LOCATION" "Q1L3"
					( Origin gPackager )
				)
				( attribute "CDS_SEC" "1"
					( Origin gPackager )
				)
				( attribute "LOCATION" "Q1L3"
					( Origin gFrontEnd )
				)
				( attribute "MATERIAL" "IC"
					( Origin gFrontEnd )
				)
				( attribute "PACK_TYPE" "SM"
					( Origin gFrontEnd )
				)
				( attribute "PART_NUMBER" "C52245-001"
					( Origin gFrontEnd )
				)
				( attribute "PHYS_PAGE" "168"
					( Origin gFrontEnd )
				)
				( attribute "ROOM" "UART_MUX"
					( Origin gFrontEnd )
				)
				( attribute "ROT" "0"
					( Origin gFrontEnd )
				)
				( attribute "SEC" "1"
					( Origin gFrontEnd )
				)
				( attribute "SEC_TYPE" "SM"
					( Origin gFrontEnd )
				)
				( attribute "VALUE" "MMBT3904"
					( Origin gFrontEnd )
				)
				( attribute "VER" "1"
					( Origin gFrontEnd )
				)
				( attribute "XY" "(-3450,2750)"
					( Origin gFrontEnd )
				)
				( attribute "CHIPS_PART_NAME" "NPN"
					( Origin gPackager )
				)
				( attribute "CDS_PART_NAME" "NPN_SM-MMBT3904,IC,C52245-001"
					( Origin gPackager )
				)
				( objectStatus "Q1L3" )
			)
			( gate "@baseboard_fab2_lib.baseboard_fab2(sch_1):page168_i11"
				( attribute "BOM_COST" "DEBUG"
					( Origin gFrontEnd )
				)
				( attribute "CDS_LIB" "mstr_discrete"
					( Origin gPackager )
				)
				( attribute "CDS_LOCATION" "R1L36"
					( Origin gPackager )
				)
				( attribute "CDS_SEC" "1"
					( Origin gPackager )
				)
				( attribute "LOCATION" "R1L36"
					( Origin gFrontEnd )
				)
				( attribute "MATERIAL" "CHIP"
					( Origin gFrontEnd )
				)
				( attribute "PACK_TYPE" "0402"
					( Origin gFrontEnd )
				)
				( attribute "PART_NUMBER" "G21796-026"
					( Origin gFrontEnd )
				)
				( attribute "PHYS_PAGE" "168"
					( Origin gFrontEnd )
				)
				( attribute "ROOM" "UART_MUX"
					( Origin gFrontEnd )
				)
				( attribute "ROT" "0"
					( Origin gFrontEnd )
				)
				( attribute "SEC" "1"
					( Origin gFrontEnd )
				)
				( attribute "SEC_TYPE" "0402"
					( Origin gFrontEnd )
				)
				( attribute "TOLERANCE" "1%"
					( Origin gFrontEnd )
				)
				( attribute "VALUE" "1.00K"
					( Origin gFrontEnd )
				)
				( attribute "VER" "2"
					( Origin gFrontEnd )
				)
				( attribute "WATTAGE" "1/16W"
					( Origin gFrontEnd )
				)
				( attribute "XY" "(-3400,3050)"
					( Origin gFrontEnd )
				)
				( attribute "CHIPS_PART_NAME" "RES"
					( Origin gPackager )
				)
				( attribute "CDS_PART_NAME" "RES_0402-1.00K,1%,1/16W,CHIP,GA"
					( Origin gPackager )
				)
				( objectStatus "R1L36" )
			)
			( gate "@baseboard_fab2_lib.baseboard_fab2(sch_1):page168_i18"
				( attribute "BOM_COST" "DEBUG"
					( Origin gFrontEnd )
				)
				( attribute "CDS_LIB" "mstr_discrete"
					( Origin gPackager )
				)
				( attribute "CDS_LOCATION" "Q1L4"
					( Origin gPackager )
				)
				( attribute "CDS_SEC" "2"
					( Origin gPackager )
				)
				( attribute "LOCATION" "Q1L4"
					( Origin gFrontEnd )
				)
				( attribute "MATERIAL" "FET"
					( Origin gFrontEnd )
				)
				( attribute "PACK_TYPE" "SMLF"
					( Origin gFrontEnd )
				)
				( attribute "PART_NUMBER" "D24280-001"
					( Origin gFrontEnd )
				)
				( attribute "PHYS_PAGE" "168"
					( Origin gFrontEnd )
				)
				( attribute "ROOM" "UART_MUX"
					( Origin gFrontEnd )
				)
				( attribute "ROT" "0"
					( Origin gFrontEnd )
				)
				( attribute "SEC" "2"
					( Origin gFrontEnd )
				)
				( attribute "SEC_TYPE" "SMLF"
					( Origin gFrontEnd )
				)
				( attribute "VALUE" "2N7002DW"
					( Origin gFrontEnd )
				)
				( attribute "VER" "5"
					( Origin gFrontEnd )
				)
				( attribute "XY" "(-1525,4425)"
					( Origin gFrontEnd )
				)
				( attribute "CHIPS_PART_NAME" "FET_N_DUAL"
					( Origin gPackager )
				)
				( attribute "CDS_PART_NAME" "FET_N_DUAL_SMLF-2N7002DW,FET,DA"
					( Origin gPackager )
				)
				( objectStatus "Q1L4" )
			)
			( gate "@baseboard_fab2_lib.baseboard_fab2(sch_1):page168_i19"
				( attribute "BOM_COST" "DEBUG"
					( Origin gFrontEnd )
				)
				( attribute "CDS_LIB" "mstr_discrete"
					( Origin gPackager )
				)
				( attribute "CDS_LOCATION" "Q1L4"
					( Origin gPackager )
				)
				( attribute "CDS_SEC" "1"
					( Origin gPackager )
				)
				( attribute "LOCATION" "Q1L4"
					( Origin gFrontEnd )
				)
				( attribute "MATERIAL" "FET"
					( Origin gFrontEnd )
				)
				( attribute "PACK_TYPE" "SMLF"
					( Origin gFrontEnd )
				)
				( attribute "PART_NUMBER" "D24280-001"
					( Origin gFrontEnd )
				)
				( attribute "PHYS_PAGE" "168"
					( Origin gFrontEnd )
				)
				( attribute "ROOM" "UART_MUX"
					( Origin gFrontEnd )
				)
				( attribute "ROT" "0"
					( Origin gFrontEnd )
				)
				( attribute "SEC" "1"
					( Origin gFrontEnd )
				)
				( attribute "SEC_TYPE" "SMLF"
					( Origin gFrontEnd )
				)
				( attribute "VALUE" "2N7002DW"
					( Origin gFrontEnd )
				)
				( attribute "VER" "5"
					( Origin gFrontEnd )
				)
				( attribute "XY" "(-2425,3000)"
					( Origin gFrontEnd )
				)
				( attribute "CHIPS_PART_NAME" "FET_N_DUAL"
					( Origin gPackager )
				)
				( attribute "CDS_PART_NAME" "FET_N_DUAL_SMLF-2N7002DW,FET,DA"
					( Origin gPackager )
				)
				( objectStatus "Q1L4" )
			)
			( gate "@baseboard_fab2_lib.baseboard_fab2(sch_1):page168_i22"
				( attribute "BOM_COST" "DEBUG"
					( Origin gFrontEnd )
				)
				( attribute "CDS_LIB" "mstr_discrete"
					( Origin gPackager )
				)
				( attribute "CDS_LOCATION" "R1L38"
					( Origin gPackager )
				)
				( attribute "CDS_SEC" "1"
					( Origin gPackager )
				)
				( attribute "LOCATION" "R1L38"
					( Origin gFrontEnd )
				)
				( attribute "MATERIAL" "CHIP"
					( Origin gFrontEnd )
				)
				( attribute "PACK_TYPE" "0402"
					( Origin gFrontEnd )
				)
				( attribute "PART_NUMBER" "G21796-026"
					( Origin gFrontEnd )
				)
				( attribute "PHYS_PAGE" "168"
					( Origin gFrontEnd )
				)
				( attribute "ROOM" "UART_MUX"
					( Origin gFrontEnd )
				)
				( attribute "ROT" "0"
					( Origin gFrontEnd )
				)
				( attribute "SEC" "1"
					( Origin gFrontEnd )
				)
				( attribute "SEC_TYPE" "0402"
					( Origin gFrontEnd )
				)
				( attribute "TOLERANCE" "1%"
					( Origin gFrontEnd )
				)
				( attribute "VALUE" "1.00K"
					( Origin gFrontEnd )
				)
				( attribute "VER" "2"
					( Origin gFrontEnd )
				)
				( attribute "WATTAGE" "1/16W"
					( Origin gFrontEnd )
				)
				( attribute "XY" "(-2425,3425)"
					( Origin gFrontEnd )
				)
				( attribute "CHIPS_PART_NAME" "RES"
					( Origin gPackager )
				)
				( attribute "CDS_PART_NAME" "RES_0402-1.00K,1%,1/16W,CHIP,GA"
					( Origin gPackager )
				)
				( objectStatus "R1L38" )
			)
			( gate "@baseboard_fab2_lib.baseboard_fab2(sch_1):page169_i56"
				( attribute "BOM_COST" "SM_HM"
					( Origin gFrontEnd )
				)
				( attribute "CDS_LIB" "mstr_discrete"
					( Origin gPackager )
				)
				( attribute "CDS_LOCATION" "C1U21"
					( Origin gPackager )
				)
				( attribute "CDS_SEC" "1"
					( Origin gPackager )
				)
				( attribute "LOCATION" "C1U21"
					( Origin gFrontEnd )
				)
				( attribute "MATERIAL" "COG"
					( Origin gFrontEnd )
				)
				( attribute "PACK_TYPE" "0402LF"
					( Origin gFrontEnd )
				)
				( attribute "PART_NUMBER" "A36095-025"
					( Origin gFrontEnd )
				)
				( attribute "PHYS_PAGE" "169"
					( Origin gFrontEnd )
				)
				( attribute "ROOM" "BMC_VOLT_MONITOR"
					( Origin gFrontEnd )
				)
				( attribute "ROT" "0"
					( Origin gFrontEnd )
				)
				( attribute "SEC" "1"
					( Origin gFrontEnd )
				)
				( attribute "SEC_TYPE" "0402LF"
					( Origin gFrontEnd )
				)
				( attribute "TOLERANCE" "5%"
					( Origin gFrontEnd )
				)
				( attribute "VALUE" "47.0PF"
					( Origin gFrontEnd )
				)
				( attribute "VER" "1"
					( Origin gFrontEnd )
				)
				( attribute "VOLTAGE" "50V"
					( Units "uVoltage" "V" 1.000000)
					( Origin gFrontEnd )
				)
				( attribute "XY" "(-4825,3250)"
					( Origin gFrontEnd )
				)
				( attribute "CHIPS_PART_NAME" "CAP"
					( Origin gPackager )
				)
				( attribute "CDS_PART_NAME" "CAP_0402LF-47.0PF,50V,5%,COG,AA"
					( Origin gPackager )
				)
				( objectStatus "C1U21" )
			)
			( gate "@baseboard_fab2_lib.baseboard_fab2(sch_1):page169_i57"
				( attribute "BOM_COST" "SM_HM"
					( Origin gFrontEnd )
				)
				( attribute "CDS_LIB" "mstr_discrete"
					( Origin gPackager )
				)
				( attribute "CDS_LOCATION" "FB1U3"
					( Origin gPackager )
				)
				( attribute "CDS_SEC" "1"
					( Origin gPackager )
				)
				( attribute "LOCATION" "FB1U3"
					( Origin gFrontEnd )
				)
				( attribute "MATERIAL" "FB"
					( Origin gFrontEnd )
				)
				( attribute "PACK_TYPE" "SMLF"
					( Origin gFrontEnd )
				)
				( attribute "PART_NUMBER" "693286-021"
					( Origin gFrontEnd )
				)
				( attribute "PHYS_PAGE" "169"
					( Origin gFrontEnd )
				)
				( attribute "ROOM" "BMC_VOLT_MONITOR"
					( Origin gFrontEnd )
				)
				( attribute "ROT" "0"
					( Origin gFrontEnd )
				)
				( attribute "SEC" "1"
					( Origin gFrontEnd )
				)
				( attribute "SEC_TYPE" "SMLF"
					( Origin gFrontEnd )
				)
				( attribute "VALUE" "30"
					( Origin gFrontEnd )
				)
				( attribute "VER" "4"
					( Origin gFrontEnd )
				)
				( attribute "XY" "(-4825,3600)"
					( Origin gFrontEnd )
				)
				( attribute "CHIPS_PART_NAME" "FERRITE"
					( Origin gPackager )
				)
				( attribute "CDS_PART_NAME" "FERRITE_SMLF-30,FB,693286-021"
					( Origin gPackager )
				)
				( objectStatus "FB1U3" )
			)
			( gate "@baseboard_fab2_lib.baseboard_fab2(sch_1):page169_i68"
				( attribute "BOM_COST" "SM_HM"
					( Origin gFrontEnd )
				)
				( attribute "CDS_LIB" "mstr_discrete"
					( Origin gPackager )
				)
				( attribute "CDS_LOCATION" "C9G21"
					( Origin gPackager )
				)
				( attribute "CDS_SEC" "1"
					( Origin gPackager )
				)
				( attribute "LOCATION" "C9G21"
					( Origin gFrontEnd )
				)
				( attribute "MATERIAL" "COG"
					( Origin gFrontEnd )
				)
				( attribute "PACK_TYPE" "0402LF"
					( Origin gFrontEnd )
				)
				( attribute "PART_NUMBER" "A36095-025"
					( Origin gFrontEnd )
				)
				( attribute "PHYS_PAGE" "169"
					( Origin gFrontEnd )
				)
				( attribute "ROOM" "BMC_VOLT_MONITOR"
					( Origin gFrontEnd )
				)
				( attribute "ROT" "0"
					( Origin gFrontEnd )
				)
				( attribute "SEC" "1"
					( Origin gFrontEnd )
				)
				( attribute "SEC_TYPE" "0402LF"
					( Origin gFrontEnd )
				)
				( attribute "TOLERANCE" "5%"
					( Origin gFrontEnd )
				)
				( attribute "VALUE" "47.0PF"
					( Origin gFrontEnd )
				)
				( attribute "VER" "1"
					( Origin gFrontEnd )
				)
				( attribute "VOLTAGE" "50V"
					( Units "uVoltage" "V" 1.000000)
					( Origin gFrontEnd )
				)
				( attribute "XY" "(-2500,1350)"
					( Origin gFrontEnd )
				)
				( attribute "CHIPS_PART_NAME" "CAP"
					( Origin gPackager )
				)
				( attribute "CDS_PART_NAME" "CAP_0402LF-47.0PF,50V,5%,COG,AA"
					( Origin gPackager )
				)
				( objectStatus "C9G21" )
			)
			( gate "@baseboard_fab2_lib.baseboard_fab2(sch_1):page169_i80"
				( attribute "BOM_COST" "SM_HM"
					( Origin gFrontEnd )
				)
				( attribute "CDS_LIB" "mstr_discrete"
					( Origin gPackager )
				)
				( attribute "CDS_LOCATION" "C9G17"
					( Origin gPackager )
				)
				( attribute "CDS_SEC" "1"
					( Origin gPackager )
				)
				( attribute "LOCATION" "C9G17"
					( Origin gFrontEnd )
				)
				( attribute "MATERIAL" "COG"
					( Origin gFrontEnd )
				)
				( attribute "PACK_TYPE" "0402LF"
					( Origin gFrontEnd )
				)
				( attribute "PART_NUMBER" "A36095-025"
					( Origin gFrontEnd )
				)
				( attribute "PHYS_PAGE" "169"
					( Origin gFrontEnd )
				)
				( attribute "ROOM" "BMC_VOLT_MONITOR"
					( Origin gFrontEnd )
				)
				( attribute "ROT" "0"
					( Origin gFrontEnd )
				)
				( attribute "SEC" "1"
					( Origin gFrontEnd )
				)
				( attribute "SEC_TYPE" "0402LF"
					( Origin gFrontEnd )
				)
				( attribute "TOLERANCE" "5%"
					( Origin gFrontEnd )
				)
				( attribute "VALUE" "47.0PF"
					( Origin gFrontEnd )
				)
				( attribute "VER" "1"
					( Origin gFrontEnd )
				)
				( attribute "VOLTAGE" "50V"
					( Units "uVoltage" "V" 1.000000)
					( Origin gFrontEnd )
				)
				( attribute "XY" "(-775,1450)"
					( Origin gFrontEnd )
				)
				( attribute "CHIPS_PART_NAME" "CAP"
					( Origin gPackager )
				)
				( attribute "CDS_PART_NAME" "CAP_0402LF-47.0PF,50V,5%,COG,AA"
					( Origin gPackager )
				)
				( objectStatus "C9G17" )
			)
			( gate "@baseboard_fab2_lib.baseboard_fab2(sch_1):page169_i82"
				( attribute "BOM_COST" "SM_HM"
					( Origin gFrontEnd )
				)
				( attribute "CDS_LIB" "mstr_discrete"
					( Origin gPackager )
				)
				( attribute "CDS_LOCATION" "R1U32"
					( Origin gPackager )
				)
				( attribute "CDS_SEC" "1"
					( Origin gPackager )
				)
				( attribute "LOCATION" "R1U32"
					( Origin gFrontEnd )
				)
				( attribute "MATERIAL" "CHIP"
					( Origin gFrontEnd )
				)
				( attribute "PACK_TYPE" "0402"
					( Origin gFrontEnd )
				)
				( attribute "PART_NUMBER" "G21796-140"
					( Origin gFrontEnd )
				)
				( attribute "PHYS_PAGE" "169"
					( Origin gFrontEnd )
				)
				( attribute "ROOM" "BMC_VOLT_MONITOR"
					( Origin gFrontEnd )
				)
				( attribute "ROT" "0"
					( Origin gFrontEnd )
				)
				( attribute "SEC" "1"
					( Origin gFrontEnd )
				)
				( attribute "SEC_TYPE" "0402"
					( Origin gFrontEnd )
				)
				( attribute "TOLERANCE" "1%"
					( Origin gFrontEnd )
				)
				( attribute "VALUE" "5.11K"
					( Origin gFrontEnd )
				)
				( attribute "VER" "2"
					( Origin gFrontEnd )
				)
				( attribute "WATTAGE" "1/16W"
					( Origin gFrontEnd )
				)
				( attribute "XY" "(-1125,1825)"
					( Origin gFrontEnd )
				)
				( attribute "CHIPS_PART_NAME" "RES"
					( Origin gPackager )
				)
				( attribute "CDS_PART_NAME" "RES_0402-5.11K,1%,1/16W,CHIP,GA"
					( Origin gPackager )
				)
				( objectStatus "R1U32" )
			)
			( gate "@baseboard_fab2_lib.baseboard_fab2(sch_1):page169_i86"
				( attribute "BOM_COST" "SM_HM"
					( Origin gFrontEnd )
				)
				( attribute "CDS_LIB" "mstr_discrete"
					( Origin gPackager )
				)
				( attribute "CDS_LOCATION" "C9G20"
					( Origin gPackager )
				)
				( attribute "CDS_SEC" "1"
					( Origin gPackager )
				)
				( attribute "LOCATION" "C9G20"
					( Origin gFrontEnd )
				)
				( attribute "MATERIAL" "COG"
					( Origin gFrontEnd )
				)
				( attribute "PACK_TYPE" "0402LF"
					( Origin gFrontEnd )
				)
				( attribute "PART_NUMBER" "A36095-025"
					( Origin gFrontEnd )
				)
				( attribute "PHYS_PAGE" "169"
					( Origin gFrontEnd )
				)
				( attribute "ROOM" "BMC_VOLT_MONITOR"
					( Origin gFrontEnd )
				)
				( attribute "ROT" "0"
					( Origin gFrontEnd )
				)
				( attribute "SEC" "1"
					( Origin gFrontEnd )
				)
				( attribute "SEC_TYPE" "0402LF"
					( Origin gFrontEnd )
				)
				( attribute "TOLERANCE" "5%"
					( Origin gFrontEnd )
				)
				( attribute "VALUE" "47.0PF"
					( Origin gFrontEnd )
				)
				( attribute "VER" "1"
					( Origin gFrontEnd )
				)
				( attribute "VOLTAGE" "50V"
					( Units "uVoltage" "V" 1.000000)
					( Origin gFrontEnd )
				)
				( attribute "XY" "(-4475,1425)"
					( Origin gFrontEnd )
				)
				( attribute "CHIPS_PART_NAME" "CAP"
					( Origin gPackager )
				)
				( attribute "CDS_PART_NAME" "CAP_0402LF-47.0PF,50V,5%,COG,AA"
					( Origin gPackager )
				)
				( objectStatus "C9G20" )
			)
			( gate "@baseboard_fab2_lib.baseboard_fab2(sch_1):page169_i88"
				( attribute "BOM_COST" "SM_HM"
					( Origin gFrontEnd )
				)
				( attribute "CDS_LIB" "mstr_discrete"
					( Origin gPackager )
				)
				( attribute "CDS_LOCATION" "R1U39"
					( Origin gPackager )
				)
				( attribute "CDS_SEC" "1"
					( Origin gPackager )
				)
				( attribute "LOCATION" "R1U39"
					( Origin gFrontEnd )
				)
				( attribute "MATERIAL" "CHIP"
					( Origin gFrontEnd )
				)
				( attribute "PACK_TYPE" "0402"
					( Origin gFrontEnd )
				)
				( attribute "PART_NUMBER" "G21796-140"
					( Origin gFrontEnd )
				)
				( attribute "PHYS_PAGE" "169"
					( Origin gFrontEnd )
				)
				( attribute "ROOM" "BMC_VOLT_MONITOR"
					( Origin gFrontEnd )
				)
				( attribute "ROT" "0"
					( Origin gFrontEnd )
				)
				( attribute "SEC" "1"
					( Origin gFrontEnd )
				)
				( attribute "SEC_TYPE" "0402"
					( Origin gFrontEnd )
				)
				( attribute "TOLERANCE" "1%"
					( Origin gFrontEnd )
				)
				( attribute "VALUE" "5.11K"
					( Origin gFrontEnd )
				)
				( attribute "VER" "2"
					( Origin gFrontEnd )
				)
				( attribute "WATTAGE" "1/16W"
					( Origin gFrontEnd )
				)
				( attribute "XY" "(-4825,1800)"
					( Origin gFrontEnd )
				)
				( attribute "CHIPS_PART_NAME" "RES"
					( Origin gPackager )
				)
				( attribute "CDS_PART_NAME" "RES_0402-5.11K,1%,1/16W,CHIP,GA"
					( Origin gPackager )
				)
				( objectStatus "R1U39" )
			)
			( gate "@baseboard_fab2_lib.baseboard_fab2(sch_1):page169_i106"
				( attribute "BOM_COST" "SM_HM"
					( Origin gFrontEnd )
				)
				( attribute "CDS_LIB" "mstr_discrete"
					( Origin gPackager )
				)
				( attribute "CDS_LOCATION" "R9G26"
					( Origin gPackager )
				)
				( attribute "CDS_SEC" "1"
					( Origin gPackager )
				)
				( attribute "LOCATION" "R9G26"
					( Origin gFrontEnd )
				)
				( attribute "MATERIAL" "CHIP"
					( Origin gFrontEnd )
				)
				( attribute "PACK_TYPE" "0402"
					( Origin gFrontEnd )
				)
				( attribute "PART_NUMBER" "G21796-010"
					( Origin gFrontEnd )
				)
				( attribute "PHYS_PAGE" "169"
					( Origin gFrontEnd )
				)
				( attribute "ROOM" "BMC_VOLT_MONITOR"
					( Origin gFrontEnd )
				)
				( attribute "ROT" "0"
					( Origin gFrontEnd )
				)
				( attribute "SEC" "1"
					( Origin gFrontEnd )
				)
				( attribute "SEC_TYPE" "0402"
					( Origin gFrontEnd )
				)
				( attribute "TOLERANCE" "1%"
					( Origin gFrontEnd )
				)
				( attribute "VALUE" "100.0K"
					( Origin gFrontEnd )
				)
				( attribute "VER" "2"
					( Origin gFrontEnd )
				)
				( attribute "WATTAGE" "1/16W"
					( Origin gFrontEnd )
				)
				( attribute "XY" "(400,2725)"
					( Origin gFrontEnd )
				)
				( attribute "CHIPS_PART_NAME" "RES"
					( Origin gPackager )
				)
				( attribute "CDS_PART_NAME" "RES_0402-100.0K,1%,1/16W,CHIP,A"
					( Origin gPackager )
				)
				( objectStatus "R9G26" )
			)
			( gate "@baseboard_fab2_lib.baseboard_fab2(sch_1):page169_i108"
				( attribute "BOM_COST" "SM_HM"
					( Origin gFrontEnd )
				)
				( attribute "CDS_LIB" "mstr_discrete"
					( Origin gPackager )
				)
				( attribute "CDS_LOCATION" "C9G22"
					( Origin gPackager )
				)
				( attribute "CDS_SEC" "1"
					( Origin gPackager )
				)
				( attribute "LOCATION" "C9G22"
					( Origin gFrontEnd )
				)
				( attribute "MATERIAL" "COG"
					( Origin gFrontEnd )
				)
				( attribute "PACK_TYPE" "0402LF"
					( Origin gFrontEnd )
				)
				( attribute "PART_NUMBER" "A36094-025"
					( Origin gFrontEnd )
				)
				( attribute "PHYS_PAGE" "169"
					( Origin gFrontEnd )
				)
				( attribute "ROOM" "BMC_VOLT_MONITOR"
					( Origin gFrontEnd )
				)
				( attribute "ROT" "0"
					( Origin gFrontEnd )
				)
				( attribute "SEC" "1"
					( Origin gFrontEnd )
				)
				( attribute "SEC_TYPE" "0402LF"
					( Origin gFrontEnd )
				)
				( attribute "TOLERANCE" "5%"
					( Origin gFrontEnd )
				)
				( attribute "VALUE" "10.0PF"
					( Origin gFrontEnd )
				)
				( attribute "VER" "1"
					( Origin gFrontEnd )
				)
				( attribute "VOLTAGE" "50V"
					( Units "uVoltage" "V" 1.000000)
					( Origin gFrontEnd )
				)
				( attribute "XY" "(800,2700)"
					( Origin gFrontEnd )
				)
				( attribute "CHIPS_PART_NAME" "CAP"
					( Origin gPackager )
				)
				( attribute "CDS_PART_NAME" "CAP_0402LF-10.0PF,50V,5%,COG,AA"
					( Origin gPackager )
				)
				( objectStatus "C9G22" )
			)
			( gate "@baseboard_fab2_lib.baseboard_fab2(sch_1):page169_i170"
				( attribute "CDS_LIB" "w_hdl"
					( Origin gPackager )
				)
				( attribute "CDS_LMAN_SYM_OUTLINE" "-50,75,50,-75"
					( Origin gPackager )
				)
				( attribute "LOCATION" "R1U44"
					( Origin gFrontEnd )
				)
				( attribute "PACK_TYPE" "SMD-RG"
					( Origin gFrontEnd )
				)
				( attribute "PART_NUMBER" "64.18215.6DL"
					( Origin gFrontEnd )
				)
				( attribute "PHYS_PAGE" "169"
					( Origin gFrontEnd )
				)
				( attribute "ROT" "0"
					( Origin gFrontEnd )
				)
				( attribute "SEC" "1"
					( Origin gFrontEnd )
				)
				( attribute "SEC_TYPE" "SMD-RG"
					( Origin gFrontEnd )
				)
				( attribute "VALUE" "1K82R2F-1-GP"
					( Origin gFrontEnd )
				)
				( attribute "VER" "1"
					( Origin gFrontEnd )
				)
				( attribute "XY" "(-2850,1375)"
					( Origin gFrontEnd )
				)
				( attribute "CHIPS_PART_NAME" "1K82R2F-1-GP"
					( Origin gPackager )
				)
				( attribute "CDS_PART_NAME" "1K82R2F-1-GP_SMD-RG-1K82R2F-1-A"
					( Origin gPackager )
				)
				( attribute "CDS_LOCATION" "R1U44"
					( Origin gPackager )
				)
				( attribute "CDS_SEC" "1"
					( Origin gPackager )
				)
				( attribute "ATTRIBUTE" "1.82KOHM"
					( Origin gFrontEnd )
				)
				( attribute "RATED" "1/16W"
					( Origin gFrontEnd )
				)
				( attribute "TOLERANCE" "1%"
					( Origin gFrontEnd )
				)
				( attribute "PACK_SIZE" "0402"
					( Origin gFrontEnd )
				)
				( objectStatus "R1U44" )
			)
			( gate "@baseboard_fab2_lib.baseboard_fab2(sch_1):page169_i115"
				( attribute "BOM_COST" "SM_HM"
					( Origin gFrontEnd )
				)
				( attribute "CDS_LIB" "mstr_discrete"
					( Origin gPackager )
				)
				( attribute "CDS_LOCATION" "R1U47"
					( Origin gPackager )
				)
				( attribute "CDS_SEC" "1"
					( Origin gPackager )
				)
				( attribute "LOCATION" "R1U47"
					( Origin gFrontEnd )
				)
				( attribute "MATERIAL" "CHIP"
					( Origin gFrontEnd )
				)
				( attribute "PACK_TYPE" "0402"
					( Origin gFrontEnd )
				)
				( attribute "PART_NUMBER" "G21796-140"
					( Origin gFrontEnd )
				)
				( attribute "PHYS_PAGE" "169"
					( Origin gFrontEnd )
				)
				( attribute "ROOM" "BMC_VOLT_MONITOR"
					( Origin gFrontEnd )
				)
				( attribute "ROT" "0"
					( Origin gFrontEnd )
				)
				( attribute "SEC" "1"
					( Origin gFrontEnd )
				)
				( attribute "SEC_TYPE" "0402"
					( Origin gFrontEnd )
				)
				( attribute "TOLERANCE" "1%"
					( Origin gFrontEnd )
				)
				( attribute "VALUE" "5.11K"
					( Origin gFrontEnd )
				)
				( attribute "VER" "2"
					( Origin gFrontEnd )
				)
				( attribute "WATTAGE" "1/16W"
					( Origin gFrontEnd )
				)
				( attribute "XY" "(-2850,1750)"
					( Origin gFrontEnd )
				)
				( attribute "CHIPS_PART_NAME" "RES"
					( Origin gPackager )
				)
				( attribute "CDS_PART_NAME" "RES_0402-5.11K,1%,1/16W,CHIP,GA"
					( Origin gPackager )
				)
				( objectStatus "R1U47" )
			)
			( gate "@baseboard_fab2_lib.baseboard_fab2(sch_1):page169_i126"
				( attribute "BOM_COST" "SM_HM"
					( Origin gFrontEnd )
				)
				( attribute "CDS_LIB" "mstr_discrete"
					( Origin gPackager )
				)
				( attribute "CDS_LOCATION" "R1U50"
					( Origin gPackager )
				)
				( attribute "CDS_SEC" "1"
					( Origin gPackager )
				)
				( attribute "LOCATION" "R1U50"
					( Origin gFrontEnd )
				)
				( attribute "MATERIAL" "CHIP"
					( Origin gFrontEnd )
				)
				( attribute "PACK_TYPE" "0402"
					( Origin gFrontEnd )
				)
				( attribute "PART_NUMBER" "G21796-080"
					( Origin gFrontEnd )
				)
				( attribute "PHYS_PAGE" "169"
					( Origin gFrontEnd )
				)
				( attribute "ROOM" "BMC_VOLT_MONITOR"
					( Origin gFrontEnd )
				)
				( attribute "ROT" "0"
					( Origin gFrontEnd )
				)
				( attribute "SEC" "1"
					( Origin gFrontEnd )
				)
				( attribute "SEC_TYPE" "0402"
					( Origin gFrontEnd )
				)
				( attribute "TOLERANCE" "1%"
					( Origin gFrontEnd )
				)
				( attribute "VALUE" "200.0K"
					( Origin gFrontEnd )
				)
				( attribute "VER" "2"
					( Origin gFrontEnd )
				)
				( attribute "WATTAGE" "1/16W"
					( Origin gFrontEnd )
				)
				( attribute "XY" "(200,4025)"
					( Origin gFrontEnd )
				)
				( attribute "CHIPS_PART_NAME" "RES"
					( Origin gPackager )
				)
				( attribute "CDS_PART_NAME" "RES_0402-200.0K,1%,1/16W,CHIP,A"
					( Origin gPackager )
				)
				( objectStatus "R1U50" )
			)
			( gate "@baseboard_fab2_lib.baseboard_fab2(sch_1):page169_i139"
				( attribute "BOM_COST" "SM_HM"
					( Origin gFrontEnd )
				)
				( attribute "CDS_LIB" "mstr_discrete"
					( Origin gPackager )
				)
				( attribute "CDS_LOCATION" "C9G15"
					( Origin gPackager )
				)
				( attribute "CDS_SEC" "1"
					( Origin gPackager )
				)
				( attribute "LOCATION" "C9G15"
					( Origin gFrontEnd )
				)
				( attribute "MATERIAL" "COG"
					( Origin gFrontEnd )
				)
				( attribute "PACK_TYPE" "0402LF"
					( Origin gFrontEnd )
				)
				( attribute "PART_NUMBER" "A36095-025"
					( Origin gFrontEnd )
				)
				( attribute "PHYS_PAGE" "169"
					( Origin gFrontEnd )
				)
				( attribute "ROOM" "BMC_VOLT_MONITOR"
					( Origin gFrontEnd )
				)
				( attribute "ROT" "0"
					( Origin gFrontEnd )
				)
				( attribute "SEC" "1"
					( Origin gFrontEnd )
				)
				( attribute "SEC_TYPE" "0402LF"
					( Origin gFrontEnd )
				)
				( attribute "TOLERANCE" "5%"
					( Origin gFrontEnd )
				)
				( attribute "VALUE" "47.0PF"
					( Origin gFrontEnd )
				)
				( attribute "VER" "1"
					( Origin gFrontEnd )
				)
				( attribute "VOLTAGE" "50V"
					( Units "uVoltage" "V" 1.000000)
					( Origin gFrontEnd )
				)
				( attribute "XY" "(-4350,4550)"
					( Origin gFrontEnd )
				)
				( attribute "CHIPS_PART_NAME" "CAP"
					( Origin gPackager )
				)
				( attribute "CDS_PART_NAME" "CAP_0402LF-47.0PF,50V,5%,COG,AA"
					( Origin gPackager )
				)
				( objectStatus "C9G15" )
			)
			( gate "@baseboard_fab2_lib.baseboard_fab2(sch_1):page169_i141"
				( attribute "BOM_COST" "SM_HM"
					( Origin gFrontEnd )
				)
				( attribute "CDS_LIB" "mstr_discrete"
					( Origin gPackager )
				)
				( attribute "CDS_LOCATION" "R1U29"
					( Origin gPackager )
				)
				( attribute "CDS_SEC" "1"
					( Origin gPackager )
				)
				( attribute "LOCATION" "R1U29"
					( Origin gFrontEnd )
				)
				( attribute "MATERIAL" "CHIP"
					( Origin gFrontEnd )
				)
				( attribute "PACK_TYPE" "0402"
					( Origin gFrontEnd )
				)
				( attribute "PART_NUMBER" "G21796-140"
					( Origin gFrontEnd )
				)
				( attribute "PHYS_PAGE" "169"
					( Origin gFrontEnd )
				)
				( attribute "ROOM" "BMC_VOLT_MONITOR"
					( Origin gFrontEnd )
				)
				( attribute "ROT" "0"
					( Origin gFrontEnd )
				)
				( attribute "SEC" "1"
					( Origin gFrontEnd )
				)
				( attribute "SEC_TYPE" "0402"
					( Origin gFrontEnd )
				)
				( attribute "TOLERANCE" "1%"
					( Origin gFrontEnd )
				)
				( attribute "VALUE" "5.11K"
					( Origin gFrontEnd )
				)
				( attribute "VER" "2"
					( Origin gFrontEnd )
				)
				( attribute "WATTAGE" "1/16W"
					( Origin gFrontEnd )
				)
				( attribute "XY" "(-4700,4950)"
					( Origin gFrontEnd )
				)
				( attribute "CHIPS_PART_NAME" "RES"
					( Origin gPackager )
				)
				( attribute "CDS_PART_NAME" "RES_0402-5.11K,1%,1/16W,CHIP,GA"
					( Origin gPackager )
				)
				( objectStatus "R1U29" )
			)
			( gate "@baseboard_fab2_lib.baseboard_fab2(sch_1):page169_i146"
				( attribute "BOM_COST" "SM_HM"
					( Origin gFrontEnd )
				)
				( attribute "CDS_LIB" "mstr_discrete"
					( Origin gPackager )
				)
				( attribute "CDS_LOCATION" "C9G14"
					( Origin gPackager )
				)
				( attribute "CDS_SEC" "1"
					( Origin gPackager )
				)
				( attribute "LOCATION" "C9G14"
					( Origin gFrontEnd )
				)
				( attribute "MATERIAL" "COG"
					( Origin gFrontEnd )
				)
				( attribute "PACK_TYPE" "0402LF"
					( Origin gFrontEnd )
				)
				( attribute "PART_NUMBER" "A36095-025"
					( Origin gFrontEnd )
				)
				( attribute "PHYS_PAGE" "169"
					( Origin gFrontEnd )
				)
				( attribute "ROOM" "BMC_VOLT_MONITOR"
					( Origin gFrontEnd )
				)
				( attribute "ROT" "0"
					( Origin gFrontEnd )
				)
				( attribute "SEC" "1"
					( Origin gFrontEnd )
				)
				( attribute "SEC_TYPE" "0402LF"
					( Origin gFrontEnd )
				)
				( attribute "TOLERANCE" "5%"
					( Origin gFrontEnd )
				)
				( attribute "VALUE" "47.0PF"
					( Origin gFrontEnd )
				)
				( attribute "VER" "1"
					( Origin gFrontEnd )
				)
				( attribute "VOLTAGE" "50V"
					( Units "uVoltage" "V" 1.000000)
					( Origin gFrontEnd )
				)
				( attribute "XY" "(-2550,4600)"
					( Origin gFrontEnd )
				)
				( attribute "CHIPS_PART_NAME" "CAP"
					( Origin gPackager )
				)
				( attribute "CDS_PART_NAME" "CAP_0402LF-47.0PF,50V,5%,COG,AA"
					( Origin gPackager )
				)
				( objectStatus "C9G14" )
			)
			( gate "@baseboard_fab2_lib.baseboard_fab2(sch_1):page169_i148"
				( attribute "BOM_COST" "SM_HM"
					( Origin gFrontEnd )
				)
				( attribute "CDS_LIB" "mstr_discrete"
					( Origin gPackager )
				)
				( attribute "CDS_LOCATION" "R1U26"
					( Origin gPackager )
				)
				( attribute "CDS_SEC" "1"
					( Origin gPackager )
				)
				( attribute "LOCATION" "R1U26"
					( Origin gFrontEnd )
				)
				( attribute "MATERIAL" "CHIP"
					( Origin gFrontEnd )
				)
				( attribute "PACK_TYPE" "0402"
					( Origin gFrontEnd )
				)
				( attribute "PART_NUMBER" "G21796-140"
					( Origin gFrontEnd )
				)
				( attribute "PHYS_PAGE" "169"
					( Origin gFrontEnd )
				)
				( attribute "ROOM" "BMC_VOLT_MONITOR"
					( Origin gFrontEnd )
				)
				( attribute "ROT" "0"
					( Origin gFrontEnd )
				)
				( attribute "SEC" "1"
					( Origin gFrontEnd )
				)
				( attribute "SEC_TYPE" "0402"
					( Origin gFrontEnd )
				)
				( attribute "TOLERANCE" "1%"
					( Origin gFrontEnd )
				)
				( attribute "VALUE" "5.11K"
					( Origin gFrontEnd )
				)
				( attribute "VER" "2"
					( Origin gFrontEnd )
				)
				( attribute "WATTAGE" "1/16W"
					( Origin gFrontEnd )
				)
				( attribute "XY" "(-2900,5000)"
					( Origin gFrontEnd )
				)
				( attribute "CHIPS_PART_NAME" "RES"
					( Origin gPackager )
				)
				( attribute "CDS_PART_NAME" "RES_0402-5.11K,1%,1/16W,CHIP,GA"
					( Origin gPackager )
				)
				( objectStatus "R1U26" )
			)
			( gate "@baseboard_fab2_lib.baseboard_fab2(sch_1):page169_i169"
				( attribute "CDS_LIB" "w_hdl"
					( Origin gPackager )
				)
				( attribute "CDS_LMAN_SYM_OUTLINE" "-50,75,50,-75"
					( Origin gPackager )
				)
				( attribute "LOCATION" "R1U28"
					( Origin gFrontEnd )
				)
				( attribute "PACK_TYPE" "SMD-RG"
					( Origin gFrontEnd )
				)
				( attribute "PART_NUMBER" "64.18215.6DL"
					( Origin gFrontEnd )
				)
				( attribute "PHYS_PAGE" "169"
					( Origin gFrontEnd )
				)
				( attribute "ROT" "0"
					( Origin gFrontEnd )
				)
				( attribute "VALUE" "1K82R2F-1-GP"
					( Origin gFrontEnd )
				)
				( attribute "VER" "1"
					( Origin gFrontEnd )
				)
				( attribute "XY" "(-4700,4575)"
					( Origin gFrontEnd )
				)
				( attribute "CHIPS_PART_NAME" "1K82R2F-1-GP"
					( Origin gPackager )
				)
				( attribute "CDS_PART_NAME" "1K82R2F-1-GP_SMD-RG-1K82R2F-1-A"
					( Origin gPackager )
				)
				( attribute "SEC" "1"
					( Origin gFrontEnd )
				)
				( attribute "SEC_TYPE" "SMD-RG"
					( Origin gFrontEnd )
				)
				( attribute "CDS_LOCATION" "R1U28"
					( Origin gPackager )
				)
				( attribute "CDS_SEC" "1"
					( Origin gPackager )
				)
				( attribute "ATTRIBUTE" "1.82KOHM"
					( Origin gFrontEnd )
				)
				( attribute "RATED" "1/16W"
					( Origin gFrontEnd )
				)
				( attribute "TOLERANCE" "1%"
					( Origin gFrontEnd )
				)
				( attribute "PACK_SIZE" "0402"
					( Origin gFrontEnd )
				)
				( objectStatus "R1U28" )
			)
			( gate "@baseboard_fab2_lib.baseboard_fab2(sch_1):page169_i153"
				( attribute "BOM_COST" "SM_HM"
					( Origin gFrontEnd )
				)
				( attribute "CDS_LIB" "mstr_discrete"
					( Origin gPackager )
				)
				( attribute "CDS_LOCATION" "C9G18"
					( Origin gPackager )
				)
				( attribute "CDS_SEC" "1"
					( Origin gPackager )
				)
				( attribute "LOCATION" "C9G18"
					( Origin gFrontEnd )
				)
				( attribute "MATERIAL" "COG"
					( Origin gFrontEnd )
				)
				( attribute "PACK_TYPE" "0402LF"
					( Origin gFrontEnd )
				)
				( attribute "PART_NUMBER" "A36095-025"
					( Origin gFrontEnd )
				)
				( attribute "PHYS_PAGE" "169"
					( Origin gFrontEnd )
				)
				( attribute "ROOM" "BMC_VOLT_MONITOR"
					( Origin gFrontEnd )
				)
				( attribute "ROT" "0"
					( Origin gFrontEnd )
				)
				( attribute "SEC" "1"
					( Origin gFrontEnd )
				)
				( attribute "SEC_TYPE" "0402LF"
					( Origin gFrontEnd )
				)
				( attribute "TOLERANCE" "5%"
					( Origin gFrontEnd )
				)
				( attribute "VALUE" "47.0PF"
					( Origin gFrontEnd )
				)
				( attribute "VER" "1"
					( Origin gFrontEnd )
				)
				( attribute "VOLTAGE" "50V"
					( Units "uVoltage" "V" 1.000000)
					( Origin gFrontEnd )
				)
				( attribute "XY" "(800,1475)"
					( Origin gFrontEnd )
				)
				( attribute "CHIPS_PART_NAME" "CAP"
					( Origin gPackager )
				)
				( attribute "CDS_PART_NAME" "CAP_0402LF-47.0PF,50V,5%,COG,AA"
					( Origin gPackager )
				)
				( objectStatus "C9G18" )
			)
			( gate "@baseboard_fab2_lib.baseboard_fab2(sch_1):page169_i155"
				( attribute "BOM_COST" "SM_HM"
					( Origin gFrontEnd )
				)
				( attribute "CDS_LIB" "mstr_discrete"
					( Origin gPackager )
				)
				( attribute "CDS_LOCATION" "FB1U4"
					( Origin gPackager )
				)
				( attribute "CDS_SEC" "1"
					( Origin gPackager )
				)
				( attribute "LOCATION" "FB1U4"
					( Origin gFrontEnd )
				)
				( attribute "MATERIAL" "FB"
					( Origin gFrontEnd )
				)
				( attribute "PACK_TYPE" "SMLF"
					( Origin gFrontEnd )
				)
				( attribute "PART_NUMBER" "693286-021"
					( Origin gFrontEnd )
				)
				( attribute "PHYS_PAGE" "169"
					( Origin gFrontEnd )
				)
				( attribute "ROOM" "BMC_VOLT_MONITOR"
					( Origin gFrontEnd )
				)
				( attribute "ROT" "0"
					( Origin gFrontEnd )
				)
				( attribute "SEC" "1"
					( Origin gFrontEnd )
				)
				( attribute "SEC_TYPE" "SMLF"
					( Origin gFrontEnd )
				)
				( attribute "VALUE" "30"
					( Origin gFrontEnd )
				)
				( attribute "VER" "4"
					( Origin gFrontEnd )
				)
				( attribute "XY" "(800,1850)"
					( Origin gFrontEnd )
				)
				( attribute "CHIPS_PART_NAME" "FERRITE"
					( Origin gPackager )
				)
				( attribute "CDS_PART_NAME" "FERRITE_SMLF-30,FB,693286-021"
					( Origin gPackager )
				)
				( objectStatus "FB1U4" )
			)
			( gate "@baseboard_fab2_lib.baseboard_fab2(sch_1):page169_i157"
				( attribute "BOM_COST" "SM_HM"
					( Origin gFrontEnd )
				)
				( attribute "CDS_LIB" "mstr_discrete"
					( Origin gPackager )
				)
				( attribute "CDS_LOCATION" "Q9G1"
					( Origin gPackager )
				)
				( attribute "CDS_SEC" "2"
					( Origin gPackager )
				)
				( attribute "LOCATION" "Q9G1"
					( Origin gFrontEnd )
				)
				( attribute "MATERIAL" "FET"
					( Origin gFrontEnd )
				)
				( attribute "PACK_TYPE" "SMLF"
					( Origin gFrontEnd )
				)
				( attribute "PART_NUMBER" "E40049-001"
					( Origin gFrontEnd )
				)
				( attribute "PHYS_PAGE" "169"
					( Origin gFrontEnd )
				)
				( attribute "ROOM" "BMC_VOLT_MONITOR"
					( Origin gFrontEnd )
				)
				( attribute "ROT" "0"
					( Origin gFrontEnd )
				)
				( attribute "SEC" "2"
					( Origin gFrontEnd )
				)
				( attribute "SEC_TYPE" "SMLF"
					( Origin gFrontEnd )
				)
				( attribute "VALUE" "NTJD4001N"
					( Origin gFrontEnd )
				)
				( attribute "VER" "5"
					( Origin gFrontEnd )
				)
				( attribute "XY" "(200,3225)"
					( Origin gFrontEnd )
				)
				( attribute "CHIPS_PART_NAME" "FET_N_DUAL"
					( Origin gPackager )
				)
				( attribute "CDS_PART_NAME" "FET_N_DUAL_SMLF-NTJD4001N,FET,A"
					( Origin gPackager )
				)
				( objectStatus "Q9G1" )
			)
			( gate "@baseboard_fab2_lib.baseboard_fab2(sch_1):page169_i162"
				( attribute "BOM_COST" "SM_HM"
					( Origin gFrontEnd )
				)
				( attribute "CDS_LIB" "mstr_discrete"
					( Origin gPackager )
				)
				( attribute "CDS_LOCATION" "Q9G1"
					( Origin gPackager )
				)
				( attribute "CDS_SEC" "1"
					( Origin gPackager )
				)
				( attribute "LOCATION" "Q9G1"
					( Origin gFrontEnd )
				)
				( attribute "MATERIAL" "FET"
					( Origin gFrontEnd )
				)
				( attribute "PACK_TYPE" "SMLF"
					( Origin gFrontEnd )
				)
				( attribute "PART_NUMBER" "E40049-001"
					( Origin gFrontEnd )
				)
				( attribute "PHYS_PAGE" "169"
					( Origin gFrontEnd )
				)
				( attribute "ROOM" "BMC_VOLT_MONITOR"
					( Origin gFrontEnd )
				)
				( attribute "ROT" "0"
					( Origin gFrontEnd )
				)
				( attribute "SEC" "1"
					( Origin gFrontEnd )
				)
				( attribute "SEC_TYPE" "SMLF"
					( Origin gFrontEnd )
				)
				( attribute "VALUE" "NTJD4001N"
					( Origin gFrontEnd )
				)
				( attribute "VER" "5"
					( Origin gFrontEnd )
				)
				( attribute "XY" "(-875,2900)"
					( Origin gFrontEnd )
				)
				( attribute "CHIPS_PART_NAME" "FET_N_DUAL"
					( Origin gPackager )
				)
				( attribute "CDS_PART_NAME" "FET_N_DUAL_SMLF-NTJD4001N,FET,A"
					( Origin gPackager )
				)
				( objectStatus "Q9G1" )
			)
			( gate "@baseboard_fab2_lib.baseboard_fab2(sch_1):page169_i163"
				( attribute "BOM_COST" "SM_HM"
					( Origin gFrontEnd )
				)
				( attribute "CDS_LIB" "mstr_discrete"
					( Origin gPackager )
				)
				( attribute "CDS_LOCATION" "R1U49"
					( Origin gPackager )
				)
				( attribute "CDS_SEC" "1"
					( Origin gPackager )
				)
				( attribute "LOCATION" "R1U49"
					( Origin gFrontEnd )
				)
				( attribute "MATERIAL" "CHIP"
					( Origin gFrontEnd )
				)
				( attribute "PACK_TYPE" "0402"
					( Origin gFrontEnd )
				)
				( attribute "PART_NUMBER" "G21796-344"
					( Origin gFrontEnd )
				)
				( attribute "PHYS_PAGE" "169"
					( Origin gFrontEnd )
				)
				( attribute "ROOM" "BMC_VOLT_MONITOR"
					( Origin gFrontEnd )
				)
				( attribute "ROT" "0"
					( Origin gFrontEnd )
				)
				( attribute "SEC" "1"
					( Origin gFrontEnd )
				)
				( attribute "SEC_TYPE" "0402"
					( Origin gFrontEnd )
				)
				( attribute "TOLERANCE" "1%"
					( Origin gFrontEnd )
				)
				( attribute "VALUE" "2.7K"
					( Origin gFrontEnd )
				)
				( attribute "VER" "2"
					( Origin gFrontEnd )
				)
				( attribute "WATTAGE" "1/16W"
					( Origin gFrontEnd )
				)
				( attribute "XY" "(-650,3375)"
					( Origin gFrontEnd )
				)
				( attribute "CHIPS_PART_NAME" "RES"
					( Origin gPackager )
				)
				( attribute "CDS_PART_NAME" "RES_0402-2.7K,1%,1/16W,CHIP,G2A"
					( Origin gPackager )
				)
				( objectStatus "R1U49" )
			)
			( gate "@baseboard_fab2_lib.baseboard_fab2(sch_1):page169_i164"
				( attribute "CDS_LIB" "mstr_discrete"
					( Origin gPackager )
				)
				( attribute "CDS_LOCATION" "R9G35"
					( Origin gPackager )
				)
				( attribute "CDS_SEC" "1"
					( Origin gPackager )
				)
				( attribute "LOCATION" "R9G35"
					( Origin gFrontEnd )
				)
				( attribute "MATERIAL" "CHIP"
					( Origin gFrontEnd )
				)
				( attribute "PACK_TYPE" "0402"
					( Origin gFrontEnd )
				)
				( attribute "PART_NUMBER" "G21796-344"
					( Origin gFrontEnd )
				)
				( attribute "PHYS_PAGE" "169"
					( Origin gFrontEnd )
				)
				( attribute "ROT" "0"
					( Origin gFrontEnd )
				)
				( attribute "SEC" "1"
					( Origin gFrontEnd )
				)
				( attribute "SEC_TYPE" "0402"
					( Origin gFrontEnd )
				)
				( attribute "TOLERANCE" "1%"
					( Origin gFrontEnd )
				)
				( attribute "VALUE" "2.7K"
					( Origin gFrontEnd )
				)
				( attribute "VER" "2"
					( Origin gFrontEnd )
				)
				( attribute "WATTAGE" "1/16W"
					( Origin gFrontEnd )
				)
				( attribute "XY" "(-1400,3025)"
					( Origin gFrontEnd )
				)
				( attribute "CHIPS_PART_NAME" "RES"
					( Origin gPackager )
				)
				( attribute "CDS_PART_NAME" "RES_0402-2.7K,1%,1/16W,CHIP,G2A"
					( Origin gPackager )
				)
				( objectStatus "R9G35" )
			)
			( gate "@baseboard_fab2_lib.baseboard_fab2(sch_1):page170_i2"
				( attribute "BOM_COST" "FAST_PROCHOT"
					( Origin gFrontEnd )
				)
				( attribute "CDS_LIB" "mstr_discrete"
					( Origin gPackager )
				)
				( attribute "CDS_LOCATION" "R2P3"
					( Origin gPackager )
				)
				( attribute "CDS_SEC" "1"
					( Origin gPackager )
				)
				( attribute "LOCATION" "R2P3"
					( Origin gFrontEnd )
				)
				( attribute "MATERIAL" "CHIP"
					( Origin gFrontEnd )
				)
				( attribute "PACK_TYPE" "0402"
					( Origin gFrontEnd )
				)
				( attribute "PART_NUMBER" "G21796-072"
					( Origin gFrontEnd )
				)
				( attribute "PHYS_PAGE" "170"
					( Origin gFrontEnd )
				)
				( attribute "ROOM" "FAST_PROCHOT"
					( Origin gFrontEnd )
				)
				( attribute "ROT" "0"
					( Origin gFrontEnd )
				)
				( attribute "SEC" "1"
					( Origin gFrontEnd )
				)
				( attribute "SEC_TYPE" "0402"
					( Origin gFrontEnd )
				)
				( attribute "TOLERANCE" "1%"
					( Origin gFrontEnd )
				)
				( attribute "VALUE" "4.75K"
					( Origin gFrontEnd )
				)
				( attribute "VER" "2"
					( Origin gFrontEnd )
				)
				( attribute "WATTAGE" "1/16W"
					( Origin gFrontEnd )
				)
				( attribute "XY" "(-2125,5250)"
					( Origin gFrontEnd )
				)
				( attribute "CHIPS_PART_NAME" "RES"
					( Origin gPackager )
				)
				( attribute "CDS_PART_NAME" "RES_0402-4.75K,1%,1/16W,CHIP,GA"
					( Origin gPackager )
				)
				( objectStatus "R2P3" )
			)
			( gate "@baseboard_fab2_lib.baseboard_fab2(sch_1):page170_i4"
				( attribute "BOM_COST" "FAST_PROCHOT"
					( Origin gFrontEnd )
				)
				( attribute "CDS_LIB" "mstr_ttl"
					( Origin gPackager )
				)
				( attribute "CDS_LOCATION" "U8D3"
					( Origin gPackager )
				)
				( attribute "CDS_SEC" "1"
					( Origin gPackager )
				)
				( attribute "LOCATION" "U8D3"
					( Origin gFrontEnd )
				)
				( attribute "MATERIAL" "IC"
					( Origin gFrontEnd )
				)
				( attribute "PACK_TYPE" "SOP"
					( Origin gFrontEnd )
				)
				( attribute "PART_NUMBER" "C88419-001"
					( Origin gFrontEnd )
				)
				( attribute "PHYS_PAGE" "170"
					( Origin gFrontEnd )
				)
				( attribute "ROOM" "FAST_PROCHOT"
					( Origin gFrontEnd )
				)
				( attribute "ROT" "0"
					( Origin gFrontEnd )
				)
				( attribute "SEC" "1"
					( Origin gPackager )
				)
				( attribute "VALUE" "74LVC1G07"
					( Origin gFrontEnd )
				)
				( attribute "VER" "1"
					( Origin gFrontEnd )
				)
				( attribute "XY" "(-2400,4775)"
					( Origin gFrontEnd )
				)
				( attribute "CHIPS_PART_NAME" "TTL1G07_A"
					( Origin gPackager )
				)
				( attribute "CDS_PART_NAME" "TTL1G07_A_SOP-74LVC1G07,IC,C88B"
					( Origin gPackager )
				)
				( objectStatus "U8D3" )
			)
			( gate "@baseboard_fab2_lib.baseboard_fab2(sch_1):page170_i8"
				( attribute "BOM_COST" "FAST_PROCHOT"
					( Origin gFrontEnd )
				)
				( attribute "CDS_LIB" "dev_discrete"
					( Origin gPackager )
				)
				( attribute "CDS_LOCATION" "C2P1"
					( Origin gPackager )
				)
				( attribute "CDS_SEC" "1"
					( Origin gPackager )
				)
				( attribute "LOCATION" "C2P1"
					( Origin gFrontEnd )
				)
				( attribute "MATERIAL" "X7R"
					( Origin gFrontEnd )
				)
				( attribute "PACK_TYPE" "0402V"
					( Origin gFrontEnd )
				)
				( attribute "PART_NUMBER" "A36096-030"
					( Origin gFrontEnd )
				)
				( attribute "PHYS_PAGE" "170"
					( Origin gFrontEnd )
				)
				( attribute "ROOM" "FAST_PROCHOT"
					( Origin gFrontEnd )
				)
				( attribute "ROT" "0"
					( Origin gFrontEnd )
				)
				( attribute "SEC" "1"
					( Origin gFrontEnd )
				)
				( attribute "SEC_TYPE" "0402V"
					( Origin gFrontEnd )
				)
				( attribute "TOLERANCE" "10%"
					( Origin gFrontEnd )
				)
				( attribute "VALUE" "0.1UF"
					( Origin gFrontEnd )
				)
				( attribute "VER" "1"
					( Origin gFrontEnd )
				)
				( attribute "VOLTAGE" "16V"
					( Units "uVoltage" "V" 1.000000)
					( Origin gFrontEnd )
				)
				( attribute "XY" "(-5100,3350)"
					( Origin gFrontEnd )
				)
				( attribute "CHIPS_PART_NAME" "CAP_A"
					( Origin gPackager )
				)
				( attribute "CDS_PART_NAME" "CAP_A_0402V-0.1UF,16V,10%,X7R,A"
					( Origin gPackager )
				)
				( objectStatus "C2P1" )
			)
			( gate "@baseboard_fab2_lib.baseboard_fab2(sch_1):page170_i10"
				( attribute "BOM_COST" "FAST_PROCHOT"
					( Origin gFrontEnd )
				)
				( attribute "CDS_LIB" "mstr_ttl"
					( Origin gPackager )
				)
				( attribute "CDS_LOCATION" "U8E1"
					( Origin gPackager )
				)
				( attribute "CDS_SEC" "4"
					( Origin gPackager )
				)
				( attribute "LOCATION" "U8E1"
					( Origin gFrontEnd )
				)
				( attribute "MATERIAL" "IC"
					( Origin gFrontEnd )
				)
				( attribute "PACK_TYPE" "QFN15"
					( Origin gFrontEnd )
				)
				( attribute "PART_NUMBER" "D90404-001"
					( Origin gFrontEnd )
				)
				( attribute "PHYS_PAGE" "170"
					( Origin gFrontEnd )
				)
				( attribute "ROOM" "FAST_PROCHOT"
					( Origin gFrontEnd )
				)
				( attribute "ROT" "0"
					( Origin gFrontEnd )
				)
				( attribute "SEC" "4"
					( Origin gFrontEnd )
				)
				( attribute "SEC_TYPE" "QFN15"
					( Origin gFrontEnd )
				)
				( attribute "VALUE" "74LVC08A"
					( Origin gFrontEnd )
				)
				( attribute "VER" "1"
					( Origin gFrontEnd )
				)
				( attribute "XY" "(-1175,4375)"
					( Origin gFrontEnd )
				)
				( attribute "CHIPS_PART_NAME" "TTL08"
					( Origin gPackager )
				)
				( attribute "CDS_PART_NAME" "TTL08_QFN15-74LVC08A,IC,D90404B"
					( Origin gPackager )
				)
				( objectStatus "U8E1" )
			)
			( gate "@baseboard_fab2_lib.baseboard_fab2(sch_1):page170_i11"
				( attribute "BOM_COST" "FAST_PROCHOT"
					( Origin gFrontEnd )
				)
				( attribute "CDS_LIB" "mstr_ttl"
					( Origin gPackager )
				)
				( attribute "CDS_LOCATION" "U8E1"
					( Origin gPackager )
				)
				( attribute "CDS_SEC" "3"
					( Origin gPackager )
				)
				( attribute "LOCATION" "U8E1"
					( Origin gFrontEnd )
				)
				( attribute "MATERIAL" "IC"
					( Origin gFrontEnd )
				)
				( attribute "PACK_TYPE" "QFN15"
					( Origin gFrontEnd )
				)
				( attribute "PART_NUMBER" "D90404-001"
					( Origin gFrontEnd )
				)
				( attribute "PHYS_PAGE" "170"
					( Origin gFrontEnd )
				)
				( attribute "ROOM" "FAST_PROCHOT"
					( Origin gFrontEnd )
				)
				( attribute "ROT" "0"
					( Origin gFrontEnd )
				)
				( attribute "SEC" "3"
					( Origin gFrontEnd )
				)
				( attribute "SEC_TYPE" "QFN15"
					( Origin gFrontEnd )
				)
				( attribute "VALUE" "74LVC08A"
					( Origin gFrontEnd )
				)
				( attribute "VER" "1"
					( Origin gFrontEnd )
				)
				( attribute "XY" "(-1175,3650)"
					( Origin gFrontEnd )
				)
				( attribute "CHIPS_PART_NAME" "TTL08"
					( Origin gPackager )
				)
				( attribute "CDS_PART_NAME" "TTL08_QFN15-74LVC08A,IC,D90404B"
					( Origin gPackager )
				)
				( objectStatus "U8E1" )
			)
			( gate "@baseboard_fab2_lib.baseboard_fab2(sch_1):page170_i12"
				( attribute "BOM_COST" "FAST_PROCHOT"
					( Origin gFrontEnd )
				)
				( attribute "CDS_LIB" "mstr_ttl"
					( Origin gPackager )
				)
				( attribute "CDS_LOCATION" "U8E1"
					( Origin gPackager )
				)
				( attribute "CDS_SEC" "1"
					( Origin gPackager )
				)
				( attribute "LOCATION" "U8E1"
					( Origin gFrontEnd )
				)
				( attribute "MATERIAL" "IC"
					( Origin gFrontEnd )
				)
				( attribute "PACK_TYPE" "QFN15"
					( Origin gFrontEnd )
				)
				( attribute "PART_NUMBER" "D90404-001"
					( Origin gFrontEnd )
				)
				( attribute "PHYS_PAGE" "170"
					( Origin gFrontEnd )
				)
				( attribute "ROOM" "FAST_PROCHOT"
					( Origin gFrontEnd )
				)
				( attribute "ROT" "0"
					( Origin gFrontEnd )
				)
				( attribute "SEC" "1"
					( Origin gFrontEnd )
				)
				( attribute "SEC_TYPE" "QFN15"
					( Origin gFrontEnd )
				)
				( attribute "VALUE" "74LVC08A"
					( Origin gFrontEnd )
				)
				( attribute "VER" "1"
					( Origin gFrontEnd )
				)
				( attribute "XY" "(-25,4075)"
					( Origin gFrontEnd )
				)
				( attribute "CHIPS_PART_NAME" "TTL08"
					( Origin gPackager )
				)
				( attribute "CDS_PART_NAME" "TTL08_QFN15-74LVC08A,IC,D90404B"
					( Origin gPackager )
				)
				( objectStatus "U8E1" )
			)
			( gate "@baseboard_fab2_lib.baseboard_fab2(sch_1):page170_i20"
				( attribute "BOM_COST" "FAST_PROCHOT"
					( Origin gFrontEnd )
				)
				( attribute "CDS_LIB" "mstr_ttl"
					( Origin gPackager )
				)
				( attribute "CDS_LOCATION" "U1R2"
					( Origin gPackager )
				)
				( attribute "CDS_SEC" "1"
					( Origin gPackager )
				)
				( attribute "LOCATION" "U1R2"
					( Origin gFrontEnd )
				)
				( attribute "MATERIAL" "IC"
					( Origin gFrontEnd )
				)
				( attribute "PACK_TYPE" "SOT"
					( Origin gFrontEnd )
				)
				( attribute "PART_NUMBER" "A79322-001"
					( Origin gFrontEnd )
				)
				( attribute "PHYS_PAGE" "170"
					( Origin gFrontEnd )
				)
				( attribute "ROOM" "FAST_PROCHOT"
					( Origin gFrontEnd )
				)
				( attribute "ROT" "0"
					( Origin gFrontEnd )
				)
				( attribute "SEC" "1"
					( Origin gFrontEnd )
				)
				( attribute "SEC_TYPE" "SOT"
					( Origin gFrontEnd )
				)
				( attribute "VALUE" "74HC1G126"
					( Origin gFrontEnd )
				)
				( attribute "VER" "1"
					( Origin gFrontEnd )
				)
				( attribute "XY" "(-2525,2525)"
					( Origin gFrontEnd )
				)
				( attribute "CHIPS_PART_NAME" "TTL1G126_A"
					( Origin gPackager )
				)
				( attribute "CDS_PART_NAME" "TTL1G126_A_SOT-74HC1G126,IC,A7B"
					( Origin gPackager )
				)
				( objectStatus "U1R2" )
			)
			( gate "@baseboard_fab2_lib.baseboard_fab2(sch_1):page170_i30"
				( attribute "BOM_COST" "FAST_PROCHOT"
					( Origin gFrontEnd )
				)
				( attribute "CDS_LIB" "dev_discrete"
					( Origin gPackager )
				)
				( attribute "CDS_LOCATION" "C1R27"
					( Origin gPackager )
				)
				( attribute "CDS_SEC" "1"
					( Origin gPackager )
				)
				( attribute "LOCATION" "C1R27"
					( Origin gFrontEnd )
				)
				( attribute "MATERIAL" "X7R"
					( Origin gFrontEnd )
				)
				( attribute "PACK_TYPE" "0402V"
					( Origin gFrontEnd )
				)
				( attribute "PART_NUMBER" "A36096-030"
					( Origin gFrontEnd )
				)
				( attribute "PHYS_PAGE" "170"
					( Origin gFrontEnd )
				)
				( attribute "ROOM" "FAST_PROCHOT"
					( Origin gFrontEnd )
				)
				( attribute "ROT" "0"
					( Origin gFrontEnd )
				)
				( attribute "SEC" "1"
					( Origin gFrontEnd )
				)
				( attribute "SEC_TYPE" "0402V"
					( Origin gFrontEnd )
				)
				( attribute "TOLERANCE" "10%"
					( Origin gFrontEnd )
				)
				( attribute "VALUE" "0.1UF"
					( Origin gFrontEnd )
				)
				( attribute "VER" "1"
					( Origin gFrontEnd )
				)
				( attribute "VOLTAGE" "16V"
					( Units "uVoltage" "V" 1.000000)
					( Origin gFrontEnd )
				)
				( attribute "XY" "(-5150,1325)"
					( Origin gFrontEnd )
				)
				( attribute "CHIPS_PART_NAME" "CAP_A"
					( Origin gPackager )
				)
				( attribute "CDS_PART_NAME" "CAP_A_0402V-0.1UF,16V,10%,X7R,A"
					( Origin gPackager )
				)
				( objectStatus "C1R27" )
			)
			( gate "@baseboard_fab2_lib.baseboard_fab2(sch_1):page170_i33"
				( attribute "BOM_COST" "FAST_PROCHOT"
					( Origin gFrontEnd )
				)
				( attribute "CDS_LIB" "dev_discrete"
					( Origin gPackager )
				)
				( attribute "CDS_LOCATION" "C8D2"
					( Origin gPackager )
				)
				( attribute "CDS_SEC" "1"
					( Origin gPackager )
				)
				( attribute "LOCATION" "C8D2"
					( Origin gFrontEnd )
				)
				( attribute "MATERIAL" "X7R"
					( Origin gFrontEnd )
				)
				( attribute "PACK_TYPE" "0402V"
					( Origin gFrontEnd )
				)
				( attribute "PART_NUMBER" "A36096-030"
					( Origin gFrontEnd )
				)
				( attribute "PHYS_PAGE" "170"
					( Origin gFrontEnd )
				)
				( attribute "ROOM" "FAST_PROCHOT"
					( Origin gFrontEnd )
				)
				( attribute "ROT" "0"
					( Origin gFrontEnd )
				)
				( attribute "SEC" "1"
					( Origin gFrontEnd )
				)
				( attribute "SEC_TYPE" "0402V"
					( Origin gFrontEnd )
				)
				( attribute "TOLERANCE" "10%"
					( Origin gFrontEnd )
				)
				( attribute "VALUE" "0.1UF"
					( Origin gFrontEnd )
				)
				( attribute "VER" "1"
					( Origin gFrontEnd )
				)
				( attribute "VOLTAGE" "16V"
					( Units "uVoltage" "V" 1.000000)
					( Origin gFrontEnd )
				)
				( attribute "XY" "(-200,4775)"
					( Origin gFrontEnd )
				)
				( attribute "CHIPS_PART_NAME" "CAP_A"
					( Origin gPackager )
				)
				( attribute "CDS_PART_NAME" "CAP_A_0402V-0.1UF,16V,10%,X7R,A"
					( Origin gPackager )
				)
				( objectStatus "C8D2" )
			)
			( gate "@baseboard_fab2_lib.baseboard_fab2(sch_1):page170_i38"
				( attribute "BOM_COST" "PROC_SIDEBAND"
					( Origin gFrontEnd )
				)
				( attribute "CDS_LIB" "mstr_ttl"
					( Origin gPackager )
				)
				( attribute "CDS_LOCATION" "U8D5"
					( Origin gPackager )
				)
				( attribute "CDS_SEC" "1"
					( Origin gPackager )
				)
				( attribute "LOCATION" "U8D5"
					( Origin gFrontEnd )
				)
				( attribute "MATERIAL" "IC"
					( Origin gFrontEnd )
				)
				( attribute "PACK_TYPE" "SOT"
					( Origin gFrontEnd )
				)
				( attribute "PART_NUMBER" "A79322-001"
					( Origin gFrontEnd )
				)
				( attribute "PHYS_PAGE" "170"
					( Origin gFrontEnd )
				)
				( attribute "ROOM" "PROC_SIDEBAND"
					( Origin gFrontEnd )
				)
				( attribute "ROT" "0"
					( Origin gFrontEnd )
				)
				( attribute "SEC" "1"
					( Origin gFrontEnd )
				)
				( attribute "SEC_TYPE" "SOT"
					( Origin gFrontEnd )
				)
				( attribute "VALUE" "74HC1G126"
					( Origin gFrontEnd )
				)
				( attribute "VER" "1"
					( Origin gFrontEnd )
				)
				( attribute "XY" "(-3500,4775)"
					( Origin gFrontEnd )
				)
				( attribute "CHIPS_PART_NAME" "TTL1G126_A"
					( Origin gPackager )
				)
				( attribute "CDS_PART_NAME" "TTL1G126_A_SOT-74HC1G126,IC,A7B"
					( Origin gPackager )
				)
				( objectStatus "U8D5" )
			)
			( gate "@baseboard_fab2_lib.baseboard_fab2(sch_1):page170_i40"
				( attribute "BOM_COST" "PROC_SIDEBAND"
					( Origin gFrontEnd )
				)
				( attribute "CDS_LIB" "dev_discrete"
					( Origin gPackager )
				)
				( attribute "CDS_LOCATION" "C8E2"
					( Origin gPackager )
				)
				( attribute "CDS_SEC" "1"
					( Origin gPackager )
				)
				( attribute "LOCATION" "C8E2"
					( Origin gFrontEnd )
				)
				( attribute "MATERIAL" "X7R"
					( Origin gFrontEnd )
				)
				( attribute "PACK_TYPE" "0402V"
					( Origin gFrontEnd )
				)
				( attribute "PART_NUMBER" "A36096-030"
					( Origin gFrontEnd )
				)
				( attribute "PHYS_PAGE" "170"
					( Origin gFrontEnd )
				)
				( attribute "ROOM" "PROC_SIDEBAND"
					( Origin gFrontEnd )
				)
				( attribute "ROT" "0"
					( Origin gFrontEnd )
				)
				( attribute "SEC" "1"
					( Origin gFrontEnd )
				)
				( attribute "SEC_TYPE" "0402V"
					( Origin gFrontEnd )
				)
				( attribute "TOLERANCE" "10%"
					( Origin gFrontEnd )
				)
				( attribute "VALUE" "0.1UF"
					( Origin gFrontEnd )
				)
				( attribute "VER" "1"
					( Origin gFrontEnd )
				)
				( attribute "VOLTAGE" "16V"
					( Units "uVoltage" "V" 1.000000)
					( Origin gFrontEnd )
				)
				( attribute "XY" "(-1350,5100)"
					( Origin gFrontEnd )
				)
				( attribute "CHIPS_PART_NAME" "CAP_A"
					( Origin gPackager )
				)
				( attribute "CDS_PART_NAME" "CAP_A_0402V-0.1UF,16V,10%,X7R,A"
					( Origin gPackager )
				)
				( objectStatus "C8E2" )
			)
			( gate "@baseboard_fab2_lib.baseboard_fab2(sch_1):page170_i42"
				( attribute "BOM_COST" "PROC_SIDEBAND"
					( Origin gFrontEnd )
				)
				( attribute "CDS_LIB" "mstr_discrete"
					( Origin gPackager )
				)
				( attribute "CDS_LOCATION" "C8D3"
					( Origin gPackager )
				)
				( attribute "LOCATION" "C8D3"
					( Origin gFrontEnd )
				)
				( attribute "MATERIAL" "EMPTY"
					( Origin gFrontEnd )
				)
				( attribute "PACK_TYPE" "0402LF"
					( Origin gFrontEnd )
				)
				( attribute "PART_NUMBER" "A36096-049"
					( Origin gFrontEnd )
				)
				( attribute "PHYS_PAGE" "170"
					( Origin gFrontEnd )
				)
				( attribute "ROOM" "PROC_SIDEBAND"
					( Origin gFrontEnd )
				)
				( attribute "ROT" "0"
					( Origin gFrontEnd )
				)
				( attribute "SEC" "1"
					( Origin gFrontEnd )
				)
				( attribute "SEC_TYPE" "0402LF"
					( Origin gFrontEnd )
				)
				( attribute "TOLERANCE" "10%"
					( Origin gFrontEnd )
				)
				( attribute "VALUE" "470PF"
					( Origin gFrontEnd )
				)
				( attribute "VER" "1"
					( Origin gFrontEnd )
				)
				( attribute "VOLTAGE" "50V"
					( Units "uVoltage" "V" 1.000000)
					( Origin gFrontEnd )
				)
				( attribute "XY" "(-3700,4250)"
					( Origin gFrontEnd )
				)
				( attribute "CHIPS_PART_NAME" "CAP"
					( Origin gPackager )
				)
				( attribute "CDS_PART_NAME" "CAP_0402LF-470PF,50V,10%,EMPTYA"
					( Origin gPackager )
				)
				( attribute "CDS_SEC" "1"
					( Origin gPackager )
				)
				( objectStatus "C8D3" )
			)
			( gate "@baseboard_fab2_lib.baseboard_fab2(sch_1):page170_i46"
				( attribute "BOM_COST" "FAST_PROCHOT"
					( Origin gFrontEnd )
				)
				( attribute "CDS_LIB" "mstr_ttl"
					( Origin gPackager )
				)
				( attribute "CDS_LOCATION" "U1R1"
					( Origin gPackager )
				)
				( attribute "CDS_SEC" "1"
					( Origin gPackager )
				)
				( attribute "LOCATION" "U1R1"
					( Origin gFrontEnd )
				)
				( attribute "MATERIAL" "IC"
					( Origin gFrontEnd )
				)
				( attribute "PACK_TYPE" "SOP"
					( Origin gFrontEnd )
				)
				( attribute "PART_NUMBER" "C88419-001"
					( Origin gFrontEnd )
				)
				( attribute "PHYS_PAGE" "170"
					( Origin gFrontEnd )
				)
				( attribute "ROOM" "FAST_PROCHOT"
					( Origin gFrontEnd )
				)
				( attribute "ROT" "0"
					( Origin gFrontEnd )
				)
				( attribute "SEC" "1"
					( Origin gFrontEnd )
				)
				( attribute "SEC_TYPE" "SOP"
					( Origin gFrontEnd )
				)
				( attribute "VALUE" "74LVC1G07"
					( Origin gFrontEnd )
				)
				( attribute "VER" "1"
					( Origin gFrontEnd )
				)
				( attribute "XY" "(-1225,2525)"
					( Origin gFrontEnd )
				)
				( attribute "CHIPS_PART_NAME" "TTL1G07_A"
					( Origin gPackager )
				)
				( attribute "CDS_PART_NAME" "TTL1G07_A_SOP-74LVC1G07,IC,C88B"
					( Origin gPackager )
				)
				( objectStatus "U1R1" )
			)
			( gate "@baseboard_fab2_lib.baseboard_fab2(sch_1):page170_i49"
				( attribute "BOM_COST" "FAST_PROCHOT"
					( Origin gFrontEnd )
				)
				( attribute "CDS_LIB" "dev_discrete"
					( Origin gPackager )
				)
				( attribute "CDS_LOCATION" "C1R28"
					( Origin gPackager )
				)
				( attribute "CDS_SEC" "1"
					( Origin gPackager )
				)
				( attribute "LOCATION" "C1R28"
					( Origin gFrontEnd )
				)
				( attribute "MATERIAL" "X7R"
					( Origin gFrontEnd )
				)
				( attribute "PACK_TYPE" "0402V"
					( Origin gFrontEnd )
				)
				( attribute "PART_NUMBER" "A36096-030"
					( Origin gFrontEnd )
				)
				( attribute "PHYS_PAGE" "170"
					( Origin gFrontEnd )
				)
				( attribute "ROOM" "FAST_PROCHOT"
					( Origin gFrontEnd )
				)
				( attribute "ROT" "0"
					( Origin gFrontEnd )
				)
				( attribute "SEC" "1"
					( Origin gFrontEnd )
				)
				( attribute "SEC_TYPE" "0402V"
					( Origin gFrontEnd )
				)
				( attribute "TOLERANCE" "10%"
					( Origin gFrontEnd )
				)
				( attribute "VALUE" "0.1UF"
					( Origin gFrontEnd )
				)
				( attribute "VER" "1"
					( Origin gFrontEnd )
				)
				( attribute "VOLTAGE" "16V"
					( Units "uVoltage" "V" 1.000000)
					( Origin gFrontEnd )
				)
				( attribute "XY" "(-1600,1700)"
					( Origin gFrontEnd )
				)
				( attribute "CHIPS_PART_NAME" "CAP_A"
					( Origin gPackager )
				)
				( attribute "CDS_PART_NAME" "CAP_A_0402V-0.1UF,16V,10%,X7R,A"
					( Origin gPackager )
				)
				( objectStatus "C1R28" )
			)
			( gate "@baseboard_fab2_lib.baseboard_fab2(sch_1):page170_i51"
				( attribute "BOM_COST" "PROC_SIDEBAND"
					( Origin gFrontEnd )
				)
				( attribute "CDS_LIB" "mstr_discrete"
					( Origin gPackager )
				)
				( attribute "CDS_LOCATION" "R1R8"
					( Origin gPackager )
				)
				( attribute "CDS_SEC" "1"
					( Origin gPackager )
				)
				( attribute "LOCATION" "R1R8"
					( Origin gFrontEnd )
				)
				( attribute "MATERIAL" "CHIP"
					( Origin gFrontEnd )
				)
				( attribute "PACK_TYPE" "0402"
					( Origin gFrontEnd )
				)
				( attribute "PART_NUMBER" "G21497-005"
					( Origin gFrontEnd )
				)
				( attribute "PHYS_PAGE" "170"
					( Origin gFrontEnd )
				)
				( attribute "ROOM" "PROC_SIDEBAND"
					( Origin gFrontEnd )
				)
				( attribute "ROT" "0"
					( Origin gFrontEnd )
				)
				( attribute "SEC" "1"
					( Origin gFrontEnd )
				)
				( attribute "SEC_TYPE" "0402"
					( Origin gFrontEnd )
				)
				( attribute "TOLERANCE" "5%"
					( Origin gFrontEnd )
				)
				( attribute "VALUE" "0.0"
					( Origin gFrontEnd )
				)
				( attribute "VER" "1"
					( Origin gFrontEnd )
				)
				( attribute "WATTAGE" "1/16W"
					( Origin gFrontEnd )
				)
				( attribute "XY" "(-475,2525)"
					( Origin gFrontEnd )
				)
				( attribute "CHIPS_PART_NAME" "RES"
					( Origin gPackager )
				)
				( attribute "CDS_PART_NAME" "RES_0402-0.0,5%,1/16W,CHIP,G21A"
					( Origin gPackager )
				)
				( objectStatus "R1R8" )
			)
			( gate "@baseboard_fab2_lib.baseboard_fab2(sch_1):page170_i54"
				( attribute "BOM_COST" "FAST_PROCHOT"
					( Origin gFrontEnd )
				)
				( attribute "CDS_LIB" "mstr_discrete"
					( Origin gPackager )
				)
				( attribute "CDS_LOCATION" "R2T3"
					( Origin gPackager )
				)
				( attribute "CDS_SEC" "1"
					( Origin gPackager )
				)
				( attribute "LOCATION" "R2T3"
					( Origin gFrontEnd )
				)
				( attribute "MATERIAL" "CHIP"
					( Origin gFrontEnd )
				)
				( attribute "PACK_TYPE" "0402"
					( Origin gFrontEnd )
				)
				( attribute "PART_NUMBER" "G21796-072"
					( Origin gFrontEnd )
				)
				( attribute "PHYS_PAGE" "170"
					( Origin gFrontEnd )
				)
				( attribute "ROOM" "FAST_PROCHOT"
					( Origin gFrontEnd )
				)
				( attribute "ROT" "0"
					( Origin gFrontEnd )
				)
				( attribute "SEC" "1"
					( Origin gFrontEnd )
				)
				( attribute "SEC_TYPE" "0402"
					( Origin gFrontEnd )
				)
				( attribute "TOLERANCE" "1%"
					( Origin gFrontEnd )
				)
				( attribute "VALUE" "4.75K"
					( Origin gFrontEnd )
				)
				( attribute "VER" "2"
					( Origin gFrontEnd )
				)
				( attribute "WATTAGE" "1/16W"
					( Origin gFrontEnd )
				)
				( attribute "XY" "(-3450,2075)"
					( Origin gFrontEnd )
				)
				( attribute "CHIPS_PART_NAME" "RES"
					( Origin gPackager )
				)
				( attribute "CDS_PART_NAME" "RES_0402-4.75K,1%,1/16W,CHIP,GA"
					( Origin gPackager )
				)
				( objectStatus "R2T3" )
			)
			( gate "@baseboard_fab2_lib.baseboard_fab2(sch_1):page170_i56"
				( attribute "BOM_COST" "PROC_SIDEBAND"
					( Origin gFrontEnd )
				)
				( attribute "CDS_LIB" "mstr_discrete"
					( Origin gPackager )
				)
				( attribute "CDS_LOCATION" "R2P5"
					( Origin gPackager )
				)
				( attribute "CDS_SEC" "1"
					( Origin gPackager )
				)
				( attribute "LOCATION" "R2P5"
					( Origin gFrontEnd )
				)
				( attribute "MATERIAL" "CHIP"
					( Origin gFrontEnd )
				)
				( attribute "PACK_TYPE" "0402"
					( Origin gFrontEnd )
				)
				( attribute "PART_NUMBER" "G21796-072"
					( Origin gFrontEnd )
				)
				( attribute "PHYS_PAGE" "170"
					( Origin gFrontEnd )
				)
				( attribute "ROOM" "PROC_SIDEBAND"
					( Origin gFrontEnd )
				)
				( attribute "ROT" "0"
					( Origin gFrontEnd )
				)
				( attribute "SEC" "1"
					( Origin gFrontEnd )
				)
				( attribute "SEC_TYPE" "0402"
					( Origin gFrontEnd )
				)
				( attribute "TOLERANCE" "1%"
					( Origin gFrontEnd )
				)
				( attribute "VALUE" "4.75K"
					( Origin gFrontEnd )
				)
				( attribute "VER" "2"
					( Origin gFrontEnd )
				)
				( attribute "WATTAGE" "1/16W"
					( Origin gFrontEnd )
				)
				( attribute "XY" "(-4150,5100)"
					( Origin gFrontEnd )
				)
				( attribute "CHIPS_PART_NAME" "RES"
					( Origin gPackager )
				)
				( attribute "CDS_PART_NAME" "RES_0402-4.75K,1%,1/16W,CHIP,GA"
					( Origin gPackager )
				)
				( objectStatus "R2P5" )
			)
			( gate "@baseboard_fab2_lib.baseboard_fab2(sch_1):page170_i58"
				( attribute "BOM_COST" "PROC_SIDEBAND"
					( Origin gFrontEnd )
				)
				( attribute "CDS_LIB" "mstr_discrete"
					( Origin gPackager )
				)
				( attribute "CDS_LOCATION" "Q2P1"
					( Origin gPackager )
				)
				( attribute "CDS_SEC" "1"
					( Origin gPackager )
				)
				( attribute "LOCATION" "Q2P1"
					( Origin gFrontEnd )
				)
				( attribute "MATERIAL" "FET"
					( Origin gFrontEnd )
				)
				( attribute "PACK_TYPE" "SOT23LF"
					( Origin gFrontEnd )
				)
				( attribute "PART_NUMBER" "C79254-001"
					( Origin gFrontEnd )
				)
				( attribute "PHYS_PAGE" "170"
					( Origin gFrontEnd )
				)
				( attribute "ROOM" "PROC_SIDEBAND"
					( Origin gFrontEnd )
				)
				( attribute "ROT" "0"
					( Origin gFrontEnd )
				)
				( attribute "SEC" "1"
					( Origin gFrontEnd )
				)
				( attribute "SEC_TYPE" "SOT23LF"
					( Origin gFrontEnd )
				)
				( attribute "VALUE" "2N7002"
					( Origin gFrontEnd )
				)
				( attribute "VER" "8"
					( Origin gFrontEnd )
				)
				( attribute "XY" "(-4150,4225)"
					( Origin gFrontEnd )
				)
				( attribute "CHIPS_PART_NAME" "FET_N"
					( Origin gPackager )
				)
				( attribute "CDS_PART_NAME" "FET_N_SOT23LF-2N7002,FET,C7925A"
					( Origin gPackager )
				)
				( objectStatus "Q2P1" )
			)
			( gate "@baseboard_fab2_lib.baseboard_fab2(sch_1):page170_i61"
				( attribute "BOM_COST" "PROC_SIDEBAND"
					( Origin gFrontEnd )
				)
				( attribute "CDS_LIB" "mstr_discrete"
					( Origin gPackager )
				)
				( attribute "CDS_LOCATION" "R2P13"
					( Origin gPackager )
				)
				( attribute "CDS_SEC" "1"
					( Origin gPackager )
				)
				( attribute "LOCATION" "R2P13"
					( Origin gFrontEnd )
				)
				( attribute "MATERIAL" "CHIP"
					( Origin gFrontEnd )
				)
				( attribute "PACK_TYPE" "0402"
					( Origin gFrontEnd )
				)
				( attribute "PART_NUMBER" "G21796-072"
					( Origin gFrontEnd )
				)
				( attribute "PHYS_PAGE" "170"
					( Origin gFrontEnd )
				)
				( attribute "ROOM" "PROC_SIDEBAND"
					( Origin gFrontEnd )
				)
				( attribute "ROT" "0"
					( Origin gFrontEnd )
				)
				( attribute "SEC" "1"
					( Origin gFrontEnd )
				)
				( attribute "SEC_TYPE" "0402"
					( Origin gFrontEnd )
				)
				( attribute "TOLERANCE" "1%"
					( Origin gFrontEnd )
				)
				( attribute "VALUE" "4.75K"
					( Origin gFrontEnd )
				)
				( attribute "VER" "2"
					( Origin gFrontEnd )
				)
				( attribute "WATTAGE" "1/16W"
					( Origin gFrontEnd )
				)
				( attribute "XY" "(-4600,4350)"
					( Origin gFrontEnd )
				)
				( attribute "CHIPS_PART_NAME" "RES"
					( Origin gPackager )
				)
				( attribute "CDS_PART_NAME" "RES_0402-4.75K,1%,1/16W,CHIP,GA"
					( Origin gPackager )
				)
				( objectStatus "R2P13" )
			)
			( gate "@baseboard_fab2_lib.baseboard_fab2(sch_1):page170_i63"
				( attribute "BOM_COST" "PROC_SIDEBAND"
					( Origin gFrontEnd )
				)
				( attribute "CDS_LIB" "mstr_discrete"
					( Origin gPackager )
				)
				( attribute "CDS_LOCATION" "R2P11"
					( Origin gPackager )
				)
				( attribute "LOCATION" "R2P11"
					( Origin gFrontEnd )
				)
				( attribute "MATERIAL" "EMPTY"
					( Origin gFrontEnd )
				)
				( attribute "PACK_TYPE" "0402"
					( Origin gFrontEnd )
				)
				( attribute "PART_NUMBER" "G21796-026"
					( Origin gFrontEnd )
				)
				( attribute "PHYS_PAGE" "170"
					( Origin gFrontEnd )
				)
				( attribute "ROOM" "PROC_SIDEBAND"
					( Origin gFrontEnd )
				)
				( attribute "ROT" "0"
					( Origin gFrontEnd )
				)
				( attribute "SEC" "1"
					( Origin gFrontEnd )
				)
				( attribute "TOLERANCE" "1%"
					( Origin gFrontEnd )
				)
				( attribute "VALUE" "1.00K"
					( Origin gFrontEnd )
				)
				( attribute "VER" "2"
					( Origin gFrontEnd )
				)
				( attribute "WATTAGE" "1/16W"
					( Origin gFrontEnd )
				)
				( attribute "XY" "(-4525,3925)"
					( Origin gFrontEnd )
				)
				( attribute "CHIPS_PART_NAME" "RES"
					( Origin gPackager )
				)
				( attribute "CDS_PART_NAME" "RES_0402-1.00K,1%,1/16W,EMPTY,A"
					( Origin gPackager )
				)
				( attribute "SEC_TYPE" "0402"
					( Origin gFrontEnd )
				)
				( attribute "CDS_SEC" "1"
					( Origin gPackager )
				)
				( objectStatus "R2P11" )
			)
			( gate "@baseboard_fab2_lib.baseboard_fab2(sch_1):page170_i65"
				( attribute "BOM_COST" "PROC_SIDEBAND"
					( Origin gFrontEnd )
				)
				( attribute "CDS_LIB" "mstr_discrete"
					( Origin gPackager )
				)
				( attribute "CDS_LOCATION" "R9F3"
					( Origin gPackager )
				)
				( attribute "CDS_SEC" "1"
					( Origin gPackager )
				)
				( attribute "LOCATION" "R9F3"
					( Origin gFrontEnd )
				)
				( attribute "MATERIAL" "CHIP"
					( Origin gFrontEnd )
				)
				( attribute "PACK_TYPE" "0402"
					( Origin gFrontEnd )
				)
				( attribute "PART_NUMBER" "G21796-072"
					( Origin gFrontEnd )
				)
				( attribute "PHYS_PAGE" "170"
					( Origin gFrontEnd )
				)
				( attribute "ROOM" "PROC_SIDEBAND"
					( Origin gFrontEnd )
				)
				( attribute "ROT" "0"
					( Origin gFrontEnd )
				)
				( attribute "SEC" "1"
					( Origin gFrontEnd )
				)
				( attribute "SEC_TYPE" "0402"
					( Origin gFrontEnd )
				)
				( attribute "TOLERANCE" "1%"
					( Origin gFrontEnd )
				)
				( attribute "VALUE" "4.75K"
					( Origin gFrontEnd )
				)
				( attribute "VER" "2"
					( Origin gFrontEnd )
				)
				( attribute "WATTAGE" "1/16W"
					( Origin gFrontEnd )
				)
				( attribute "XY" "(-2950,2775)"
					( Origin gFrontEnd )
				)
				( attribute "CHIPS_PART_NAME" "RES"
					( Origin gPackager )
				)
				( attribute "CDS_PART_NAME" "RES_0402-4.75K,1%,1/16W,CHIP,GA"
					( Origin gPackager )
				)
				( objectStatus "R9F3" )
			)
			( gate "@baseboard_fab2_lib.baseboard_fab2(sch_1):page170_i67"
				( attribute "BOM_COST" "PROC_SIDEBAND"
					( Origin gFrontEnd )
				)
				( attribute "CDS_LIB" "mstr_discrete"
					( Origin gPackager )
				)
				( attribute "CDS_LOCATION" "Q8F2"
					( Origin gPackager )
				)
				( attribute "CDS_SEC" "1"
					( Origin gPackager )
				)
				( attribute "LOCATION" "Q8F2"
					( Origin gFrontEnd )
				)
				( attribute "MATERIAL" "FET"
					( Origin gFrontEnd )
				)
				( attribute "PACK_TYPE" "SOT23LF"
					( Origin gFrontEnd )
				)
				( attribute "PART_NUMBER" "C79254-001"
					( Origin gFrontEnd )
				)
				( attribute "PHYS_PAGE" "170"
					( Origin gFrontEnd )
				)
				( attribute "ROOM" "PROC_SIDEBAND"
					( Origin gFrontEnd )
				)
				( attribute "ROT" "0"
					( Origin gFrontEnd )
				)
				( attribute "SEC" "1"
					( Origin gFrontEnd )
				)
				( attribute "SEC_TYPE" "SOT23LF"
					( Origin gFrontEnd )
				)
				( attribute "VALUE" "2N7002"
					( Origin gFrontEnd )
				)
				( attribute "VER" "8"
					( Origin gFrontEnd )
				)
				( attribute "XY" "(-2950,1900)"
					( Origin gFrontEnd )
				)
				( attribute "CHIPS_PART_NAME" "FET_N"
					( Origin gPackager )
				)
				( attribute "CDS_PART_NAME" "FET_N_SOT23LF-2N7002,FET,C7925A"
					( Origin gPackager )
				)
				( objectStatus "Q8F2" )
			)
			( gate "@baseboard_fab2_lib.baseboard_fab2(sch_1):page170_i71"
				( attribute "BOM_COST" "FAST_PROCHOT"
					( Origin gFrontEnd )
				)
				( attribute "CDS_LIB" "mstr_discrete"
					( Origin gPackager )
				)
				( attribute "CDS_LOCATION" "R8D26"
					( Origin gPackager )
				)
				( attribute "CDS_SEC" "1"
					( Origin gPackager )
				)
				( attribute "LOCATION" "R8D26"
					( Origin gFrontEnd )
				)
				( attribute "MATERIAL" "CHIP"
					( Origin gFrontEnd )
				)
				( attribute "PACK_TYPE" "0402"
					( Origin gFrontEnd )
				)
				( attribute "PART_NUMBER" "G21796-072"
					( Origin gFrontEnd )
				)
				( attribute "PHYS_PAGE" "170"
					( Origin gFrontEnd )
				)
				( attribute "ROOM" "FAST_PROCHOT"
					( Origin gFrontEnd )
				)
				( attribute "ROT" "0"
					( Origin gFrontEnd )
				)
				( attribute "SEC" "1"
					( Origin gFrontEnd )
				)
				( attribute "SEC_TYPE" "0402"
					( Origin gFrontEnd )
				)
				( attribute "TOLERANCE" "1%"
					( Origin gFrontEnd )
				)
				( attribute "VALUE" "4.75K"
					( Origin gFrontEnd )
				)
				( attribute "VER" "2"
					( Origin gFrontEnd )
				)
				( attribute "WATTAGE" "1/16W"
					( Origin gFrontEnd )
				)
				( attribute "XY" "(-3150,5100)"
					( Origin gFrontEnd )
				)
				( attribute "CHIPS_PART_NAME" "RES"
					( Origin gPackager )
				)
				( attribute "CDS_PART_NAME" "RES_0402-4.75K,1%,1/16W,CHIP,GA"
					( Origin gPackager )
				)
				( objectStatus "R8D26" )
			)
			( gate "@baseboard_fab2_lib.baseboard_fab2(sch_1):page170_i73"
				( attribute "BOM_COST" "FAST_PROCHOT"
					( Origin gFrontEnd )
				)
				( attribute "CDS_LIB" "mstr_discrete"
					( Origin gPackager )
				)
				( attribute "CDS_LOCATION" "R1R5"
					( Origin gPackager )
				)
				( attribute "CDS_SEC" "1"
					( Origin gPackager )
				)
				( attribute "LOCATION" "R1R5"
					( Origin gFrontEnd )
				)
				( attribute "MATERIAL" "CHIP"
					( Origin gFrontEnd )
				)
				( attribute "PACK_TYPE" "0402"
					( Origin gFrontEnd )
				)
				( attribute "PART_NUMBER" "G21796-072"
					( Origin gFrontEnd )
				)
				( attribute "PHYS_PAGE" "170"
					( Origin gFrontEnd )
				)
				( attribute "ROOM" "FAST_PROCHOT"
					( Origin gFrontEnd )
				)
				( attribute "ROT" "0"
					( Origin gFrontEnd )
				)
				( attribute "SEC" "1"
					( Origin gFrontEnd )
				)
				( attribute "SEC_TYPE" "0402"
					( Origin gFrontEnd )
				)
				( attribute "TOLERANCE" "1%"
					( Origin gFrontEnd )
				)
				( attribute "VALUE" "4.75K"
					( Origin gFrontEnd )
				)
				( attribute "VER" "2"
					( Origin gFrontEnd )
				)
				( attribute "WATTAGE" "1/16W"
					( Origin gFrontEnd )
				)
				( attribute "XY" "(-2025,2850)"
					( Origin gFrontEnd )
				)
				( attribute "CHIPS_PART_NAME" "RES"
					( Origin gPackager )
				)
				( attribute "CDS_PART_NAME" "RES_0402-4.75K,1%,1/16W,CHIP,GA"
					( Origin gPackager )
				)
				( objectStatus "R1R5" )
			)
			( gate "@baseboard_fab2_lib.baseboard_fab2(sch_1):page170_i74"
				( attribute "CDS_LIB" "mstr_discrete"
					( Origin gPackager )
				)
				( attribute "CDS_LOCATION" "R2P4"
					( Origin gPackager )
				)
				( attribute "LOCATION" "R2P4"
					( Origin gFrontEnd )
				)
				( attribute "MATERIAL" "CHIP"
					( Origin gFrontEnd )
				)
				( attribute "PACK_TYPE" "0402"
					( Origin gFrontEnd )
				)
				( attribute "PART_NUMBER" "G21796-074"
					( Origin gFrontEnd )
				)
				( attribute "PHYS_PAGE" "170"
					( Origin gFrontEnd )
				)
				( attribute "ROT" "0"
					( Origin gFrontEnd )
				)
				( attribute "SEC" "1"
					( Origin gFrontEnd )
				)
				( attribute "TOLERANCE" "1%"
					( Origin gFrontEnd )
				)
				( attribute "VALUE" "33.2"
					( Origin gFrontEnd )
				)
				( attribute "VER" "1"
					( Origin gFrontEnd )
				)
				( attribute "WATTAGE" "1/16W"
					( Origin gFrontEnd )
				)
				( attribute "XY" "(-1675,4775)"
					( Origin gFrontEnd )
				)
				( attribute "CHIPS_PART_NAME" "RES"
					( Origin gPackager )
				)
				( attribute "CDS_PART_NAME" "RES_0402-33.2,1%,1/16W,CHIP,G2A"
					( Origin gPackager )
				)
				( attribute "SEC_TYPE" "0402"
					( Origin gFrontEnd )
				)
				( attribute "CDS_SEC" "1"
					( Origin gPackager )
				)
				( objectStatus "R2P4" )
			)
			( gate "@baseboard_fab2_lib.baseboard_fab2(sch_1):page172_i5"
				( attribute "CDS_LIB" "dev_discrete"
					( Origin gPackager )
				)
				( attribute "CDS_LOCATION" "C2L49"
					( Origin gPackager )
				)
				( attribute "CDS_SEC" "1"
					( Origin gPackager )
				)
				( attribute "LOCATION" "C2L49"
					( Origin gFrontEnd )
				)
				( attribute "MATERIAL" "X7R"
					( Origin gFrontEnd )
				)
				( attribute "PACK_TYPE" "0402V"
					( Origin gFrontEnd )
				)
				( attribute "PART_NUMBER" "A36096-045"
					( Origin gFrontEnd )
				)
				( attribute "PHYS_PAGE" "172"
					( Origin gFrontEnd )
				)
				( attribute "ROOM" "ST_SATA"
					( Origin gFrontEnd )
				)
				( attribute "ROT" "0"
					( Origin gFrontEnd )
				)
				( attribute "SEC" "1"
					( Origin gFrontEnd )
				)
				( attribute "SEC_TYPE" "0402V"
					( Origin gFrontEnd )
				)
				( attribute "TOLERANCE" "10%"
					( Origin gFrontEnd )
				)
				( attribute "VALUE" "0.01UF"
					( Origin gFrontEnd )
				)
				( attribute "VER" "2"
					( Origin gFrontEnd )
				)
				( attribute "VOLTAGE" "25V"
					( Units "uVoltage" "V" 1.000000)
					( Origin gFrontEnd )
				)
				( attribute "XY" "(1225,2100)"
					( Origin gFrontEnd )
				)
				( attribute "CHIPS_PART_NAME" "CAP_A"
					( Origin gPackager )
				)
				( attribute "CDS_PART_NAME" "CAP_A_0402V-0.01UF,25V,10%,X7RA"
					( Origin gPackager )
				)
				( objectStatus "C2L49" )
			)
			( gate "@baseboard_fab2_lib.baseboard_fab2(sch_1):page172_i6"
				( attribute "CDS_LIB" "dev_discrete"
					( Origin gPackager )
				)
				( attribute "CDS_LOCATION" "C2L52"
					( Origin gPackager )
				)
				( attribute "CDS_SEC" "1"
					( Origin gPackager )
				)
				( attribute "LOCATION" "C2L52"
					( Origin gFrontEnd )
				)
				( attribute "MATERIAL" "X7R"
					( Origin gFrontEnd )
				)
				( attribute "PACK_TYPE" "0402V"
					( Origin gFrontEnd )
				)
				( attribute "PART_NUMBER" "A36096-045"
					( Origin gFrontEnd )
				)
				( attribute "PHYS_PAGE" "172"
					( Origin gFrontEnd )
				)
				( attribute "ROOM" "ST_SATA"
					( Origin gFrontEnd )
				)
				( attribute "ROT" "0"
					( Origin gFrontEnd )
				)
				( attribute "SEC" "1"
					( Origin gFrontEnd )
				)
				( attribute "SEC_TYPE" "0402V"
					( Origin gFrontEnd )
				)
				( attribute "TOLERANCE" "10%"
					( Origin gFrontEnd )
				)
				( attribute "VALUE" "0.01UF"
					( Origin gFrontEnd )
				)
				( attribute "VER" "2"
					( Origin gFrontEnd )
				)
				( attribute "VOLTAGE" "25V"
					( Units "uVoltage" "V" 1.000000)
					( Origin gFrontEnd )
				)
				( attribute "XY" "(0,2300)"
					( Origin gFrontEnd )
				)
				( attribute "CHIPS_PART_NAME" "CAP_A"
					( Origin gPackager )
				)
				( attribute "CDS_PART_NAME" "CAP_A_0402V-0.01UF,25V,10%,X7RA"
					( Origin gPackager )
				)
				( objectStatus "C2L52" )
			)
			( gate "@baseboard_fab2_lib.baseboard_fab2(sch_1):page172_i7"
				( attribute "CDS_LIB" "dev_discrete"
					( Origin gPackager )
				)
				( attribute "CDS_LOCATION" "C2L50"
					( Origin gPackager )
				)
				( attribute "CDS_SEC" "1"
					( Origin gPackager )
				)
				( attribute "LOCATION" "C2L50"
					( Origin gFrontEnd )
				)
				( attribute "MATERIAL" "X7R"
					( Origin gFrontEnd )
				)
				( attribute "PACK_TYPE" "0402V"
					( Origin gFrontEnd )
				)
				( attribute "PART_NUMBER" "A36096-045"
					( Origin gFrontEnd )
				)
				( attribute "PHYS_PAGE" "172"
					( Origin gFrontEnd )
				)
				( attribute "ROOM" "ST_SATA"
					( Origin gFrontEnd )
				)
				( attribute "ROT" "0"
					( Origin gFrontEnd )
				)
				( attribute "SEC" "1"
					( Origin gFrontEnd )
				)
				( attribute "SEC_TYPE" "0402V"
					( Origin gFrontEnd )
				)
				( attribute "TOLERANCE" "10%"
					( Origin gFrontEnd )
				)
				( attribute "VALUE" "0.01UF"
					( Origin gFrontEnd )
				)
				( attribute "VER" "2"
					( Origin gFrontEnd )
				)
				( attribute "VOLTAGE" "25V"
					( Units "uVoltage" "V" 1.000000)
					( Origin gFrontEnd )
				)
				( attribute "XY" "(350,2150)"
					( Origin gFrontEnd )
				)
				( attribute "CHIPS_PART_NAME" "CAP_A"
					( Origin gPackager )
				)
				( attribute "CDS_PART_NAME" "CAP_A_0402V-0.01UF,25V,10%,X7RA"
					( Origin gPackager )
				)
				( objectStatus "C2L50" )
			)
			( gate "@baseboard_fab2_lib.baseboard_fab2(sch_1):page172_i8"
				( attribute "CDS_LIB" "dev_discrete"
					( Origin gPackager )
				)
				( attribute "CDS_LOCATION" "C2L51"
					( Origin gPackager )
				)
				( attribute "CDS_SEC" "1"
					( Origin gPackager )
				)
				( attribute "LOCATION" "C2L51"
					( Origin gFrontEnd )
				)
				( attribute "MATERIAL" "X7R"
					( Origin gFrontEnd )
				)
				( attribute "PACK_TYPE" "0402V"
					( Origin gFrontEnd )
				)
				( attribute "PART_NUMBER" "A36096-045"
					( Origin gFrontEnd )
				)
				( attribute "PHYS_PAGE" "172"
					( Origin gFrontEnd )
				)
				( attribute "ROOM" "ST_SATA"
					( Origin gFrontEnd )
				)
				( attribute "ROT" "0"
					( Origin gFrontEnd )
				)
				( attribute "SEC" "1"
					( Origin gFrontEnd )
				)
				( attribute "SEC_TYPE" "0402V"
					( Origin gFrontEnd )
				)
				( attribute "TOLERANCE" "10%"
					( Origin gFrontEnd )
				)
				( attribute "VALUE" "0.01UF"
					( Origin gFrontEnd )
				)
				( attribute "VER" "2"
					( Origin gFrontEnd )
				)
				( attribute "VOLTAGE" "25V"
					( Units "uVoltage" "V" 1.000000)
					( Origin gFrontEnd )
				)
				( attribute "XY" "(750,2250)"
					( Origin gFrontEnd )
				)
				( attribute "CHIPS_PART_NAME" "CAP_A"
					( Origin gPackager )
				)
				( attribute "CDS_PART_NAME" "CAP_A_0402V-0.01UF,25V,10%,X7RA"
					( Origin gPackager )
				)
				( objectStatus "C2L51" )
			)
			( gate "@baseboard_fab2_lib.baseboard_fab2(sch_1):page172_i36"
				( attribute "CDS_LIB" "mstr_discrete"
					( Origin gPackager )
				)
				( attribute "CDS_LOCATION" "C9B2"
					( Origin gPackager )
				)
				( attribute "CDS_SEC" "1"
					( Origin gPackager )
				)
				( attribute "LOCATION" "C9B2"
					( Origin gFrontEnd )
				)
				( attribute "MATERIAL" "X6S"
					( Origin gFrontEnd )
				)
				( attribute "PACK_TYPE" "0805"
					( Origin gFrontEnd )
				)
				( attribute "PART_NUMBER" "C95333-007"
					( Origin gFrontEnd )
				)
				( attribute "PHYS_PAGE" "172"
					( Origin gFrontEnd )
				)
				( attribute "ROOM" "ST_SATA"
					( Origin gFrontEnd )
				)
				( attribute "ROT" "0"
					( Origin gFrontEnd )
				)
				( attribute "SEC" "1"
					( Origin gFrontEnd )
				)
				( attribute "SEC_TYPE" "0805"
					( Origin gFrontEnd )
				)
				( attribute "TOLERANCE" "10%"
					( Origin gFrontEnd )
				)
				( attribute "VALUE" "10UF"
					( Origin gFrontEnd )
				)
				( attribute "VER" "1"
					( Origin gFrontEnd )
				)
				( attribute "VOLTAGE" "16V"
					( Units "uVoltage" "V" 1.000000)
					( Origin gFrontEnd )
				)
				( attribute "XY" "(-650,250)"
					( Origin gFrontEnd )
				)
				( attribute "CHIPS_PART_NAME" "CAP"
					( Origin gPackager )
				)
				( attribute "CDS_PART_NAME" "CAP_0805-10UF,16V,10%,X6S,C953A"
					( Origin gPackager )
				)
				( objectStatus "C9B2" )
			)
			( gate "@baseboard_fab2_lib.baseboard_fab2(sch_1):page172_i39"
				( attribute "CDS_LIB" "mstr_discrete"
					( Origin gPackager )
				)
				( attribute "CDS_LOCATION" "C9B1"
					( Origin gPackager )
				)
				( attribute "CDS_SEC" "1"
					( Origin gPackager )
				)
				( attribute "LOCATION" "C9B1"
					( Origin gFrontEnd )
				)
				( attribute "MATERIAL" "X6S"
					( Origin gFrontEnd )
				)
				( attribute "PACK_TYPE" "0805"
					( Origin gFrontEnd )
				)
				( attribute "PART_NUMBER" "C95333-007"
					( Origin gFrontEnd )
				)
				( attribute "PHYS_PAGE" "172"
					( Origin gFrontEnd )
				)
				( attribute "ROOM" "ST_SATA"
					( Origin gFrontEnd )
				)
				( attribute "ROT" "0"
					( Origin gFrontEnd )
				)
				( attribute "SEC" "1"
					( Origin gFrontEnd )
				)
				( attribute "SEC_TYPE" "0805"
					( Origin gFrontEnd )
				)
				( attribute "TOLERANCE" "10%"
					( Origin gFrontEnd )
				)
				( attribute "VALUE" "10UF"
					( Origin gFrontEnd )
				)
				( attribute "VER" "1"
					( Origin gFrontEnd )
				)
				( attribute "VOLTAGE" "16V"
					( Units "uVoltage" "V" 1.000000)
					( Origin gFrontEnd )
				)
				( attribute "XY" "(-1050,250)"
					( Origin gFrontEnd )
				)
				( attribute "CHIPS_PART_NAME" "CAP"
					( Origin gPackager )
				)
				( attribute "CDS_PART_NAME" "CAP_0805-10UF,16V,10%,X6S,C953A"
					( Origin gPackager )
				)
				( objectStatus "C9B1" )
			)
			( gate "@baseboard_fab2_lib.baseboard_fab2(sch_1):page150_i191"
				( attribute "BOM_COST" "SM_CONTROLLER"
					( Origin gFrontEnd )
				)
				( attribute "CDS_LIB" "mstr_discrete"
					( Origin gPackager )
				)
				( attribute "CDS_LOCATION" "R25W108"
					( Origin gPackager )
				)
				( attribute "CDS_SEC" "1"
					( Origin gPackager )
				)
				( attribute "LOCATION" "R25W108"
					( Origin gFrontEnd )
				)
				( attribute "MATERIAL" "EMPTY"
					( Origin gFrontEnd )
				)
				( attribute "PACK_TYPE" "0402"
					( Origin gFrontEnd )
				)
				( attribute "PART_NUMBER" "G21796-072"
					( Origin gFrontEnd )
				)
				( attribute "PHYS_PAGE" "150"
					( Origin gFrontEnd )
				)
				( attribute "ROOM" "BMC"
					( Origin gFrontEnd )
				)
				( attribute "ROT" "0"
					( Origin gFrontEnd )
				)
				( attribute "SEC" "1"
					( Origin gFrontEnd )
				)
				( attribute "SEC_TYPE" "0402"
					( Origin gFrontEnd )
				)
				( attribute "TOLERANCE" "1%"
					( Origin gFrontEnd )
				)
				( attribute "VALUE" "4.75K"
					( Origin gFrontEnd )
				)
				( attribute "VER" "1"
					( Origin gFrontEnd )
				)
				( attribute "WATTAGE" "1/16W"
					( Origin gFrontEnd )
				)
				( attribute "XY" "(-600,-2100)"
					( Origin gFrontEnd )
				)
				( attribute "CHIPS_PART_NAME" "RES"
					( Origin gPackager )
				)
				( attribute "CDS_PART_NAME" "RES_0402-4.75K,1%,1/16W,EMPTY,A"
					( Origin gPackager )
				)
				( objectStatus "R25W108" )
			)
			( gate "@baseboard_fab2_lib.baseboard_fab2(sch_1):page150_i189"
				( attribute "BOM_COST" "NT_GBE_BASE"
					( Origin gFrontEnd )
				)
				( attribute "CDS_LIB" "mstr_discrete"
					( Origin gPackager )
				)
				( attribute "CDS_LOCATION" "R25W116"
					( Origin gPackager )
				)
				( attribute "LOCATION" "R25W116"
					( Origin gFrontEnd )
				)
				( attribute "MATERIAL" "EMPTY"
					( Origin gFrontEnd )
				)
				( attribute "PACK_TYPE" "0402"
					( Origin gFrontEnd )
				)
				( attribute "PART_NUMBER" "G21796-027"
					( Origin gFrontEnd )
				)
				( attribute "PHYS_PAGE" "150"
					( Origin gFrontEnd )
				)
				( attribute "ROOM" "NIC_SPRV"
					( Origin gFrontEnd )
				)
				( attribute "ROT" "1"
					( Origin gFrontEnd )
				)
				( attribute "SEC" "1"
					( Origin gFrontEnd )
				)
				( attribute "SEC_TYPE" "0402"
					( Origin gFrontEnd )
				)
				( attribute "TOLERANCE" "1%"
					( Origin gFrontEnd )
				)
				( attribute "VALUE" "3.32K"
					( Origin gFrontEnd )
				)
				( attribute "VER" "2"
					( Origin gFrontEnd )
				)
				( attribute "WATTAGE" "1/16W"
					( Origin gFrontEnd )
				)
				( attribute "XY" "(-600,-850)"
					( Origin gFrontEnd )
				)
				( attribute "CHIPS_PART_NAME" "RES"
					( Origin gPackager )
				)
				( attribute "CDS_PART_NAME" "RES_0402-3.32K,1%,1/16W,EMPTY,A"
					( Origin gPackager )
				)
				( attribute "CDS_SEC" "1"
					( Origin gPackager )
				)
				( objectStatus "R25W116" )
			)
			( gate "@baseboard_fab2_lib.baseboard_fab2(sch_1):page173_i163"
				( attribute "BOM_COST" "ST_SATA"
					( Origin gFrontEnd )
				)
				( attribute "CDS_LIB" "mstr_conn"
					( Origin gPackager )
				)
				( attribute "CDS_LOCATION" "J8A1"
					( Origin gPackager )
				)
				( attribute "CDS_SEC" "1"
					( Origin gPackager )
				)
				( attribute "LOCATION" "J8A1"
					( Origin gFrontEnd )
				)
				( attribute "MATERIAL" "CONN"
					( Origin gFrontEnd )
				)
				( attribute "PACK_TYPE" "CP"
					( Origin gFrontEnd )
				)
				( attribute "PART_NUMBER" "G97614-002"
					( Origin gFrontEnd )
				)
				( attribute "PHYS_PAGE" "173"
					( Origin gFrontEnd )
				)
				( attribute "ROOM" "ST_SATA"
					( Origin gFrontEnd )
				)
				( attribute "ROT" "0"
					( Origin gFrontEnd )
				)
				( attribute "SEC" "1"
					( Origin gFrontEnd )
				)
				( attribute "SEC_TYPE" "CP"
					( Origin gFrontEnd )
				)
				( attribute "VER" "1"
					( Origin gFrontEnd )
				)
				( attribute "XY" "(-2025,3100)"
					( Origin gFrontEnd )
				)
				( attribute "CHIPS_PART_NAME" "CONN72_G97614002_A"
					( Origin gPackager )
				)
				( attribute "CDS_PART_NAME" "CONN72_G97614002_A_CP-CONN,G97A"
					( Origin gPackager )
				)
				( objectStatus "J8A1" )
			)
			( gate "@baseboard_fab2_lib.baseboard_fab2(sch_1):page173_i165"
				( attribute "BOM_COST" "ST_SATA"
					( Origin gFrontEnd )
				)
				( attribute "CDS_LIB" "dev_discrete"
					( Origin gPackager )
				)
				( attribute "CDS_LOCATION" "C2L13"
					( Origin gPackager )
				)
				( attribute "CDS_SEC" "1"
					( Origin gPackager )
				)
				( attribute "LOCATION" "C2L13"
					( Origin gFrontEnd )
				)
				( attribute "MATERIAL" "X7R"
					( Origin gFrontEnd )
				)
				( attribute "PACK_TYPE" "0402V"
					( Origin gFrontEnd )
				)
				( attribute "PART_NUMBER" "A36096-045"
					( Origin gFrontEnd )
				)
				( attribute "PHYS_PAGE" "173"
					( Origin gFrontEnd )
				)
				( attribute "ROOM" "ST_SATA"
					( Origin gFrontEnd )
				)
				( attribute "ROT" "0"
					( Origin gFrontEnd )
				)
				( attribute "SEC" "1"
					( Origin gFrontEnd )
				)
				( attribute "SEC_TYPE" "0402V"
					( Origin gFrontEnd )
				)
				( attribute "TOLERANCE" "10%"
					( Origin gFrontEnd )
				)
				( attribute "VALUE" "0.01UF"
					( Origin gFrontEnd )
				)
				( attribute "VER" "2"
					( Origin gFrontEnd )
				)
				( attribute "VOLTAGE" "25V"
					( Units "uVoltage" "V" 1.000000)
					( Origin gFrontEnd )
				)
				( attribute "XY" "(-4900,3550)"
					( Origin gFrontEnd )
				)
				( attribute "CHIPS_PART_NAME" "CAP_A"
					( Origin gPackager )
				)
				( attribute "CDS_PART_NAME" "CAP_A_0402V-0.01UF,25V,10%,X7RA"
					( Origin gPackager )
				)
				( objectStatus "C2L13" )
			)
			( gate "@baseboard_fab2_lib.baseboard_fab2(sch_1):page173_i166"
				( attribute "BOM_COST" "ST_SATA"
					( Origin gFrontEnd )
				)
				( attribute "CDS_LIB" "dev_discrete"
					( Origin gPackager )
				)
				( attribute "CDS_LOCATION" "C2L6"
					( Origin gPackager )
				)
				( attribute "CDS_SEC" "1"
					( Origin gPackager )
				)
				( attribute "LOCATION" "C2L6"
					( Origin gFrontEnd )
				)
				( attribute "MATERIAL" "X7R"
					( Origin gFrontEnd )
				)
				( attribute "PACK_TYPE" "0402V"
					( Origin gFrontEnd )
				)
				( attribute "PART_NUMBER" "A36096-045"
					( Origin gFrontEnd )
				)
				( attribute "PHYS_PAGE" "173"
					( Origin gFrontEnd )
				)
				( attribute "ROOM" "ST_SATA"
					( Origin gFrontEnd )
				)
				( attribute "ROT" "0"
					( Origin gFrontEnd )
				)
				( attribute "SEC" "1"
					( Origin gFrontEnd )
				)
				( attribute "SEC_TYPE" "0402V"
					( Origin gFrontEnd )
				)
				( attribute "TOLERANCE" "10%"
					( Origin gFrontEnd )
				)
				( attribute "VALUE" "0.01UF"
					( Origin gFrontEnd )
				)
				( attribute "VER" "2"
					( Origin gFrontEnd )
				)
				( attribute "VOLTAGE" "25V"
					( Units "uVoltage" "V" 1.000000)
					( Origin gFrontEnd )
				)
				( attribute "XY" "(-4850,4050)"
					( Origin gFrontEnd )
				)
				( attribute "CHIPS_PART_NAME" "CAP_A"
					( Origin gPackager )
				)
				( attribute "CDS_PART_NAME" "CAP_A_0402V-0.01UF,25V,10%,X7RA"
					( Origin gPackager )
				)
				( objectStatus "C2L6" )
			)
			( gate "@baseboard_fab2_lib.baseboard_fab2(sch_1):page173_i172"
				( attribute "BOM_COST" "ST_SATA"
					( Origin gFrontEnd )
				)
				( attribute "CDS_LIB" "dev_discrete"
					( Origin gPackager )
				)
				( attribute "CDS_LOCATION" "C2L19"
					( Origin gPackager )
				)
				( attribute "CDS_SEC" "1"
					( Origin gPackager )
				)
				( attribute "LOCATION" "C2L19"
					( Origin gFrontEnd )
				)
				( attribute "MATERIAL" "X7R"
					( Origin gFrontEnd )
				)
				( attribute "PACK_TYPE" "0402V"
					( Origin gFrontEnd )
				)
				( attribute "PART_NUMBER" "A36096-045"
					( Origin gFrontEnd )
				)
				( attribute "PHYS_PAGE" "173"
					( Origin gFrontEnd )
				)
				( attribute "ROOM" "ST_SATA"
					( Origin gFrontEnd )
				)
				( attribute "ROT" "0"
					( Origin gFrontEnd )
				)
				( attribute "SEC" "1"
					( Origin gFrontEnd )
				)
				( attribute "SEC_TYPE" "0402V"
					( Origin gFrontEnd )
				)
				( attribute "TOLERANCE" "10%"
					( Origin gFrontEnd )
				)
				( attribute "VALUE" "0.01UF"
					( Origin gFrontEnd )
				)
				( attribute "VER" "2"
					( Origin gFrontEnd )
				)
				( attribute "VOLTAGE" "25V"
					( Units "uVoltage" "V" 1.000000)
					( Origin gFrontEnd )
				)
				( attribute "XY" "(-4575,4550)"
					( Origin gFrontEnd )
				)
				( attribute "CHIPS_PART_NAME" "CAP_A"
					( Origin gPackager )
				)
				( attribute "CDS_PART_NAME" "CAP_A_0402V-0.01UF,25V,10%,X7RA"
					( Origin gPackager )
				)
				( objectStatus "C2L19" )
			)
			( gate "@baseboard_fab2_lib.baseboard_fab2(sch_1):page173_i173"
				( attribute "BOM_COST" "ST_SATA"
					( Origin gFrontEnd )
				)
				( attribute "CDS_LIB" "dev_discrete"
					( Origin gPackager )
				)
				( attribute "CDS_LOCATION" "C2L10"
					( Origin gPackager )
				)
				( attribute "CDS_SEC" "1"
					( Origin gPackager )
				)
				( attribute "LOCATION" "C2L10"
					( Origin gFrontEnd )
				)
				( attribute "MATERIAL" "X7R"
					( Origin gFrontEnd )
				)
				( attribute "PACK_TYPE" "0402V"
					( Origin gFrontEnd )
				)
				( attribute "PART_NUMBER" "A36096-045"
					( Origin gFrontEnd )
				)
				( attribute "PHYS_PAGE" "173"
					( Origin gFrontEnd )
				)
				( attribute "ROOM" "ST_SATA"
					( Origin gFrontEnd )
				)
				( attribute "ROT" "0"
					( Origin gFrontEnd )
				)
				( attribute "SEC" "1"
					( Origin gFrontEnd )
				)
				( attribute "SEC_TYPE" "0402V"
					( Origin gFrontEnd )
				)
				( attribute "TOLERANCE" "10%"
					( Origin gFrontEnd )
				)
				( attribute "VALUE" "0.01UF"
					( Origin gFrontEnd )
				)
				( attribute "VER" "2"
					( Origin gFrontEnd )
				)
				( attribute "VOLTAGE" "25V"
					( Units "uVoltage" "V" 1.000000)
					( Origin gFrontEnd )
				)
				( attribute "XY" "(-4575,4200)"
					( Origin gFrontEnd )
				)
				( attribute "CHIPS_PART_NAME" "CAP_A"
					( Origin gPackager )
				)
				( attribute "CDS_PART_NAME" "CAP_A_0402V-0.01UF,25V,10%,X7RA"
					( Origin gPackager )
				)
				( objectStatus "C2L10" )
			)
			( gate "@baseboard_fab2_lib.baseboard_fab2(sch_1):page173_i174"
				( attribute "BOM_COST" "ST_SATA"
					( Origin gFrontEnd )
				)
				( attribute "CDS_LIB" "dev_discrete"
					( Origin gPackager )
				)
				( attribute "CDS_LOCATION" "C2L17"
					( Origin gPackager )
				)
				( attribute "CDS_SEC" "1"
					( Origin gPackager )
				)
				( attribute "LOCATION" "C2L17"
					( Origin gFrontEnd )
				)
				( attribute "MATERIAL" "X7R"
					( Origin gFrontEnd )
				)
				( attribute "PACK_TYPE" "0402V"
					( Origin gFrontEnd )
				)
				( attribute "PART_NUMBER" "A36096-045"
					( Origin gFrontEnd )
				)
				( attribute "PHYS_PAGE" "173"
					( Origin gFrontEnd )
				)
				( attribute "ROOM" "ST_SATA"
					( Origin gFrontEnd )
				)
				( attribute "ROT" "0"
					( Origin gFrontEnd )
				)
				( attribute "SEC" "1"
					( Origin gFrontEnd )
				)
				( attribute "SEC_TYPE" "0402V"
					( Origin gFrontEnd )
				)
				( attribute "TOLERANCE" "10%"
					( Origin gFrontEnd )
				)
				( attribute "VALUE" "0.01UF"
					( Origin gFrontEnd )
				)
				( attribute "VER" "2"
					( Origin gFrontEnd )
				)
				( attribute "VOLTAGE" "25V"
					( Units "uVoltage" "V" 1.000000)
					( Origin gFrontEnd )
				)
				( attribute "XY" "(-4850,4400)"
					( Origin gFrontEnd )
				)
				( attribute "CHIPS_PART_NAME" "CAP_A"
					( Origin gPackager )
				)
				( attribute "CDS_PART_NAME" "CAP_A_0402V-0.01UF,25V,10%,X7RA"
					( Origin gPackager )
				)
				( objectStatus "C2L17" )
			)
			( gate "@baseboard_fab2_lib.baseboard_fab2(sch_1):page173_i191"
				( attribute "BOM_COST" "ST_SATA"
					( Origin gFrontEnd )
				)
				( attribute "CDS_LIB" "dev_discrete"
					( Origin gPackager )
				)
				( attribute "CDS_LOCATION" "C2L15"
					( Origin gPackager )
				)
				( attribute "CDS_SEC" "1"
					( Origin gPackager )
				)
				( attribute "LOCATION" "C2L15"
					( Origin gFrontEnd )
				)
				( attribute "MATERIAL" "X7R"
					( Origin gFrontEnd )
				)
				( attribute "PACK_TYPE" "0402V"
					( Origin gFrontEnd )
				)
				( attribute "PART_NUMBER" "A36096-045"
					( Origin gFrontEnd )
				)
				( attribute "PHYS_PAGE" "173"
					( Origin gFrontEnd )
				)
				( attribute "ROOM" "ST_SATA"
					( Origin gFrontEnd )
				)
				( attribute "ROT" "0"
					( Origin gFrontEnd )
				)
				( attribute "SEC" "1"
					( Origin gFrontEnd )
				)
				( attribute "SEC_TYPE" "0402V"
					( Origin gFrontEnd )
				)
				( attribute "TOLERANCE" "10%"
					( Origin gFrontEnd )
				)
				( attribute "VALUE" "0.01UF"
					( Origin gFrontEnd )
				)
				( attribute "VER" "2"
					( Origin gFrontEnd )
				)
				( attribute "VOLTAGE" "25V"
					( Units "uVoltage" "V" 1.000000)
					( Origin gFrontEnd )
				)
				( attribute "XY" "(-4575,3700)"
					( Origin gFrontEnd )
				)
				( attribute "CHIPS_PART_NAME" "CAP_A"
					( Origin gPackager )
				)
				( attribute "CDS_PART_NAME" "CAP_A_0402V-0.01UF,25V,10%,X7RA"
					( Origin gPackager )
				)
				( objectStatus "C2L15" )
			)
			( gate "@baseboard_fab2_lib.baseboard_fab2(sch_1):page173_i192"
				( attribute "BOM_COST" "ST_SATA"
					( Origin gFrontEnd )
				)
				( attribute "CDS_LIB" "dev_discrete"
					( Origin gPackager )
				)
				( attribute "CDS_LOCATION" "C2L4"
					( Origin gPackager )
				)
				( attribute "CDS_SEC" "1"
					( Origin gPackager )
				)
				( attribute "LOCATION" "C2L4"
					( Origin gFrontEnd )
				)
				( attribute "MATERIAL" "X7R"
					( Origin gFrontEnd )
				)
				( attribute "PACK_TYPE" "0402V"
					( Origin gFrontEnd )
				)
				( attribute "PART_NUMBER" "A36096-045"
					( Origin gFrontEnd )
				)
				( attribute "PHYS_PAGE" "173"
					( Origin gFrontEnd )
				)
				( attribute "ROOM" "ST_SATA"
					( Origin gFrontEnd )
				)
				( attribute "ROT" "0"
					( Origin gFrontEnd )
				)
				( attribute "SEC" "1"
					( Origin gFrontEnd )
				)
				( attribute "SEC_TYPE" "0402V"
					( Origin gFrontEnd )
				)
				( attribute "TOLERANCE" "10%"
					( Origin gFrontEnd )
				)
				( attribute "VALUE" "0.01UF"
					( Origin gFrontEnd )
				)
				( attribute "VER" "2"
					( Origin gFrontEnd )
				)
				( attribute "VOLTAGE" "25V"
					( Units "uVoltage" "V" 1.000000)
					( Origin gFrontEnd )
				)
				( attribute "XY" "(-4575,3350)"
					( Origin gFrontEnd )
				)
				( attribute "CHIPS_PART_NAME" "CAP_A"
					( Origin gPackager )
				)
				( attribute "CDS_PART_NAME" "CAP_A_0402V-0.01UF,25V,10%,X7RA"
					( Origin gPackager )
				)
				( objectStatus "C2L4" )
			)
			( gate "@baseboard_fab2_lib.baseboard_fab2(sch_1):page173_i194"
				( attribute "BOM_COST" "ST_SATA"
					( Origin gFrontEnd )
				)
				( attribute "CDS_LIB" "dev_discrete"
					( Origin gPackager )
				)
				( attribute "CDS_LOCATION" "C2L3"
					( Origin gPackager )
				)
				( attribute "CDS_SEC" "1"
					( Origin gPackager )
				)
				( attribute "LOCATION" "C2L3"
					( Origin gFrontEnd )
				)
				( attribute "MATERIAL" "X7R"
					( Origin gFrontEnd )
				)
				( attribute "PACK_TYPE" "0402V"
					( Origin gFrontEnd )
				)
				( attribute "PART_NUMBER" "A36096-045"
					( Origin gFrontEnd )
				)
				( attribute "PHYS_PAGE" "173"
					( Origin gFrontEnd )
				)
				( attribute "ROOM" "ST_SATA"
					( Origin gFrontEnd )
				)
				( attribute "ROT" "0"
					( Origin gFrontEnd )
				)
				( attribute "SEC" "1"
					( Origin gFrontEnd )
				)
				( attribute "SEC_TYPE" "0402V"
					( Origin gFrontEnd )
				)
				( attribute "TOLERANCE" "10%"
					( Origin gFrontEnd )
				)
				( attribute "VALUE" "0.01UF"
					( Origin gFrontEnd )
				)
				( attribute "VER" "2"
					( Origin gFrontEnd )
				)
				( attribute "VOLTAGE" "25V"
					( Units "uVoltage" "V" 1.000000)
					( Origin gFrontEnd )
				)
				( attribute "XY" "(-4900,3200)"
					( Origin gFrontEnd )
				)
				( attribute "CHIPS_PART_NAME" "CAP_A"
					( Origin gPackager )
				)
				( attribute "CDS_PART_NAME" "CAP_A_0402V-0.01UF,25V,10%,X7RA"
					( Origin gPackager )
				)
				( objectStatus "C2L3" )
			)
			( gate "@baseboard_fab2_lib.baseboard_fab2(sch_1):page173_i195"
				( attribute "BOM_COST" "ST_SATA"
					( Origin gFrontEnd )
				)
				( attribute "CDS_LIB" "dev_discrete"
					( Origin gPackager )
				)
				( attribute "CDS_LOCATION" "C2L20"
					( Origin gPackager )
				)
				( attribute "CDS_SEC" "1"
					( Origin gPackager )
				)
				( attribute "LOCATION" "C2L20"
					( Origin gFrontEnd )
				)
				( attribute "MATERIAL" "X7R"
					( Origin gFrontEnd )
				)
				( attribute "PACK_TYPE" "0402V"
					( Origin gFrontEnd )
				)
				( attribute "PART_NUMBER" "A36096-045"
					( Origin gFrontEnd )
				)
				( attribute "PHYS_PAGE" "173"
					( Origin gFrontEnd )
				)
				( attribute "ROOM" "ST_SATA"
					( Origin gFrontEnd )
				)
				( attribute "ROT" "0"
					( Origin gFrontEnd )
				)
				( attribute "SEC" "1"
					( Origin gFrontEnd )
				)
				( attribute "SEC_TYPE" "0402V"
					( Origin gFrontEnd )
				)
				( attribute "TOLERANCE" "10%"
					( Origin gFrontEnd )
				)
				( attribute "VALUE" "0.01UF"
					( Origin gFrontEnd )
				)
				( attribute "VER" "2"
					( Origin gFrontEnd )
				)
				( attribute "VOLTAGE" "25V"
					( Units "uVoltage" "V" 1.000000)
					( Origin gFrontEnd )
				)
				( attribute "XY" "(-4600,2900)"
					( Origin gFrontEnd )
				)
				( attribute "CHIPS_PART_NAME" "CAP_A"
					( Origin gPackager )
				)
				( attribute "CDS_PART_NAME" "CAP_A_0402V-0.01UF,25V,10%,X7RA"
					( Origin gPackager )
				)
				( objectStatus "C2L20" )
			)
			( gate "@baseboard_fab2_lib.baseboard_fab2(sch_1):page173_i196"
				( attribute "BOM_COST" "ST_SATA"
					( Origin gFrontEnd )
				)
				( attribute "CDS_LIB" "dev_discrete"
					( Origin gPackager )
				)
				( attribute "CDS_LOCATION" "C2L12"
					( Origin gPackager )
				)
				( attribute "CDS_SEC" "1"
					( Origin gPackager )
				)
				( attribute "LOCATION" "C2L12"
					( Origin gFrontEnd )
				)
				( attribute "MATERIAL" "X7R"
					( Origin gFrontEnd )
				)
				( attribute "PACK_TYPE" "0402V"
					( Origin gFrontEnd )
				)
				( attribute "PART_NUMBER" "A36096-045"
					( Origin gFrontEnd )
				)
				( attribute "PHYS_PAGE" "173"
					( Origin gFrontEnd )
				)
				( attribute "ROOM" "ST_SATA"
					( Origin gFrontEnd )
				)
				( attribute "ROT" "0"
					( Origin gFrontEnd )
				)
				( attribute "SEC" "1"
					( Origin gFrontEnd )
				)
				( attribute "SEC_TYPE" "0402V"
					( Origin gFrontEnd )
				)
				( attribute "TOLERANCE" "10%"
					( Origin gFrontEnd )
				)
				( attribute "VALUE" "0.01UF"
					( Origin gFrontEnd )
				)
				( attribute "VER" "2"
					( Origin gFrontEnd )
				)
				( attribute "VOLTAGE" "25V"
					( Units "uVoltage" "V" 1.000000)
					( Origin gFrontEnd )
				)
				( attribute "XY" "(-4575,2550)"
					( Origin gFrontEnd )
				)
				( attribute "CHIPS_PART_NAME" "CAP_A"
					( Origin gPackager )
				)
				( attribute "CDS_PART_NAME" "CAP_A_0402V-0.01UF,25V,10%,X7RA"
					( Origin gPackager )
				)
				( objectStatus "C2L12" )
			)
			( gate "@baseboard_fab2_lib.baseboard_fab2(sch_1):page173_i197"
				( attribute "BOM_COST" "ST_SATA"
					( Origin gFrontEnd )
				)
				( attribute "CDS_LIB" "dev_discrete"
					( Origin gPackager )
				)
				( attribute "CDS_LOCATION" "C2L18"
					( Origin gPackager )
				)
				( attribute "CDS_SEC" "1"
					( Origin gPackager )
				)
				( attribute "LOCATION" "C2L18"
					( Origin gFrontEnd )
				)
				( attribute "MATERIAL" "X7R"
					( Origin gFrontEnd )
				)
				( attribute "PACK_TYPE" "0402V"
					( Origin gFrontEnd )
				)
				( attribute "PART_NUMBER" "A36096-045"
					( Origin gFrontEnd )
				)
				( attribute "PHYS_PAGE" "173"
					( Origin gFrontEnd )
				)
				( attribute "ROOM" "ST_SATA"
					( Origin gFrontEnd )
				)
				( attribute "ROT" "0"
					( Origin gFrontEnd )
				)
				( attribute "SEC" "1"
					( Origin gFrontEnd )
				)
				( attribute "SEC_TYPE" "0402V"
					( Origin gFrontEnd )
				)
				( attribute "TOLERANCE" "10%"
					( Origin gFrontEnd )
				)
				( attribute "VALUE" "0.01UF"
					( Origin gFrontEnd )
				)
				( attribute "VER" "2"
					( Origin gFrontEnd )
				)
				( attribute "VOLTAGE" "25V"
					( Units "uVoltage" "V" 1.000000)
					( Origin gFrontEnd )
				)
				( attribute "XY" "(-4950,2750)"
					( Origin gFrontEnd )
				)
				( attribute "CHIPS_PART_NAME" "CAP_A"
					( Origin gPackager )
				)
				( attribute "CDS_PART_NAME" "CAP_A_0402V-0.01UF,25V,10%,X7RA"
					( Origin gPackager )
				)
				( objectStatus "C2L18" )
			)
			( gate "@baseboard_fab2_lib.baseboard_fab2(sch_1):page173_i205"
				( attribute "BOM_COST" "ST_SATA"
					( Origin gFrontEnd )
				)
				( attribute "CDS_LIB" "dev_discrete"
					( Origin gPackager )
				)
				( attribute "CDS_LOCATION" "C2L16"
					( Origin gPackager )
				)
				( attribute "CDS_SEC" "1"
					( Origin gPackager )
				)
				( attribute "LOCATION" "C2L16"
					( Origin gFrontEnd )
				)
				( attribute "MATERIAL" "X7R"
					( Origin gFrontEnd )
				)
				( attribute "PACK_TYPE" "0402V"
					( Origin gFrontEnd )
				)
				( attribute "PART_NUMBER" "A36096-045"
					( Origin gFrontEnd )
				)
				( attribute "PHYS_PAGE" "173"
					( Origin gFrontEnd )
				)
				( attribute "ROOM" "ST_SATA"
					( Origin gFrontEnd )
				)
				( attribute "ROT" "0"
					( Origin gFrontEnd )
				)
				( attribute "SEC" "1"
					( Origin gFrontEnd )
				)
				( attribute "SEC_TYPE" "0402V"
					( Origin gFrontEnd )
				)
				( attribute "TOLERANCE" "10%"
					( Origin gFrontEnd )
				)
				( attribute "VALUE" "0.01UF"
					( Origin gFrontEnd )
				)
				( attribute "VER" "2"
					( Origin gFrontEnd )
				)
				( attribute "VOLTAGE" "25V"
					( Units "uVoltage" "V" 1.000000)
					( Origin gFrontEnd )
				)
				( attribute "XY" "(-4575,2050)"
					( Origin gFrontEnd )
				)
				( attribute "CHIPS_PART_NAME" "CAP_A"
					( Origin gPackager )
				)
				( attribute "CDS_PART_NAME" "CAP_A_0402V-0.01UF,25V,10%,X7RA"
					( Origin gPackager )
				)
				( objectStatus "C2L16" )
			)
			( gate "@baseboard_fab2_lib.baseboard_fab2(sch_1):page173_i206"
				( attribute "BOM_COST" "ST_SATA"
					( Origin gFrontEnd )
				)
				( attribute "CDS_LIB" "dev_discrete"
					( Origin gPackager )
				)
				( attribute "CDS_LOCATION" "C2L7"
					( Origin gPackager )
				)
				( attribute "CDS_SEC" "1"
					( Origin gPackager )
				)
				( attribute "LOCATION" "C2L7"
					( Origin gFrontEnd )
				)
				( attribute "MATERIAL" "X7R"
					( Origin gFrontEnd )
				)
				( attribute "PACK_TYPE" "0402V"
					( Origin gFrontEnd )
				)
				( attribute "PART_NUMBER" "A36096-045"
					( Origin gFrontEnd )
				)
				( attribute "PHYS_PAGE" "173"
					( Origin gFrontEnd )
				)
				( attribute "ROOM" "ST_SATA"
					( Origin gFrontEnd )
				)
				( attribute "ROT" "0"
					( Origin gFrontEnd )
				)
				( attribute "SEC" "1"
					( Origin gFrontEnd )
				)
				( attribute "SEC_TYPE" "0402V"
					( Origin gFrontEnd )
				)
				( attribute "TOLERANCE" "10%"
					( Origin gFrontEnd )
				)
				( attribute "VALUE" "0.01UF"
					( Origin gFrontEnd )
				)
				( attribute "VER" "2"
					( Origin gFrontEnd )
				)
				( attribute "VOLTAGE" "25V"
					( Units "uVoltage" "V" 1.000000)
					( Origin gFrontEnd )
				)
				( attribute "XY" "(-4575,1700)"
					( Origin gFrontEnd )
				)
				( attribute "CHIPS_PART_NAME" "CAP_A"
					( Origin gPackager )
				)
				( attribute "CDS_PART_NAME" "CAP_A_0402V-0.01UF,25V,10%,X7RA"
					( Origin gPackager )
				)
				( objectStatus "C2L7" )
			)
			( gate "@baseboard_fab2_lib.baseboard_fab2(sch_1):page173_i207"
				( attribute "BOM_COST" "ST_SATA"
					( Origin gFrontEnd )
				)
				( attribute "CDS_LIB" "dev_discrete"
					( Origin gPackager )
				)
				( attribute "CDS_LOCATION" "C2L9"
					( Origin gPackager )
				)
				( attribute "CDS_SEC" "1"
					( Origin gPackager )
				)
				( attribute "LOCATION" "C2L9"
					( Origin gFrontEnd )
				)
				( attribute "MATERIAL" "X7R"
					( Origin gFrontEnd )
				)
				( attribute "PACK_TYPE" "0402V"
					( Origin gFrontEnd )
				)
				( attribute "PART_NUMBER" "A36096-045"
					( Origin gFrontEnd )
				)
				( attribute "PHYS_PAGE" "173"
					( Origin gFrontEnd )
				)
				( attribute "ROOM" "ST_SATA"
					( Origin gFrontEnd )
				)
				( attribute "ROT" "0"
					( Origin gFrontEnd )
				)
				( attribute "SEC" "1"
					( Origin gFrontEnd )
				)
				( attribute "SEC_TYPE" "0402V"
					( Origin gFrontEnd )
				)
				( attribute "TOLERANCE" "10%"
					( Origin gFrontEnd )
				)
				( attribute "VALUE" "0.01UF"
					( Origin gFrontEnd )
				)
				( attribute "VER" "2"
					( Origin gFrontEnd )
				)
				( attribute "VOLTAGE" "25V"
					( Units "uVoltage" "V" 1.000000)
					( Origin gFrontEnd )
				)
				( attribute "XY" "(-4950,2400)"
					( Origin gFrontEnd )
				)
				( attribute "CHIPS_PART_NAME" "CAP_A"
					( Origin gPackager )
				)
				( attribute "CDS_PART_NAME" "CAP_A_0402V-0.01UF,25V,10%,X7RA"
					( Origin gPackager )
				)
				( objectStatus "C2L9" )
			)
			( gate "@baseboard_fab2_lib.baseboard_fab2(sch_1):page173_i208"
				( attribute "BOM_COST" "ST_SATA"
					( Origin gFrontEnd )
				)
				( attribute "CDS_LIB" "dev_discrete"
					( Origin gPackager )
				)
				( attribute "CDS_LOCATION" "C2L14"
					( Origin gPackager )
				)
				( attribute "CDS_SEC" "1"
					( Origin gPackager )
				)
				( attribute "LOCATION" "C2L14"
					( Origin gFrontEnd )
				)
				( attribute "MATERIAL" "X7R"
					( Origin gFrontEnd )
				)
				( attribute "PACK_TYPE" "0402V"
					( Origin gFrontEnd )
				)
				( attribute "PART_NUMBER" "A36096-045"
					( Origin gFrontEnd )
				)
				( attribute "PHYS_PAGE" "173"
					( Origin gFrontEnd )
				)
				( attribute "ROOM" "ST_SATA"
					( Origin gFrontEnd )
				)
				( attribute "ROT" "0"
					( Origin gFrontEnd )
				)
				( attribute "SEC" "1"
					( Origin gFrontEnd )
				)
				( attribute "SEC_TYPE" "0402V"
					( Origin gFrontEnd )
				)
				( attribute "TOLERANCE" "10%"
					( Origin gFrontEnd )
				)
				( attribute "VALUE" "0.01UF"
					( Origin gFrontEnd )
				)
				( attribute "VER" "2"
					( Origin gFrontEnd )
				)
				( attribute "VOLTAGE" "25V"
					( Units "uVoltage" "V" 1.000000)
					( Origin gFrontEnd )
				)
				( attribute "XY" "(-4975,1850)"
					( Origin gFrontEnd )
				)
				( attribute "CHIPS_PART_NAME" "CAP_A"
					( Origin gPackager )
				)
				( attribute "CDS_PART_NAME" "CAP_A_0402V-0.01UF,25V,10%,X7RA"
					( Origin gPackager )
				)
				( objectStatus "C2L14" )
			)
			( gate "@baseboard_fab2_lib.baseboard_fab2(sch_1):page173_i209"
				( attribute "BOM_COST" "ST_SATA"
					( Origin gFrontEnd )
				)
				( attribute "CDS_LIB" "dev_discrete"
					( Origin gPackager )
				)
				( attribute "CDS_LOCATION" "C2L5"
					( Origin gPackager )
				)
				( attribute "CDS_SEC" "1"
					( Origin gPackager )
				)
				( attribute "LOCATION" "C2L5"
					( Origin gFrontEnd )
				)
				( attribute "MATERIAL" "X7R"
					( Origin gFrontEnd )
				)
				( attribute "PACK_TYPE" "0402V"
					( Origin gFrontEnd )
				)
				( attribute "PART_NUMBER" "A36096-045"
					( Origin gFrontEnd )
				)
				( attribute "PHYS_PAGE" "173"
					( Origin gFrontEnd )
				)
				( attribute "ROOM" "ST_SATA"
					( Origin gFrontEnd )
				)
				( attribute "ROT" "0"
					( Origin gFrontEnd )
				)
				( attribute "SEC" "1"
					( Origin gFrontEnd )
				)
				( attribute "SEC_TYPE" "0402V"
					( Origin gFrontEnd )
				)
				( attribute "TOLERANCE" "10%"
					( Origin gFrontEnd )
				)
				( attribute "VALUE" "0.01UF"
					( Origin gFrontEnd )
				)
				( attribute "VER" "2"
					( Origin gFrontEnd )
				)
				( attribute "VOLTAGE" "25V"
					( Units "uVoltage" "V" 1.000000)
					( Origin gFrontEnd )
				)
				( attribute "XY" "(-4975,1500)"
					( Origin gFrontEnd )
				)
				( attribute "CHIPS_PART_NAME" "CAP_A"
					( Origin gPackager )
				)
				( attribute "CDS_PART_NAME" "CAP_A_0402V-0.01UF,25V,10%,X7RA"
					( Origin gPackager )
				)
				( objectStatus "C2L5" )
			)
			( gate "@baseboard_fab2_lib.baseboard_fab2(sch_1):page173_i220"
				( attribute "BOM_COST" "ST_SATA"
					( Origin gFrontEnd )
				)
				( attribute "CDS_LIB" "dev_discrete"
					( Origin gPackager )
				)
				( attribute "CDS_LOCATION" "C2L40"
					( Origin gPackager )
				)
				( attribute "CDS_SEC" "1"
					( Origin gPackager )
				)
				( attribute "LOCATION" "C2L40"
					( Origin gFrontEnd )
				)
				( attribute "MATERIAL" "X7R"
					( Origin gFrontEnd )
				)
				( attribute "PACK_TYPE" "0402V"
					( Origin gFrontEnd )
				)
				( attribute "PART_NUMBER" "A36096-045"
					( Origin gFrontEnd )
				)
				( attribute "PHYS_PAGE" "173"
					( Origin gFrontEnd )
				)
				( attribute "ROOM" "ST_SATA"
					( Origin gFrontEnd )
				)
				( attribute "ROT" "0"
					( Origin gFrontEnd )
				)
				( attribute "SEC" "1"
					( Origin gFrontEnd )
				)
				( attribute "SEC_TYPE" "0402V"
					( Origin gFrontEnd )
				)
				( attribute "TOLERANCE" "10%"
					( Origin gFrontEnd )
				)
				( attribute "VALUE" "0.01UF"
					( Origin gFrontEnd )
				)
				( attribute "VER" "2"
					( Origin gFrontEnd )
				)
				( attribute "VOLTAGE" "25V"
					( Units "uVoltage" "V" 1.000000)
					( Origin gFrontEnd )
				)
				( attribute "XY" "(1025,4525)"
					( Origin gFrontEnd )
				)
				( attribute "CHIPS_PART_NAME" "CAP_A"
					( Origin gPackager )
				)
				( attribute "CDS_PART_NAME" "CAP_A_0402V-0.01UF,25V,10%,X7RA"
					( Origin gPackager )
				)
				( objectStatus "C2L40" )
			)
			( gate "@baseboard_fab2_lib.baseboard_fab2(sch_1):page173_i221"
				( attribute "BOM_COST" "ST_SATA"
					( Origin gFrontEnd )
				)
				( attribute "CDS_LIB" "dev_discrete"
					( Origin gPackager )
				)
				( attribute "CDS_LOCATION" "C2L39"
					( Origin gPackager )
				)
				( attribute "CDS_SEC" "1"
					( Origin gPackager )
				)
				( attribute "LOCATION" "C2L39"
					( Origin gFrontEnd )
				)
				( attribute "MATERIAL" "X7R"
					( Origin gFrontEnd )
				)
				( attribute "PACK_TYPE" "0402V"
					( Origin gFrontEnd )
				)
				( attribute "PART_NUMBER" "A36096-045"
					( Origin gFrontEnd )
				)
				( attribute "PHYS_PAGE" "173"
					( Origin gFrontEnd )
				)
				( attribute "ROOM" "ST_SATA"
					( Origin gFrontEnd )
				)
				( attribute "ROT" "0"
					( Origin gFrontEnd )
				)
				( attribute "SEC" "1"
					( Origin gFrontEnd )
				)
				( attribute "SEC_TYPE" "0402V"
					( Origin gFrontEnd )
				)
				( attribute "TOLERANCE" "10%"
					( Origin gFrontEnd )
				)
				( attribute "VALUE" "0.01UF"
					( Origin gFrontEnd )
				)
				( attribute "VER" "2"
					( Origin gFrontEnd )
				)
				( attribute "VOLTAGE" "25V"
					( Units "uVoltage" "V" 1.000000)
					( Origin gFrontEnd )
				)
				( attribute "XY" "(650,4675)"
					( Origin gFrontEnd )
				)
				( attribute "CHIPS_PART_NAME" "CAP_A"
					( Origin gPackager )
				)
				( attribute "CDS_PART_NAME" "CAP_A_0402V-0.01UF,25V,10%,X7RA"
					( Origin gPackager )
				)
				( objectStatus "C2L39" )
			)
			( gate "@baseboard_fab2_lib.baseboard_fab2(sch_1):page173_i222"
				( attribute "BOM_COST" "ST_SATA"
					( Origin gFrontEnd )
				)
				( attribute "CDS_LIB" "dev_discrete"
					( Origin gPackager )
				)
				( attribute "CDS_LOCATION" "C2L43"
					( Origin gPackager )
				)
				( attribute "CDS_SEC" "1"
					( Origin gPackager )
				)
				( attribute "LOCATION" "C2L43"
					( Origin gFrontEnd )
				)
				( attribute "MATERIAL" "X7R"
					( Origin gFrontEnd )
				)
				( attribute "PACK_TYPE" "0402V"
					( Origin gFrontEnd )
				)
				( attribute "PART_NUMBER" "A36096-045"
					( Origin gFrontEnd )
				)
				( attribute "PHYS_PAGE" "173"
					( Origin gFrontEnd )
				)
				( attribute "ROOM" "ST_SATA"
					( Origin gFrontEnd )
				)
				( attribute "ROT" "0"
					( Origin gFrontEnd )
				)
				( attribute "SEC" "1"
					( Origin gFrontEnd )
				)
				( attribute "SEC_TYPE" "0402V"
					( Origin gFrontEnd )
				)
				( attribute "TOLERANCE" "10%"
					( Origin gFrontEnd )
				)
				( attribute "VALUE" "0.01UF"
					( Origin gFrontEnd )
				)
				( attribute "VER" "2"
					( Origin gFrontEnd )
				)
				( attribute "VOLTAGE" "25V"
					( Units "uVoltage" "V" 1.000000)
					( Origin gFrontEnd )
				)
				( attribute "XY" "(650,4325)"
					( Origin gFrontEnd )
				)
				( attribute "CHIPS_PART_NAME" "CAP_A"
					( Origin gPackager )
				)
				( attribute "CDS_PART_NAME" "CAP_A_0402V-0.01UF,25V,10%,X7RA"
					( Origin gPackager )
				)
				( objectStatus "C2L43" )
			)
			( gate "@baseboard_fab2_lib.baseboard_fab2(sch_1):page173_i228"
				( attribute "BOM_COST" "ST_SATA"
					( Origin gFrontEnd )
				)
				( attribute "CDS_LIB" "dev_discrete"
					( Origin gPackager )
				)
				( attribute "CDS_LOCATION" "C2L44"
					( Origin gPackager )
				)
				( attribute "CDS_SEC" "1"
					( Origin gPackager )
				)
				( attribute "LOCATION" "C2L44"
					( Origin gFrontEnd )
				)
				( attribute "MATERIAL" "X7R"
					( Origin gFrontEnd )
				)
				( attribute "PACK_TYPE" "0402V"
					( Origin gFrontEnd )
				)
				( attribute "PART_NUMBER" "A36096-045"
					( Origin gFrontEnd )
				)
				( attribute "PHYS_PAGE" "173"
					( Origin gFrontEnd )
				)
				( attribute "ROOM" "ST_SATA"
					( Origin gFrontEnd )
				)
				( attribute "ROT" "0"
					( Origin gFrontEnd )
				)
				( attribute "SEC" "1"
					( Origin gFrontEnd )
				)
				( attribute "SEC_TYPE" "0402V"
					( Origin gFrontEnd )
				)
				( attribute "TOLERANCE" "10%"
					( Origin gFrontEnd )
				)
				( attribute "VALUE" "0.01UF"
					( Origin gFrontEnd )
				)
				( attribute "VER" "2"
					( Origin gFrontEnd )
				)
				( attribute "VOLTAGE" "25V"
					( Units "uVoltage" "V" 1.000000)
					( Origin gFrontEnd )
				)
				( attribute "XY" "(1025,4175)"
					( Origin gFrontEnd )
				)
				( attribute "CHIPS_PART_NAME" "CAP_A"
					( Origin gPackager )
				)
				( attribute "CDS_PART_NAME" "CAP_A_0402V-0.01UF,25V,10%,X7RA"
					( Origin gPackager )
				)
				( objectStatus "C2L44" )
			)
			( gate "@baseboard_fab2_lib.baseboard_fab2(sch_1):page173_i233"
				( attribute "BOM_COST" "ST_SATA"
					( Origin gFrontEnd )
				)
				( attribute "CDS_LIB" "dev_discrete"
					( Origin gPackager )
				)
				( attribute "CDS_LOCATION" "C2L42"
					( Origin gPackager )
				)
				( attribute "CDS_SEC" "1"
					( Origin gPackager )
				)
				( attribute "LOCATION" "C2L42"
					( Origin gFrontEnd )
				)
				( attribute "MATERIAL" "X7R"
					( Origin gFrontEnd )
				)
				( attribute "PACK_TYPE" "0402V"
					( Origin gFrontEnd )
				)
				( attribute "PART_NUMBER" "A36096-045"
					( Origin gFrontEnd )
				)
				( attribute "PHYS_PAGE" "173"
					( Origin gFrontEnd )
				)
				( attribute "ROOM" "ST_SATA"
					( Origin gFrontEnd )
				)
				( attribute "ROT" "0"
					( Origin gFrontEnd )
				)
				( attribute "SEC" "1"
					( Origin gFrontEnd )
				)
				( attribute "SEC_TYPE" "0402V"
					( Origin gFrontEnd )
				)
				( attribute "TOLERANCE" "10%"
					( Origin gFrontEnd )
				)
				( attribute "VALUE" "0.01UF"
					( Origin gFrontEnd )
				)
				( attribute "VER" "2"
					( Origin gFrontEnd )
				)
				( attribute "VOLTAGE" "25V"
					( Units "uVoltage" "V" 1.000000)
					( Origin gFrontEnd )
				)
				( attribute "XY" "(1000,3500)"
					( Origin gFrontEnd )
				)
				( attribute "CHIPS_PART_NAME" "CAP_A"
					( Origin gPackager )
				)
				( attribute "CDS_PART_NAME" "CAP_A_0402V-0.01UF,25V,10%,X7RA"
					( Origin gPackager )
				)
				( objectStatus "C2L42" )
			)
			( gate "@baseboard_fab2_lib.baseboard_fab2(sch_1):page173_i234"
				( attribute "BOM_COST" "ST_SATA"
					( Origin gFrontEnd )
				)
				( attribute "CDS_LIB" "dev_discrete"
					( Origin gPackager )
				)
				( attribute "CDS_LOCATION" "C2L22"
					( Origin gPackager )
				)
				( attribute "CDS_SEC" "1"
					( Origin gPackager )
				)
				( attribute "LOCATION" "C2L22"
					( Origin gFrontEnd )
				)
				( attribute "MATERIAL" "X7R"
					( Origin gFrontEnd )
				)
				( attribute "PACK_TYPE" "0402V"
					( Origin gFrontEnd )
				)
				( attribute "PART_NUMBER" "A36096-045"
					( Origin gFrontEnd )
				)
				( attribute "PHYS_PAGE" "173"
					( Origin gFrontEnd )
				)
				( attribute "ROOM" "ST_SATA"
					( Origin gFrontEnd )
				)
				( attribute "ROT" "0"
					( Origin gFrontEnd )
				)
				( attribute "SEC" "1"
					( Origin gFrontEnd )
				)
				( attribute "SEC_TYPE" "0402V"
					( Origin gFrontEnd )
				)
				( attribute "TOLERANCE" "10%"
					( Origin gFrontEnd )
				)
				( attribute "VALUE" "0.01UF"
					( Origin gFrontEnd )
				)
				( attribute "VER" "2"
					( Origin gFrontEnd )
				)
				( attribute "VOLTAGE" "25V"
					( Units "uVoltage" "V" 1.000000)
					( Origin gFrontEnd )
				)
				( attribute "XY" "(1025,3075)"
					( Origin gFrontEnd )
				)
				( attribute "CHIPS_PART_NAME" "CAP_A"
					( Origin gPackager )
				)
				( attribute "CDS_PART_NAME" "CAP_A_0402V-0.01UF,25V,10%,X7RA"
					( Origin gPackager )
				)
				( objectStatus "C2L22" )
			)
			( gate "@baseboard_fab2_lib.baseboard_fab2(sch_1):page173_i238"
				( attribute "BOM_COST" "ST_SATA"
					( Origin gFrontEnd )
				)
				( attribute "CDS_LIB" "dev_discrete"
					( Origin gPackager )
				)
				( attribute "CDS_LOCATION" "C2L37"
					( Origin gPackager )
				)
				( attribute "CDS_SEC" "1"
					( Origin gPackager )
				)
				( attribute "LOCATION" "C2L37"
					( Origin gFrontEnd )
				)
				( attribute "MATERIAL" "X7R"
					( Origin gFrontEnd )
				)
				( attribute "PACK_TYPE" "0402V"
					( Origin gFrontEnd )
				)
				( attribute "PART_NUMBER" "A36096-045"
					( Origin gFrontEnd )
				)
				( attribute "PHYS_PAGE" "173"
					( Origin gFrontEnd )
				)
				( attribute "ROOM" "ST_SATA"
					( Origin gFrontEnd )
				)
				( attribute "ROT" "0"
					( Origin gFrontEnd )
				)
				( attribute "SEC" "1"
					( Origin gFrontEnd )
				)
				( attribute "SEC_TYPE" "0402V"
					( Origin gFrontEnd )
				)
				( attribute "TOLERANCE" "10%"
					( Origin gFrontEnd )
				)
				( attribute "VALUE" "0.01UF"
					( Origin gFrontEnd )
				)
				( attribute "VER" "2"
					( Origin gFrontEnd )
				)
				( attribute "VOLTAGE" "25V"
					( Units "uVoltage" "V" 1.000000)
					( Origin gFrontEnd )
				)
				( attribute "XY" "(1025,2725)"
					( Origin gFrontEnd )
				)
				( attribute "CHIPS_PART_NAME" "CAP_A"
					( Origin gPackager )
				)
				( attribute "CDS_PART_NAME" "CAP_A_0402V-0.01UF,25V,10%,X7RA"
					( Origin gPackager )
				)
				( objectStatus "C2L37" )
			)
			( gate "@baseboard_fab2_lib.baseboard_fab2(sch_1):page173_i239"
				( attribute "BOM_COST" "ST_SATA"
					( Origin gFrontEnd )
				)
				( attribute "CDS_LIB" "dev_discrete"
					( Origin gPackager )
				)
				( attribute "CDS_LOCATION" "C2L47"
					( Origin gPackager )
				)
				( attribute "CDS_SEC" "1"
					( Origin gPackager )
				)
				( attribute "LOCATION" "C2L47"
					( Origin gFrontEnd )
				)
				( attribute "MATERIAL" "X7R"
					( Origin gFrontEnd )
				)
				( attribute "PACK_TYPE" "0402V"
					( Origin gFrontEnd )
				)
				( attribute "PART_NUMBER" "A36096-045"
					( Origin gFrontEnd )
				)
				( attribute "PHYS_PAGE" "173"
					( Origin gFrontEnd )
				)
				( attribute "ROOM" "ST_SATA"
					( Origin gFrontEnd )
				)
				( attribute "ROT" "0"
					( Origin gFrontEnd )
				)
				( attribute "SEC" "1"
					( Origin gFrontEnd )
				)
				( attribute "SEC_TYPE" "0402V"
					( Origin gFrontEnd )
				)
				( attribute "TOLERANCE" "10%"
					( Origin gFrontEnd )
				)
				( attribute "VALUE" "0.01UF"
					( Origin gFrontEnd )
				)
				( attribute "VER" "2"
					( Origin gFrontEnd )
				)
				( attribute "VOLTAGE" "25V"
					( Units "uVoltage" "V" 1.000000)
					( Origin gFrontEnd )
				)
				( attribute "XY" "(650,2925)"
					( Origin gFrontEnd )
				)
				( attribute "CHIPS_PART_NAME" "CAP_A"
					( Origin gPackager )
				)
				( attribute "CDS_PART_NAME" "CAP_A_0402V-0.01UF,25V,10%,X7RA"
					( Origin gPackager )
				)
				( objectStatus "C2L47" )
			)
			( gate "@baseboard_fab2_lib.baseboard_fab2(sch_1):page173_i240"
				( attribute "BOM_COST" "ST_SATA"
					( Origin gFrontEnd )
				)
				( attribute "CDS_LIB" "dev_discrete"
					( Origin gPackager )
				)
				( attribute "CDS_LOCATION" "C2L27"
					( Origin gPackager )
				)
				( attribute "CDS_SEC" "1"
					( Origin gPackager )
				)
				( attribute "LOCATION" "C2L27"
					( Origin gFrontEnd )
				)
				( attribute "MATERIAL" "X7R"
					( Origin gFrontEnd )
				)
				( attribute "PACK_TYPE" "0402V"
					( Origin gFrontEnd )
				)
				( attribute "PART_NUMBER" "A36096-045"
					( Origin gFrontEnd )
				)
				( attribute "PHYS_PAGE" "173"
					( Origin gFrontEnd )
				)
				( attribute "ROOM" "ST_SATA"
					( Origin gFrontEnd )
				)
				( attribute "ROT" "0"
					( Origin gFrontEnd )
				)
				( attribute "SEC" "1"
					( Origin gFrontEnd )
				)
				( attribute "SEC_TYPE" "0402V"
					( Origin gFrontEnd )
				)
				( attribute "TOLERANCE" "10%"
					( Origin gFrontEnd )
				)
				( attribute "VALUE" "0.01UF"
					( Origin gFrontEnd )
				)
				( attribute "VER" "2"
					( Origin gFrontEnd )
				)
				( attribute "VOLTAGE" "25V"
					( Units "uVoltage" "V" 1.000000)
					( Origin gFrontEnd )
				)
				( attribute "XY" "(650,2500)"
					( Origin gFrontEnd )
				)
				( attribute "CHIPS_PART_NAME" "CAP_A"
					( Origin gPackager )
				)
				( attribute "CDS_PART_NAME" "CAP_A_0402V-0.01UF,25V,10%,X7RA"
					( Origin gPackager )
				)
				( objectStatus "C2L27" )
			)
			( gate "@baseboard_fab2_lib.baseboard_fab2(sch_1):page173_i241"
				( attribute "BOM_COST" "ST_SATA"
					( Origin gFrontEnd )
				)
				( attribute "CDS_LIB" "dev_discrete"
					( Origin gPackager )
				)
				( attribute "CDS_LOCATION" "C2L23"
					( Origin gPackager )
				)
				( attribute "CDS_SEC" "1"
					( Origin gPackager )
				)
				( attribute "LOCATION" "C2L23"
					( Origin gFrontEnd )
				)
				( attribute "MATERIAL" "X7R"
					( Origin gFrontEnd )
				)
				( attribute "PACK_TYPE" "0402V"
					( Origin gFrontEnd )
				)
				( attribute "PART_NUMBER" "A36096-045"
					( Origin gFrontEnd )
				)
				( attribute "PHYS_PAGE" "173"
					( Origin gFrontEnd )
				)
				( attribute "ROOM" "ST_SATA"
					( Origin gFrontEnd )
				)
				( attribute "ROT" "0"
					( Origin gFrontEnd )
				)
				( attribute "SEC" "1"
					( Origin gFrontEnd )
				)
				( attribute "SEC_TYPE" "0402V"
					( Origin gFrontEnd )
				)
				( attribute "TOLERANCE" "10%"
					( Origin gFrontEnd )
				)
				( attribute "VALUE" "0.01UF"
					( Origin gFrontEnd )
				)
				( attribute "VER" "2"
					( Origin gFrontEnd )
				)
				( attribute "VOLTAGE" "25V"
					( Units "uVoltage" "V" 1.000000)
					( Origin gFrontEnd )
				)
				( attribute "XY" "(625,3300)"
					( Origin gFrontEnd )
				)
				( attribute "CHIPS_PART_NAME" "CAP_A"
					( Origin gPackager )
				)
				( attribute "CDS_PART_NAME" "CAP_A_0402V-0.01UF,25V,10%,X7RA"
					( Origin gPackager )
				)
				( objectStatus "C2L23" )
			)
			( gate "@baseboard_fab2_lib.baseboard_fab2(sch_1):page173_i242"
				( attribute "BOM_COST" "ST_SATA"
					( Origin gFrontEnd )
				)
				( attribute "CDS_LIB" "dev_discrete"
					( Origin gPackager )
				)
				( attribute "CDS_LOCATION" "C2L41"
					( Origin gPackager )
				)
				( attribute "CDS_SEC" "1"
					( Origin gPackager )
				)
				( attribute "LOCATION" "C2L41"
					( Origin gFrontEnd )
				)
				( attribute "MATERIAL" "X7R"
					( Origin gFrontEnd )
				)
				( attribute "PACK_TYPE" "0402V"
					( Origin gFrontEnd )
				)
				( attribute "PART_NUMBER" "A36096-045"
					( Origin gFrontEnd )
				)
				( attribute "PHYS_PAGE" "173"
					( Origin gFrontEnd )
				)
				( attribute "ROOM" "ST_SATA"
					( Origin gFrontEnd )
				)
				( attribute "ROT" "0"
					( Origin gFrontEnd )
				)
				( attribute "SEC" "1"
					( Origin gFrontEnd )
				)
				( attribute "SEC_TYPE" "0402V"
					( Origin gFrontEnd )
				)
				( attribute "TOLERANCE" "10%"
					( Origin gFrontEnd )
				)
				( attribute "VALUE" "0.01UF"
					( Origin gFrontEnd )
				)
				( attribute "VER" "2"
					( Origin gFrontEnd )
				)
				( attribute "VOLTAGE" "25V"
					( Units "uVoltage" "V" 1.000000)
					( Origin gFrontEnd )
				)
				( attribute "XY" "(625,3650)"
					( Origin gFrontEnd )
				)
				( attribute "CHIPS_PART_NAME" "CAP_A"
					( Origin gPackager )
				)
				( attribute "CDS_PART_NAME" "CAP_A_0402V-0.01UF,25V,10%,X7RA"
					( Origin gPackager )
				)
				( objectStatus "C2L41" )
			)
			( gate "@baseboard_fab2_lib.baseboard_fab2(sch_1):page173_i255"
				( attribute "BOM_COST" "ST_SATA"
					( Origin gFrontEnd )
				)
				( attribute "CDS_LIB" "dev_discrete"
					( Origin gPackager )
				)
				( attribute "CDS_LOCATION" "C2L26"
					( Origin gPackager )
				)
				( attribute "CDS_SEC" "1"
					( Origin gPackager )
				)
				( attribute "LOCATION" "C2L26"
					( Origin gFrontEnd )
				)
				( attribute "MATERIAL" "X7R"
					( Origin gFrontEnd )
				)
				( attribute "PACK_TYPE" "0402V"
					( Origin gFrontEnd )
				)
				( attribute "PART_NUMBER" "A36096-045"
					( Origin gFrontEnd )
				)
				( attribute "PHYS_PAGE" "173"
					( Origin gFrontEnd )
				)
				( attribute "ROOM" "ST_SATA"
					( Origin gFrontEnd )
				)
				( attribute "ROT" "0"
					( Origin gFrontEnd )
				)
				( attribute "SEC" "1"
					( Origin gFrontEnd )
				)
				( attribute "SEC_TYPE" "0402V"
					( Origin gFrontEnd )
				)
				( attribute "TOLERANCE" "10%"
					( Origin gFrontEnd )
				)
				( attribute "VALUE" "0.01UF"
					( Origin gFrontEnd )
				)
				( attribute "VER" "2"
					( Origin gFrontEnd )
				)
				( attribute "VOLTAGE" "25V"
					( Units "uVoltage" "V" 1.000000)
					( Origin gFrontEnd )
				)
				( attribute "XY" "(1025,2350)"
					( Origin gFrontEnd )
				)
				( attribute "CHIPS_PART_NAME" "CAP_A"
					( Origin gPackager )
				)
				( attribute "CDS_PART_NAME" "CAP_A_0402V-0.01UF,25V,10%,X7RA"
					( Origin gPackager )
				)
				( objectStatus "C2L26" )
			)
			( gate "@baseboard_fab2_lib.baseboard_fab2(sch_1):page173_i256"
				( attribute "BOM_COST" "ST_SATA"
					( Origin gFrontEnd )
				)
				( attribute "CDS_LIB" "dev_discrete"
					( Origin gPackager )
				)
				( attribute "CDS_LOCATION" "C2L38"
					( Origin gPackager )
				)
				( attribute "CDS_SEC" "1"
					( Origin gPackager )
				)
				( attribute "LOCATION" "C2L38"
					( Origin gFrontEnd )
				)
				( attribute "MATERIAL" "X7R"
					( Origin gFrontEnd )
				)
				( attribute "PACK_TYPE" "0402V"
					( Origin gFrontEnd )
				)
				( attribute "PART_NUMBER" "A36096-045"
					( Origin gFrontEnd )
				)
				( attribute "PHYS_PAGE" "173"
					( Origin gFrontEnd )
				)
				( attribute "ROOM" "ST_SATA"
					( Origin gFrontEnd )
				)
				( attribute "ROT" "0"
					( Origin gFrontEnd )
				)
				( attribute "SEC" "1"
					( Origin gFrontEnd )
				)
				( attribute "SEC_TYPE" "0402V"
					( Origin gFrontEnd )
				)
				( attribute "TOLERANCE" "10%"
					( Origin gFrontEnd )
				)
				( attribute "VALUE" "0.01UF"
					( Origin gFrontEnd )
				)
				( attribute "VER" "2"
					( Origin gFrontEnd )
				)
				( attribute "VOLTAGE" "25V"
					( Units "uVoltage" "V" 1.000000)
					( Origin gFrontEnd )
				)
				( attribute "XY" "(1050,1900)"
					( Origin gFrontEnd )
				)
				( attribute "CHIPS_PART_NAME" "CAP_A"
					( Origin gPackager )
				)
				( attribute "CDS_PART_NAME" "CAP_A_0402V-0.01UF,25V,10%,X7RA"
					( Origin gPackager )
				)
				( objectStatus "C2L38" )
			)
			( gate "@baseboard_fab2_lib.baseboard_fab2(sch_1):page173_i257"
				( attribute "BOM_COST" "ST_SATA"
					( Origin gFrontEnd )
				)
				( attribute "CDS_LIB" "dev_discrete"
					( Origin gPackager )
				)
				( attribute "CDS_LOCATION" "C2L48"
					( Origin gPackager )
				)
				( attribute "CDS_SEC" "1"
					( Origin gPackager )
				)
				( attribute "LOCATION" "C2L48"
					( Origin gFrontEnd )
				)
				( attribute "MATERIAL" "X7R"
					( Origin gFrontEnd )
				)
				( attribute "PACK_TYPE" "0402V"
					( Origin gFrontEnd )
				)
				( attribute "PART_NUMBER" "A36096-045"
					( Origin gFrontEnd )
				)
				( attribute "PHYS_PAGE" "173"
					( Origin gFrontEnd )
				)
				( attribute "ROOM" "ST_SATA"
					( Origin gFrontEnd )
				)
				( attribute "ROT" "0"
					( Origin gFrontEnd )
				)
				( attribute "SEC" "1"
					( Origin gFrontEnd )
				)
				( attribute "SEC_TYPE" "0402V"
					( Origin gFrontEnd )
				)
				( attribute "TOLERANCE" "10%"
					( Origin gFrontEnd )
				)
				( attribute "VALUE" "0.01UF"
					( Origin gFrontEnd )
				)
				( attribute "VER" "2"
					( Origin gFrontEnd )
				)
				( attribute "VOLTAGE" "25V"
					( Units "uVoltage" "V" 1.000000)
					( Origin gFrontEnd )
				)
				( attribute "XY" "(650,2050)"
					( Origin gFrontEnd )
				)
				( attribute "CHIPS_PART_NAME" "CAP_A"
					( Origin gPackager )
				)
				( attribute "CDS_PART_NAME" "CAP_A_0402V-0.01UF,25V,10%,X7RA"
					( Origin gPackager )
				)
				( objectStatus "C2L48" )
			)
			( gate "@baseboard_fab2_lib.baseboard_fab2(sch_1):page173_i258"
				( attribute "BOM_COST" "ST_SATA"
					( Origin gFrontEnd )
				)
				( attribute "CDS_LIB" "dev_discrete"
					( Origin gPackager )
				)
				( attribute "CDS_LOCATION" "C2L24"
					( Origin gPackager )
				)
				( attribute "CDS_SEC" "1"
					( Origin gPackager )
				)
				( attribute "LOCATION" "C2L24"
					( Origin gFrontEnd )
				)
				( attribute "MATERIAL" "X7R"
					( Origin gFrontEnd )
				)
				( attribute "PACK_TYPE" "0402V"
					( Origin gFrontEnd )
				)
				( attribute "PART_NUMBER" "A36096-045"
					( Origin gFrontEnd )
				)
				( attribute "PHYS_PAGE" "173"
					( Origin gFrontEnd )
				)
				( attribute "ROOM" "ST_SATA"
					( Origin gFrontEnd )
				)
				( attribute "ROT" "0"
					( Origin gFrontEnd )
				)
				( attribute "SEC" "1"
					( Origin gFrontEnd )
				)
				( attribute "SEC_TYPE" "0402V"
					( Origin gFrontEnd )
				)
				( attribute "TOLERANCE" "10%"
					( Origin gFrontEnd )
				)
				( attribute "VALUE" "0.01UF"
					( Origin gFrontEnd )
				)
				( attribute "VER" "2"
					( Origin gFrontEnd )
				)
				( attribute "VOLTAGE" "25V"
					( Units "uVoltage" "V" 1.000000)
					( Origin gFrontEnd )
				)
				( attribute "XY" "(650,1700)"
					( Origin gFrontEnd )
				)
				( attribute "CHIPS_PART_NAME" "CAP_A"
					( Origin gPackager )
				)
				( attribute "CDS_PART_NAME" "CAP_A_0402V-0.01UF,25V,10%,X7RA"
					( Origin gPackager )
				)
				( objectStatus "C2L24" )
			)
			( gate "@baseboard_fab2_lib.baseboard_fab2(sch_1):page173_i259"
				( attribute "BOM_COST" "ST_SATA"
					( Origin gFrontEnd )
				)
				( attribute "CDS_LIB" "dev_discrete"
					( Origin gPackager )
				)
				( attribute "CDS_LOCATION" "C2L21"
					( Origin gPackager )
				)
				( attribute "CDS_SEC" "1"
					( Origin gPackager )
				)
				( attribute "LOCATION" "C2L21"
					( Origin gFrontEnd )
				)
				( attribute "MATERIAL" "X7R"
					( Origin gFrontEnd )
				)
				( attribute "PACK_TYPE" "0402V"
					( Origin gFrontEnd )
				)
				( attribute "PART_NUMBER" "A36096-045"
					( Origin gFrontEnd )
				)
				( attribute "PHYS_PAGE" "173"
					( Origin gFrontEnd )
				)
				( attribute "ROOM" "ST_SATA"
					( Origin gFrontEnd )
				)
				( attribute "ROT" "0"
					( Origin gFrontEnd )
				)
				( attribute "SEC" "1"
					( Origin gFrontEnd )
				)
				( attribute "SEC_TYPE" "0402V"
					( Origin gFrontEnd )
				)
				( attribute "TOLERANCE" "10%"
					( Origin gFrontEnd )
				)
				( attribute "VALUE" "0.01UF"
					( Origin gFrontEnd )
				)
				( attribute "VER" "2"
					( Origin gFrontEnd )
				)
				( attribute "VOLTAGE" "25V"
					( Units "uVoltage" "V" 1.000000)
					( Origin gFrontEnd )
				)
				( attribute "XY" "(1050,1550)"
					( Origin gFrontEnd )
				)
				( attribute "CHIPS_PART_NAME" "CAP_A"
					( Origin gPackager )
				)
				( attribute "CDS_PART_NAME" "CAP_A_0402V-0.01UF,25V,10%,X7RA"
					( Origin gPackager )
				)
				( objectStatus "C2L21" )
			)
			( gate "@baseboard_fab2_lib.baseboard_fab2(sch_1):page173_i261"
				( attribute "BOM_COST" "ST_SATA"
					( Origin gFrontEnd )
				)
				( attribute "CDS_LIB" "mstr_discrete"
					( Origin gPackager )
				)
				( attribute "CDS_LOCATION" "R2L23"
					( Origin gPackager )
				)
				( attribute "CDS_SEC" "1"
					( Origin gPackager )
				)
				( attribute "LOCATION" "R2L23"
					( Origin gFrontEnd )
				)
				( attribute "MATERIAL" "CHIP"
					( Origin gFrontEnd )
				)
				( attribute "PACK_TYPE" "0402"
					( Origin gFrontEnd )
				)
				( attribute "PART_NUMBER" "G21796-001"
					( Origin gFrontEnd )
				)
				( attribute "PHYS_PAGE" "173"
					( Origin gFrontEnd )
				)
				( attribute "ROOM" "ST_SATA"
					( Origin gFrontEnd )
				)
				( attribute "ROT" "0"
					( Origin gFrontEnd )
				)
				( attribute "SEC" "1"
					( Origin gFrontEnd )
				)
				( attribute "SEC_TYPE" "0402"
					( Origin gFrontEnd )
				)
				( attribute "TOLERANCE" "1%"
					( Origin gFrontEnd )
				)
				( attribute "VALUE" "2.0K"
					( Origin gFrontEnd )
				)
				( attribute "VER" "1"
					( Origin gFrontEnd )
				)
				( attribute "WATTAGE" "1/16W"
					( Origin gFrontEnd )
				)
				( attribute "XY" "(-3900,2200)"
					( Origin gFrontEnd )
				)
				( attribute "CHIPS_PART_NAME" "RES"
					( Origin gPackager )
				)
				( attribute "CDS_PART_NAME" "RES_0402-2.0K,1%,1/16W,CHIP,G2A"
					( Origin gPackager )
				)
				( objectStatus "R2L23" )
			)
			( gate "@baseboard_fab2_lib.baseboard_fab2(sch_1):page173_i263"
				( attribute "BOM_COST" "ST_SATA"
					( Origin gFrontEnd )
				)
				( attribute "CDS_LIB" "mstr_discrete"
					( Origin gPackager )
				)
				( attribute "CDS_LOCATION" "R2L21"
					( Origin gPackager )
				)
				( attribute "CDS_SEC" "1"
					( Origin gPackager )
				)
				( attribute "LOCATION" "R2L21"
					( Origin gFrontEnd )
				)
				( attribute "MATERIAL" "CHIP"
					( Origin gFrontEnd )
				)
				( attribute "PACK_TYPE" "0402"
					( Origin gFrontEnd )
				)
				( attribute "PART_NUMBER" "G21796-001"
					( Origin gFrontEnd )
				)
				( attribute "PHYS_PAGE" "173"
					( Origin gFrontEnd )
				)
				( attribute "ROOM" "ST_SATA"
					( Origin gFrontEnd )
				)
				( attribute "ROT" "0"
					( Origin gFrontEnd )
				)
				( attribute "SEC" "1"
					( Origin gFrontEnd )
				)
				( attribute "SEC_TYPE" "0402"
					( Origin gFrontEnd )
				)
				( attribute "TOLERANCE" "1%"
					( Origin gFrontEnd )
				)
				( attribute "VALUE" "2.0K"
					( Origin gFrontEnd )
				)
				( attribute "VER" "2"
					( Origin gFrontEnd )
				)
				( attribute "WATTAGE" "1/16W"
					( Origin gFrontEnd )
				)
				( attribute "XY" "(-3900,4675)"
					( Origin gFrontEnd )
				)
				( attribute "CHIPS_PART_NAME" "RES"
					( Origin gPackager )
				)
				( attribute "CDS_PART_NAME" "RES_0402-2.0K,1%,1/16W,CHIP,G2A"
					( Origin gPackager )
				)
				( objectStatus "R2L21" )
			)
			( gate "@baseboard_fab2_lib.baseboard_fab2(sch_1):page173_i264"
				( attribute "BOM_COST" "ST_SATA"
					( Origin gFrontEnd )
				)
				( attribute "CDS_LIB" "mstr_discrete"
					( Origin gPackager )
				)
				( attribute "CDS_LOCATION" "R2L22"
					( Origin gPackager )
				)
				( attribute "CDS_SEC" "1"
					( Origin gPackager )
				)
				( attribute "LOCATION" "R2L22"
					( Origin gFrontEnd )
				)
				( attribute "MATERIAL" "CHIP"
					( Origin gFrontEnd )
				)
				( attribute "PACK_TYPE" "0402"
					( Origin gFrontEnd )
				)
				( attribute "PART_NUMBER" "G21796-026"
					( Origin gFrontEnd )
				)
				( attribute "PHYS_PAGE" "173"
					( Origin gFrontEnd )
				)
				( attribute "ROOM" "ST_SATA"
					( Origin gFrontEnd )
				)
				( attribute "ROT" "0"
					( Origin gFrontEnd )
				)
				( attribute "SEC" "1"
					( Origin gFrontEnd )
				)
				( attribute "SEC_TYPE" "0402"
					( Origin gFrontEnd )
				)
				( attribute "TOLERANCE" "1%"
					( Origin gFrontEnd )
				)
				( attribute "VALUE" "1.00K"
					( Origin gFrontEnd )
				)
				( attribute "VER" "2"
					( Origin gFrontEnd )
				)
				( attribute "WATTAGE" "1/16W"
					( Origin gFrontEnd )
				)
				( attribute "XY" "(1625,2000)"
					( Origin gFrontEnd )
				)
				( attribute "CHIPS_PART_NAME" "RES"
					( Origin gPackager )
				)
				( attribute "CDS_PART_NAME" "RES_0402-1.00K,1%,1/16W,CHIP,GA"
					( Origin gPackager )
				)
				( objectStatus "R2L22" )
			)
			( gate "@baseboard_fab2_lib.baseboard_fab2(sch_1):page173_i266"
				( attribute "BOM_COST" "ST_SATA"
					( Origin gFrontEnd )
				)
				( attribute "CDS_LIB" "mstr_discrete"
					( Origin gPackager )
				)
				( attribute "CDS_LOCATION" "R2L18"
					( Origin gPackager )
				)
				( attribute "CDS_SEC" "1"
					( Origin gPackager )
				)
				( attribute "LOCATION" "R2L18"
					( Origin gFrontEnd )
				)
				( attribute "MATERIAL" "CHIP"
					( Origin gFrontEnd )
				)
				( attribute "PACK_TYPE" "0402"
					( Origin gFrontEnd )
				)
				( attribute "PART_NUMBER" "G21796-026"
					( Origin gFrontEnd )
				)
				( attribute "PHYS_PAGE" "173"
					( Origin gFrontEnd )
				)
				( attribute "ROOM" "ST_SATA"
					( Origin gFrontEnd )
				)
				( attribute "ROT" "0"
					( Origin gFrontEnd )
				)
				( attribute "SEC" "1"
					( Origin gFrontEnd )
				)
				( attribute "SEC_TYPE" "0402"
					( Origin gFrontEnd )
				)
				( attribute "TOLERANCE" "1%"
					( Origin gFrontEnd )
				)
				( attribute "VALUE" "1.00K"
					( Origin gFrontEnd )
				)
				( attribute "VER" "2"
					( Origin gFrontEnd )
				)
				( attribute "WATTAGE" "1/16W"
					( Origin gFrontEnd )
				)
				( attribute "XY" "(1675,3500)"
					( Origin gFrontEnd )
				)
				( attribute "CHIPS_PART_NAME" "RES"
					( Origin gPackager )
				)
				( attribute "CDS_PART_NAME" "RES_0402-1.00K,1%,1/16W,CHIP,GA"
					( Origin gPackager )
				)
				( objectStatus "R2L18" )
			)
			( gate "@baseboard_fab2_lib.baseboard_fab2(sch_1):page164_i87"
				( attribute "BOM_COST" "SM_THERM"
					( Origin gFrontEnd )
				)
				( attribute "CDS_LIB" "mstr_discrete"
					( Origin gPackager )
				)
				( attribute "CDS_LOCATION" "R6W41"
					( Origin gPackager )
				)
				( attribute "CDS_SEC" "1"
					( Origin gPackager )
				)
				( attribute "LOCATION" "R6W41"
					( Origin gFrontEnd )
				)
				( attribute "MATERIAL" "CHIP"
					( Origin gFrontEnd )
				)
				( attribute "PACK_TYPE" "0402"
					( Origin gFrontEnd )
				)
				( attribute "PART_NUMBER" "G21796-072"
					( Origin gFrontEnd )
				)
				( attribute "PHYS_PAGE" "164"
					( Origin gFrontEnd )
				)
				( attribute "ROOM" "CPU_FANS"
					( Origin gFrontEnd )
				)
				( attribute "ROT" "2"
					( Origin gFrontEnd )
				)
				( attribute "SEC" "1"
					( Origin gFrontEnd )
				)
				( attribute "SEC_TYPE" "0402"
					( Origin gFrontEnd )
				)
				( attribute "TOLERANCE" "1%"
					( Origin gFrontEnd )
				)
				( attribute "VALUE" "4.75K"
					( Origin gFrontEnd )
				)
				( attribute "VER" "2"
					( Origin gFrontEnd )
				)
				( attribute "WATTAGE" "1/16W"
					( Origin gFrontEnd )
				)
				( attribute "XY" "(-1000,3750)"
					( Origin gFrontEnd )
				)
				( attribute "CHIPS_PART_NAME" "RES"
					( Origin gPackager )
				)
				( attribute "CDS_PART_NAME" "RES_0402-4.75K,1%,1/16W,CHIP,GA"
					( Origin gPackager )
				)
				( objectStatus "R6W41" )
			)
			( gate "@baseboard_fab2_lib.baseboard_fab2(sch_1):page149_i129"
				( attribute "BOM_COST" "PROC_SOCKET"
					( Origin gFrontEnd )
				)
				( attribute "CDS_LIB" "mstr_discrete"
					( Origin gPackager )
				)
				( attribute "CDS_LOCATION" "C25W29"
					( Origin gPackager )
				)
				( attribute "CDS_SEC" "1"
					( Origin gPackager )
				)
				( attribute "LOCATION" "C25W29"
					( Origin gFrontEnd )
				)
				( attribute "MATERIAL" "X6S"
					( Origin gFrontEnd )
				)
				( attribute "PACK_TYPE" "0603LF"
					( Origin gFrontEnd )
				)
				( attribute "PART_NUMBER" "E15431-001"
					( Origin gFrontEnd )
				)
				( attribute "PHYS_PAGE" "149"
					( Origin gFrontEnd )
				)
				( attribute "ROOM" "CPU0"
					( Origin gFrontEnd )
				)
				( attribute "ROT" "0"
					( Origin gFrontEnd )
				)
				( attribute "SEC" "1"
					( Origin gFrontEnd )
				)
				( attribute "SEC_TYPE" "0603LF"
					( Origin gFrontEnd )
				)
				( attribute "TOLERANCE" "20%"
					( Origin gFrontEnd )
				)
				( attribute "VALUE" "10UF"
					( Origin gFrontEnd )
				)
				( attribute "VER" "1"
					( Origin gFrontEnd )
				)
				( attribute "VOLTAGE" "4V"
					( Units "uVoltage" "V" 1.000000)
					( Origin gFrontEnd )
				)
				( attribute "XY" "(150,5400)"
					( Origin gFrontEnd )
				)
				( attribute "CHIPS_PART_NAME" "CAP"
					( Origin gPackager )
				)
				( attribute "CDS_PART_NAME" "CAP_0603LF-10UF,4V,20%,X6S,E15A"
					( Origin gPackager )
				)
				( objectStatus "C25W29" )
			)
			( gate "@baseboard_fab2_lib.baseboard_fab2(sch_1):page164_i78"
				( attribute "BOM_COST" "SM_THERM"
					( Origin gFrontEnd )
				)
				( attribute "CDS_LIB" "mstr_discrete"
					( Origin gPackager )
				)
				( attribute "CDS_LOCATION" "R6W44"
					( Origin gPackager )
				)
				( attribute "CDS_SEC" "1"
					( Origin gPackager )
				)
				( attribute "LOCATION" "R6W44"
					( Origin gFrontEnd )
				)
				( attribute "MATERIAL" "CHIP"
					( Origin gFrontEnd )
				)
				( attribute "PACK_TYPE" "0402"
					( Origin gFrontEnd )
				)
				( attribute "PART_NUMBER" "G21796-072"
					( Origin gFrontEnd )
				)
				( attribute "PHYS_PAGE" "164"
					( Origin gFrontEnd )
				)
				( attribute "ROOM" "CPU_FANS"
					( Origin gFrontEnd )
				)
				( attribute "ROT" "2"
					( Origin gFrontEnd )
				)
				( attribute "SEC" "1"
					( Origin gFrontEnd )
				)
				( attribute "SEC_TYPE" "0402"
					( Origin gFrontEnd )
				)
				( attribute "TOLERANCE" "1%"
					( Origin gFrontEnd )
				)
				( attribute "VALUE" "4.75K"
					( Origin gFrontEnd )
				)
				( attribute "VER" "2"
					( Origin gFrontEnd )
				)
				( attribute "WATTAGE" "1/16W"
					( Origin gFrontEnd )
				)
				( attribute "XY" "(-1650,2350)"
					( Origin gFrontEnd )
				)
				( attribute "CHIPS_PART_NAME" "RES"
					( Origin gPackager )
				)
				( attribute "CDS_PART_NAME" "RES_0402-4.75K,1%,1/16W,CHIP,GA"
					( Origin gPackager )
				)
				( objectStatus "R6W44" )
			)
			( gate "@baseboard_fab2_lib.baseboard_fab2(sch_1):page164_i76"
				( attribute "CDS_LIB" "mstr_discrete"
					( Origin gPackager )
				)
				( attribute "CDS_LOCATION" "R6W47"
					( Origin gPackager )
				)
				( attribute "CDS_SEC" "1"
					( Origin gPackager )
				)
				( attribute "LOCATION" "R6W47"
					( Origin gFrontEnd )
				)
				( attribute "MATERIAL" "EMPTY"
					( Origin gFrontEnd )
				)
				( attribute "NO_XNET_CONNECTION" "1"
					( Origin gFrontEnd )
				)
				( attribute "PACK_TYPE" "0402"
					( Origin gFrontEnd )
				)
				( attribute "PART_NUMBER" "G21796-072"
					( Origin gFrontEnd )
				)
				( attribute "PHYS_PAGE" "164"
					( Origin gFrontEnd )
				)
				( attribute "ROOM" "HOT_SWAP"
					( Origin gFrontEnd )
				)
				( attribute "ROT" "0"
					( Origin gFrontEnd )
				)
				( attribute "SEC" "1"
					( Origin gFrontEnd )
				)
				( attribute "SEC_TYPE" "0402"
					( Origin gFrontEnd )
				)
				( attribute "TOLERANCE" "1%"
					( Origin gFrontEnd )
				)
				( attribute "VALUE" "4.75K"
					( Origin gFrontEnd )
				)
				( attribute "VER" "2"
					( Origin gFrontEnd )
				)
				( attribute "WATTAGE" "1/16W"
					( Origin gFrontEnd )
				)
				( attribute "XY" "(-1650,1800)"
					( Origin gFrontEnd )
				)
				( attribute "CHIPS_PART_NAME" "RES"
					( Origin gPackager )
				)
				( attribute "CDS_PART_NAME" "RES_0402-4.75K,1%,1/16W,EMPTY,A"
					( Origin gPackager )
				)
				( objectStatus "R6W47" )
			)
			( gate "@baseboard_fab2_lib.baseboard_fab2(sch_1):page164_i66"
				( attribute "CDS_LIB" "dev_discrete"
					( Origin gPackager )
				)
				( attribute "CDS_LOCATION" "C6W14"
					( Origin gPackager )
				)
				( attribute "CDS_SEC" "1"
					( Origin gPackager )
				)
				( attribute "LOCATION" "C6W14"
					( Origin gFrontEnd )
				)
				( attribute "MATERIAL" "X7R"
					( Origin gFrontEnd )
				)
				( attribute "PACK_TYPE" "0402V"
					( Origin gFrontEnd )
				)
				( attribute "PART_NUMBER" "A36096-030"
					( Origin gFrontEnd )
				)
				( attribute "PHYS_PAGE" "164"
					( Origin gFrontEnd )
				)
				( attribute "ROOM" "VDDQ_KLM_PWR_VR"
					( Origin gFrontEnd )
				)
				( attribute "ROT" "0"
					( Origin gFrontEnd )
				)
				( attribute "SEC" "1"
					( Origin gFrontEnd )
				)
				( attribute "SEC_TYPE" "0402V"
					( Origin gFrontEnd )
				)
				( attribute "TOLERANCE" "10%"
					( Origin gFrontEnd )
				)
				( attribute "VALUE" "0.1UF"
					( Origin gFrontEnd )
				)
				( attribute "VER" "1"
					( Origin gFrontEnd )
				)
				( attribute "VOLTAGE" "16V"
					( Units "uVoltage" "V" 1.000000)
					( Origin gFrontEnd )
				)
				( attribute "XY" "(-3400,3900)"
					( Origin gFrontEnd )
				)
				( attribute "CHIPS_PART_NAME" "CAP_A"
					( Origin gPackager )
				)
				( attribute "CDS_PART_NAME" "CAP_A_0402V-0.1UF,16V,10%,X7R,A"
					( Origin gPackager )
				)
				( objectStatus "C6W14" )
			)
			( gate "@baseboard_fab2_lib.baseboard_fab2(sch_1):page175_i4"
				( attribute "BOM_COST" "MIO_CHASSIS"
					( Origin gFrontEnd )
				)
				( attribute "CDS_LIB" "mstr_discrete"
					( Origin gPackager )
				)
				( attribute "CDS_LOCATION" "R1L31"
					( Origin gPackager )
				)
				( attribute "CDS_SEC" "1"
					( Origin gPackager )
				)
				( attribute "LOCATION" "R1L31"
					( Origin gFrontEnd )
				)
				( attribute "MATERIAL" "CHIP"
					( Origin gFrontEnd )
				)
				( attribute "PACK_TYPE" "0402"
					( Origin gFrontEnd )
				)
				( attribute "PART_NUMBER" "G21796-004"
					( Origin gFrontEnd )
				)
				( attribute "PHYS_PAGE" "175"
					( Origin gFrontEnd )
				)
				( attribute "ROOM" "MIO_CHASSIS"
					( Origin gFrontEnd )
				)
				( attribute "ROT" "0"
					( Origin gFrontEnd )
				)
				( attribute "SEC" "1"
					( Origin gFrontEnd )
				)
				( attribute "SEC_TYPE" "0402"
					( Origin gFrontEnd )
				)
				( attribute "TOLERANCE" "1%"
					( Origin gFrontEnd )
				)
				( attribute "VALUE" "200.0"
					( Origin gFrontEnd )
				)
				( attribute "VER" "1"
					( Origin gFrontEnd )
				)
				( attribute "WATTAGE" "1/16W"
					( Origin gFrontEnd )
				)
				( attribute "XY" "(-5650,4175)"
					( Origin gFrontEnd )
				)
				( attribute "CHIPS_PART_NAME" "RES"
					( Origin gPackager )
				)
				( attribute "CDS_PART_NAME" "RES_0402-200.0,1%,1/16W,CHIP,GA"
					( Origin gPackager )
				)
				( objectStatus "R1L31" )
			)
			( gate "@baseboard_fab2_lib.baseboard_fab2(sch_1):page175_i5"
				( attribute "BOM_COST" "MIO_CHASSIS"
					( Origin gFrontEnd )
				)
				( attribute "CDS_LIB" "mstr_discrete"
					( Origin gPackager )
				)
				( attribute "CDS_LOCATION" "R1L27"
					( Origin gPackager )
				)
				( attribute "CDS_SEC" "1"
					( Origin gPackager )
				)
				( attribute "LOCATION" "R1L27"
					( Origin gFrontEnd )
				)
				( attribute "MATERIAL" "CHIP"
					( Origin gFrontEnd )
				)
				( attribute "PACK_TYPE" "0402"
					( Origin gFrontEnd )
				)
				( attribute "PART_NUMBER" "G21796-072"
					( Origin gFrontEnd )
				)
				( attribute "PHYS_PAGE" "175"
					( Origin gFrontEnd )
				)
				( attribute "ROOM" "MIO_CHASSIS"
					( Origin gFrontEnd )
				)
				( attribute "ROT" "0"
					( Origin gFrontEnd )
				)
				( attribute "SEC" "1"
					( Origin gFrontEnd )
				)
				( attribute "SEC_TYPE" "0402"
					( Origin gFrontEnd )
				)
				( attribute "TOLERANCE" "1%"
					( Origin gFrontEnd )
				)
				( attribute "VALUE" "4.75K"
					( Origin gFrontEnd )
				)
				( attribute "VER" "2"
					( Origin gFrontEnd )
				)
				( attribute "WATTAGE" "1/16W"
					( Origin gFrontEnd )
				)
				( attribute "XY" "(-5925,4475)"
					( Origin gFrontEnd )
				)
				( attribute "CHIPS_PART_NAME" "RES"
					( Origin gPackager )
				)
				( attribute "CDS_PART_NAME" "RES_0402-4.75K,1%,1/16W,CHIP,GA"
					( Origin gPackager )
				)
				( objectStatus "R1L27" )
			)
			( gate "@baseboard_fab2_lib.baseboard_fab2(sch_1):page175_i18"
				( attribute "CHIPS_PART_NAME" "TTL2G14"
					( Origin gPackager )
				)
			)
			( gate "@baseboard_fab2_lib.baseboard_fab2(sch_1):page175_i11"
				( attribute "BOM_COST" "MIO_CHASSIS"
					( Origin gFrontEnd )
				)
				( attribute "CDS_LIB" "dev_discrete"
					( Origin gPackager )
				)
				( attribute "CDS_LOCATION" "C1L18"
					( Origin gPackager )
				)
				( attribute "CDS_SEC" "1"
					( Origin gPackager )
				)
				( attribute "LOCATION" "C1L18"
					( Origin gFrontEnd )
				)
				( attribute "MATERIAL" "X6S"
					( Origin gFrontEnd )
				)
				( attribute "PACK_TYPE" "0402V"
					( Origin gFrontEnd )
				)
				( attribute "PART_NUMBER" "D97712-004"
					( Origin gFrontEnd )
				)
				( attribute "PHYS_PAGE" "175"
					( Origin gFrontEnd )
				)
				( attribute "ROOM" "MIO_CHASSIS"
					( Origin gFrontEnd )
				)
				( attribute "ROT" "0"
					( Origin gFrontEnd )
				)
				( attribute "SEC" "1"
					( Origin gFrontEnd )
				)
				( attribute "SEC_TYPE" "0402V"
					( Origin gFrontEnd )
				)
				( attribute "TOLERANCE" "10%"
					( Origin gFrontEnd )
				)
				( attribute "VALUE" "1.0UF"
					( Origin gFrontEnd )
				)
				( attribute "VER" "1"
					( Origin gFrontEnd )
				)
				( attribute "VOLTAGE" "6.3V"
					( Units "uVoltage" "V" 1.000000)
					( Origin gFrontEnd )
				)
				( attribute "XY" "(-4975,3950)"
					( Origin gFrontEnd )
				)
				( attribute "CHIPS_PART_NAME" "CAP_A"
					( Origin gPackager )
				)
				( attribute "CDS_PART_NAME" "CAP_A_0402V-1.0UF,6.3V,10%,X6SA"
					( Origin gPackager )
				)
				( objectStatus "C1L18" )
			)
			( gate "@baseboard_fab2_lib.baseboard_fab2(sch_1):page175_i13"
				( attribute "BOM_COST" "MIO_CHASSIS"
					( Origin gFrontEnd )
				)
				( attribute "CDS_LIB" "mstr_discrete"
					( Origin gPackager )
				)
				( attribute "CDS_LOCATION" "R1L26"
					( Origin gPackager )
				)
				( attribute "CDS_SEC" "1"
					( Origin gPackager )
				)
				( attribute "LOCATION" "R1L26"
					( Origin gFrontEnd )
				)
				( attribute "MATERIAL" "CHIP"
					( Origin gFrontEnd )
				)
				( attribute "PACK_TYPE" "0402"
					( Origin gFrontEnd )
				)
				( attribute "PART_NUMBER" "G21796-074"
					( Origin gFrontEnd )
				)
				( attribute "PHYS_PAGE" "175"
					( Origin gFrontEnd )
				)
				( attribute "ROOM" "MIO_CHASSIS"
					( Origin gFrontEnd )
				)
				( attribute "ROT" "0"
					( Origin gFrontEnd )
				)
				( attribute "SEC" "1"
					( Origin gFrontEnd )
				)
				( attribute "SEC_TYPE" "0402"
					( Origin gFrontEnd )
				)
				( attribute "TOLERANCE" "1%"
					( Origin gFrontEnd )
				)
				( attribute "VALUE" "33.2"
					( Origin gFrontEnd )
				)
				( attribute "VER" "1"
					( Origin gFrontEnd )
				)
				( attribute "WATTAGE" "1/16W"
					( Origin gFrontEnd )
				)
				( attribute "XY" "(-2275,4075)"
					( Origin gFrontEnd )
				)
				( attribute "CHIPS_PART_NAME" "RES"
					( Origin gPackager )
				)
				( attribute "CDS_PART_NAME" "RES_0402-33.2,1%,1/16W,CHIP,G2A"
					( Origin gPackager )
				)
				( objectStatus "R1L26" )
			)
			( gate "@baseboard_fab2_lib.baseboard_fab2(sch_1):page175_i15"
				( attribute "CHIPS_PART_NAME" "TTL2G14"
					( Origin gPackager )
				)
			)
			( gate "@baseboard_fab2_lib.baseboard_fab2(sch_1):page175_i10"
				( attribute "CHIPS_PART_NAME" "TTL2G14"
					( Origin gPackager )
				)
			)
			( gate "@baseboard_fab2_lib.baseboard_fab2(sch_1):page175_i19"
				( attribute "BOM_COST" "MIO_CHASSIS"
					( Origin gFrontEnd )
				)
				( attribute "CDS_LIB" "dev_discrete"
					( Origin gPackager )
				)
				( attribute "CDS_LOCATION" "C1L10"
					( Origin gPackager )
				)
				( attribute "CDS_SEC" "1"
					( Origin gPackager )
				)
				( attribute "LOCATION" "C1L10"
					( Origin gFrontEnd )
				)
				( attribute "MATERIAL" "X6S"
					( Origin gFrontEnd )
				)
				( attribute "PACK_TYPE" "0402V"
					( Origin gFrontEnd )
				)
				( attribute "PART_NUMBER" "D97712-004"
					( Origin gFrontEnd )
				)
				( attribute "PHYS_PAGE" "175"
					( Origin gFrontEnd )
				)
				( attribute "ROOM" "MIO_CHASSIS"
					( Origin gFrontEnd )
				)
				( attribute "ROT" "0"
					( Origin gFrontEnd )
				)
				( attribute "SEC" "1"
					( Origin gFrontEnd )
				)
				( attribute "SEC_TYPE" "0402V"
					( Origin gFrontEnd )
				)
				( attribute "TOLERANCE" "10%"
					( Origin gFrontEnd )
				)
				( attribute "VALUE" "1.0UF"
					( Origin gFrontEnd )
				)
				( attribute "VER" "1"
					( Origin gFrontEnd )
				)
				( attribute "VOLTAGE" "6.3V"
					( Units "uVoltage" "V" 1.000000)
					( Origin gFrontEnd )
				)
				( attribute "XY" "(-4925,2550)"
					( Origin gFrontEnd )
				)
				( attribute "CHIPS_PART_NAME" "CAP_A"
					( Origin gPackager )
				)
				( attribute "CDS_PART_NAME" "CAP_A_0402V-1.0UF,6.3V,10%,X6SA"
					( Origin gPackager )
				)
				( objectStatus "C1L10" )
			)
			( gate "@baseboard_fab2_lib.baseboard_fab2(sch_1):page175_i22"
				( attribute "BOM_COST" "MIO_CHASSIS"
					( Origin gFrontEnd )
				)
				( attribute "CDS_LIB" "mstr_discrete"
					( Origin gPackager )
				)
				( attribute "CDS_LOCATION" "R1L22"
					( Origin gPackager )
				)
				( attribute "CDS_SEC" "1"
					( Origin gPackager )
				)
				( attribute "LOCATION" "R1L22"
					( Origin gFrontEnd )
				)
				( attribute "MATERIAL" "CHIP"
					( Origin gFrontEnd )
				)
				( attribute "PACK_TYPE" "0402"
					( Origin gFrontEnd )
				)
				( attribute "PART_NUMBER" "G21796-004"
					( Origin gFrontEnd )
				)
				( attribute "PHYS_PAGE" "175"
					( Origin gFrontEnd )
				)
				( attribute "ROOM" "MIO_CHASSIS"
					( Origin gFrontEnd )
				)
				( attribute "ROT" "0"
					( Origin gFrontEnd )
				)
				( attribute "SEC" "1"
					( Origin gFrontEnd )
				)
				( attribute "SEC_TYPE" "0402"
					( Origin gFrontEnd )
				)
				( attribute "TOLERANCE" "1%"
					( Origin gFrontEnd )
				)
				( attribute "VALUE" "200.0"
					( Origin gFrontEnd )
				)
				( attribute "VER" "1"
					( Origin gFrontEnd )
				)
				( attribute "WATTAGE" "1/16W"
					( Origin gFrontEnd )
				)
				( attribute "XY" "(-5600,2775)"
					( Origin gFrontEnd )
				)
				( attribute "CHIPS_PART_NAME" "RES"
					( Origin gPackager )
				)
				( attribute "CDS_PART_NAME" "RES_0402-200.0,1%,1/16W,CHIP,GA"
					( Origin gPackager )
				)
				( objectStatus "R1L22" )
			)
			( gate "@baseboard_fab2_lib.baseboard_fab2(sch_1):page111_i97"
				( attribute "BOM_COST" "MIO_CHASSIS"
					( Origin gFrontEnd )
				)
				( attribute "CDS_LIB" "mstr_discrete"
					( Origin gPackager )
				)
				( attribute "LOCATION" "R1L28"
					( Origin gFrontEnd )
				)
				( attribute "MATERIAL" "EMPTY"
					( Origin gFrontEnd )
				)
				( attribute "PACK_TYPE" "0402"
					( Origin gFrontEnd )
				)
				( attribute "PART_NUMBER" "G21796-072"
					( Origin gFrontEnd )
				)
				( attribute "PHYS_PAGE" "111"
					( Origin gFrontEnd )
				)
				( attribute "ROOM" "MIO_CHASSIS"
					( Origin gFrontEnd )
				)
				( attribute "ROT" "0"
					( Origin gFrontEnd )
				)
				( attribute "TOLERANCE" "1%"
					( Origin gFrontEnd )
				)
				( attribute "VALUE" "4.75K"
					( Origin gFrontEnd )
				)
				( attribute "VER" "2"
					( Origin gFrontEnd )
				)
				( attribute "WATTAGE" "1/16W"
					( Origin gFrontEnd )
				)
				( attribute "XY" "(2175,2800)"
					( Origin gFrontEnd )
				)
				( attribute "CHIPS_PART_NAME" "RES"
					( Origin gPackager )
				)
				( attribute "CDS_PART_NAME" "RES_0402-4.75K,1%,1/16W,EMPTY,A"
					( Origin gPackager )
				)
				( attribute "SEC" "1"
					( Origin gFrontEnd )
				)
				( attribute "SEC_TYPE" "0402"
					( Origin gFrontEnd )
				)
				( attribute "CDS_LOCATION" "R1L28"
					( Origin gPackager )
				)
				( attribute "CDS_SEC" "1"
					( Origin gPackager )
				)
				( objectStatus "R1L28" )
			)
			( gate "@baseboard_fab2_lib.baseboard_fab2(sch_1):page175_i9"
				( attribute "CHIPS_PART_NAME" "TTL2G14"
					( Origin gPackager )
				)
			)
			( gate "@baseboard_fab2_lib.baseboard_fab2(sch_1):page175_i37"
				( attribute "BOM_COST" "MIO_CHASSIS"
					( Origin gFrontEnd )
				)
				( attribute "CDS_LIB" "dev_discrete"
					( Origin gPackager )
				)
				( attribute "CDS_LOCATION" "C1L17"
					( Origin gPackager )
				)
				( attribute "CDS_SEC" "1"
					( Origin gPackager )
				)
				( attribute "LOCATION" "C1L17"
					( Origin gFrontEnd )
				)
				( attribute "MATERIAL" "X7R"
					( Origin gFrontEnd )
				)
				( attribute "PACK_TYPE" "0402V"
					( Origin gFrontEnd )
				)
				( attribute "PART_NUMBER" "A36096-030"
					( Origin gFrontEnd )
				)
				( attribute "PHYS_PAGE" "175"
					( Origin gFrontEnd )
				)
				( attribute "ROOM" "MIO_CHASSIS"
					( Origin gFrontEnd )
				)
				( attribute "ROT" "0"
					( Origin gFrontEnd )
				)
				( attribute "SEC" "1"
					( Origin gFrontEnd )
				)
				( attribute "SEC_TYPE" "0402V"
					( Origin gFrontEnd )
				)
				( attribute "TOLERANCE" "10%"
					( Origin gFrontEnd )
				)
				( attribute "VALUE" "0.1UF"
					( Origin gFrontEnd )
				)
				( attribute "VER" "1"
					( Origin gFrontEnd )
				)
				( attribute "VOLTAGE" "16V"
					( Units "uVoltage" "V" 1.000000)
					( Origin gFrontEnd )
				)
				( attribute "XY" "(-2950,4450)"
					( Origin gFrontEnd )
				)
				( attribute "CHIPS_PART_NAME" "CAP_A"
					( Origin gPackager )
				)
				( attribute "CDS_PART_NAME" "CAP_A_0402V-0.1UF,16V,10%,X7R,A"
					( Origin gPackager )
				)
				( objectStatus "C1L17" )
			)
			( gate "@baseboard_fab2_lib.baseboard_fab2(sch_1):page175_i38"
				( attribute "BOM_COST" "MIO_CHASSIS"
					( Origin gFrontEnd )
				)
				( attribute "CDS_LIB" "dev_discrete"
					( Origin gPackager )
				)
				( attribute "CDS_LOCATION" "C1L9"
					( Origin gPackager )
				)
				( attribute "CDS_SEC" "1"
					( Origin gPackager )
				)
				( attribute "LOCATION" "C1L9"
					( Origin gFrontEnd )
				)
				( attribute "MATERIAL" "X7R"
					( Origin gFrontEnd )
				)
				( attribute "PACK_TYPE" "0402V"
					( Origin gFrontEnd )
				)
				( attribute "PART_NUMBER" "A36096-030"
					( Origin gFrontEnd )
				)
				( attribute "PHYS_PAGE" "175"
					( Origin gFrontEnd )
				)
				( attribute "ROOM" "MIO_CHASSIS"
					( Origin gFrontEnd )
				)
				( attribute "ROT" "0"
					( Origin gFrontEnd )
				)
				( attribute "SEC" "1"
					( Origin gFrontEnd )
				)
				( attribute "SEC_TYPE" "0402V"
					( Origin gFrontEnd )
				)
				( attribute "TOLERANCE" "10%"
					( Origin gFrontEnd )
				)
				( attribute "VALUE" "0.1UF"
					( Origin gFrontEnd )
				)
				( attribute "VER" "1"
					( Origin gFrontEnd )
				)
				( attribute "VOLTAGE" "16V"
					( Units "uVoltage" "V" 1.000000)
					( Origin gFrontEnd )
				)
				( attribute "XY" "(-2975,3000)"
					( Origin gFrontEnd )
				)
				( attribute "CHIPS_PART_NAME" "CAP_A"
					( Origin gPackager )
				)
				( attribute "CDS_PART_NAME" "CAP_A_0402V-0.1UF,16V,10%,X7R,A"
					( Origin gPackager )
				)
				( objectStatus "C1L9" )
			)
			( gate "@baseboard_fab2_lib.baseboard_fab2(sch_1):page175_i40"
				( attribute "BOM_COST" "MIO_CHASSIS"
					( Origin gFrontEnd )
				)
				( attribute "CDS_LIB" "dev_discrete"
					( Origin gPackager )
				)
				( attribute "CDS_LOCATION" "C9A3"
					( Origin gPackager )
				)
				( attribute "CDS_SEC" "1"
					( Origin gPackager )
				)
				( attribute "LOCATION" "C9A3"
					( Origin gFrontEnd )
				)
				( attribute "MATERIAL" "X7R"
					( Origin gFrontEnd )
				)
				( attribute "PACK_TYPE" "0402V"
					( Origin gFrontEnd )
				)
				( attribute "PART_NUMBER" "A36096-030"
					( Origin gFrontEnd )
				)
				( attribute "PHYS_PAGE" "175"
					( Origin gFrontEnd )
				)
				( attribute "ROOM" "MIO_CHASSIS"
					( Origin gFrontEnd )
				)
				( attribute "ROT" "0"
					( Origin gFrontEnd )
				)
				( attribute "SEC" "1"
					( Origin gFrontEnd )
				)
				( attribute "SEC_TYPE" "0402V"
					( Origin gFrontEnd )
				)
				( attribute "TOLERANCE" "10%"
					( Origin gFrontEnd )
				)
				( attribute "VALUE" "0.1UF"
					( Origin gFrontEnd )
				)
				( attribute "VER" "1"
					( Origin gFrontEnd )
				)
				( attribute "VOLTAGE" "16V"
					( Units "uVoltage" "V" 1.000000)
					( Origin gFrontEnd )
				)
				( attribute "XY" "(-575,3500)"
					( Origin gFrontEnd )
				)
				( attribute "CHIPS_PART_NAME" "CAP_A"
					( Origin gPackager )
				)
				( attribute "CDS_PART_NAME" "CAP_A_0402V-0.1UF,16V,10%,X7R,A"
					( Origin gPackager )
				)
				( objectStatus "C9A3" )
			)
			( gate "@baseboard_fab2_lib.baseboard_fab2(sch_1):page175_i45"
				( attribute "BOM_COST" "MIO_CHASSIS"
					( Origin gFrontEnd )
				)
				( attribute "CDS_LIB" "mstr_discrete"
					( Origin gPackager )
				)
				( attribute "CDS_LOCATION" "R1L33"
					( Origin gPackager )
				)
				( attribute "CDS_SEC" "1"
					( Origin gPackager )
				)
				( attribute "LOCATION" "R1L33"
					( Origin gFrontEnd )
				)
				( attribute "MATERIAL" "CHIP"
					( Origin gFrontEnd )
				)
				( attribute "PACK_TYPE" "0402"
					( Origin gFrontEnd )
				)
				( attribute "PART_NUMBER" "G21796-271"
					( Origin gFrontEnd )
				)
				( attribute "PHYS_PAGE" "175"
					( Origin gFrontEnd )
				)
				( attribute "ROOM" "MIO_CHASSIS"
					( Origin gFrontEnd )
				)
				( attribute "ROT" "0"
					( Origin gFrontEnd )
				)
				( attribute "SEC" "1"
					( Origin gFrontEnd )
				)
				( attribute "SEC_TYPE" "0402"
					( Origin gFrontEnd )
				)
				( attribute "TOLERANCE" "1.0%"
					( Origin gFrontEnd )
				)
				( attribute "VALUE" "221"
					( Origin gFrontEnd )
				)
				( attribute "VER" "1"
					( Origin gFrontEnd )
				)
				( attribute "WATTAGE" "1/16W"
					( Origin gFrontEnd )
				)
				( attribute "XY" "(-4000,1550)"
					( Origin gFrontEnd )
				)
				( attribute "CHIPS_PART_NAME" "RES"
					( Origin gPackager )
				)
				( attribute "CDS_PART_NAME" "RES_0402-221,1.0%,1/16W,CHIP,GA"
					( Origin gPackager )
				)
				( objectStatus "R1L33" )
			)
			( gate "@baseboard_fab2_lib.baseboard_fab2(sch_1):page175_i49"
				( attribute "BOM_COST" "MIO_CHASSIS"
					( Origin gFrontEnd )
				)
				( attribute "CDS_LIB" "mstr_discrete"
					( Origin gPackager )
				)
				( attribute "CDS_LOCATION" "Q9A3"
					( Origin gPackager )
				)
				( attribute "LOCATION" "Q9A3"
					( Origin gFrontEnd )
				)
				( attribute "MATERIAL" "FET"
					( Origin gFrontEnd )
				)
				( attribute "PACK_TYPE" "SOT23LF"
					( Origin gFrontEnd )
				)
				( attribute "PART_NUMBER" "C79254-001"
					( Origin gFrontEnd )
				)
				( attribute "PHYS_PAGE" "175"
					( Origin gFrontEnd )
				)
				( attribute "ROOM" "MIO_CHASSIS"
					( Origin gFrontEnd )
				)
				( attribute "ROT" "0"
					( Origin gFrontEnd )
				)
				( attribute "SEC" "1"
					( Origin gFrontEnd )
				)
				( attribute "SEC_TYPE" "SOT23LF"
					( Origin gFrontEnd )
				)
				( attribute "VALUE" "2N7002"
					( Origin gFrontEnd )
				)
				( attribute "VER" "8"
					( Origin gFrontEnd )
				)
				( attribute "XY" "(-5025,1175)"
					( Origin gFrontEnd )
				)
				( attribute "CHIPS_PART_NAME" "FET_N"
					( Origin gPackager )
				)
				( attribute "CDS_PART_NAME" "FET_N_SOT23LF-2N7002,FET,C7925A"
					( Origin gPackager )
				)
				( attribute "CDS_SEC" "1"
					( Origin gPackager )
				)
				( objectStatus "Q9A3" )
			)
			( gate "@baseboard_fab2_lib.baseboard_fab2(sch_1):page175_i50"
				( attribute "BOM_COST" "MIO_CHASSIS"
					( Origin gFrontEnd )
				)
				( attribute "CDS_LIB" "mstr_discrete"
					( Origin gPackager )
				)
				( attribute "CDS_LOCATION" "DS9A1"
					( Origin gPackager )
				)
				( attribute "CDS_SEC" "1"
					( Origin gPackager )
				)
				( attribute "COLOR" "BLUE"
					( Origin gFrontEnd )
				)
				( attribute "LOCATION" "DS9A1"
					( Origin gFrontEnd )
				)
				( attribute "MATERIAL" "IC"
					( Origin gFrontEnd )
				)
				( attribute "PACK_TYPE" "1NC"
					( Origin gFrontEnd )
				)
				( attribute "PART_NUMBER" "C96565-012"
					( Origin gFrontEnd )
				)
				( attribute "PHYS_PAGE" "175"
					( Origin gFrontEnd )
				)
				( attribute "ROOM" "MIO_CHASSIS"
					( Origin gFrontEnd )
				)
				( attribute "ROT" "0"
					( Origin gFrontEnd )
				)
				( attribute "SEC" "1"
					( Origin gPackager )
				)
				( attribute "VER" "3"
					( Origin gFrontEnd )
				)
				( attribute "XY" "(-1700,1025)"
					( Origin gFrontEnd )
				)
				( attribute "CHIPS_PART_NAME" "LED"
					( Origin gPackager )
				)
				( attribute "CDS_PART_NAME" "LED_1NC-BLUE,IC,C96565-012"
					( Origin gPackager )
				)
				( objectStatus "DS9A1" )
			)
			( gate "@baseboard_fab2_lib.baseboard_fab2(sch_1):page175_i57"
				( attribute "BOM_COST" "MIO_CHASSIS"
					( Origin gFrontEnd )
				)
				( attribute "CDS_LIB" "mstr_ttl"
					( Origin gPackager )
				)
				( attribute "CDS_LOCATION" "U1L2"
					( Origin gPackager )
				)
				( attribute "CDS_SEC" "1"
					( Origin gPackager )
				)
				( attribute "LOCATION" "U1L2"
					( Origin gFrontEnd )
				)
				( attribute "MATERIAL" "IC"
					( Origin gFrontEnd )
				)
				( attribute "PACK_TYPE" "SOTLF"
					( Origin gFrontEnd )
				)
				( attribute "PART_NUMBER" "D39848-001"
					( Origin gFrontEnd )
				)
				( attribute "PHYS_PAGE" "175"
					( Origin gFrontEnd )
				)
				( attribute "ROOM" "MIO_CHASSIS"
					( Origin gFrontEnd )
				)
				( attribute "ROT" "0"
					( Origin gFrontEnd )
				)
				( attribute "SEC" "1"
					( Origin gPackager )
				)
				( attribute "VALUE" "74AHCT1G86"
					( Origin gFrontEnd )
				)
				( attribute "VER" "1"
					( Origin gFrontEnd )
				)
				( attribute "XY" "(-2750,1025)"
					( Origin gFrontEnd )
				)
				( attribute "CHIPS_PART_NAME" "TTL1G86"
					( Origin gPackager )
				)
				( attribute "CDS_PART_NAME" "TTL1G86_SOTLF-74AHCT1G86,IC,D3B"
					( Origin gPackager )
				)
				( objectStatus "U1L2" )
			)
			( gate "@baseboard_fab2_lib.baseboard_fab2(sch_1):page175_i58"
				( attribute "BOM_COST" "MIO_CHASSIS"
					( Origin gFrontEnd )
				)
				( attribute "CDS_LIB" "mstr_discrete"
					( Origin gPackager )
				)
				( attribute "CDS_LOCATION" "R1L8"
					( Origin gPackager )
				)
				( attribute "CDS_SEC" "1"
					( Origin gPackager )
				)
				( attribute "LOCATION" "R1L8"
					( Origin gFrontEnd )
				)
				( attribute "MATERIAL" "CHIP"
					( Origin gFrontEnd )
				)
				( attribute "PACK_TYPE" "0402"
					( Origin gFrontEnd )
				)
				( attribute "PART_NUMBER" "G21497-024"
					( Origin gFrontEnd )
				)
				( attribute "PHYS_PAGE" "175"
					( Origin gFrontEnd )
				)
				( attribute "ROOM" "MIO_CHASSIS"
					( Origin gFrontEnd )
				)
				( attribute "ROT" "0"
					( Origin gFrontEnd )
				)
				( attribute "SEC" "1"
					( Origin gFrontEnd )
				)
				( attribute "SEC_TYPE" "0402"
					( Origin gFrontEnd )
				)
				( attribute "TOLERANCE" "5%"
					( Origin gFrontEnd )
				)
				( attribute "VALUE" "470.0"
					( Origin gFrontEnd )
				)
				( attribute "VER" "2"
					( Origin gFrontEnd )
				)
				( attribute "WATTAGE" "1/16W"
					( Origin gFrontEnd )
				)
				( attribute "XY" "(-1175,1350)"
					( Origin gFrontEnd )
				)
				( attribute "CHIPS_PART_NAME" "RES"
					( Origin gPackager )
				)
				( attribute "CDS_PART_NAME" "RES_0402-470.0,5%,1/16W,CHIP,GA"
					( Origin gPackager )
				)
				( objectStatus "R1L8" )
			)
			( gate "@baseboard_fab2_lib.baseboard_fab2(sch_1):page175_i63"
				( attribute "BOM_COST" "MIO_CHASSIS"
					( Origin gFrontEnd )
				)
				( attribute "CDS_LIB" "mstr_discrete"
					( Origin gPackager )
				)
				( attribute "CDS_LOCATION" "R1L12"
					( Origin gPackager )
				)
				( attribute "CDS_SEC" "1"
					( Origin gPackager )
				)
				( attribute "LOCATION" "R1L12"
					( Origin gFrontEnd )
				)
				( attribute "MATERIAL" "CHIP"
					( Origin gFrontEnd )
				)
				( attribute "PACK_TYPE" "0402"
					( Origin gFrontEnd )
				)
				( attribute "PART_NUMBER" "G21497-005"
					( Origin gFrontEnd )
				)
				( attribute "PHYS_PAGE" "175"
					( Origin gFrontEnd )
				)
				( attribute "ROOM" "MIO_CHASSIS"
					( Origin gFrontEnd )
				)
				( attribute "ROT" "0"
					( Origin gFrontEnd )
				)
				( attribute "SEC" "1"
					( Origin gFrontEnd )
				)
				( attribute "SEC_TYPE" "0402"
					( Origin gFrontEnd )
				)
				( attribute "TOLERANCE" "5%"
					( Origin gFrontEnd )
				)
				( attribute "VALUE" "0.0"
					( Origin gFrontEnd )
				)
				( attribute "VER" "1"
					( Origin gFrontEnd )
				)
				( attribute "WATTAGE" "1/16W"
					( Origin gFrontEnd )
				)
				( attribute "XY" "(-3525,1075)"
					( Origin gFrontEnd )
				)
				( attribute "CHIPS_PART_NAME" "RES"
					( Origin gPackager )
				)
				( attribute "CDS_PART_NAME" "RES_0402-0.0,5%,1/16W,CHIP,G21A"
					( Origin gPackager )
				)
				( objectStatus "R1L12" )
			)
			( gate "@baseboard_fab2_lib.baseboard_fab2(sch_1):page175_i64"
				( attribute "BOM_COST" "MIO_CHASSIS"
					( Origin gFrontEnd )
				)
				( attribute "CDS_LIB" "dev_discrete"
					( Origin gPackager )
				)
				( attribute "CDS_LOCATION" "C1L4"
					( Origin gPackager )
				)
				( attribute "CDS_SEC" "1"
					( Origin gPackager )
				)
				( attribute "LOCATION" "C1L4"
					( Origin gFrontEnd )
				)
				( attribute "MATERIAL" "X7R"
					( Origin gFrontEnd )
				)
				( attribute "PACK_TYPE" "0402V"
					( Origin gFrontEnd )
				)
				( attribute "PART_NUMBER" "A36096-030"
					( Origin gFrontEnd )
				)
				( attribute "PHYS_PAGE" "175"
					( Origin gFrontEnd )
				)
				( attribute "ROOM" "MIO_CHASSIS"
					( Origin gFrontEnd )
				)
				( attribute "ROT" "0"
					( Origin gFrontEnd )
				)
				( attribute "SEC" "1"
					( Origin gFrontEnd )
				)
				( attribute "SEC_TYPE" "0402V"
					( Origin gFrontEnd )
				)
				( attribute "TOLERANCE" "10%"
					( Origin gFrontEnd )
				)
				( attribute "VALUE" "0.1UF"
					( Origin gFrontEnd )
				)
				( attribute "VER" "1"
					( Origin gFrontEnd )
				)
				( attribute "VOLTAGE" "16V"
					( Units "uVoltage" "V" 1.000000)
					( Origin gFrontEnd )
				)
				( attribute "XY" "(-2900,1725)"
					( Origin gFrontEnd )
				)
				( attribute "CHIPS_PART_NAME" "CAP_A"
					( Origin gPackager )
				)
				( attribute "CDS_PART_NAME" "CAP_A_0402V-0.1UF,16V,10%,X7R,A"
					( Origin gPackager )
				)
				( objectStatus "C1L4" )
			)
			( gate "@baseboard_fab2_lib.baseboard_fab2(sch_1):page175_i67"
				( attribute "BOM_COST" "MIO_CHASSIS"
					( Origin gFrontEnd )
				)
				( attribute "CDS_LIB" "mstr_discrete"
					( Origin gPackager )
				)
				( attribute "CDS_LOCATION" "DS9A3"
					( Origin gPackager )
				)
				( attribute "CDS_SEC" "1"
					( Origin gPackager )
				)
				( attribute "COLOR" "YELLOW"
					( Origin gFrontEnd )
				)
				( attribute "LOCATION" "DS9A3"
					( Origin gFrontEnd )
				)
				( attribute "MATERIAL" "IC"
					( Origin gFrontEnd )
				)
				( attribute "PACK_TYPE" "1NCLF"
					( Origin gFrontEnd )
				)
				( attribute "PART_NUMBER" "C96565-003"
					( Origin gFrontEnd )
				)
				( attribute "PHYS_PAGE" "175"
					( Origin gFrontEnd )
				)
				( attribute "ROOM" "MIO_CHASSIS"
					( Origin gFrontEnd )
				)
				( attribute "ROT" "0"
					( Origin gFrontEnd )
				)
				( attribute "SEC" "1"
					( Origin gFrontEnd )
				)
				( attribute "SEC_TYPE" "1NCLF"
					( Origin gFrontEnd )
				)
				( attribute "VER" "3"
					( Origin gFrontEnd )
				)
				( attribute "XY" "(-4600,1550)"
					( Origin gFrontEnd )
				)
				( attribute "CHIPS_PART_NAME" "LED"
					( Origin gPackager )
				)
				( attribute "CDS_PART_NAME" "LED_1NCLF-YELLOW,IC,C96565-003"
					( Origin gPackager )
				)
				( objectStatus "DS9A3" )
			)
			( gate "@baseboard_fab2_lib.baseboard_fab2(sch_1):page175_i78"
				( attribute "BOM_COST" "MIO_CHASSIS"
					( Origin gFrontEnd )
				)
				( attribute "CDS_LIB" "mstr_misc"
					( Origin gPackager )
				)
				( attribute "CDS_LMAN_SYM_OUTLINE" "-100,125,100,-75"
					( Origin gPackager )
				)
				( attribute "CDS_LOCATION" "S9A1"
					( Origin gPackager )
				)
				( attribute "CDS_SEC" "1"
					( Origin gPackager )
				)
				( attribute "LOCATION" "S9A1"
					( Origin gFrontEnd )
				)
				( attribute "MATERIAL" "IC"
					( Origin gFrontEnd )
				)
				( attribute "PACK_TYPE" "SM"
					( Origin gFrontEnd )
				)
				( attribute "PART_NUMBER" "D37771-002"
					( Origin gFrontEnd )
				)
				( attribute "PHYS_PAGE" "175"
					( Origin gFrontEnd )
				)
				( attribute "ROOM" "MIO_CHASSIS"
					( Origin gFrontEnd )
				)
				( attribute "ROT" "3"
					( Origin gFrontEnd )
				)
				( attribute "SEC" "1"
					( Origin gFrontEnd )
				)
				( attribute "SEC_TYPE" "SM"
					( Origin gFrontEnd )
				)
				( attribute "VER" "1"
					( Origin gFrontEnd )
				)
				( attribute "XY" "(-7075,2675)"
					( Origin gFrontEnd )
				)
				( attribute "CHIPS_PART_NAME" "SWITCH_D37771002"
					( Origin gPackager )
				)
				( attribute "CDS_PART_NAME" "SWITCH_D37771002_SM-IC,D37771-A"
					( Origin gPackager )
				)
				( objectStatus "S9A1" )
			)
			( gate "@baseboard_fab2_lib.baseboard_fab2(sch_1):page153_i185"
				( attribute "CDS_LIB" "w_hdl"
					( Origin gPackager )
				)
				( attribute "CDS_LMAN_SYM_OUTLINE" "-275,375,275,-375"
					( Origin gPackager )
				)
				( attribute "LOCATION" "U3T1"
					( Origin gFrontEnd )
				)
				( attribute "PACK_TYPE" "MEMORY-G4"
					( Origin gFrontEnd )
				)
				( attribute "PART_NUMBER" "72.25256.H01"
					( Origin gFrontEnd )
				)
				( attribute "PHYS_PAGE" "153"
					( Origin gFrontEnd )
				)
				( attribute "ROT" "0"
					( Origin gFrontEnd )
				)
				( attribute "SEC" "1"
					( Origin gFrontEnd )
				)
				( attribute "SEC_TYPE" "MEMORY-G4"
					( Origin gFrontEnd )
				)
				( attribute "VALUE" "W25Q256FVFIG-GP"
					( Origin gFrontEnd )
				)
				( attribute "VER" "1"
					( Origin gFrontEnd )
				)
				( attribute "XY" "(-4950,1800)"
					( Origin gFrontEnd )
				)
				( attribute "CHIPS_PART_NAME" "W25Q256FVFIG-GP"
					( Origin gPackager )
				)
				( attribute "CDS_PART_NAME" "W25Q256FVFIG-GP_MEMORY-G4-W25QA"
					( Origin gPackager )
				)
				( attribute "CDS_LOCATION" "U3T1"
					( Origin gPackager )
				)
				( attribute "CDS_SEC" "1"
					( Origin gPackager )
				)
				( attribute "GROUP" "NI_BIOS_ROM2"
					( Origin gFrontEnd )
				)
				( objectStatus "U3T1" )
			)
			( gate "@baseboard_fab2_lib.baseboard_fab2(sch_1):page176_i16"
				( attribute "BOM_COST" "MIO_USB"
					( Origin gFrontEnd )
				)
				( attribute "CDS_LIB" "mstr_discrete"
					( Origin gPackager )
				)
				( attribute "CDS_LOCATION" "R1M5"
					( Origin gPackager )
				)
				( attribute "CDS_SEC" "1"
					( Origin gPackager )
				)
				( attribute "LOCATION" "R1M5"
					( Origin gFrontEnd )
				)
				( attribute "MATERIAL" "CHIP"
					( Origin gFrontEnd )
				)
				( attribute "PACK_TYPE" "0402"
					( Origin gFrontEnd )
				)
				( attribute "PART_NUMBER" "G21497-005"
					( Origin gFrontEnd )
				)
				( attribute "PHYS_PAGE" "176"
					( Origin gFrontEnd )
				)
				( attribute "ROOM" "USB_REAR"
					( Origin gFrontEnd )
				)
				( attribute "ROT" "0"
					( Origin gFrontEnd )
				)
				( attribute "SEC" "1"
					( Origin gFrontEnd )
				)
				( attribute "SEC_TYPE" "0402"
					( Origin gFrontEnd )
				)
				( attribute "TOLERANCE" "5%"
					( Origin gFrontEnd )
				)
				( attribute "VALUE" "0.0"
					( Origin gFrontEnd )
				)
				( attribute "VER" "1"
					( Origin gFrontEnd )
				)
				( attribute "WATTAGE" "1/16W"
					( Origin gFrontEnd )
				)
				( attribute "XY" "(-5650,4600)"
					( Origin gFrontEnd )
				)
				( attribute "CHIPS_PART_NAME" "RES"
					( Origin gPackager )
				)
				( attribute "CDS_PART_NAME" "RES_0402-0.0,5%,1/16W,CHIP,G21A"
					( Origin gPackager )
				)
				( attribute "POP" "NOPOP"
					( Origin gFrontEnd )
				)
				( objectStatus "R1M5" )
			)
			( gate "@baseboard_fab2_lib.baseboard_fab2(sch_1):page176_i31"
				( attribute "BOM_COST" "MIO_USB"
					( Origin gFrontEnd )
				)
				( attribute "CDS_LIB" "mstr_discrete"
					( Origin gPackager )
				)
				( attribute "CDS_LOCATION" "R1M6"
					( Origin gPackager )
				)
				( attribute "CDS_SEC" "1"
					( Origin gPackager )
				)
				( attribute "LOCATION" "R1M6"
					( Origin gFrontEnd )
				)
				( attribute "MATERIAL" "CHIP"
					( Origin gFrontEnd )
				)
				( attribute "PACK_TYPE" "0402"
					( Origin gFrontEnd )
				)
				( attribute "PART_NUMBER" "G21497-005"
					( Origin gFrontEnd )
				)
				( attribute "PHYS_PAGE" "176"
					( Origin gFrontEnd )
				)
				( attribute "ROOM" "USB"
					( Origin gFrontEnd )
				)
				( attribute "ROT" "0"
					( Origin gFrontEnd )
				)
				( attribute "SEC" "1"
					( Origin gFrontEnd )
				)
				( attribute "SEC_TYPE" "0402"
					( Origin gFrontEnd )
				)
				( attribute "TOLERANCE" "5%"
					( Origin gFrontEnd )
				)
				( attribute "VALUE" "0.0"
					( Origin gFrontEnd )
				)
				( attribute "VER" "1"
					( Origin gFrontEnd )
				)
				( attribute "WATTAGE" "1/16W"
					( Origin gFrontEnd )
				)
				( attribute "XY" "(-5650,5550)"
					( Origin gFrontEnd )
				)
				( attribute "CHIPS_PART_NAME" "RES"
					( Origin gPackager )
				)
				( attribute "CDS_PART_NAME" "RES_0402-0.0,5%,1/16W,CHIP,G21A"
					( Origin gPackager )
				)
				( attribute "POP" "NOPOP"
					( Origin gFrontEnd )
				)
				( objectStatus "R1M6" )
			)
			( gate "@baseboard_fab2_lib.baseboard_fab2(sch_1):page176_i69"
				( attribute "CDS_LIB" "mstr_conn"
					( Origin gPackager )
				)
				( attribute "CDS_LOCATION" "J9B1"
					( Origin gPackager )
				)
				( attribute "CDS_SEC" "1"
					( Origin gPackager )
				)
				( attribute "LOCATION" "J9B1"
					( Origin gFrontEnd )
				)
				( attribute "MATERIAL" "CONN"
					( Origin gFrontEnd )
				)
				( attribute "PACK_TYPE" "PIP2"
					( Origin gFrontEnd )
				)
				( attribute "PART_NUMBER" "H51826-001"
					( Origin gFrontEnd )
				)
				( attribute "PHYS_PAGE" "176"
					( Origin gFrontEnd )
				)
				( attribute "ROOM" "USB_REAR"
					( Origin gFrontEnd )
				)
				( attribute "ROT" "0"
					( Origin gFrontEnd )
				)
				( attribute "SEC" "1"
					( Origin gPackager )
				)
				( attribute "VER" "2"
					( Origin gFrontEnd )
				)
				( attribute "XY" "(-1300,4550)"
					( Origin gFrontEnd )
				)
				( attribute "CHIPS_PART_NAME" "CONN9_H51826001"
					( Origin gPackager )
				)
				( attribute "CDS_PART_NAME" "CONN9_H51826001_PIP2-CONN,H518A"
					( Origin gPackager )
				)
				( objectStatus "J9B1" )
			)
			( gate "@baseboard_fab2_lib.baseboard_fab2(sch_1):page176_i98"
				( attribute "BOM_COST" "MIO_USB"
					( Origin gFrontEnd )
				)
				( attribute "CDS_LIB" "mstr_discrete"
					( Origin gPackager )
				)
				( attribute "CDS_LOCATION" "CR1M2"
					( Origin gPackager )
				)
				( attribute "CDS_SEC" "1"
					( Origin gPackager )
				)
				( attribute "LOCATION" "CR1M2"
					( Origin gFrontEnd )
				)
				( attribute "MATERIAL" "IC"
					( Origin gFrontEnd )
				)
				( attribute "PACK_TYPE" "SM9"
					( Origin gFrontEnd )
				)
				( attribute "PART_NUMBER" "G18435-001"
					( Origin gFrontEnd )
				)
				( attribute "PHYS_PAGE" "176"
					( Origin gFrontEnd )
				)
				( attribute "ROOM" "USB_REAR"
					( Origin gFrontEnd )
				)
				( attribute "ROT" "0"
					( Origin gFrontEnd )
				)
				( attribute "SEC" "1"
					( Origin gFrontEnd )
				)
				( attribute "SEC_TYPE" "SM9"
					( Origin gFrontEnd )
				)
				( attribute "VALUE" "ESD3V3U4ULC"
					( Origin gFrontEnd )
				)
				( attribute "VER" "7"
					( Origin gFrontEnd )
				)
				( attribute "XY" "(-3950,4500)"
					( Origin gFrontEnd )
				)
				( attribute "CHIPS_PART_NAME" "DIODEAC_DUAL_ARRAY"
					( Origin gPackager )
				)
				( attribute "CDS_PART_NAME" "DIODEAC_DUAL_ARRAY_SM9-ESD3V3UA"
					( Origin gPackager )
				)
				( objectStatus "CR1M2" )
			)
			( gate "@baseboard_fab2_lib.baseboard_fab2(sch_1):page176_i100"
				( attribute "BOM_COST" "MIO_USB"
					( Origin gFrontEnd )
				)
				( attribute "CDS_LIB" "mstr_vreg"
					( Origin gPackager )
				)
				( attribute "CDS_LOCATION" "U1M3"
					( Origin gPackager )
				)
				( attribute "CDS_SEC" "1"
					( Origin gPackager )
				)
				( attribute "LOCATION" "U1M3"
					( Origin gFrontEnd )
				)
				( attribute "MATERIAL" "IC"
					( Origin gFrontEnd )
				)
				( attribute "PACK_TYPE" "SM"
					( Origin gFrontEnd )
				)
				( attribute "PART_NUMBER" "H66405-001"
					( Origin gFrontEnd )
				)
				( attribute "PHYS_PAGE" "176"
					( Origin gFrontEnd )
				)
				( attribute "ROOM" "USB_REAR"
					( Origin gFrontEnd )
				)
				( attribute "ROT" "0"
					( Origin gFrontEnd )
				)
				( attribute "SEC" "1"
					( Origin gFrontEnd )
				)
				( attribute "SEC_TYPE" "SM"
					( Origin gFrontEnd )
				)
				( attribute "VER" "1"
					( Origin gFrontEnd )
				)
				( attribute "XY" "(-4125,3325)"
					( Origin gFrontEnd )
				)
				( attribute "CHIPS_PART_NAME" "TPS2061"
					( Origin gPackager )
				)
				( attribute "CDS_PART_NAME" "TPS2061_SM-IC,H66405-001"
					( Origin gPackager )
				)
				( objectStatus "U1M3" )
			)
			( gate "@baseboard_fab2_lib.baseboard_fab2(sch_1):page176_i105"
				( attribute "BOM_COST" "MIO_USB"
					( Origin gFrontEnd )
				)
				( attribute "CDS_LIB" "mstr_discrete"
					( Origin gPackager )
				)
				( attribute "CDS_LOCATION" "R1M24"
					( Origin gPackager )
				)
				( attribute "CDS_SEC" "1"
					( Origin gPackager )
				)
				( attribute "LOCATION" "R1M24"
					( Origin gFrontEnd )
				)
				( attribute "MATERIAL" "CHIP"
					( Origin gFrontEnd )
				)
				( attribute "PACK_TYPE" "0402"
					( Origin gFrontEnd )
				)
				( attribute "PART_NUMBER" "G21796-016"
					( Origin gFrontEnd )
				)
				( attribute "PHYS_PAGE" "176"
					( Origin gFrontEnd )
				)
				( attribute "ROOM" "USB_REAR"
					( Origin gFrontEnd )
				)
				( attribute "ROT" "0"
					( Origin gFrontEnd )
				)
				( attribute "SEC" "1"
					( Origin gFrontEnd )
				)
				( attribute "SEC_TYPE" "0402"
					( Origin gFrontEnd )
				)
				( attribute "TOLERANCE" "1%"
					( Origin gFrontEnd )
				)
				( attribute "VALUE" "10.0K"
					( Origin gFrontEnd )
				)
				( attribute "VER" "2"
					( Origin gFrontEnd )
				)
				( attribute "WATTAGE" "1/16W"
					( Origin gFrontEnd )
				)
				( attribute "XY" "(-3700,3675)"
					( Origin gFrontEnd )
				)
				( attribute "CHIPS_PART_NAME" "RES"
					( Origin gPackager )
				)
				( attribute "CDS_PART_NAME" "RES_0402-10.0K,1%,1/16W,CHIP,GA"
					( Origin gPackager )
				)
				( objectStatus "R1M24" )
			)
			( gate "@baseboard_fab2_lib.baseboard_fab2(sch_1):page176_i108"
				( attribute "BOM_COST" "MIO_USB"
					( Origin gFrontEnd )
				)
				( attribute "CDS_LIB" "dev_discrete"
					( Origin gPackager )
				)
				( attribute "CDS_LOCATION" "C1M38"
					( Origin gPackager )
				)
				( attribute "CDS_SEC" "1"
					( Origin gPackager )
				)
				( attribute "LOCATION" "C1M38"
					( Origin gFrontEnd )
				)
				( attribute "MATERIAL" "X7R"
					( Origin gFrontEnd )
				)
				( attribute "PACK_TYPE" "0402V"
					( Origin gFrontEnd )
				)
				( attribute "PART_NUMBER" "A36096-030"
					( Origin gFrontEnd )
				)
				( attribute "PHYS_PAGE" "176"
					( Origin gFrontEnd )
				)
				( attribute "ROOM" "USB_REAR"
					( Origin gFrontEnd )
				)
				( attribute "ROT" "0"
					( Origin gFrontEnd )
				)
				( attribute "SEC" "1"
					( Origin gFrontEnd )
				)
				( attribute "SEC_TYPE" "0402V"
					( Origin gFrontEnd )
				)
				( attribute "TOLERANCE" "10%"
					( Origin gFrontEnd )
				)
				( attribute "VALUE" "0.1UF"
					( Origin gFrontEnd )
				)
				( attribute "VER" "1"
					( Origin gFrontEnd )
				)
				( attribute "VOLTAGE" "16V"
					( Units "uVoltage" "V" 1.000000)
					( Origin gFrontEnd )
				)
				( attribute "XY" "(-5225,3525)"
					( Origin gFrontEnd )
				)
				( attribute "CHIPS_PART_NAME" "CAP_A"
					( Origin gPackager )
				)
				( attribute "CDS_PART_NAME" "CAP_A_0402V-0.1UF,16V,10%,X7R,A"
					( Origin gPackager )
				)
				( objectStatus "C1M38" )
			)
			( gate "@baseboard_fab2_lib.baseboard_fab2(sch_1):page176_i111"
				( attribute "BOM_COST" "MIO_USB"
					( Origin gFrontEnd )
				)
				( attribute "CDS_LIB" "mstr_discrete"
					( Origin gPackager )
				)
				( attribute "CDS_LOCATION" "R1M25"
					( Origin gPackager )
				)
				( attribute "CDS_SEC" "1"
					( Origin gPackager )
				)
				( attribute "LOCATION" "R1M25"
					( Origin gFrontEnd )
				)
				( attribute "MATERIAL" "CHIP"
					( Origin gFrontEnd )
				)
				( attribute "PACK_TYPE" "0402"
					( Origin gFrontEnd )
				)
				( attribute "PART_NUMBER" "G21796-016"
					( Origin gFrontEnd )
				)
				( attribute "PHYS_PAGE" "176"
					( Origin gFrontEnd )
				)
				( attribute "ROOM" "USB_REAR"
					( Origin gFrontEnd )
				)
				( attribute "ROT" "0"
					( Origin gFrontEnd )
				)
				( attribute "SEC" "1"
					( Origin gFrontEnd )
				)
				( attribute "SEC_TYPE" "0402"
					( Origin gFrontEnd )
				)
				( attribute "TOLERANCE" "1%"
					( Origin gFrontEnd )
				)
				( attribute "VALUE" "10.0K"
					( Origin gFrontEnd )
				)
				( attribute "VER" "2"
					( Origin gFrontEnd )
				)
				( attribute "WATTAGE" "1/16W"
					( Origin gFrontEnd )
				)
				( attribute "XY" "(-5200,3000)"
					( Origin gFrontEnd )
				)
				( attribute "CHIPS_PART_NAME" "RES"
					( Origin gPackager )
				)
				( attribute "CDS_PART_NAME" "RES_0402-10.0K,1%,1/16W,CHIP,GA"
					( Origin gPackager )
				)
				( objectStatus "R1M25" )
			)
			( gate "@baseboard_fab2_lib.baseboard_fab2(sch_1):page176_i113"
				( attribute "CDS_LIB" "mstr_discrete"
					( Origin gPackager )
				)
				( attribute "CDS_LOCATION" "C9B8"
					( Origin gPackager )
				)
				( attribute "CDS_SEC" "1"
					( Origin gPackager )
				)
				( attribute "LOCATION" "C9B8"
					( Origin gFrontEnd )
				)
				( attribute "MATERIAL" "POSCAP"
					( Origin gFrontEnd )
				)
				( attribute "PACK_TYPE" "7343HLF"
					( Origin gFrontEnd )
				)
				( attribute "PART_NUMBER" "724613-043"
					( Origin gFrontEnd )
				)
				( attribute "PHYS_PAGE" "176"
					( Origin gFrontEnd )
				)
				( attribute "ROT" "0"
					( Origin gFrontEnd )
				)
				( attribute "SEC" "1"
					( Origin gFrontEnd )
				)
				( attribute "SEC_TYPE" "7343HLF"
					( Origin gFrontEnd )
				)
				( attribute "TOLERANCE" "20%"
					( Origin gFrontEnd )
				)
				( attribute "VALUE" "330UF"
					( Origin gFrontEnd )
				)
				( attribute "VER" "1"
					( Origin gFrontEnd )
				)
				( attribute "VOLTAGE" "10V"
					( Units "uVoltage" "V" 1.000000)
					( Origin gFrontEnd )
				)
				( attribute "XY" "(-3650,3150)"
					( Origin gFrontEnd )
				)
				( attribute "CHIPS_PART_NAME" "CAPP"
					( Origin gPackager )
				)
				( attribute "CDS_PART_NAME" "CAPP_7343HLF-330UF,10V,20%,POSA"
					( Origin gPackager )
				)
				( objectStatus "C9B8" )
			)
			( gate "@baseboard_fab2_lib.baseboard_fab2(sch_1):page177_i3"
				( attribute "CDS_LIB" "mstr_discrete"
					( Origin gPackager )
				)
				( attribute "CDS_LOCATION" "R1M13"
					( Origin gPackager )
				)
				( attribute "CDS_SEC" "1"
					( Origin gPackager )
				)
				( attribute "LOCATION" "R1M13"
					( Origin gFrontEnd )
				)
				( attribute "MATERIAL" "CHIP"
					( Origin gFrontEnd )
				)
				( attribute "PACK_TYPE" "0402"
					( Origin gFrontEnd )
				)
				( attribute "PART_NUMBER" "G21497-005"
					( Origin gFrontEnd )
				)
				( attribute "PHYS_PAGE" "177"
					( Origin gFrontEnd )
				)
				( attribute "ROOM" "MIO_CHASSIS"
					( Origin gFrontEnd )
				)
				( attribute "ROT" "0"
					( Origin gFrontEnd )
				)
				( attribute "SEC" "1"
					( Origin gPackager )
				)
				( attribute "TOLERANCE" "5%"
					( Origin gFrontEnd )
				)
				( attribute "VALUE" "0.0"
					( Origin gFrontEnd )
				)
				( attribute "VER" "1"
					( Origin gFrontEnd )
				)
				( attribute "WATTAGE" "1/16W"
					( Origin gFrontEnd )
				)
				( attribute "XY" "(-7900,6225)"
					( Origin gFrontEnd )
				)
				( attribute "CHIPS_PART_NAME" "RES"
					( Origin gPackager )
				)
				( attribute "CDS_PART_NAME" "RES_0402-0.0,5%,1/16W,CHIP,G21A"
					( Origin gPackager )
				)
				( objectStatus "R1M13" )
			)
			( gate "@baseboard_fab2_lib.baseboard_fab2(sch_1):page177_i6"
				( attribute "CDS_LIB" "mstr_discrete"
					( Origin gPackager )
				)
				( attribute "CDS_LOCATION" "R1M10"
					( Origin gPackager )
				)
				( attribute "CDS_SEC" "1"
					( Origin gPackager )
				)
				( attribute "LOCATION" "R1M10"
					( Origin gFrontEnd )
				)
				( attribute "MATERIAL" "CHIP"
					( Origin gFrontEnd )
				)
				( attribute "PACK_TYPE" "0402"
					( Origin gFrontEnd )
				)
				( attribute "PART_NUMBER" "G21497-005"
					( Origin gFrontEnd )
				)
				( attribute "PHYS_PAGE" "177"
					( Origin gFrontEnd )
				)
				( attribute "ROOM" "MIO_CHASSIS"
					( Origin gFrontEnd )
				)
				( attribute "ROT" "0"
					( Origin gFrontEnd )
				)
				( attribute "SEC" "1"
					( Origin gPackager )
				)
				( attribute "TOLERANCE" "5%"
					( Origin gFrontEnd )
				)
				( attribute "VALUE" "0.0"
					( Origin gFrontEnd )
				)
				( attribute "VER" "1"
					( Origin gFrontEnd )
				)
				( attribute "WATTAGE" "1/16W"
					( Origin gFrontEnd )
				)
				( attribute "XY" "(-8100,6325)"
					( Origin gFrontEnd )
				)
				( attribute "CHIPS_PART_NAME" "RES"
					( Origin gPackager )
				)
				( attribute "CDS_PART_NAME" "RES_0402-0.0,5%,1/16W,CHIP,G21A"
					( Origin gPackager )
				)
				( objectStatus "R1M10" )
			)
			( gate "@baseboard_fab2_lib.baseboard_fab2(sch_1):page177_i8"
				( attribute "CDS_LIB" "mstr_discrete"
					( Origin gPackager )
				)
				( attribute "CDS_LOCATION" "R1M12"
					( Origin gPackager )
				)
				( attribute "CDS_SEC" "1"
					( Origin gPackager )
				)
				( attribute "LOCATION" "R1M12"
					( Origin gFrontEnd )
				)
				( attribute "MATERIAL" "CHIP"
					( Origin gFrontEnd )
				)
				( attribute "PACK_TYPE" "0402"
					( Origin gFrontEnd )
				)
				( attribute "PART_NUMBER" "G21796-016"
					( Origin gFrontEnd )
				)
				( attribute "PHYS_PAGE" "177"
					( Origin gFrontEnd )
				)
				( attribute "ROOM" "MIO_CHASSIS"
					( Origin gFrontEnd )
				)
				( attribute "ROT" "0"
					( Origin gFrontEnd )
				)
				( attribute "SEC" "1"
					( Origin gFrontEnd )
				)
				( attribute "SEC_TYPE" "0402"
					( Origin gFrontEnd )
				)
				( attribute "TOLERANCE" "1%"
					( Origin gFrontEnd )
				)
				( attribute "VALUE" "10.0K"
					( Origin gFrontEnd )
				)
				( attribute "VER" "2"
					( Origin gFrontEnd )
				)
				( attribute "WATTAGE" "1/16W"
					( Origin gFrontEnd )
				)
				( attribute "XY" "(-6975,6550)"
					( Origin gFrontEnd )
				)
				( attribute "CHIPS_PART_NAME" "RES"
					( Origin gPackager )
				)
				( attribute "CDS_PART_NAME" "RES_0402-10.0K,1%,1/16W,CHIP,GA"
					( Origin gPackager )
				)
				( objectStatus "R1M12" )
			)
			( gate "@baseboard_fab2_lib.baseboard_fab2(sch_1):page177_i9"
				( attribute "CDS_LIB" "mstr_discrete"
					( Origin gPackager )
				)
				( attribute "CDS_LOCATION" "R1M11"
					( Origin gPackager )
				)
				( attribute "CDS_SEC" "1"
					( Origin gPackager )
				)
				( attribute "LOCATION" "R1M11"
					( Origin gFrontEnd )
				)
				( attribute "MATERIAL" "CHIP"
					( Origin gFrontEnd )
				)
				( attribute "PACK_TYPE" "0402"
					( Origin gFrontEnd )
				)
				( attribute "PART_NUMBER" "G21796-016"
					( Origin gFrontEnd )
				)
				( attribute "PHYS_PAGE" "177"
					( Origin gFrontEnd )
				)
				( attribute "ROOM" "MIO_CHASSIS"
					( Origin gFrontEnd )
				)
				( attribute "ROT" "2"
					( Origin gFrontEnd )
				)
				( attribute "SEC" "1"
					( Origin gFrontEnd )
				)
				( attribute "SEC_TYPE" "0402"
					( Origin gFrontEnd )
				)
				( attribute "TOLERANCE" "1%"
					( Origin gFrontEnd )
				)
				( attribute "VALUE" "10.0K"
					( Origin gFrontEnd )
				)
				( attribute "VER" "2"
					( Origin gFrontEnd )
				)
				( attribute "WATTAGE" "1/16W"
					( Origin gFrontEnd )
				)
				( attribute "XY" "(-7025,6550)"
					( Origin gFrontEnd )
				)
				( attribute "CHIPS_PART_NAME" "RES"
					( Origin gPackager )
				)
				( attribute "CDS_PART_NAME" "RES_0402-10.0K,1%,1/16W,CHIP,GA"
					( Origin gPackager )
				)
				( objectStatus "R1M11" )
			)
			( gate "@baseboard_fab2_lib.baseboard_fab2(sch_1):page177_i20"
				( attribute "CDS_LIB" "dev_discrete"
					( Origin gPackager )
				)
				( attribute "CDS_LOCATION" "C1M3"
					( Origin gPackager )
				)
				( attribute "CDS_SEC" "1"
					( Origin gPackager )
				)
				( attribute "LOCATION" "C1M3"
					( Origin gFrontEnd )
				)
				( attribute "MATERIAL" "X6S"
					( Origin gFrontEnd )
				)
				( attribute "PACK_TYPE" "0402V"
					( Origin gFrontEnd )
				)
				( attribute "PART_NUMBER" "D97712-004"
					( Origin gFrontEnd )
				)
				( attribute "PHYS_PAGE" "177"
					( Origin gFrontEnd )
				)
				( attribute "ROOM" "MIO_CHASSIS"
					( Origin gFrontEnd )
				)
				( attribute "ROT" "0"
					( Origin gFrontEnd )
				)
				( attribute "SEC" "1"
					( Origin gPackager )
				)
				( attribute "TOLERANCE" "10%"
					( Origin gFrontEnd )
				)
				( attribute "VALUE" "1.0UF"
					( Origin gFrontEnd )
				)
				( attribute "VER" "1"
					( Origin gFrontEnd )
				)
				( attribute "VOLTAGE" "6.3V"
					( Units "uVoltage" "V" 1.000000)
					( Origin gFrontEnd )
				)
				( attribute "XY" "(-5625,5425)"
					( Origin gFrontEnd )
				)
				( attribute "CHIPS_PART_NAME" "CAP_A"
					( Origin gPackager )
				)
				( attribute "CDS_PART_NAME" "CAP_A_0402V-1.0UF,6.3V,10%,X6SA"
					( Origin gPackager )
				)
				( objectStatus "C1M3" )
			)
			( gate "@baseboard_fab2_lib.baseboard_fab2(sch_1):page177_i31"
				( attribute "CDS_LIB" "mstr_discrete"
					( Origin gPackager )
				)
				( attribute "CDS_LOCATION" "DS9A6"
					( Origin gPackager )
				)
				( attribute "CDS_SEC" "1"
					( Origin gPackager )
				)
				( attribute "COLOR" "GREEN"
					( Origin gFrontEnd )
				)
				( attribute "LOCATION" "DS9A6"
					( Origin gFrontEnd )
				)
				( attribute "MATERIAL" "IC"
					( Origin gFrontEnd )
				)
				( attribute "PACK_TYPE" "A1LF"
					( Origin gFrontEnd )
				)
				( attribute "PART_NUMBER" "C97278-010"
					( Origin gFrontEnd )
				)
				( attribute "PHYS_PAGE" "177"
					( Origin gFrontEnd )
				)
				( attribute "ROOM" "MIO_CHASSIS"
					( Origin gFrontEnd )
				)
				( attribute "ROT" "0"
					( Origin gFrontEnd )
				)
				( attribute "SEC" "1"
					( Origin gFrontEnd )
				)
				( attribute "SEC_TYPE" "A1LF"
					( Origin gFrontEnd )
				)
				( attribute "VER" "2"
					( Origin gFrontEnd )
				)
				( attribute "XY" "(-3825,8475)"
					( Origin gFrontEnd )
				)
				( attribute "CHIPS_PART_NAME" "LED"
					( Origin gPackager )
				)
				( attribute "CDS_PART_NAME" "LED_A1LF-GREEN,IC,C97278-010"
					( Origin gPackager )
				)
				( objectStatus "DS9A6" )
			)
			( gate "@baseboard_fab2_lib.baseboard_fab2(sch_1):page177_i33"
				( attribute "CDS_LIB" "mstr_discrete"
					( Origin gPackager )
				)
				( attribute "CDS_LOCATION" "R1L37"
					( Origin gPackager )
				)
				( attribute "CDS_SEC" "1"
					( Origin gPackager )
				)
				( attribute "LOCATION" "R1L37"
					( Origin gFrontEnd )
				)
				( attribute "MATERIAL" "CHIP"
					( Origin gFrontEnd )
				)
				( attribute "PACK_TYPE" "0402"
					( Origin gFrontEnd )
				)
				( attribute "PART_NUMBER" "G21796-076"
					( Origin gFrontEnd )
				)
				( attribute "PHYS_PAGE" "177"
					( Origin gFrontEnd )
				)
				( attribute "ROOM" "MIO_CHASSIS"
					( Origin gFrontEnd )
				)
				( attribute "ROT" "0"
					( Origin gFrontEnd )
				)
				( attribute "SEC" "1"
					( Origin gPackager )
				)
				( attribute "SIGNAL_MODEL" "DEFAULT_RESISTOR_332OHM_2_1"
					( Origin gFrontEnd )
				)
				( attribute "TOLERANCE" "1%"
					( Origin gFrontEnd )
				)
				( attribute "VALUE" "301.0"
					( Origin gFrontEnd )
				)
				( attribute "VER" "2"
					( Origin gFrontEnd )
				)
				( attribute "WATTAGE" "1/16W"
					( Origin gFrontEnd )
				)
				( attribute "XY" "(-3825,8850)"
					( Origin gFrontEnd )
				)
				( attribute "CHIPS_PART_NAME" "RES"
					( Origin gPackager )
				)
				( attribute "CDS_PART_NAME" "RES_0402-301.0,1%,1/16W,CHIP,GA"
					( Origin gPackager )
				)
				( objectStatus "R1L37" )
			)
			( gate "@baseboard_fab2_lib.baseboard_fab2(sch_1):page177_i42"
				( attribute "CDS_LIB" "mstr_discrete"
					( Origin gPackager )
				)
				( attribute "CDS_LOCATION" "DS9A2"
					( Origin gPackager )
				)
				( attribute "CDS_SEC" "1"
					( Origin gPackager )
				)
				( attribute "COLOR" "GREEN"
					( Origin gFrontEnd )
				)
				( attribute "LOCATION" "DS9A2"
					( Origin gFrontEnd )
				)
				( attribute "MATERIAL" "IC"
					( Origin gFrontEnd )
				)
				( attribute "PACK_TYPE" "1NCLF"
					( Origin gFrontEnd )
				)
				( attribute "PART_NUMBER" "C96565-011"
					( Origin gFrontEnd )
				)
				( attribute "PHYS_PAGE" "177"
					( Origin gFrontEnd )
				)
				( attribute "ROOM" "MIO_CHASSIS"
					( Origin gFrontEnd )
				)
				( attribute "ROT" "0"
					( Origin gFrontEnd )
				)
				( attribute "SEC" "1"
					( Origin gFrontEnd )
				)
				( attribute "SEC_TYPE" "1NCLF"
					( Origin gFrontEnd )
				)
				( attribute "VER" "3"
					( Origin gFrontEnd )
				)
				( attribute "XY" "(-5550,6275)"
					( Origin gFrontEnd )
				)
				( attribute "CHIPS_PART_NAME" "LED"
					( Origin gPackager )
				)
				( attribute "CDS_PART_NAME" "LED_1NCLF-GREEN,IC,C96565-011"
					( Origin gPackager )
				)
				( attribute "NEW_PN" "83.00320.A70"
					( Origin gFrontEnd )
				)
				( objectStatus "DS9A2" )
			)
			( gate "@baseboard_fab2_lib.baseboard_fab2(sch_1):page177_i43"
				( attribute "CDS_LIB" "mstr_discrete"
					( Origin gPackager )
				)
				( attribute "CDS_LOCATION" "R1L21"
					( Origin gPackager )
				)
				( attribute "CDS_SEC" "1"
					( Origin gPackager )
				)
				( attribute "LOCATION" "R1L21"
					( Origin gFrontEnd )
				)
				( attribute "MATERIAL" "CHIP"
					( Origin gFrontEnd )
				)
				( attribute "PACK_TYPE" "0402"
					( Origin gFrontEnd )
				)
				( attribute "PART_NUMBER" "G21796-298"
					( Origin gFrontEnd )
				)
				( attribute "PHYS_PAGE" "177"
					( Origin gFrontEnd )
				)
				( attribute "ROOM" "MIO_CHASSIS"
					( Origin gFrontEnd )
				)
				( attribute "ROT" "0"
					( Origin gFrontEnd )
				)
				( attribute "SEC" "1"
					( Origin gFrontEnd )
				)
				( attribute "SEC_TYPE" "0402"
					( Origin gFrontEnd )
				)
				( attribute "TOLERANCE" "1.0%"
					( Origin gFrontEnd )
				)
				( attribute "VALUE" "64.9"
					( Origin gFrontEnd )
				)
				( attribute "VER" "2"
					( Origin gFrontEnd )
				)
				( attribute "WATTAGE" "1/16W"
					( Origin gFrontEnd )
				)
				( attribute "XY" "(-4675,6600)"
					( Origin gFrontEnd )
				)
				( attribute "CHIPS_PART_NAME" "RES"
					( Origin gPackager )
				)
				( attribute "CDS_PART_NAME" "RES_0402-64.9,1.0%,1/16W,CHIP,A"
					( Origin gPackager )
				)
				( attribute "CONFIG" "64.12005.6DL"
					( Origin gFrontEnd )
				)
				( objectStatus "R1L21" )
			)
			( gate "@baseboard_fab2_lib.baseboard_fab2(sch_1):page177_i70"
				( attribute "BOM_COST" "MIO_CHASSIS"
					( Origin gFrontEnd )
				)
				( attribute "CDS_LIB" "mstr_ttl"
					( Origin gPackager )
				)
				( attribute "CDS_LOCATION" "U1M1"
					( Origin gPackager )
				)
				( attribute "CDS_SEC" "1"
					( Origin gPackager )
				)
				( attribute "LOCATION" "U1M1"
					( Origin gFrontEnd )
				)
				( attribute "MATERIAL" "IC"
					( Origin gFrontEnd )
				)
				( attribute "PACK_TYPE" "SOTLF"
					( Origin gFrontEnd )
				)
				( attribute "PART_NUMBER" "D10321-001"
					( Origin gFrontEnd )
				)
				( attribute "PHYS_PAGE" "177"
					( Origin gFrontEnd )
				)
				( attribute "ROOM" "MIO_CHASSIS"
					( Origin gFrontEnd )
				)
				( attribute "ROT" "0"
					( Origin gFrontEnd )
				)
				( attribute "SEC" "1"
					( Origin gFrontEnd )
				)
				( attribute "SEC_TYPE" "SOTLF"
					( Origin gFrontEnd )
				)
				( attribute "VALUE" "NC7SZ08"
					( Origin gFrontEnd )
				)
				( attribute "VER" "1"
					( Origin gFrontEnd )
				)
				( attribute "XY" "(-6550,6275)"
					( Origin gFrontEnd )
				)
				( attribute "CHIPS_PART_NAME" "TTL1G08"
					( Origin gPackager )
				)
				( attribute "CDS_PART_NAME" "TTL1G08_SOTLF-NC7SZ08,IC,D1032C"
					( Origin gPackager )
				)
				( objectStatus "U1M1" )
			)
			( gate "@baseboard_fab2_lib.baseboard_fab2(sch_1):page177_i71"
				( attribute "BOM_COST" "SM_CONTROLLER"
					( Origin gFrontEnd )
				)
				( attribute "CDS_LIB" "mstr_discrete"
					( Origin gPackager )
				)
				( attribute "CDS_LOCATION" "DS9F1"
					( Origin gPackager )
				)
				( attribute "CDS_SEC" "1"
					( Origin gPackager )
				)
				( attribute "COLOR" "RED"
					( Origin gFrontEnd )
				)
				( attribute "LOCATION" "DS9F1"
					( Origin gFrontEnd )
				)
				( attribute "MATERIAL" "IC"
					( Origin gFrontEnd )
				)
				( attribute "PACK_TYPE" "A1"
					( Origin gFrontEnd )
				)
				( attribute "PART_NUMBER" "D14725-005"
					( Origin gFrontEnd )
				)
				( attribute "PHYS_PAGE" "177"
					( Origin gFrontEnd )
				)
				( attribute "ROOM" "BMC"
					( Origin gFrontEnd )
				)
				( attribute "ROT" "0"
					( Origin gFrontEnd )
				)
				( attribute "SEC" "1"
					( Origin gFrontEnd )
				)
				( attribute "SEC_TYPE" "A1"
					( Origin gFrontEnd )
				)
				( attribute "VER" "2"
					( Origin gFrontEnd )
				)
				( attribute "XY" "(-7200,8475)"
					( Origin gFrontEnd )
				)
				( attribute "CHIPS_PART_NAME" "LED"
					( Origin gPackager )
				)
				( attribute "CDS_PART_NAME" "LED_A1-RED,IC,D14725-005"
					( Origin gPackager )
				)
				( objectStatus "DS9F1" )
			)
			( gate "@baseboard_fab2_lib.baseboard_fab2(sch_1):page177_i72"
				( attribute "BOM_COST" "SM_CONTROLLER"
					( Origin gFrontEnd )
				)
				( attribute "CDS_LIB" "mstr_discrete"
					( Origin gPackager )
				)
				( attribute "CDS_LOCATION" "R9F28"
					( Origin gPackager )
				)
				( attribute "CDS_SEC" "1"
					( Origin gPackager )
				)
				( attribute "LOCATION" "R9F28"
					( Origin gFrontEnd )
				)
				( attribute "MATERIAL" "CHIP"
					( Origin gFrontEnd )
				)
				( attribute "PACK_TYPE" "0402"
					( Origin gFrontEnd )
				)
				( attribute "PART_NUMBER" "G21796-271"
					( Origin gFrontEnd )
				)
				( attribute "PHYS_PAGE" "177"
					( Origin gFrontEnd )
				)
				( attribute "ROOM" "BMC"
					( Origin gFrontEnd )
				)
				( attribute "ROT" "0"
					( Origin gFrontEnd )
				)
				( attribute "SEC" "1"
					( Origin gFrontEnd )
				)
				( attribute "SEC_TYPE" "0402"
					( Origin gFrontEnd )
				)
				( attribute "TOLERANCE" "1.0%"
					( Origin gFrontEnd )
				)
				( attribute "VALUE" "221"
					( Origin gFrontEnd )
				)
				( attribute "VER" "2"
					( Origin gFrontEnd )
				)
				( attribute "WATTAGE" "1/16W"
					( Origin gFrontEnd )
				)
				( attribute "XY" "(-7200,8825)"
					( Origin gFrontEnd )
				)
				( attribute "CHIPS_PART_NAME" "RES"
					( Origin gPackager )
				)
				( attribute "CDS_PART_NAME" "RES_0402-221,1.0%,1/16W,CHIP,GA"
					( Origin gPackager )
				)
				( objectStatus "R9F28" )
			)
			( gate "@baseboard_fab2_lib.baseboard_fab2(sch_1):page177_i76"
				( attribute "BOM_COST" "SM_CONTROLLER"
					( Origin gFrontEnd )
				)
				( attribute "CDS_LIB" "mstr_discrete"
					( Origin gPackager )
				)
				( attribute "CDS_LOCATION" "R9F30"
					( Origin gPackager )
				)
				( attribute "CDS_SEC" "1"
					( Origin gPackager )
				)
				( attribute "LOCATION" "R9F30"
					( Origin gFrontEnd )
				)
				( attribute "MATERIAL" "CHIP"
					( Origin gFrontEnd )
				)
				( attribute "PACK_TYPE" "0402"
					( Origin gFrontEnd )
				)
				( attribute "PART_NUMBER" "G21796-072"
					( Origin gFrontEnd )
				)
				( attribute "PHYS_PAGE" "177"
					( Origin gFrontEnd )
				)
				( attribute "ROOM" "BMC"
					( Origin gFrontEnd )
				)
				( attribute "ROT" "0"
					( Origin gFrontEnd )
				)
				( attribute "SEC" "1"
					( Origin gFrontEnd )
				)
				( attribute "SEC_TYPE" "0402"
					( Origin gFrontEnd )
				)
				( attribute "TOLERANCE" "1%"
					( Origin gFrontEnd )
				)
				( attribute "VALUE" "4.75K"
					( Origin gFrontEnd )
				)
				( attribute "VER" "2"
					( Origin gFrontEnd )
				)
				( attribute "WATTAGE" "1/16W"
					( Origin gFrontEnd )
				)
				( attribute "XY" "(-8800,7850)"
					( Origin gFrontEnd )
				)
				( attribute "CHIPS_PART_NAME" "RES"
					( Origin gPackager )
				)
				( attribute "CDS_PART_NAME" "RES_0402-4.75K,1%,1/16W,CHIP,GA"
					( Origin gPackager )
				)
				( objectStatus "R9F30" )
			)
			( gate "@baseboard_fab2_lib.baseboard_fab2(sch_1):page177_i79"
				( attribute "BOM_COST" "SM_CONTROLLER"
					( Origin gFrontEnd )
				)
				( attribute "CDS_LIB" "mstr_discrete"
					( Origin gPackager )
				)
				( attribute "CDS_LOCATION" "Q9F1"
					( Origin gPackager )
				)
				( attribute "CDS_SEC" "2"
					( Origin gPackager )
				)
				( attribute "LOCATION" "Q9F1"
					( Origin gFrontEnd )
				)
				( attribute "MATERIAL" "FET"
					( Origin gFrontEnd )
				)
				( attribute "PACK_TYPE" "SMLF"
					( Origin gFrontEnd )
				)
				( attribute "PART_NUMBER" "E40049-001"
					( Origin gFrontEnd )
				)
				( attribute "PHYS_PAGE" "177"
					( Origin gFrontEnd )
				)
				( attribute "ROOM" "BMC"
					( Origin gFrontEnd )
				)
				( attribute "ROT" "0"
					( Origin gFrontEnd )
				)
				( attribute "SEC" "2"
					( Origin gFrontEnd )
				)
				( attribute "SEC_TYPE" "SMLF"
					( Origin gFrontEnd )
				)
				( attribute "VALUE" "NTJD4001N"
					( Origin gFrontEnd )
				)
				( attribute "VER" "5"
					( Origin gFrontEnd )
				)
				( attribute "XY" "(-7200,8050)"
					( Origin gFrontEnd )
				)
				( attribute "CHIPS_PART_NAME" "FET_N_DUAL"
					( Origin gPackager )
				)
				( attribute "CDS_PART_NAME" "FET_N_DUAL_SMLF-NTJD4001N,FET,A"
					( Origin gPackager )
				)
				( objectStatus "Q9F1" )
			)
			( gate "@baseboard_fab2_lib.baseboard_fab2(sch_1):page177_i80"
				( attribute "BOM_COST" "SM_CONTROLLER"
					( Origin gFrontEnd )
				)
				( attribute "CDS_LIB" "mstr_discrete"
					( Origin gPackager )
				)
				( attribute "CDS_LOCATION" "Q9F1"
					( Origin gPackager )
				)
				( attribute "CDS_SEC" "1"
					( Origin gPackager )
				)
				( attribute "LOCATION" "Q9F1"
					( Origin gFrontEnd )
				)
				( attribute "MATERIAL" "FET"
					( Origin gFrontEnd )
				)
				( attribute "PACK_TYPE" "SMLF"
					( Origin gFrontEnd )
				)
				( attribute "PART_NUMBER" "E40049-001"
					( Origin gFrontEnd )
				)
				( attribute "PHYS_PAGE" "177"
					( Origin gFrontEnd )
				)
				( attribute "ROOM" "BMC"
					( Origin gFrontEnd )
				)
				( attribute "ROT" "0"
					( Origin gFrontEnd )
				)
				( attribute "SEC" "1"
					( Origin gFrontEnd )
				)
				( attribute "SEC_TYPE" "SMLF"
					( Origin gFrontEnd )
				)
				( attribute "VALUE" "NTJD4001N"
					( Origin gFrontEnd )
				)
				( attribute "VER" "5"
					( Origin gFrontEnd )
				)
				( attribute "XY" "(-8125,7675)"
					( Origin gFrontEnd )
				)
				( attribute "CHIPS_PART_NAME" "FET_N_DUAL"
					( Origin gPackager )
				)
				( attribute "CDS_PART_NAME" "FET_N_DUAL_SMLF-NTJD4001N,FET,A"
					( Origin gPackager )
				)
				( objectStatus "Q9F1" )
			)
			( gate "@baseboard_fab2_lib.baseboard_fab2(sch_1):page177_i82"
				( attribute "BOM_COST" "SM_CONTROLLER"
					( Origin gFrontEnd )
				)
				( attribute "CDS_LIB" "mstr_discrete"
					( Origin gPackager )
				)
				( attribute "CDS_LOCATION" "R9F52"
					( Origin gPackager )
				)
				( attribute "CDS_SEC" "1"
					( Origin gPackager )
				)
				( attribute "LOCATION" "R9F52"
					( Origin gFrontEnd )
				)
				( attribute "MATERIAL" "CHIP"
					( Origin gFrontEnd )
				)
				( attribute "PACK_TYPE" "0402"
					( Origin gFrontEnd )
				)
				( attribute "PART_NUMBER" "G21796-072"
					( Origin gFrontEnd )
				)
				( attribute "PHYS_PAGE" "177"
					( Origin gFrontEnd )
				)
				( attribute "ROOM" "BMC"
					( Origin gFrontEnd )
				)
				( attribute "ROT" "0"
					( Origin gFrontEnd )
				)
				( attribute "SEC" "1"
					( Origin gFrontEnd )
				)
				( attribute "SEC_TYPE" "0402"
					( Origin gFrontEnd )
				)
				( attribute "TOLERANCE" "1%"
					( Origin gFrontEnd )
				)
				( attribute "VALUE" "4.75K"
					( Origin gFrontEnd )
				)
				( attribute "VER" "2"
					( Origin gFrontEnd )
				)
				( attribute "WATTAGE" "1/16W"
					( Origin gFrontEnd )
				)
				( attribute "XY" "(-8125,8225)"
					( Origin gFrontEnd )
				)
				( attribute "CHIPS_PART_NAME" "RES"
					( Origin gPackager )
				)
				( attribute "CDS_PART_NAME" "RES_0402-4.75K,1%,1/16W,CHIP,GA"
					( Origin gPackager )
				)
				( objectStatus "R9F52" )
			)
			( gate "@baseboard_fab2_lib.baseboard_fab2(sch_1):page178_i1"
				( attribute "BOM_COST" "ST_SATA"
					( Origin gFrontEnd )
				)
				( attribute "CDS_LIB" "mstr_discrete"
					( Origin gPackager )
				)
				( attribute "CDS_LOCATION" "R8D20"
					( Origin gPackager )
				)
				( attribute "CDS_SEC" "1"
					( Origin gPackager )
				)
				( attribute "LOCATION" "R8D20"
					( Origin gFrontEnd )
				)
				( attribute "MATERIAL" "CHIP"
					( Origin gFrontEnd )
				)
				( attribute "PACK_TYPE" "0402"
					( Origin gFrontEnd )
				)
				( attribute "PART_NUMBER" "G21796-047"
					( Origin gFrontEnd )
				)
				( attribute "PHYS_PAGE" "178"
					( Origin gFrontEnd )
				)
				( attribute "ROOM" "ST_SATA"
					( Origin gFrontEnd )
				)
				( attribute "ROT" "0"
					( Origin gFrontEnd )
				)
				( attribute "SEC" "1"
					( Origin gFrontEnd )
				)
				( attribute "SEC_TYPE" "0402"
					( Origin gFrontEnd )
				)
				( attribute "TOLERANCE" "1%"
					( Origin gFrontEnd )
				)
				( attribute "VALUE" "49.9"
					( Origin gFrontEnd )
				)
				( attribute "VER" "1"
					( Origin gFrontEnd )
				)
				( attribute "WATTAGE" "1/16W"
					( Origin gFrontEnd )
				)
				( attribute "XY" "(-800,3725)"
					( Origin gFrontEnd )
				)
				( attribute "CHIPS_PART_NAME" "RES"
					( Origin gPackager )
				)
				( attribute "CDS_PART_NAME" "RES_0402-49.9,1%,1/16W,CHIP,G2A"
					( Origin gPackager )
				)
				( objectStatus "R8D20" )
			)
			( gate "@baseboard_fab2_lib.baseboard_fab2(sch_1):page178_i2"
				( attribute "BOM_COST" "ST_SATA"
					( Origin gFrontEnd )
				)
				( attribute "CDS_LIB" "mstr_discrete"
					( Origin gPackager )
				)
				( attribute "CDS_LOCATION" "R2L12"
					( Origin gPackager )
				)
				( attribute "CDS_SEC" "1"
					( Origin gPackager )
				)
				( attribute "LOCATION" "R2L12"
					( Origin gFrontEnd )
				)
				( attribute "MATERIAL" "CHIP"
					( Origin gFrontEnd )
				)
				( attribute "PACK_TYPE" "0402"
					( Origin gFrontEnd )
				)
				( attribute "PART_NUMBER" "G21796-001"
					( Origin gFrontEnd )
				)
				( attribute "PHYS_PAGE" "178"
					( Origin gFrontEnd )
				)
				( attribute "ROOM" "ST_SATA"
					( Origin gFrontEnd )
				)
				( attribute "ROT" "2"
					( Origin gFrontEnd )
				)
				( attribute "SEC" "1"
					( Origin gFrontEnd )
				)
				( attribute "SEC_TYPE" "0402"
					( Origin gFrontEnd )
				)
				( attribute "TOLERANCE" "1%"
					( Origin gFrontEnd )
				)
				( attribute "VALUE" "2.0K"
					( Origin gFrontEnd )
				)
				( attribute "VER" "2"
					( Origin gFrontEnd )
				)
				( attribute "WATTAGE" "1/16W"
					( Origin gFrontEnd )
				)
				( attribute "XY" "(-200,4125)"
					( Origin gFrontEnd )
				)
				( attribute "CHIPS_PART_NAME" "RES"
					( Origin gPackager )
				)
				( attribute "CDS_PART_NAME" "RES_0402-2.0K,1%,1/16W,CHIP,G2A"
					( Origin gPackager )
				)
				( objectStatus "R2L12" )
			)
			( gate "@baseboard_fab2_lib.baseboard_fab2(sch_1):page178_i8"
				( attribute "BOM_COST" "ST_SATA"
					( Origin gFrontEnd )
				)
				( attribute "CDS_LIB" "mstr_discrete"
					( Origin gPackager )
				)
				( attribute "CDS_LOCATION" "R8D19"
					( Origin gPackager )
				)
				( attribute "CDS_SEC" "1"
					( Origin gPackager )
				)
				( attribute "LOCATION" "R8D19"
					( Origin gFrontEnd )
				)
				( attribute "MATERIAL" "CHIP"
					( Origin gFrontEnd )
				)
				( attribute "PACK_TYPE" "0402"
					( Origin gFrontEnd )
				)
				( attribute "PART_NUMBER" "G21796-047"
					( Origin gFrontEnd )
				)
				( attribute "PHYS_PAGE" "178"
					( Origin gFrontEnd )
				)
				( attribute "ROOM" "ST_SATA"
					( Origin gFrontEnd )
				)
				( attribute "ROT" "0"
					( Origin gFrontEnd )
				)
				( attribute "SEC" "1"
					( Origin gFrontEnd )
				)
				( attribute "SEC_TYPE" "0402"
					( Origin gFrontEnd )
				)
				( attribute "TOLERANCE" "1%"
					( Origin gFrontEnd )
				)
				( attribute "VALUE" "49.9"
					( Origin gFrontEnd )
				)
				( attribute "VER" "1"
					( Origin gFrontEnd )
				)
				( attribute "WATTAGE" "1/16W"
					( Origin gFrontEnd )
				)
				( attribute "XY" "(-800,3575)"
					( Origin gFrontEnd )
				)
				( attribute "CHIPS_PART_NAME" "RES"
					( Origin gPackager )
				)
				( attribute "CDS_PART_NAME" "RES_0402-49.9,1%,1/16W,CHIP,G2A"
					( Origin gPackager )
				)
				( objectStatus "R8D19" )
			)
			( gate "@baseboard_fab2_lib.baseboard_fab2(sch_1):page178_i11"
				( attribute "BOM_COST" "ST_SATA"
					( Origin gFrontEnd )
				)
				( attribute "CDS_LIB" "mstr_discrete"
					( Origin gPackager )
				)
				( attribute "CDS_LOCATION" "R2N31"
					( Origin gPackager )
				)
				( attribute "CDS_SEC" "1"
					( Origin gPackager )
				)
				( attribute "LOCATION" "R2N31"
					( Origin gFrontEnd )
				)
				( attribute "MATERIAL" "CHIP"
					( Origin gFrontEnd )
				)
				( attribute "PACK_TYPE" "0402"
					( Origin gFrontEnd )
				)
				( attribute "PART_NUMBER" "G21796-047"
					( Origin gFrontEnd )
				)
				( attribute "PHYS_PAGE" "178"
					( Origin gFrontEnd )
				)
				( attribute "ROOM" "ST_SATA"
					( Origin gFrontEnd )
				)
				( attribute "ROT" "0"
					( Origin gFrontEnd )
				)
				( attribute "SEC" "1"
					( Origin gFrontEnd )
				)
				( attribute "SEC_TYPE" "0402"
					( Origin gFrontEnd )
				)
				( attribute "TOLERANCE" "1%"
					( Origin gFrontEnd )
				)
				( attribute "VALUE" "49.9"
					( Origin gFrontEnd )
				)
				( attribute "VER" "1"
					( Origin gFrontEnd )
				)
				( attribute "WATTAGE" "1/16W"
					( Origin gFrontEnd )
				)
				( attribute "XY" "(-800,3425)"
					( Origin gFrontEnd )
				)
				( attribute "CHIPS_PART_NAME" "RES"
					( Origin gPackager )
				)
				( attribute "CDS_PART_NAME" "RES_0402-49.9,1%,1/16W,CHIP,G2A"
					( Origin gPackager )
				)
				( objectStatus "R2N31" )
			)
			( gate "@baseboard_fab2_lib.baseboard_fab2(sch_1):page178_i12"
				( attribute "BOM_COST" "ST_SATA"
					( Origin gFrontEnd )
				)
				( attribute "CDS_LIB" "mstr_discrete"
					( Origin gPackager )
				)
				( attribute "CDS_LOCATION" "R2L15"
					( Origin gPackager )
				)
				( attribute "CDS_SEC" "1"
					( Origin gPackager )
				)
				( attribute "LOCATION" "R2L15"
					( Origin gFrontEnd )
				)
				( attribute "MATERIAL" "CHIP"
					( Origin gFrontEnd )
				)
				( attribute "PACK_TYPE" "0402"
					( Origin gFrontEnd )
				)
				( attribute "PART_NUMBER" "G21796-001"
					( Origin gFrontEnd )
				)
				( attribute "PHYS_PAGE" "178"
					( Origin gFrontEnd )
				)
				( attribute "ROOM" "ST_SATA"
					( Origin gFrontEnd )
				)
				( attribute "ROT" "2"
					( Origin gFrontEnd )
				)
				( attribute "SEC" "1"
					( Origin gFrontEnd )
				)
				( attribute "SEC_TYPE" "0402"
					( Origin gFrontEnd )
				)
				( attribute "TOLERANCE" "1%"
					( Origin gFrontEnd )
				)
				( attribute "VALUE" "2.0K"
					( Origin gFrontEnd )
				)
				( attribute "VER" "2"
					( Origin gFrontEnd )
				)
				( attribute "WATTAGE" "1/16W"
					( Origin gFrontEnd )
				)
				( attribute "XY" "(225,4125)"
					( Origin gFrontEnd )
				)
				( attribute "CHIPS_PART_NAME" "RES"
					( Origin gPackager )
				)
				( attribute "CDS_PART_NAME" "RES_0402-2.0K,1%,1/16W,CHIP,G2A"
					( Origin gPackager )
				)
				( objectStatus "R2L15" )
			)
			( gate "@baseboard_fab2_lib.baseboard_fab2(sch_1):page178_i13"
				( attribute "BOM_COST" "ST_SATA"
					( Origin gFrontEnd )
				)
				( attribute "CDS_LIB" "mstr_discrete"
					( Origin gPackager )
				)
				( attribute "CDS_LOCATION" "R2L11"
					( Origin gPackager )
				)
				( attribute "CDS_SEC" "1"
					( Origin gPackager )
				)
				( attribute "LOCATION" "R2L11"
					( Origin gFrontEnd )
				)
				( attribute "MATERIAL" "CHIP"
					( Origin gFrontEnd )
				)
				( attribute "PACK_TYPE" "0402"
					( Origin gFrontEnd )
				)
				( attribute "PART_NUMBER" "G21796-001"
					( Origin gFrontEnd )
				)
				( attribute "PHYS_PAGE" "178"
					( Origin gFrontEnd )
				)
				( attribute "ROOM" "ST_SATA"
					( Origin gFrontEnd )
				)
				( attribute "ROT" "2"
					( Origin gFrontEnd )
				)
				( attribute "SEC" "1"
					( Origin gFrontEnd )
				)
				( attribute "SEC_TYPE" "0402"
					( Origin gFrontEnd )
				)
				( attribute "TOLERANCE" "1%"
					( Origin gFrontEnd )
				)
				( attribute "VALUE" "2.0K"
					( Origin gFrontEnd )
				)
				( attribute "VER" "2"
					( Origin gFrontEnd )
				)
				( attribute "WATTAGE" "1/16W"
					( Origin gFrontEnd )
				)
				( attribute "XY" "(575,4125)"
					( Origin gFrontEnd )
				)
				( attribute "CHIPS_PART_NAME" "RES"
					( Origin gPackager )
				)
				( attribute "CDS_PART_NAME" "RES_0402-2.0K,1%,1/16W,CHIP,G2A"
					( Origin gPackager )
				)
				( objectStatus "R2L11" )
			)
			( gate "@baseboard_fab2_lib.baseboard_fab2(sch_1):page178_i17"
				( attribute "BOM_COST" "ST_SATA"
					( Origin gFrontEnd )
				)
				( attribute "CDS_LIB" "mstr_discrete"
					( Origin gPackager )
				)
				( attribute "CDS_LOCATION" "R2L6"
					( Origin gPackager )
				)
				( attribute "CDS_SEC" "1"
					( Origin gPackager )
				)
				( attribute "LOCATION" "R2L6"
					( Origin gFrontEnd )
				)
				( attribute "MATERIAL" "CHIP"
					( Origin gFrontEnd )
				)
				( attribute "PACK_TYPE" "0402"
					( Origin gFrontEnd )
				)
				( attribute "PART_NUMBER" "G21796-001"
					( Origin gFrontEnd )
				)
				( attribute "PHYS_PAGE" "178"
					( Origin gFrontEnd )
				)
				( attribute "ROOM" "ST_SATA"
					( Origin gFrontEnd )
				)
				( attribute "ROT" "2"
					( Origin gFrontEnd )
				)
				( attribute "SEC" "1"
					( Origin gFrontEnd )
				)
				( attribute "SEC_TYPE" "0402"
					( Origin gFrontEnd )
				)
				( attribute "TOLERANCE" "1%"
					( Origin gFrontEnd )
				)
				( attribute "VALUE" "2.0K"
					( Origin gFrontEnd )
				)
				( attribute "VER" "2"
					( Origin gFrontEnd )
				)
				( attribute "WATTAGE" "1/16W"
					( Origin gFrontEnd )
				)
				( attribute "XY" "(475,2225)"
					( Origin gFrontEnd )
				)
				( attribute "CHIPS_PART_NAME" "RES"
					( Origin gPackager )
				)
				( attribute "CDS_PART_NAME" "RES_0402-2.0K,1%,1/16W,CHIP,G2A"
					( Origin gPackager )
				)
				( objectStatus "R2L6" )
			)
			( gate "@baseboard_fab2_lib.baseboard_fab2(sch_1):page178_i18"
				( attribute "BOM_COST" "ST_SATA"
					( Origin gFrontEnd )
				)
				( attribute "CDS_LIB" "mstr_discrete"
					( Origin gPackager )
				)
				( attribute "CDS_LOCATION" "R2L4"
					( Origin gPackager )
				)
				( attribute "CDS_SEC" "1"
					( Origin gPackager )
				)
				( attribute "LOCATION" "R2L4"
					( Origin gFrontEnd )
				)
				( attribute "MATERIAL" "CHIP"
					( Origin gFrontEnd )
				)
				( attribute "PACK_TYPE" "0402"
					( Origin gFrontEnd )
				)
				( attribute "PART_NUMBER" "G21796-001"
					( Origin gFrontEnd )
				)
				( attribute "PHYS_PAGE" "178"
					( Origin gFrontEnd )
				)
				( attribute "ROOM" "ST_SATA"
					( Origin gFrontEnd )
				)
				( attribute "ROT" "2"
					( Origin gFrontEnd )
				)
				( attribute "SEC" "1"
					( Origin gFrontEnd )
				)
				( attribute "SEC_TYPE" "0402"
					( Origin gFrontEnd )
				)
				( attribute "TOLERANCE" "1%"
					( Origin gFrontEnd )
				)
				( attribute "VALUE" "2.0K"
					( Origin gFrontEnd )
				)
				( attribute "VER" "2"
					( Origin gFrontEnd )
				)
				( attribute "WATTAGE" "1/16W"
					( Origin gFrontEnd )
				)
				( attribute "XY" "(125,2225)"
					( Origin gFrontEnd )
				)
				( attribute "CHIPS_PART_NAME" "RES"
					( Origin gPackager )
				)
				( attribute "CDS_PART_NAME" "RES_0402-2.0K,1%,1/16W,CHIP,G2A"
					( Origin gPackager )
				)
				( objectStatus "R2L4" )
			)
			( gate "@baseboard_fab2_lib.baseboard_fab2(sch_1):page178_i20"
				( attribute "BOM_COST" "ST_SATA"
					( Origin gFrontEnd )
				)
				( attribute "CDS_LIB" "mstr_discrete"
					( Origin gPackager )
				)
				( attribute "CDS_LOCATION" "R2L5"
					( Origin gPackager )
				)
				( attribute "CDS_SEC" "1"
					( Origin gPackager )
				)
				( attribute "LOCATION" "R2L5"
					( Origin gFrontEnd )
				)
				( attribute "MATERIAL" "CHIP"
					( Origin gFrontEnd )
				)
				( attribute "PACK_TYPE" "0402"
					( Origin gFrontEnd )
				)
				( attribute "PART_NUMBER" "G21796-001"
					( Origin gFrontEnd )
				)
				( attribute "PHYS_PAGE" "178"
					( Origin gFrontEnd )
				)
				( attribute "ROOM" "ST_SATA"
					( Origin gFrontEnd )
				)
				( attribute "ROT" "2"
					( Origin gFrontEnd )
				)
				( attribute "SEC" "1"
					( Origin gFrontEnd )
				)
				( attribute "SEC_TYPE" "0402"
					( Origin gFrontEnd )
				)
				( attribute "TOLERANCE" "1%"
					( Origin gFrontEnd )
				)
				( attribute "VALUE" "2.0K"
					( Origin gFrontEnd )
				)
				( attribute "VER" "2"
					( Origin gFrontEnd )
				)
				( attribute "WATTAGE" "1/16W"
					( Origin gFrontEnd )
				)
				( attribute "XY" "(-200,2225)"
					( Origin gFrontEnd )
				)
				( attribute "CHIPS_PART_NAME" "RES"
					( Origin gPackager )
				)
				( attribute "CDS_PART_NAME" "RES_0402-2.0K,1%,1/16W,CHIP,G2A"
					( Origin gPackager )
				)
				( objectStatus "R2L5" )
			)
			( gate "@baseboard_fab2_lib.baseboard_fab2(sch_1):page178_i21"
				( attribute "BOM_COST" "ST_SATA"
					( Origin gFrontEnd )
				)
				( attribute "CDS_LIB" "mstr_discrete"
					( Origin gPackager )
				)
				( attribute "CDS_LOCATION" "R8B29"
					( Origin gPackager )
				)
				( attribute "CDS_SEC" "1"
					( Origin gPackager )
				)
				( attribute "LOCATION" "R8B29"
					( Origin gFrontEnd )
				)
				( attribute "MATERIAL" "CHIP"
					( Origin gFrontEnd )
				)
				( attribute "PACK_TYPE" "0402"
					( Origin gFrontEnd )
				)
				( attribute "PART_NUMBER" "G21796-047"
					( Origin gFrontEnd )
				)
				( attribute "PHYS_PAGE" "178"
					( Origin gFrontEnd )
				)
				( attribute "ROOM" "ST_SATA"
					( Origin gFrontEnd )
				)
				( attribute "ROT" "0"
					( Origin gFrontEnd )
				)
				( attribute "SEC" "1"
					( Origin gFrontEnd )
				)
				( attribute "SEC_TYPE" "0402"
					( Origin gFrontEnd )
				)
				( attribute "TOLERANCE" "1%"
					( Origin gFrontEnd )
				)
				( attribute "VALUE" "49.9"
					( Origin gFrontEnd )
				)
				( attribute "VER" "1"
					( Origin gFrontEnd )
				)
				( attribute "WATTAGE" "1/16W"
					( Origin gFrontEnd )
				)
				( attribute "XY" "(-800,1675)"
					( Origin gFrontEnd )
				)
				( attribute "CHIPS_PART_NAME" "RES"
					( Origin gPackager )
				)
				( attribute "CDS_PART_NAME" "RES_0402-49.9,1%,1/16W,CHIP,G2A"
					( Origin gPackager )
				)
				( objectStatus "R8B29" )
			)
			( gate "@baseboard_fab2_lib.baseboard_fab2(sch_1):page178_i22"
				( attribute "BOM_COST" "ST_SATA"
					( Origin gFrontEnd )
				)
				( attribute "CDS_LIB" "mstr_discrete"
					( Origin gPackager )
				)
				( attribute "CDS_LOCATION" "R2N19"
					( Origin gPackager )
				)
				( attribute "CDS_SEC" "1"
					( Origin gPackager )
				)
				( attribute "LOCATION" "R2N19"
					( Origin gFrontEnd )
				)
				( attribute "MATERIAL" "CHIP"
					( Origin gFrontEnd )
				)
				( attribute "PACK_TYPE" "0402"
					( Origin gFrontEnd )
				)
				( attribute "PART_NUMBER" "G21796-047"
					( Origin gFrontEnd )
				)
				( attribute "PHYS_PAGE" "178"
					( Origin gFrontEnd )
				)
				( attribute "ROOM" "ST_SATA"
					( Origin gFrontEnd )
				)
				( attribute "ROT" "0"
					( Origin gFrontEnd )
				)
				( attribute "SEC" "1"
					( Origin gFrontEnd )
				)
				( attribute "SEC_TYPE" "0402"
					( Origin gFrontEnd )
				)
				( attribute "TOLERANCE" "1%"
					( Origin gFrontEnd )
				)
				( attribute "VALUE" "49.9"
					( Origin gFrontEnd )
				)
				( attribute "VER" "1"
					( Origin gFrontEnd )
				)
				( attribute "WATTAGE" "1/16W"
					( Origin gFrontEnd )
				)
				( attribute "XY" "(-800,1825)"
					( Origin gFrontEnd )
				)
				( attribute "CHIPS_PART_NAME" "RES"
					( Origin gPackager )
				)
				( attribute "CDS_PART_NAME" "RES_0402-49.9,1%,1/16W,CHIP,G2A"
					( Origin gPackager )
				)
				( objectStatus "R2N19" )
			)
			( gate "@baseboard_fab2_lib.baseboard_fab2(sch_1):page178_i23"
				( attribute "BOM_COST" "ST_SATA"
					( Origin gFrontEnd )
				)
				( attribute "CDS_LIB" "mstr_discrete"
					( Origin gPackager )
				)
				( attribute "CDS_LOCATION" "R2N22"
					( Origin gPackager )
				)
				( attribute "CDS_SEC" "1"
					( Origin gPackager )
				)
				( attribute "LOCATION" "R2N22"
					( Origin gFrontEnd )
				)
				( attribute "MATERIAL" "CHIP"
					( Origin gFrontEnd )
				)
				( attribute "PACK_TYPE" "0402"
					( Origin gFrontEnd )
				)
				( attribute "PART_NUMBER" "G21796-047"
					( Origin gFrontEnd )
				)
				( attribute "PHYS_PAGE" "178"
					( Origin gFrontEnd )
				)
				( attribute "ROOM" "ST_SATA"
					( Origin gFrontEnd )
				)
				( attribute "ROT" "0"
					( Origin gFrontEnd )
				)
				( attribute "SEC" "1"
					( Origin gFrontEnd )
				)
				( attribute "SEC_TYPE" "0402"
					( Origin gFrontEnd )
				)
				( attribute "TOLERANCE" "1%"
					( Origin gFrontEnd )
				)
				( attribute "VALUE" "49.9"
					( Origin gFrontEnd )
				)
				( attribute "VER" "1"
					( Origin gFrontEnd )
				)
				( attribute "WATTAGE" "1/16W"
					( Origin gFrontEnd )
				)
				( attribute "XY" "(-800,1525)"
					( Origin gFrontEnd )
				)
				( attribute "CHIPS_PART_NAME" "RES"
					( Origin gPackager )
				)
				( attribute "CDS_PART_NAME" "RES_0402-49.9,1%,1/16W,CHIP,G2A"
					( Origin gPackager )
				)
				( objectStatus "R2N22" )
			)
			( gate "@baseboard_fab2_lib.baseboard_fab2(sch_1):page182_i38"
				( attribute "BOM_COST" "IO_SLOT"
					( Origin gFrontEnd )
				)
				( attribute "CDS_LIB" "mstr_discrete"
					( Origin gPackager )
				)
				( attribute "CDS_LOCATION" "C9N17"
					( Origin gPackager )
				)
				( attribute "CDS_SEC" "1"
					( Origin gPackager )
				)
				( attribute "LOCATION" "C9N17"
					( Origin gFrontEnd )
				)
				( attribute "MATERIAL" "X7R"
					( Origin gFrontEnd )
				)
				( attribute "PACK_TYPE" "0402"
					( Origin gFrontEnd )
				)
				( attribute "PART_NUMBER" "A36096-155"
					( Origin gFrontEnd )
				)
				( attribute "PHYS_PAGE" "182"
					( Origin gFrontEnd )
				)
				( attribute "ROOM" "IO_SLOT"
					( Origin gFrontEnd )
				)
				( attribute "ROT" "0"
					( Origin gFrontEnd )
				)
				( attribute "SEC" "1"
					( Origin gFrontEnd )
				)
				( attribute "SEC_TYPE" "0402"
					( Origin gFrontEnd )
				)
				( attribute "TOLERANCE" "10%"
					( Origin gFrontEnd )
				)
				( attribute "VALUE" "0.22UF"
					( Origin gFrontEnd )
				)
				( attribute "VER" "2"
					( Origin gFrontEnd )
				)
				( attribute "VOLTAGE" "16V"
					( Units "uVoltage" "V" 1.000000)
					( Origin gFrontEnd )
				)
				( attribute "XY" "(-3400,1425)"
					( Origin gFrontEnd )
				)
				( attribute "CHIPS_PART_NAME" "CAP"
					( Origin gPackager )
				)
				( attribute "CDS_PART_NAME" "CAP_0402-0.22UF,16V,10%,X7R,A3A"
					( Origin gPackager )
				)
				( objectStatus "C9N17" )
			)
			( gate "@baseboard_fab2_lib.baseboard_fab2(sch_1):page182_i39"
				( attribute "BOM_COST" "IO_SLOT"
					( Origin gFrontEnd )
				)
				( attribute "CDS_LIB" "mstr_discrete"
					( Origin gPackager )
				)
				( attribute "CDS_LOCATION" "C9N18"
					( Origin gPackager )
				)
				( attribute "CDS_SEC" "1"
					( Origin gPackager )
				)
				( attribute "LOCATION" "C9N18"
					( Origin gFrontEnd )
				)
				( attribute "MATERIAL" "X7R"
					( Origin gFrontEnd )
				)
				( attribute "PACK_TYPE" "0402"
					( Origin gFrontEnd )
				)
				( attribute "PART_NUMBER" "A36096-155"
					( Origin gFrontEnd )
				)
				( attribute "PHYS_PAGE" "182"
					( Origin gFrontEnd )
				)
				( attribute "ROOM" "IO_SLOT"
					( Origin gFrontEnd )
				)
				( attribute "ROT" "0"
					( Origin gFrontEnd )
				)
				( attribute "SEC" "1"
					( Origin gFrontEnd )
				)
				( attribute "SEC_TYPE" "0402"
					( Origin gFrontEnd )
				)
				( attribute "TOLERANCE" "10%"
					( Origin gFrontEnd )
				)
				( attribute "VALUE" "0.22UF"
					( Origin gFrontEnd )
				)
				( attribute "VER" "2"
					( Origin gFrontEnd )
				)
				( attribute "VOLTAGE" "16V"
					( Units "uVoltage" "V" 1.000000)
					( Origin gFrontEnd )
				)
				( attribute "XY" "(-2925,1475)"
					( Origin gFrontEnd )
				)
				( attribute "CHIPS_PART_NAME" "CAP"
					( Origin gPackager )
				)
				( attribute "CDS_PART_NAME" "CAP_0402-0.22UF,16V,10%,X7R,A3A"
					( Origin gPackager )
				)
				( objectStatus "C9N18" )
			)
			( gate "@baseboard_fab2_lib.baseboard_fab2(sch_1):page182_i40"
				( attribute "BOM_COST" "IO_SLOT"
					( Origin gFrontEnd )
				)
				( attribute "CDS_LIB" "mstr_discrete"
					( Origin gPackager )
				)
				( attribute "CDS_LOCATION" "C9N1"
					( Origin gPackager )
				)
				( attribute "CDS_SEC" "1"
					( Origin gPackager )
				)
				( attribute "LOCATION" "C9N1"
					( Origin gFrontEnd )
				)
				( attribute "MATERIAL" "X7R"
					( Origin gFrontEnd )
				)
				( attribute "PACK_TYPE" "0402"
					( Origin gFrontEnd )
				)
				( attribute "PART_NUMBER" "A36096-155"
					( Origin gFrontEnd )
				)
				( attribute "PHYS_PAGE" "182"
					( Origin gFrontEnd )
				)
				( attribute "ROOM" "IO_SLOT"
					( Origin gFrontEnd )
				)
				( attribute "ROT" "0"
					( Origin gFrontEnd )
				)
				( attribute "SEC" "1"
					( Origin gFrontEnd )
				)
				( attribute "SEC_TYPE" "0402"
					( Origin gFrontEnd )
				)
				( attribute "TOLERANCE" "10%"
					( Origin gFrontEnd )
				)
				( attribute "VALUE" "0.22UF"
					( Origin gFrontEnd )
				)
				( attribute "VER" "2"
					( Origin gFrontEnd )
				)
				( attribute "VOLTAGE" "16V"
					( Units "uVoltage" "V" 1.000000)
					( Origin gFrontEnd )
				)
				( attribute "XY" "(-2925,1175)"
					( Origin gFrontEnd )
				)
				( attribute "CHIPS_PART_NAME" "CAP"
					( Origin gPackager )
				)
				( attribute "CDS_PART_NAME" "CAP_0402-0.22UF,16V,10%,X7R,A3A"
					( Origin gPackager )
				)
				( objectStatus "C9N1" )
			)
			( gate "@baseboard_fab2_lib.baseboard_fab2(sch_1):page158_i150"
				( attribute "BOM_COST" "DEBUG"
					( Origin gFrontEnd )
				)
				( attribute "CDS_LIB" "mstr_discrete"
					( Origin gPackager )
				)
				( attribute "CDS_LOCATION" "R9F69"
					( Origin gPackager )
				)
				( attribute "CDS_SEC" "1"
					( Origin gPackager )
				)
				( attribute "LOCATION" "R9F69"
					( Origin gFrontEnd )
				)
				( attribute "MATERIAL" "CHIP"
					( Origin gFrontEnd )
				)
				( attribute "PACK_TYPE" "0402"
					( Origin gFrontEnd )
				)
				( attribute "PART_NUMBER" "G21497-005"
					( Origin gFrontEnd )
				)
				( attribute "PHYS_PAGE" "158"
					( Origin gFrontEnd )
				)
				( attribute "ROOM" "UART_MUX"
					( Origin gFrontEnd )
				)
				( attribute "ROT" "0"
					( Origin gFrontEnd )
				)
				( attribute "SEC" "1"
					( Origin gFrontEnd )
				)
				( attribute "SEC_TYPE" "0402"
					( Origin gFrontEnd )
				)
				( attribute "TOLERANCE" "5%"
					( Origin gFrontEnd )
				)
				( attribute "VALUE" "0.0"
					( Origin gFrontEnd )
				)
				( attribute "VER" "1"
					( Origin gFrontEnd )
				)
				( attribute "WATTAGE" "1/16W"
					( Origin gFrontEnd )
				)
				( attribute "XY" "(-1100,1775)"
					( Origin gFrontEnd )
				)
				( attribute "CHIPS_PART_NAME" "RES"
					( Origin gPackager )
				)
				( attribute "CDS_PART_NAME" "RES_0402-0.0,5%,1/16W,CHIP,G21A"
					( Origin gPackager )
				)
				( objectStatus "R9F69" )
			)
			( gate "@baseboard_fab2_lib.baseboard_fab2(sch_1):page158_i149"
				( attribute "BOM_COST" "DEBUG"
					( Origin gFrontEnd )
				)
				( attribute "CDS_LIB" "mstr_discrete"
					( Origin gPackager )
				)
				( attribute "CDS_LOCATION" "R9F68"
					( Origin gPackager )
				)
				( attribute "LOCATION" "R9F68"
					( Origin gFrontEnd )
				)
				( attribute "MATERIAL" "EMPTY"
					( Origin gFrontEnd )
				)
				( attribute "PACK_TYPE" "0402"
					( Origin gFrontEnd )
				)
				( attribute "PART_NUMBER" "G21497-005"
					( Origin gFrontEnd )
				)
				( attribute "PHYS_PAGE" "158"
					( Origin gFrontEnd )
				)
				( attribute "ROOM" "UART_MUX"
					( Origin gFrontEnd )
				)
				( attribute "ROT" "0"
					( Origin gFrontEnd )
				)
				( attribute "SEC" "1"
					( Origin gFrontEnd )
				)
				( attribute "TOLERANCE" "5%"
					( Origin gFrontEnd )
				)
				( attribute "VALUE" "0.0"
					( Origin gFrontEnd )
				)
				( attribute "VER" "1"
					( Origin gFrontEnd )
				)
				( attribute "WATTAGE" "1/16W"
					( Origin gFrontEnd )
				)
				( attribute "XY" "(-1250,850)"
					( Origin gFrontEnd )
				)
				( attribute "CHIPS_PART_NAME" "RES"
					( Origin gPackager )
				)
				( attribute "CDS_PART_NAME" "RES_0402-0.0,5%,1/16W,EMPTY,G2A"
					( Origin gPackager )
				)
				( attribute "SEC_TYPE" "0402"
					( Origin gFrontEnd )
				)
				( attribute "CDS_SEC" "1"
					( Origin gPackager )
				)
				( objectStatus "R9F68" )
			)
			( gate "@baseboard_fab2_lib.baseboard_fab2(sch_1):page182_i41"
				( attribute "BOM_COST" "IO_SLOT"
					( Origin gFrontEnd )
				)
				( attribute "CDS_LIB" "mstr_discrete"
					( Origin gPackager )
				)
				( attribute "CDS_LOCATION" "C9N15"
					( Origin gPackager )
				)
				( attribute "CDS_SEC" "1"
					( Origin gPackager )
				)
				( attribute "LOCATION" "C9N15"
					( Origin gFrontEnd )
				)
				( attribute "MATERIAL" "X7R"
					( Origin gFrontEnd )
				)
				( attribute "PACK_TYPE" "0402"
					( Origin gFrontEnd )
				)
				( attribute "PART_NUMBER" "A36096-155"
					( Origin gFrontEnd )
				)
				( attribute "PHYS_PAGE" "182"
					( Origin gFrontEnd )
				)
				( attribute "ROOM" "IO_SLOT"
					( Origin gFrontEnd )
				)
				( attribute "ROT" "0"
					( Origin gFrontEnd )
				)
				( attribute "SEC" "1"
					( Origin gFrontEnd )
				)
				( attribute "SEC_TYPE" "0402"
					( Origin gFrontEnd )
				)
				( attribute "TOLERANCE" "10%"
					( Origin gFrontEnd )
				)
				( attribute "VALUE" "0.22UF"
					( Origin gFrontEnd )
				)
				( attribute "VER" "2"
					( Origin gFrontEnd )
				)
				( attribute "VOLTAGE" "16V"
					( Units "uVoltage" "V" 1.000000)
					( Origin gFrontEnd )
				)
				( attribute "XY" "(-2925,1325)"
					( Origin gFrontEnd )
				)
				( attribute "CHIPS_PART_NAME" "CAP"
					( Origin gPackager )
				)
				( attribute "CDS_PART_NAME" "CAP_0402-0.22UF,16V,10%,X7R,A3A"
					( Origin gPackager )
				)
				( objectStatus "C9N15" )
			)
			( gate "@baseboard_fab2_lib.baseboard_fab2(sch_1):page182_i42"
				( attribute "BOM_COST" "IO_SLOT"
					( Origin gFrontEnd )
				)
				( attribute "CDS_LIB" "mstr_discrete"
					( Origin gPackager )
				)
				( attribute "CDS_LOCATION" "C9N6"
					( Origin gPackager )
				)
				( attribute "CDS_SEC" "1"
					( Origin gPackager )
				)
				( attribute "LOCATION" "C9N6"
					( Origin gFrontEnd )
				)
				( attribute "MATERIAL" "X7R"
					( Origin gFrontEnd )
				)
				( attribute "PACK_TYPE" "0402"
					( Origin gFrontEnd )
				)
				( attribute "PART_NUMBER" "A36096-155"
					( Origin gFrontEnd )
				)
				( attribute "PHYS_PAGE" "182"
					( Origin gFrontEnd )
				)
				( attribute "ROOM" "IO_SLOT"
					( Origin gFrontEnd )
				)
				( attribute "ROT" "0"
					( Origin gFrontEnd )
				)
				( attribute "SEC" "1"
					( Origin gFrontEnd )
				)
				( attribute "SEC_TYPE" "0402"
					( Origin gFrontEnd )
				)
				( attribute "TOLERANCE" "10%"
					( Origin gFrontEnd )
				)
				( attribute "VALUE" "0.22UF"
					( Origin gFrontEnd )
				)
				( attribute "VER" "2"
					( Origin gFrontEnd )
				)
				( attribute "VOLTAGE" "16V"
					( Units "uVoltage" "V" 1.000000)
					( Origin gFrontEnd )
				)
				( attribute "XY" "(-3400,1725)"
					( Origin gFrontEnd )
				)
				( attribute "CHIPS_PART_NAME" "CAP"
					( Origin gPackager )
				)
				( attribute "CDS_PART_NAME" "CAP_0402-0.22UF,16V,10%,X7R,A3A"
					( Origin gPackager )
				)
				( objectStatus "C9N6" )
			)
			( gate "@baseboard_fab2_lib.baseboard_fab2(sch_1):page182_i43"
				( attribute "BOM_COST" "IO_SLOT"
					( Origin gFrontEnd )
				)
				( attribute "CDS_LIB" "mstr_discrete"
					( Origin gPackager )
				)
				( attribute "CDS_LOCATION" "C9N14"
					( Origin gPackager )
				)
				( attribute "CDS_SEC" "1"
					( Origin gPackager )
				)
				( attribute "LOCATION" "C9N14"
					( Origin gFrontEnd )
				)
				( attribute "MATERIAL" "X7R"
					( Origin gFrontEnd )
				)
				( attribute "PACK_TYPE" "0402"
					( Origin gFrontEnd )
				)
				( attribute "PART_NUMBER" "A36096-155"
					( Origin gFrontEnd )
				)
				( attribute "PHYS_PAGE" "182"
					( Origin gFrontEnd )
				)
				( attribute "ROOM" "IO_SLOT"
					( Origin gFrontEnd )
				)
				( attribute "ROT" "0"
					( Origin gFrontEnd )
				)
				( attribute "SEC" "1"
					( Origin gFrontEnd )
				)
				( attribute "SEC_TYPE" "0402"
					( Origin gFrontEnd )
				)
				( attribute "TOLERANCE" "10%"
					( Origin gFrontEnd )
				)
				( attribute "VALUE" "0.22UF"
					( Origin gFrontEnd )
				)
				( attribute "VER" "2"
					( Origin gFrontEnd )
				)
				( attribute "VOLTAGE" "16V"
					( Units "uVoltage" "V" 1.000000)
					( Origin gFrontEnd )
				)
				( attribute "XY" "(-3400,1825)"
					( Origin gFrontEnd )
				)
				( attribute "CHIPS_PART_NAME" "CAP"
					( Origin gPackager )
				)
				( attribute "CDS_PART_NAME" "CAP_0402-0.22UF,16V,10%,X7R,A3A"
					( Origin gPackager )
				)
				( objectStatus "C9N14" )
			)
			( gate "@baseboard_fab2_lib.baseboard_fab2(sch_1):page182_i44"
				( attribute "BOM_COST" "IO_SLOT"
					( Origin gFrontEnd )
				)
				( attribute "CDS_LIB" "mstr_discrete"
					( Origin gPackager )
				)
				( attribute "CDS_LOCATION" "C9N4"
					( Origin gPackager )
				)
				( attribute "CDS_SEC" "1"
					( Origin gPackager )
				)
				( attribute "LOCATION" "C9N4"
					( Origin gFrontEnd )
				)
				( attribute "MATERIAL" "X7R"
					( Origin gFrontEnd )
				)
				( attribute "PACK_TYPE" "0402"
					( Origin gFrontEnd )
				)
				( attribute "PART_NUMBER" "A36096-155"
					( Origin gFrontEnd )
				)
				( attribute "PHYS_PAGE" "182"
					( Origin gFrontEnd )
				)
				( attribute "ROOM" "IO_SLOT"
					( Origin gFrontEnd )
				)
				( attribute "ROT" "0"
					( Origin gFrontEnd )
				)
				( attribute "SEC" "1"
					( Origin gFrontEnd )
				)
				( attribute "SEC_TYPE" "0402"
					( Origin gFrontEnd )
				)
				( attribute "TOLERANCE" "10%"
					( Origin gFrontEnd )
				)
				( attribute "VALUE" "0.22UF"
					( Origin gFrontEnd )
				)
				( attribute "VER" "2"
					( Origin gFrontEnd )
				)
				( attribute "VOLTAGE" "16V"
					( Units "uVoltage" "V" 1.000000)
					( Origin gFrontEnd )
				)
				( attribute "XY" "(-3400,1975)"
					( Origin gFrontEnd )
				)
				( attribute "CHIPS_PART_NAME" "CAP"
					( Origin gPackager )
				)
				( attribute "CDS_PART_NAME" "CAP_0402-0.22UF,16V,10%,X7R,A3A"
					( Origin gPackager )
				)
				( objectStatus "C9N4" )
			)
			( gate "@baseboard_fab2_lib.baseboard_fab2(sch_1):page182_i45"
				( attribute "BOM_COST" "IO_SLOT"
					( Origin gFrontEnd )
				)
				( attribute "CDS_LIB" "mstr_discrete"
					( Origin gPackager )
				)
				( attribute "CDS_LOCATION" "C9N5"
					( Origin gPackager )
				)
				( attribute "CDS_SEC" "1"
					( Origin gPackager )
				)
				( attribute "LOCATION" "C9N5"
					( Origin gFrontEnd )
				)
				( attribute "MATERIAL" "X7R"
					( Origin gFrontEnd )
				)
				( attribute "PACK_TYPE" "0402"
					( Origin gFrontEnd )
				)
				( attribute "PART_NUMBER" "A36096-155"
					( Origin gFrontEnd )
				)
				( attribute "PHYS_PAGE" "182"
					( Origin gFrontEnd )
				)
				( attribute "ROOM" "IO_SLOT"
					( Origin gFrontEnd )
				)
				( attribute "ROT" "0"
					( Origin gFrontEnd )
				)
				( attribute "SEC" "1"
					( Origin gFrontEnd )
				)
				( attribute "SEC_TYPE" "0402"
					( Origin gFrontEnd )
				)
				( attribute "TOLERANCE" "10%"
					( Origin gFrontEnd )
				)
				( attribute "VALUE" "0.22UF"
					( Origin gFrontEnd )
				)
				( attribute "VER" "2"
					( Origin gFrontEnd )
				)
				( attribute "VOLTAGE" "16V"
					( Units "uVoltage" "V" 1.000000)
					( Origin gFrontEnd )
				)
				( attribute "XY" "(-2925,1675)"
					( Origin gFrontEnd )
				)
				( attribute "CHIPS_PART_NAME" "CAP"
					( Origin gPackager )
				)
				( attribute "CDS_PART_NAME" "CAP_0402-0.22UF,16V,10%,X7R,A3A"
					( Origin gPackager )
				)
				( objectStatus "C9N5" )
			)
			( gate "@baseboard_fab2_lib.baseboard_fab2(sch_1):page182_i46"
				( attribute "BOM_COST" "IO_SLOT"
					( Origin gFrontEnd )
				)
				( attribute "CDS_LIB" "mstr_discrete"
					( Origin gPackager )
				)
				( attribute "CDS_LOCATION" "C9N16"
					( Origin gPackager )
				)
				( attribute "CDS_SEC" "1"
					( Origin gPackager )
				)
				( attribute "LOCATION" "C9N16"
					( Origin gFrontEnd )
				)
				( attribute "MATERIAL" "X7R"
					( Origin gFrontEnd )
				)
				( attribute "PACK_TYPE" "0402"
					( Origin gFrontEnd )
				)
				( attribute "PART_NUMBER" "A36096-155"
					( Origin gFrontEnd )
				)
				( attribute "PHYS_PAGE" "182"
					( Origin gFrontEnd )
				)
				( attribute "ROOM" "IO_SLOT"
					( Origin gFrontEnd )
				)
				( attribute "ROT" "0"
					( Origin gFrontEnd )
				)
				( attribute "SEC" "1"
					( Origin gFrontEnd )
				)
				( attribute "SEC_TYPE" "0402"
					( Origin gFrontEnd )
				)
				( attribute "TOLERANCE" "10%"
					( Origin gFrontEnd )
				)
				( attribute "VALUE" "0.22UF"
					( Origin gFrontEnd )
				)
				( attribute "VER" "2"
					( Origin gFrontEnd )
				)
				( attribute "VOLTAGE" "16V"
					( Units "uVoltage" "V" 1.000000)
					( Origin gFrontEnd )
				)
				( attribute "XY" "(-2925,1875)"
					( Origin gFrontEnd )
				)
				( attribute "CHIPS_PART_NAME" "CAP"
					( Origin gPackager )
				)
				( attribute "CDS_PART_NAME" "CAP_0402-0.22UF,16V,10%,X7R,A3A"
					( Origin gPackager )
				)
				( objectStatus "C9N16" )
			)
			( gate "@baseboard_fab2_lib.baseboard_fab2(sch_1):page182_i47"
				( attribute "BOM_COST" "IO_SLOT"
					( Origin gFrontEnd )
				)
				( attribute "CDS_LIB" "mstr_discrete"
					( Origin gPackager )
				)
				( attribute "CDS_LOCATION" "C9N3"
					( Origin gPackager )
				)
				( attribute "CDS_SEC" "1"
					( Origin gPackager )
				)
				( attribute "LOCATION" "C9N3"
					( Origin gFrontEnd )
				)
				( attribute "MATERIAL" "X7R"
					( Origin gFrontEnd )
				)
				( attribute "PACK_TYPE" "0402"
					( Origin gFrontEnd )
				)
				( attribute "PART_NUMBER" "A36096-155"
					( Origin gFrontEnd )
				)
				( attribute "PHYS_PAGE" "182"
					( Origin gFrontEnd )
				)
				( attribute "ROOM" "IO_SLOT"
					( Origin gFrontEnd )
				)
				( attribute "ROT" "0"
					( Origin gFrontEnd )
				)
				( attribute "SEC" "1"
					( Origin gFrontEnd )
				)
				( attribute "SEC_TYPE" "0402"
					( Origin gFrontEnd )
				)
				( attribute "TOLERANCE" "10%"
					( Origin gFrontEnd )
				)
				( attribute "VALUE" "0.22UF"
					( Origin gFrontEnd )
				)
				( attribute "VER" "2"
					( Origin gFrontEnd )
				)
				( attribute "VOLTAGE" "16V"
					( Units "uVoltage" "V" 1.000000)
					( Origin gFrontEnd )
				)
				( attribute "XY" "(-2925,2025)"
					( Origin gFrontEnd )
				)
				( attribute "CHIPS_PART_NAME" "CAP"
					( Origin gPackager )
				)
				( attribute "CDS_PART_NAME" "CAP_0402-0.22UF,16V,10%,X7R,A3A"
					( Origin gPackager )
				)
				( objectStatus "C9N3" )
			)
			( gate "@baseboard_fab2_lib.baseboard_fab2(sch_1):page182_i48"
				( attribute "BOM_COST" "IO_SLOT"
					( Origin gFrontEnd )
				)
				( attribute "CDS_LIB" "mstr_discrete"
					( Origin gPackager )
				)
				( attribute "CDS_LOCATION" "C9N7"
					( Origin gPackager )
				)
				( attribute "CDS_SEC" "1"
					( Origin gPackager )
				)
				( attribute "LOCATION" "C9N7"
					( Origin gFrontEnd )
				)
				( attribute "MATERIAL" "X7R"
					( Origin gFrontEnd )
				)
				( attribute "PACK_TYPE" "0402"
					( Origin gFrontEnd )
				)
				( attribute "PART_NUMBER" "A36096-155"
					( Origin gFrontEnd )
				)
				( attribute "PHYS_PAGE" "182"
					( Origin gFrontEnd )
				)
				( attribute "ROOM" "IO_SLOT"
					( Origin gFrontEnd )
				)
				( attribute "ROT" "0"
					( Origin gFrontEnd )
				)
				( attribute "SEC" "1"
					( Origin gFrontEnd )
				)
				( attribute "SEC_TYPE" "0402"
					( Origin gFrontEnd )
				)
				( attribute "TOLERANCE" "10%"
					( Origin gFrontEnd )
				)
				( attribute "VALUE" "0.22UF"
					( Origin gFrontEnd )
				)
				( attribute "VER" "2"
					( Origin gFrontEnd )
				)
				( attribute "VOLTAGE" "16V"
					( Units "uVoltage" "V" 1.000000)
					( Origin gFrontEnd )
				)
				( attribute "XY" "(-3400,2175)"
					( Origin gFrontEnd )
				)
				( attribute "CHIPS_PART_NAME" "CAP"
					( Origin gPackager )
				)
				( attribute "CDS_PART_NAME" "CAP_0402-0.22UF,16V,10%,X7R,A3A"
					( Origin gPackager )
				)
				( objectStatus "C9N7" )
			)
			( gate "@baseboard_fab2_lib.baseboard_fab2(sch_1):page182_i49"
				( attribute "BOM_COST" "IO_SLOT"
					( Origin gFrontEnd )
				)
				( attribute "CDS_LIB" "mstr_discrete"
					( Origin gPackager )
				)
				( attribute "CDS_LOCATION" "C9N10"
					( Origin gPackager )
				)
				( attribute "CDS_SEC" "1"
					( Origin gPackager )
				)
				( attribute "LOCATION" "C9N10"
					( Origin gFrontEnd )
				)
				( attribute "MATERIAL" "X7R"
					( Origin gFrontEnd )
				)
				( attribute "PACK_TYPE" "0402"
					( Origin gFrontEnd )
				)
				( attribute "PART_NUMBER" "A36096-155"
					( Origin gFrontEnd )
				)
				( attribute "PHYS_PAGE" "182"
					( Origin gFrontEnd )
				)
				( attribute "ROOM" "IO_SLOT"
					( Origin gFrontEnd )
				)
				( attribute "ROT" "0"
					( Origin gFrontEnd )
				)
				( attribute "SEC" "1"
					( Origin gFrontEnd )
				)
				( attribute "SEC_TYPE" "0402"
					( Origin gFrontEnd )
				)
				( attribute "TOLERANCE" "10%"
					( Origin gFrontEnd )
				)
				( attribute "VALUE" "0.22UF"
					( Origin gFrontEnd )
				)
				( attribute "VER" "2"
					( Origin gFrontEnd )
				)
				( attribute "VOLTAGE" "16V"
					( Units "uVoltage" "V" 1.000000)
					( Origin gFrontEnd )
				)
				( attribute "XY" "(-3400,2325)"
					( Origin gFrontEnd )
				)
				( attribute "CHIPS_PART_NAME" "CAP"
					( Origin gPackager )
				)
				( attribute "CDS_PART_NAME" "CAP_0402-0.22UF,16V,10%,X7R,A3A"
					( Origin gPackager )
				)
				( objectStatus "C9N10" )
			)
			( gate "@baseboard_fab2_lib.baseboard_fab2(sch_1):page182_i52"
				( attribute "BOM_COST" "IO_SLOT"
					( Origin gFrontEnd )
				)
				( attribute "CDS_LIB" "mstr_discrete"
					( Origin gPackager )
				)
				( attribute "CDS_LOCATION" "C9N9"
					( Origin gPackager )
				)
				( attribute "CDS_SEC" "1"
					( Origin gPackager )
				)
				( attribute "LOCATION" "C9N9"
					( Origin gFrontEnd )
				)
				( attribute "MATERIAL" "X7R"
					( Origin gFrontEnd )
				)
				( attribute "PACK_TYPE" "0402"
					( Origin gFrontEnd )
				)
				( attribute "PART_NUMBER" "A36096-155"
					( Origin gFrontEnd )
				)
				( attribute "PHYS_PAGE" "182"
					( Origin gFrontEnd )
				)
				( attribute "ROOM" "IO_SLOT"
					( Origin gFrontEnd )
				)
				( attribute "ROT" "0"
					( Origin gFrontEnd )
				)
				( attribute "SEC" "1"
					( Origin gFrontEnd )
				)
				( attribute "SEC_TYPE" "0402"
					( Origin gFrontEnd )
				)
				( attribute "TOLERANCE" "10%"
					( Origin gFrontEnd )
				)
				( attribute "VALUE" "0.22UF"
					( Origin gFrontEnd )
				)
				( attribute "VER" "2"
					( Origin gFrontEnd )
				)
				( attribute "VOLTAGE" "16V"
					( Units "uVoltage" "V" 1.000000)
					( Origin gFrontEnd )
				)
				( attribute "XY" "(-2925,2225)"
					( Origin gFrontEnd )
				)
				( attribute "CHIPS_PART_NAME" "CAP"
					( Origin gPackager )
				)
				( attribute "CDS_PART_NAME" "CAP_0402-0.22UF,16V,10%,X7R,A3A"
					( Origin gPackager )
				)
				( objectStatus "C9N9" )
			)
			( gate "@baseboard_fab2_lib.baseboard_fab2(sch_1):page182_i53"
				( attribute "BOM_COST" "IO_SLOT"
					( Origin gFrontEnd )
				)
				( attribute "CDS_LIB" "mstr_discrete"
					( Origin gPackager )
				)
				( attribute "CDS_LOCATION" "C9N8"
					( Origin gPackager )
				)
				( attribute "CDS_SEC" "1"
					( Origin gPackager )
				)
				( attribute "LOCATION" "C9N8"
					( Origin gFrontEnd )
				)
				( attribute "MATERIAL" "X7R"
					( Origin gFrontEnd )
				)
				( attribute "PACK_TYPE" "0402"
					( Origin gFrontEnd )
				)
				( attribute "PART_NUMBER" "A36096-155"
					( Origin gFrontEnd )
				)
				( attribute "PHYS_PAGE" "182"
					( Origin gFrontEnd )
				)
				( attribute "ROOM" "IO_SLOT"
					( Origin gFrontEnd )
				)
				( attribute "ROT" "0"
					( Origin gFrontEnd )
				)
				( attribute "SEC" "1"
					( Origin gFrontEnd )
				)
				( attribute "SEC_TYPE" "0402"
					( Origin gFrontEnd )
				)
				( attribute "TOLERANCE" "10%"
					( Origin gFrontEnd )
				)
				( attribute "VALUE" "0.22UF"
					( Origin gFrontEnd )
				)
				( attribute "VER" "2"
					( Origin gFrontEnd )
				)
				( attribute "VOLTAGE" "16V"
					( Units "uVoltage" "V" 1.000000)
					( Origin gFrontEnd )
				)
				( attribute "XY" "(-2925,2375)"
					( Origin gFrontEnd )
				)
				( attribute "CHIPS_PART_NAME" "CAP"
					( Origin gPackager )
				)
				( attribute "CDS_PART_NAME" "CAP_0402-0.22UF,16V,10%,X7R,A3A"
					( Origin gPackager )
				)
				( objectStatus "C9N8" )
			)
			( gate "@baseboard_fab2_lib.baseboard_fab2(sch_1):page184_i87"
				( attribute "BOM_COST" "MIO_SECURITY"
					( Origin gFrontEnd )
				)
				( attribute "CDS_LIB" "mstr_sconn"
					( Origin gPackager )
				)
				( attribute "CDS_LMAN_SYM_OUTLINE" "-300,450,300,-450"
					( Origin gPackager )
				)
				( attribute "CDS_LOCATION" "J8E1"
					( Origin gPackager )
				)
				( attribute "CDS_SEC" "1"
					( Origin gPackager )
				)
				( attribute "LOCATION" "J8E1"
					( Origin gFrontEnd )
				)
				( attribute "MATERIAL" "CONN"
					( Origin gFrontEnd )
				)
				( attribute "PACK_TYPE" "SM"
					( Origin gFrontEnd )
				)
				( attribute "PART_NUMBER" "H67026-001"
					( Origin gFrontEnd )
				)
				( attribute "PHYS_PAGE" "184"
					( Origin gFrontEnd )
				)
				( attribute "ROOM" "TPM"
					( Origin gFrontEnd )
				)
				( attribute "ROT" "0"
					( Origin gFrontEnd )
				)
				( attribute "SEC" "1"
					( Origin gFrontEnd )
				)
				( attribute "SEC_TYPE" "SM"
					( Origin gFrontEnd )
				)
				( attribute "VER" "1"
					( Origin gFrontEnd )
				)
				( attribute "XY" "(-3700,-3375)"
					( Origin gFrontEnd )
				)
				( attribute "CHIPS_PART_NAME" "SCONN11_H67026001"
					( Origin gPackager )
				)
				( attribute "CDS_PART_NAME" "SCONN11_H67026001_SM-CONN,H670A"
					( Origin gPackager )
				)
				( objectStatus "J8E1" )
			)
			( gate "@baseboard_fab2_lib.baseboard_fab2(sch_1):page184_i88"
				( attribute "BOM_COST" "MIO_SECURITY"
					( Origin gFrontEnd )
				)
				( attribute "CDS_LIB" "mstr_discrete"
					( Origin gPackager )
				)
				( attribute "CDS_LOCATION" "R8E9"
					( Origin gPackager )
				)
				( attribute "CDS_SEC" "1"
					( Origin gPackager )
				)
				( attribute "LOCATION" "R8E9"
					( Origin gFrontEnd )
				)
				( attribute "MATERIAL" "CHIP"
					( Origin gFrontEnd )
				)
				( attribute "PACK_TYPE" "0402"
					( Origin gFrontEnd )
				)
				( attribute "PART_NUMBER" "G21796-074"
					( Origin gFrontEnd )
				)
				( attribute "PHYS_PAGE" "184"
					( Origin gFrontEnd )
				)
				( attribute "ROOM" "TPM"
					( Origin gFrontEnd )
				)
				( attribute "ROT" "0"
					( Origin gFrontEnd )
				)
				( attribute "SEC" "1"
					( Origin gFrontEnd )
				)
				( attribute "SEC_TYPE" "0402"
					( Origin gFrontEnd )
				)
				( attribute "TOLERANCE" "1%"
					( Origin gFrontEnd )
				)
				( attribute "VALUE" "33.2"
					( Origin gFrontEnd )
				)
				( attribute "VER" "1"
					( Origin gFrontEnd )
				)
				( attribute "WATTAGE" "1/16W"
					( Origin gFrontEnd )
				)
				( attribute "XY" "(-4750,-3175)"
					( Origin gFrontEnd )
				)
				( attribute "CHIPS_PART_NAME" "RES"
					( Origin gPackager )
				)
				( attribute "CDS_PART_NAME" "RES_0402-33.2,1%,1/16W,CHIP,G2A"
					( Origin gPackager )
				)
				( objectStatus "R8E9" )
			)
			( gate "@baseboard_fab2_lib.baseboard_fab2(sch_1):page184_i92"
				( attribute "BOM_COST" "MIO_SECURITY"
					( Origin gFrontEnd )
				)
				( attribute "CDS_LIB" "mstr_discrete"
					( Origin gPackager )
				)
				( attribute "CDS_LOCATION" "R8D35"
					( Origin gPackager )
				)
				( attribute "CDS_SEC" "1"
					( Origin gPackager )
				)
				( attribute "LOCATION" "R8D35"
					( Origin gFrontEnd )
				)
				( attribute "MATERIAL" "CHIP"
					( Origin gFrontEnd )
				)
				( attribute "PACK_TYPE" "0402"
					( Origin gFrontEnd )
				)
				( attribute "PART_NUMBER" "G21497-005"
					( Origin gFrontEnd )
				)
				( attribute "PHYS_PAGE" "184"
					( Origin gFrontEnd )
				)
				( attribute "ROOM" "TPM"
					( Origin gFrontEnd )
				)
				( attribute "ROT" "0"
					( Origin gFrontEnd )
				)
				( attribute "SEC" "1"
					( Origin gFrontEnd )
				)
				( attribute "SEC_TYPE" "0402"
					( Origin gFrontEnd )
				)
				( attribute "TOLERANCE" "5%"
					( Origin gFrontEnd )
				)
				( attribute "VALUE" "0.0"
					( Origin gFrontEnd )
				)
				( attribute "VER" "1"
					( Origin gFrontEnd )
				)
				( attribute "WATTAGE" "1/16W"
					( Origin gFrontEnd )
				)
				( attribute "XY" "(-4750,-3575)"
					( Origin gFrontEnd )
				)
				( attribute "CHIPS_PART_NAME" "RES"
					( Origin gPackager )
				)
				( attribute "CDS_PART_NAME" "RES_0402-0.0,5%,1/16W,CHIP,G21A"
					( Origin gPackager )
				)
				( objectStatus "R8D35" )
			)
			( gate "@baseboard_fab2_lib.baseboard_fab2(sch_1):page184_i93"
				( attribute "BOM_COST" "MIO_SECURITY"
					( Origin gFrontEnd )
				)
				( attribute "CDS_LIB" "mstr_discrete"
					( Origin gPackager )
				)
				( attribute "CDS_LOCATION" "R8E13"
					( Origin gPackager )
				)
				( attribute "CDS_SEC" "1"
					( Origin gPackager )
				)
				( attribute "LOCATION" "R8E13"
					( Origin gFrontEnd )
				)
				( attribute "MATERIAL" "CHIP"
					( Origin gFrontEnd )
				)
				( attribute "PACK_TYPE" "0402"
					( Origin gFrontEnd )
				)
				( attribute "PART_NUMBER" "G21796-074"
					( Origin gFrontEnd )
				)
				( attribute "PHYS_PAGE" "184"
					( Origin gFrontEnd )
				)
				( attribute "ROOM" "TPM"
					( Origin gFrontEnd )
				)
				( attribute "ROT" "0"
					( Origin gFrontEnd )
				)
				( attribute "SEC" "1"
					( Origin gFrontEnd )
				)
				( attribute "SEC_TYPE" "0402"
					( Origin gFrontEnd )
				)
				( attribute "TOLERANCE" "1%"
					( Origin gFrontEnd )
				)
				( attribute "VALUE" "33.2"
					( Origin gFrontEnd )
				)
				( attribute "VER" "1"
					( Origin gFrontEnd )
				)
				( attribute "WATTAGE" "1/16W"
					( Origin gFrontEnd )
				)
				( attribute "XY" "(-4725,-3475)"
					( Origin gFrontEnd )
				)
				( attribute "CHIPS_PART_NAME" "RES"
					( Origin gPackager )
				)
				( attribute "CDS_PART_NAME" "RES_0402-33.2,1%,1/16W,CHIP,G2A"
					( Origin gPackager )
				)
				( objectStatus "R8E13" )
			)
			( gate "@baseboard_fab2_lib.baseboard_fab2(sch_1):page184_i95"
				( attribute "BOM_COST" "MIO_SECURITY"
					( Origin gFrontEnd )
				)
				( attribute "CDS_LIB" "mstr_discrete"
					( Origin gPackager )
				)
				( attribute "CDS_LOCATION" "R8E10"
					( Origin gPackager )
				)
				( attribute "CDS_SEC" "1"
					( Origin gPackager )
				)
				( attribute "LOCATION" "R8E10"
					( Origin gFrontEnd )
				)
				( attribute "MATERIAL" "CHIP"
					( Origin gFrontEnd )
				)
				( attribute "PACK_TYPE" "0402"
					( Origin gFrontEnd )
				)
				( attribute "PART_NUMBER" "G21796-074"
					( Origin gFrontEnd )
				)
				( attribute "PHYS_PAGE" "184"
					( Origin gFrontEnd )
				)
				( attribute "ROOM" "TPM"
					( Origin gFrontEnd )
				)
				( attribute "ROT" "0"
					( Origin gFrontEnd )
				)
				( attribute "SEC" "1"
					( Origin gFrontEnd )
				)
				( attribute "SEC_TYPE" "0402"
					( Origin gFrontEnd )
				)
				( attribute "TOLERANCE" "1%"
					( Origin gFrontEnd )
				)
				( attribute "VALUE" "33.2"
					( Origin gFrontEnd )
				)
				( attribute "VER" "1"
					( Origin gFrontEnd )
				)
				( attribute "WATTAGE" "1/16W"
					( Origin gFrontEnd )
				)
				( attribute "XY" "(-4725,-3375)"
					( Origin gFrontEnd )
				)
				( attribute "CHIPS_PART_NAME" "RES"
					( Origin gPackager )
				)
				( attribute "CDS_PART_NAME" "RES_0402-33.2,1%,1/16W,CHIP,G2A"
					( Origin gPackager )
				)
				( objectStatus "R8E10" )
			)
			( gate "@baseboard_fab2_lib.baseboard_fab2(sch_1):page184_i99"
				( attribute "BOM_COST" "MIO_SECURITY"
					( Origin gFrontEnd )
				)
				( attribute "CDS_LIB" "mstr_discrete"
					( Origin gPackager )
				)
				( attribute "CDS_LOCATION" "R8E1"
					( Origin gPackager )
				)
				( attribute "CDS_SEC" "1"
					( Origin gPackager )
				)
				( attribute "LOCATION" "R8E1"
					( Origin gFrontEnd )
				)
				( attribute "MATERIAL" "CHIP"
					( Origin gFrontEnd )
				)
				( attribute "PACK_TYPE" "0402"
					( Origin gFrontEnd )
				)
				( attribute "PART_NUMBER" "G21497-005"
					( Origin gFrontEnd )
				)
				( attribute "PHYS_PAGE" "184"
					( Origin gFrontEnd )
				)
				( attribute "ROOM" "TPM"
					( Origin gFrontEnd )
				)
				( attribute "ROT" "0"
					( Origin gFrontEnd )
				)
				( attribute "SEC" "1"
					( Origin gPackager )
				)
				( attribute "TOLERANCE" "5%"
					( Origin gFrontEnd )
				)
				( attribute "VALUE" "0.0"
					( Origin gFrontEnd )
				)
				( attribute "VER" "1"
					( Origin gFrontEnd )
				)
				( attribute "WATTAGE" "1/16W"
					( Origin gFrontEnd )
				)
				( attribute "XY" "(-2575,-3425)"
					( Origin gFrontEnd )
				)
				( attribute "CHIPS_PART_NAME" "RES"
					( Origin gPackager )
				)
				( attribute "CDS_PART_NAME" "RES_0402-0.0,5%,1/16W,CHIP,G21A"
					( Origin gPackager )
				)
				( objectStatus "R8E1" )
			)
			( gate "@baseboard_fab2_lib.baseboard_fab2(sch_1):page184_i104"
				( attribute "CDS_LIB" "mstr_misc"
					( Origin gPackager )
				)
				( attribute "CDS_LOCATION" "RM8D1"
					( Origin gPackager )
				)
				( attribute "CDS_SEC" "1"
					( Origin gPackager )
				)
				( attribute "LOCATION" "RM8D1"
					( Origin gFrontEnd )
				)
				( attribute "MATERIAL" "SO"
					( Origin gFrontEnd )
				)
				( attribute "PACK_TYPE" "TH1"
					( Origin gFrontEnd )
				)
				( attribute "PART_NUMBER" "H72821-001"
					( Origin gFrontEnd )
				)
				( attribute "PHYS_PAGE" "184"
					( Origin gFrontEnd )
				)
				( attribute "ROT" "0"
					( Origin gFrontEnd )
				)
				( attribute "SEC" "1"
					( Origin gFrontEnd )
				)
				( attribute "SEC_TYPE" "TH1"
					( Origin gFrontEnd )
				)
				( attribute "VER" "2"
					( Origin gFrontEnd )
				)
				( attribute "XY" "(-5125,-1900)"
					( Origin gFrontEnd )
				)
				( attribute "CHIPS_PART_NAME" "STANDOFF"
					( Origin gPackager )
				)
				( attribute "CDS_PART_NAME" "STANDOFF_TH1-SO,H72821-001"
					( Origin gPackager )
				)
				( objectStatus "RM8D1" )
			)
			( gate "@baseboard_fab2_lib.baseboard_fab2(sch_1):page185_i172"
				( attribute "BOM_COST" "ST_FLASH"
					( Origin gFrontEnd )
				)
				( attribute "CDS_LIB" "mstr_discrete"
					( Origin gPackager )
				)
				( attribute "CDS_LOCATION" "C2T13"
					( Origin gPackager )
				)
				( attribute "CDS_SEC" "1"
					( Origin gPackager )
				)
				( attribute "LOCATION" "C2T13"
					( Origin gFrontEnd )
				)
				( attribute "MATERIAL" "X7R"
					( Origin gFrontEnd )
				)
				( attribute "PACK_TYPE" "0402"
					( Origin gFrontEnd )
				)
				( attribute "PART_NUMBER" "A36096-155"
					( Origin gFrontEnd )
				)
				( attribute "PHYS_PAGE" "185"
					( Origin gFrontEnd )
				)
				( attribute "ROOM" "M_2"
					( Origin gFrontEnd )
				)
				( attribute "ROT" "0"
					( Origin gFrontEnd )
				)
				( attribute "SEC" "1"
					( Origin gFrontEnd )
				)
				( attribute "SEC_TYPE" "0402"
					( Origin gFrontEnd )
				)
				( attribute "TOLERANCE" "10%"
					( Origin gFrontEnd )
				)
				( attribute "VALUE" "0.22UF"
					( Origin gFrontEnd )
				)
				( attribute "VER" "2"
					( Origin gFrontEnd )
				)
				( attribute "VOLTAGE" "16V"
					( Units "uVoltage" "V" 1.000000)
					( Origin gFrontEnd )
				)
				( attribute "XY" "(-4850,3900)"
					( Origin gFrontEnd )
				)
				( attribute "CHIPS_PART_NAME" "CAP"
					( Origin gPackager )
				)
				( attribute "CDS_PART_NAME" "CAP_0402-0.22UF,16V,10%,X7R,A3A"
					( Origin gPackager )
				)
				( objectStatus "C2T13" )
			)
			( gate "@baseboard_fab2_lib.baseboard_fab2(sch_1):page185_i171"
				( attribute "BOM_COST" "ST_FLASH"
					( Origin gFrontEnd )
				)
				( attribute "CDS_LIB" "mstr_discrete"
					( Origin gPackager )
				)
				( attribute "CDS_LOCATION" "C2T14"
					( Origin gPackager )
				)
				( attribute "CDS_SEC" "1"
					( Origin gPackager )
				)
				( attribute "LOCATION" "C2T14"
					( Origin gFrontEnd )
				)
				( attribute "MATERIAL" "X7R"
					( Origin gFrontEnd )
				)
				( attribute "PACK_TYPE" "0402"
					( Origin gFrontEnd )
				)
				( attribute "PART_NUMBER" "A36096-155"
					( Origin gFrontEnd )
				)
				( attribute "PHYS_PAGE" "185"
					( Origin gFrontEnd )
				)
				( attribute "ROOM" "M_2"
					( Origin gFrontEnd )
				)
				( attribute "ROT" "0"
					( Origin gFrontEnd )
				)
				( attribute "SEC" "1"
					( Origin gFrontEnd )
				)
				( attribute "SEC_TYPE" "0402"
					( Origin gFrontEnd )
				)
				( attribute "TOLERANCE" "10%"
					( Origin gFrontEnd )
				)
				( attribute "VALUE" "0.22UF"
					( Origin gFrontEnd )
				)
				( attribute "VER" "2"
					( Origin gFrontEnd )
				)
				( attribute "VOLTAGE" "16V"
					( Units "uVoltage" "V" 1.000000)
					( Origin gFrontEnd )
				)
				( attribute "XY" "(-4850,3950)"
					( Origin gFrontEnd )
				)
				( attribute "CHIPS_PART_NAME" "CAP"
					( Origin gPackager )
				)
				( attribute "CDS_PART_NAME" "CAP_0402-0.22UF,16V,10%,X7R,A3A"
					( Origin gPackager )
				)
				( objectStatus "C2T14" )
			)
			( gate "@baseboard_fab2_lib.baseboard_fab2(sch_1):page185_i180"
				( attribute "BOM_COST" "ST_FLASH"
					( Origin gFrontEnd )
				)
				( attribute "CDS_LIB" "mstr_discrete"
					( Origin gPackager )
				)
				( attribute "CDS_LOCATION" "C2T23"
					( Origin gPackager )
				)
				( attribute "CDS_SEC" "1"
					( Origin gPackager )
				)
				( attribute "LOCATION" "C2T23"
					( Origin gFrontEnd )
				)
				( attribute "MATERIAL" "X7R"
					( Origin gFrontEnd )
				)
				( attribute "PACK_TYPE" "0402"
					( Origin gFrontEnd )
				)
				( attribute "PART_NUMBER" "A36096-155"
					( Origin gFrontEnd )
				)
				( attribute "PHYS_PAGE" "185"
					( Origin gFrontEnd )
				)
				( attribute "ROOM" "M_2"
					( Origin gFrontEnd )
				)
				( attribute "ROT" "0"
					( Origin gFrontEnd )
				)
				( attribute "SEC" "1"
					( Origin gFrontEnd )
				)
				( attribute "SEC_TYPE" "0402"
					( Origin gFrontEnd )
				)
				( attribute "TOLERANCE" "10%"
					( Origin gFrontEnd )
				)
				( attribute "VALUE" "0.22UF"
					( Origin gFrontEnd )
				)
				( attribute "VER" "2"
					( Origin gFrontEnd )
				)
				( attribute "VOLTAGE" "16V"
					( Units "uVoltage" "V" 1.000000)
					( Origin gFrontEnd )
				)
				( attribute "XY" "(-4850,4250)"
					( Origin gFrontEnd )
				)
				( attribute "CHIPS_PART_NAME" "CAP"
					( Origin gPackager )
				)
				( attribute "CDS_PART_NAME" "CAP_0402-0.22UF,16V,10%,X7R,A3A"
					( Origin gPackager )
				)
				( objectStatus "C2T23" )
			)
			( gate "@baseboard_fab2_lib.baseboard_fab2(sch_1):page185_i179"
				( attribute "BOM_COST" "ST_FLASH"
					( Origin gFrontEnd )
				)
				( attribute "CDS_LIB" "mstr_discrete"
					( Origin gPackager )
				)
				( attribute "CDS_LOCATION" "C2T20"
					( Origin gPackager )
				)
				( attribute "CDS_SEC" "1"
					( Origin gPackager )
				)
				( attribute "LOCATION" "C2T20"
					( Origin gFrontEnd )
				)
				( attribute "MATERIAL" "X7R"
					( Origin gFrontEnd )
				)
				( attribute "PACK_TYPE" "0402"
					( Origin gFrontEnd )
				)
				( attribute "PART_NUMBER" "A36096-155"
					( Origin gFrontEnd )
				)
				( attribute "PHYS_PAGE" "185"
					( Origin gFrontEnd )
				)
				( attribute "ROOM" "M_2"
					( Origin gFrontEnd )
				)
				( attribute "ROT" "0"
					( Origin gFrontEnd )
				)
				( attribute "SEC" "1"
					( Origin gFrontEnd )
				)
				( attribute "SEC_TYPE" "0402"
					( Origin gFrontEnd )
				)
				( attribute "TOLERANCE" "10%"
					( Origin gFrontEnd )
				)
				( attribute "VALUE" "0.22UF"
					( Origin gFrontEnd )
				)
				( attribute "VER" "2"
					( Origin gFrontEnd )
				)
				( attribute "VOLTAGE" "16V"
					( Units "uVoltage" "V" 1.000000)
					( Origin gFrontEnd )
				)
				( attribute "XY" "(-4850,4200)"
					( Origin gFrontEnd )
				)
				( attribute "CHIPS_PART_NAME" "CAP"
					( Origin gPackager )
				)
				( attribute "CDS_PART_NAME" "CAP_0402-0.22UF,16V,10%,X7R,A3A"
					( Origin gPackager )
				)
				( objectStatus "C2T20" )
			)
			( gate "@baseboard_fab2_lib.baseboard_fab2(sch_1):page107_i477"
				( attribute "CDS_LIB" "mstr_discrete"
					( Origin gPackager )
				)
				( attribute "LOCATION" "C3P33"
					( Origin gFrontEnd )
				)
				( attribute "MATERIAL" "X7R"
					( Origin gFrontEnd )
				)
				( attribute "PACK_TYPE" "0402"
					( Origin gFrontEnd )
				)
				( attribute "PART_NUMBER" "A36096-155"
					( Origin gFrontEnd )
				)
				( attribute "PHYS_PAGE" "107"
					( Origin gFrontEnd )
				)
				( attribute "ROT" "0"
					( Origin gFrontEnd )
				)
				( attribute "TOLERANCE" "10%"
					( Origin gFrontEnd )
				)
				( attribute "VALUE" "0.22UF"
					( Origin gFrontEnd )
				)
				( attribute "VER" "1"
					( Origin gFrontEnd )
				)
				( attribute "VOLTAGE" "16V"
					( Units "uVoltage" "V" 1.000000)
					( Origin gFrontEnd )
				)
				( attribute "XY" "(-5300,3675)"
					( Origin gFrontEnd )
				)
				( attribute "CHIPS_PART_NAME" "CAP"
					( Origin gPackager )
				)
				( attribute "CDS_PART_NAME" "CAP_0402-0.22UF,16V,10%,X7R,A3A"
					( Origin gPackager )
				)
				( attribute "CDS_LOCATION" "C3P33"
					( Origin gPackager )
				)
				( attribute "CDS_SEC" "1"
					( Origin gPackager )
				)
				( attribute "SEC" "1"
					( Origin gPackager )
				)
				( attribute "GROUP" "PCIE_RISER"
					( Origin gFrontEnd )
				)
				( objectStatus "C3P33" )
			)
			( gate "@baseboard_fab2_lib.baseboard_fab2(sch_1):page185_i139"
				( attribute "CDS_LIB" "dev_discrete"
					( Origin gPackager )
				)
				( attribute "LOCATION" "C8F11"
					( Origin gFrontEnd )
				)
				( attribute "MATERIAL" "X7R"
					( Origin gFrontEnd )
				)
				( attribute "PACK_TYPE" "0402V"
					( Origin gFrontEnd )
				)
				( attribute "PART_NUMBER" "A36096-045"
					( Origin gFrontEnd )
				)
				( attribute "PHYS_PAGE" "185"
					( Origin gFrontEnd )
				)
				( attribute "ROT" "1"
					( Origin gFrontEnd )
				)
				( attribute "SEC" "1"
					( Origin gFrontEnd )
				)
				( attribute "SEC_TYPE" "0402V"
					( Origin gFrontEnd )
				)
				( attribute "TOLERANCE" "10%"
					( Origin gFrontEnd )
				)
				( attribute "VALUE" "0.01UF"
					( Origin gFrontEnd )
				)
				( attribute "VER" "1"
					( Origin gFrontEnd )
				)
				( attribute "VOLTAGE" "25V"
					( Units "uVoltage" "V" 1.000000)
					( Origin gFrontEnd )
				)
				( attribute "XY" "(-2600,1600)"
					( Origin gFrontEnd )
				)
				( attribute "CHIPS_PART_NAME" "CAP_A"
					( Origin gPackager )
				)
				( attribute "CDS_PART_NAME" "CAP_A_0402V-0.01UF,25V,10%,X7RA"
					( Origin gPackager )
				)
				( attribute "CDS_LOCATION" "C8F11"
					( Origin gPackager )
				)
				( attribute "CDS_SEC" "1"
					( Origin gPackager )
				)
				( attribute "GROUP" "M2_SATA"
					( Origin gFrontEnd )
				)
				( objectStatus "C8F11" )
			)
			( gate "@baseboard_fab2_lib.baseboard_fab2(sch_1):page185_i96"
				( attribute "BOM_COST" "ST_FLASH"
					( Origin gFrontEnd )
				)
				( attribute "CDS_LIB" "mstr_discrete"
					( Origin gPackager )
				)
				( attribute "CDS_LOCATION" "C8F7"
					( Origin gPackager )
				)
				( attribute "CDS_SEC" "1"
					( Origin gPackager )
				)
				( attribute "LOCATION" "C8F7"
					( Origin gFrontEnd )
				)
				( attribute "MATERIAL" "X7R"
					( Origin gFrontEnd )
				)
				( attribute "PACK_TYPE" "0402"
					( Origin gFrontEnd )
				)
				( attribute "PART_NUMBER" "A36096-155"
					( Origin gFrontEnd )
				)
				( attribute "PHYS_PAGE" "185"
					( Origin gFrontEnd )
				)
				( attribute "ROOM" "M_2"
					( Origin gFrontEnd )
				)
				( attribute "ROT" "0"
					( Origin gFrontEnd )
				)
				( attribute "SEC" "1"
					( Origin gFrontEnd )
				)
				( attribute "SEC_TYPE" "0402"
					( Origin gFrontEnd )
				)
				( attribute "TOLERANCE" "10%"
					( Origin gFrontEnd )
				)
				( attribute "VALUE" "0.22UF"
					( Origin gFrontEnd )
				)
				( attribute "VER" "2"
					( Origin gFrontEnd )
				)
				( attribute "VOLTAGE" "16V"
					( Units "uVoltage" "V" 1.000000)
					( Origin gFrontEnd )
				)
				( attribute "XY" "(-2575,1825)"
					( Origin gFrontEnd )
				)
				( attribute "CHIPS_PART_NAME" "CAP"
					( Origin gPackager )
				)
				( attribute "CDS_PART_NAME" "CAP_0402-0.22UF,16V,10%,X7R,A3A"
					( Origin gPackager )
				)
				( attribute "GROUP" "M2_PCIE"
					( Origin gFrontEnd )
				)
				( objectStatus "C8F7" )
			)
			( gate "@baseboard_fab2_lib.baseboard_fab2(sch_1):page107_i476"
				( attribute "CDS_LIB" "mstr_discrete"
					( Origin gPackager )
				)
				( attribute "LOCATION" "C3P16"
					( Origin gFrontEnd )
				)
				( attribute "MATERIAL" "X7R"
					( Origin gFrontEnd )
				)
				( attribute "PACK_TYPE" "0402"
					( Origin gFrontEnd )
				)
				( attribute "PART_NUMBER" "A36096-155"
					( Origin gFrontEnd )
				)
				( attribute "PHYS_PAGE" "107"
					( Origin gFrontEnd )
				)
				( attribute "ROT" "0"
					( Origin gFrontEnd )
				)
				( attribute "TOLERANCE" "10%"
					( Origin gFrontEnd )
				)
				( attribute "VALUE" "0.22UF"
					( Origin gFrontEnd )
				)
				( attribute "VER" "1"
					( Origin gFrontEnd )
				)
				( attribute "VOLTAGE" "16V"
					( Units "uVoltage" "V" 1.000000)
					( Origin gFrontEnd )
				)
				( attribute "XY" "(-4500,3700)"
					( Origin gFrontEnd )
				)
				( attribute "CHIPS_PART_NAME" "CAP"
					( Origin gPackager )
				)
				( attribute "CDS_PART_NAME" "CAP_0402-0.22UF,16V,10%,X7R,A3A"
					( Origin gPackager )
				)
				( attribute "CDS_LOCATION" "C3P16"
					( Origin gPackager )
				)
				( attribute "CDS_SEC" "1"
					( Origin gPackager )
				)
				( attribute "SEC" "1"
					( Origin gPackager )
				)
				( attribute "GROUP" "PCIE_RISER"
					( Origin gFrontEnd )
				)
				( objectStatus "C3P16" )
			)
			( gate "@baseboard_fab2_lib.baseboard_fab2(sch_1):page107_i475"
				( attribute "CDS_LIB" "mstr_discrete"
					( Origin gPackager )
				)
				( attribute "LOCATION" "C3P36"
					( Origin gFrontEnd )
				)
				( attribute "MATERIAL" "X7R"
					( Origin gFrontEnd )
				)
				( attribute "PACK_TYPE" "0402"
					( Origin gFrontEnd )
				)
				( attribute "PART_NUMBER" "A36096-155"
					( Origin gFrontEnd )
				)
				( attribute "PHYS_PAGE" "107"
					( Origin gFrontEnd )
				)
				( attribute "ROT" "0"
					( Origin gFrontEnd )
				)
				( attribute "TOLERANCE" "10%"
					( Origin gFrontEnd )
				)
				( attribute "VALUE" "0.22UF"
					( Origin gFrontEnd )
				)
				( attribute "VER" "1"
					( Origin gFrontEnd )
				)
				( attribute "VOLTAGE" "16V"
					( Units "uVoltage" "V" 1.000000)
					( Origin gFrontEnd )
				)
				( attribute "XY" "(-5500,3975)"
					( Origin gFrontEnd )
				)
				( attribute "CHIPS_PART_NAME" "CAP"
					( Origin gPackager )
				)
				( attribute "CDS_PART_NAME" "CAP_0402-0.22UF,16V,10%,X7R,A3A"
					( Origin gPackager )
				)
				( attribute "CDS_LOCATION" "C3P36"
					( Origin gPackager )
				)
				( attribute "CDS_SEC" "1"
					( Origin gPackager )
				)
				( attribute "SEC" "1"
					( Origin gPackager )
				)
				( attribute "GROUP" "PCIE_RISER"
					( Origin gFrontEnd )
				)
				( objectStatus "C3P36" )
			)
			( gate "@baseboard_fab2_lib.baseboard_fab2(sch_1):page107_i474"
				( attribute "CDS_LIB" "mstr_discrete"
					( Origin gPackager )
				)
				( attribute "LOCATION" "C3P41"
					( Origin gFrontEnd )
				)
				( attribute "MATERIAL" "X7R"
					( Origin gFrontEnd )
				)
				( attribute "PACK_TYPE" "0402"
					( Origin gFrontEnd )
				)
				( attribute "PART_NUMBER" "A36096-155"
					( Origin gFrontEnd )
				)
				( attribute "PHYS_PAGE" "107"
					( Origin gFrontEnd )
				)
				( attribute "ROT" "0"
					( Origin gFrontEnd )
				)
				( attribute "TOLERANCE" "10%"
					( Origin gFrontEnd )
				)
				( attribute "VALUE" "0.22UF"
					( Origin gFrontEnd )
				)
				( attribute "VER" "1"
					( Origin gFrontEnd )
				)
				( attribute "VOLTAGE" "16V"
					( Units "uVoltage" "V" 1.000000)
					( Origin gFrontEnd )
				)
				( attribute "XY" "(-5700,3675)"
					( Origin gFrontEnd )
				)
				( attribute "CHIPS_PART_NAME" "CAP"
					( Origin gPackager )
				)
				( attribute "CDS_PART_NAME" "CAP_0402-0.22UF,16V,10%,X7R,A3A"
					( Origin gPackager )
				)
				( attribute "CDS_LOCATION" "C3P41"
					( Origin gPackager )
				)
				( attribute "CDS_SEC" "1"
					( Origin gPackager )
				)
				( attribute "SEC" "1"
					( Origin gPackager )
				)
				( attribute "GROUP" "PCIE_RISER"
					( Origin gFrontEnd )
				)
				( objectStatus "C3P41" )
			)
			( gate "@baseboard_fab2_lib.baseboard_fab2(sch_1):page185_i105"
				( attribute "BOM_COST" "ST_FLASH"
					( Origin gFrontEnd )
				)
				( attribute "CDS_LIB" "mstr_discrete"
					( Origin gPackager )
				)
				( attribute "CDS_LOCATION" "R8F18"
					( Origin gPackager )
				)
				( attribute "LOCATION" "R8F18"
					( Origin gFrontEnd )
				)
				( attribute "MATERIAL" "CHIP"
					( Origin gFrontEnd )
				)
				( attribute "PACK_TYPE" "0402"
					( Origin gFrontEnd )
				)
				( attribute "PART_NUMBER" "G21497-005"
					( Origin gFrontEnd )
				)
				( attribute "PHYS_PAGE" "185"
					( Origin gFrontEnd )
				)
				( attribute "ROOM" "M_2"
					( Origin gFrontEnd )
				)
				( attribute "ROT" "0"
					( Origin gFrontEnd )
				)
				( attribute "SEC" "1"
					( Origin gFrontEnd )
				)
				( attribute "SEC_TYPE" "0402"
					( Origin gFrontEnd )
				)
				( attribute "TOLERANCE" "5%"
					( Origin gFrontEnd )
				)
				( attribute "VALUE" "0.0"
					( Origin gFrontEnd )
				)
				( attribute "VER" "1"
					( Origin gFrontEnd )
				)
				( attribute "WATTAGE" "1/16W"
					( Origin gFrontEnd )
				)
				( attribute "XY" "(-2600,950)"
					( Origin gFrontEnd )
				)
				( attribute "CHIPS_PART_NAME" "RES"
					( Origin gPackager )
				)
				( attribute "CDS_PART_NAME" "RES_0402-0.0,5%,1/16W,CHIP,G21A"
					( Origin gPackager )
				)
				( attribute "CDS_SEC" "1"
					( Origin gPackager )
				)
				( attribute "GROUP" "M2_PCIE"
					( Origin gFrontEnd )
				)
				( objectStatus "R8F18" )
			)
			( gate "@baseboard_fab2_lib.baseboard_fab2(sch_1):page185_i106"
				( attribute "BOM_COST" "ST_FLASH"
					( Origin gFrontEnd )
				)
				( attribute "CDS_LIB" "mstr_discrete"
					( Origin gPackager )
				)
				( attribute "CDS_LOCATION" "R8F21"
					( Origin gPackager )
				)
				( attribute "CDS_SEC" "1"
					( Origin gPackager )
				)
				( attribute "LOCATION" "R8F21"
					( Origin gFrontEnd )
				)
				( attribute "MATERIAL" "CHIP"
					( Origin gFrontEnd )
				)
				( attribute "PACK_TYPE" "0402"
					( Origin gFrontEnd )
				)
				( attribute "PART_NUMBER" "G21497-005"
					( Origin gFrontEnd )
				)
				( attribute "PHYS_PAGE" "185"
					( Origin gFrontEnd )
				)
				( attribute "ROOM" "M_2"
					( Origin gFrontEnd )
				)
				( attribute "ROT" "0"
					( Origin gFrontEnd )
				)
				( attribute "SEC" "1"
					( Origin gFrontEnd )
				)
				( attribute "SEC_TYPE" "0402"
					( Origin gFrontEnd )
				)
				( attribute "TOLERANCE" "5%"
					( Origin gFrontEnd )
				)
				( attribute "VALUE" "0.0"
					( Origin gFrontEnd )
				)
				( attribute "VER" "1"
					( Origin gFrontEnd )
				)
				( attribute "WATTAGE" "1/16W"
					( Origin gFrontEnd )
				)
				( attribute "XY" "(-2575,500)"
					( Origin gFrontEnd )
				)
				( attribute "CHIPS_PART_NAME" "RES"
					( Origin gPackager )
				)
				( attribute "CDS_PART_NAME" "RES_0402-0.0,5%,1/16W,CHIP,G21A"
					( Origin gPackager )
				)
				( attribute "GROUP" "M2_PCIE"
					( Origin gFrontEnd )
				)
				( objectStatus "R8F21" )
			)
			( gate "@baseboard_fab2_lib.baseboard_fab2(sch_1):page185_i110"
				( attribute "BOM_COST" "ST_FLASH"
					( Origin gFrontEnd )
				)
				( attribute "CDS_LIB" "mstr_ttl"
					( Origin gPackager )
				)
				( attribute "CDS_LOCATION" "U2P1"
					( Origin gPackager )
				)
				( attribute "CDS_SEC" "1"
					( Origin gPackager )
				)
				( attribute "LOCATION" "U2P1"
					( Origin gFrontEnd )
				)
				( attribute "MATERIAL" "IC"
					( Origin gFrontEnd )
				)
				( attribute "PACK_TYPE" "SOP"
					( Origin gFrontEnd )
				)
				( attribute "PART_NUMBER" "C88419-001"
					( Origin gFrontEnd )
				)
				( attribute "PHYS_PAGE" "185"
					( Origin gFrontEnd )
				)
				( attribute "ROOM" "M_2"
					( Origin gFrontEnd )
				)
				( attribute "ROT" "0"
					( Origin gFrontEnd )
				)
				( attribute "SEC" "1"
					( Origin gFrontEnd )
				)
				( attribute "SEC_TYPE" "SOP"
					( Origin gFrontEnd )
				)
				( attribute "VALUE" "74LVC1G07"
					( Origin gFrontEnd )
				)
				( attribute "VER" "1"
					( Origin gFrontEnd )
				)
				( attribute "XY" "(-5150,2500)"
					( Origin gFrontEnd )
				)
				( attribute "CHIPS_PART_NAME" "TTL1G07_A"
					( Origin gPackager )
				)
				( attribute "CDS_PART_NAME" "TTL1G07_A_SOP-74LVC1G07,IC,C88B"
					( Origin gPackager )
				)
				( objectStatus "U2P1" )
			)
			( gate "@baseboard_fab2_lib.baseboard_fab2(sch_1):page185_i111"
				( attribute "BOM_COST" "ST_FLASH"
					( Origin gFrontEnd )
				)
				( attribute "CDS_LIB" "mstr_discrete"
					( Origin gPackager )
				)
				( attribute "CDS_LOCATION" "R2P15"
					( Origin gPackager )
				)
				( attribute "CDS_SEC" "1"
					( Origin gPackager )
				)
				( attribute "LOCATION" "R2P15"
					( Origin gFrontEnd )
				)
				( attribute "MATERIAL" "CHIP"
					( Origin gFrontEnd )
				)
				( attribute "PACK_TYPE" "0402"
					( Origin gFrontEnd )
				)
				( attribute "PART_NUMBER" "G21796-016"
					( Origin gFrontEnd )
				)
				( attribute "PHYS_PAGE" "185"
					( Origin gFrontEnd )
				)
				( attribute "ROOM" "M_2"
					( Origin gFrontEnd )
				)
				( attribute "ROT" "0"
					( Origin gFrontEnd )
				)
				( attribute "SEC" "1"
					( Origin gFrontEnd )
				)
				( attribute "SEC_TYPE" "0402"
					( Origin gFrontEnd )
				)
				( attribute "TOLERANCE" "1%"
					( Origin gFrontEnd )
				)
				( attribute "VALUE" "10.0K"
					( Origin gFrontEnd )
				)
				( attribute "VER" "2"
					( Origin gFrontEnd )
				)
				( attribute "WATTAGE" "1/16W"
					( Origin gFrontEnd )
				)
				( attribute "XY" "(-5500,2700)"
					( Origin gFrontEnd )
				)
				( attribute "CHIPS_PART_NAME" "RES"
					( Origin gPackager )
				)
				( attribute "CDS_PART_NAME" "RES_0402-10.0K,1%,1/16W,CHIP,GA"
					( Origin gPackager )
				)
				( objectStatus "R2P15" )
			)
			( gate "@baseboard_fab2_lib.baseboard_fab2(sch_1):page185_i113"
				( attribute "BOM_COST" "ST_FLASH"
					( Origin gFrontEnd )
				)
				( attribute "CDS_LIB" "mstr_discrete"
					( Origin gPackager )
				)
				( attribute "CDS_LOCATION" "R2P16"
					( Origin gPackager )
				)
				( attribute "CDS_SEC" "1"
					( Origin gPackager )
				)
				( attribute "LOCATION" "R2P16"
					( Origin gFrontEnd )
				)
				( attribute "MATERIAL" "CHIP"
					( Origin gFrontEnd )
				)
				( attribute "PACK_TYPE" "0402"
					( Origin gFrontEnd )
				)
				( attribute "PART_NUMBER" "G21796-016"
					( Origin gFrontEnd )
				)
				( attribute "PHYS_PAGE" "185"
					( Origin gFrontEnd )
				)
				( attribute "ROOM" "M_2"
					( Origin gFrontEnd )
				)
				( attribute "ROT" "0"
					( Origin gFrontEnd )
				)
				( attribute "SEC" "1"
					( Origin gFrontEnd )
				)
				( attribute "SEC_TYPE" "0402"
					( Origin gFrontEnd )
				)
				( attribute "TOLERANCE" "1%"
					( Origin gFrontEnd )
				)
				( attribute "VALUE" "10.0K"
					( Origin gFrontEnd )
				)
				( attribute "VER" "2"
					( Origin gFrontEnd )
				)
				( attribute "WATTAGE" "1/16W"
					( Origin gFrontEnd )
				)
				( attribute "XY" "(-4400,2800)"
					( Origin gFrontEnd )
				)
				( attribute "CHIPS_PART_NAME" "RES"
					( Origin gPackager )
				)
				( attribute "CDS_PART_NAME" "RES_0402-10.0K,1%,1/16W,CHIP,GA"
					( Origin gPackager )
				)
				( objectStatus "R2P16" )
			)
			( gate "@baseboard_fab2_lib.baseboard_fab2(sch_1):page185_i115"
				( attribute "BOM_COST" "ST_FLASH"
					( Origin gFrontEnd )
				)
				( attribute "CDS_LIB" "mstr_discrete"
					( Origin gPackager )
				)
				( attribute "CDS_LOCATION" "R2P14"
					( Origin gPackager )
				)
				( attribute "CDS_SEC" "1"
					( Origin gPackager )
				)
				( attribute "LOCATION" "R2P14"
					( Origin gFrontEnd )
				)
				( attribute "MATERIAL" "CHIP"
					( Origin gFrontEnd )
				)
				( attribute "PACK_TYPE" "0402"
					( Origin gFrontEnd )
				)
				( attribute "PART_NUMBER" "G21497-005"
					( Origin gFrontEnd )
				)
				( attribute "PHYS_PAGE" "185"
					( Origin gFrontEnd )
				)
				( attribute "ROOM" "M_2"
					( Origin gFrontEnd )
				)
				( attribute "ROT" "0"
					( Origin gFrontEnd )
				)
				( attribute "SEC" "1"
					( Origin gFrontEnd )
				)
				( attribute "SEC_TYPE" "0402"
					( Origin gFrontEnd )
				)
				( attribute "TOLERANCE" "5%"
					( Origin gFrontEnd )
				)
				( attribute "VALUE" "0.0"
					( Origin gFrontEnd )
				)
				( attribute "VER" "1"
					( Origin gFrontEnd )
				)
				( attribute "WATTAGE" "1/16W"
					( Origin gFrontEnd )
				)
				( attribute "XY" "(-4250,2500)"
					( Origin gFrontEnd )
				)
				( attribute "CHIPS_PART_NAME" "RES"
					( Origin gPackager )
				)
				( attribute "CDS_PART_NAME" "RES_0402-0.0,5%,1/16W,CHIP,G21A"
					( Origin gPackager )
				)
				( objectStatus "R2P14" )
			)
			( gate "@baseboard_fab2_lib.baseboard_fab2(sch_1):page185_i117"
				( attribute "BOM_COST" "SD_FLASH"
					( Origin gFrontEnd )
				)
				( attribute "CDS_LIB" "dev_discrete"
					( Origin gPackager )
				)
				( attribute "CDS_SEC" "1"
					( Origin gPackager )
				)
				( attribute "LOCATION" "C2P9"
					( Origin gFrontEnd )
				)
				( attribute "MATERIAL" "X7R"
					( Origin gFrontEnd )
				)
				( attribute "PACK_TYPE" "0402V"
					( Origin gFrontEnd )
				)
				( attribute "PART_NUMBER" "A36096-030"
					( Origin gFrontEnd )
				)
				( attribute "PHYS_PAGE" "185"
					( Origin gFrontEnd )
				)
				( attribute "ROOM" "M_2"
					( Origin gFrontEnd )
				)
				( attribute "ROT" "0"
					( Origin gFrontEnd )
				)
				( attribute "SEC" "1"
					( Origin gFrontEnd )
				)
				( attribute "SEC_TYPE" "0402V"
					( Origin gFrontEnd )
				)
				( attribute "TOLERANCE" "10%"
					( Origin gFrontEnd )
				)
				( attribute "VALUE" "0.1UF"
					( Origin gFrontEnd )
				)
				( attribute "VER" "1"
					( Origin gFrontEnd )
				)
				( attribute "VOLTAGE" "16V"
					( Units "uVoltage" "V" 1.000000)
					( Origin gFrontEnd )
				)
				( attribute "XY" "(-4500,1975)"
					( Origin gFrontEnd )
				)
				( attribute "CHIPS_PART_NAME" "CAP_A"
					( Origin gPackager )
				)
				( attribute "CDS_PART_NAME" "CAP_A_0402V-0.1UF,16V,10%,X7R,A"
					( Origin gPackager )
				)
				( attribute "CDS_LOCATION" "C2P9"
					( Origin gPackager )
				)
				( objectStatus "C2P9" )
			)
			( gate "@baseboard_fab2_lib.baseboard_fab2(sch_1):page185_i120"
				( attribute "BOM_COST" "SD_FLASH"
					( Origin gFrontEnd )
				)
				( attribute "CDS_LIB" "dev_discrete"
					( Origin gPackager )
				)
				( attribute "CDS_LOCATION" "C2T29"
					( Origin gPackager )
				)
				( attribute "CDS_SEC" "1"
					( Origin gPackager )
				)
				( attribute "LOCATION" "C2T29"
					( Origin gFrontEnd )
				)
				( attribute "MATERIAL" "X7R"
					( Origin gFrontEnd )
				)
				( attribute "PACK_TYPE" "0402V"
					( Origin gFrontEnd )
				)
				( attribute "PART_NUMBER" "A36096-030"
					( Origin gFrontEnd )
				)
				( attribute "PHYS_PAGE" "185"
					( Origin gFrontEnd )
				)
				( attribute "ROOM" "M_2"
					( Origin gFrontEnd )
				)
				( attribute "ROT" "0"
					( Origin gFrontEnd )
				)
				( attribute "SEC" "1"
					( Origin gFrontEnd )
				)
				( attribute "SEC_TYPE" "0402V"
					( Origin gFrontEnd )
				)
				( attribute "TOLERANCE" "10%"
					( Origin gFrontEnd )
				)
				( attribute "VALUE" "0.1UF"
					( Origin gFrontEnd )
				)
				( attribute "VER" "1"
					( Origin gFrontEnd )
				)
				( attribute "VOLTAGE" "16V"
					( Units "uVoltage" "V" 1.000000)
					( Origin gFrontEnd )
				)
				( attribute "XY" "(-4250,4575)"
					( Origin gFrontEnd )
				)
				( attribute "CHIPS_PART_NAME" "CAP_A"
					( Origin gPackager )
				)
				( attribute "CDS_PART_NAME" "CAP_A_0402V-0.1UF,16V,10%,X7R,A"
					( Origin gPackager )
				)
				( objectStatus "C2T29" )
			)
			( gate "@baseboard_fab2_lib.baseboard_fab2(sch_1):page185_i123"
				( attribute "BOM_COST" "SD_FLASH"
					( Origin gFrontEnd )
				)
				( attribute "CDS_LIB" "dev_discrete"
					( Origin gPackager )
				)
				( attribute "CDS_LOCATION" "C2T26"
					( Origin gPackager )
				)
				( attribute "CDS_SEC" "1"
					( Origin gPackager )
				)
				( attribute "LOCATION" "C2T26"
					( Origin gFrontEnd )
				)
				( attribute "MATERIAL" "X7R"
					( Origin gFrontEnd )
				)
				( attribute "PACK_TYPE" "0402V"
					( Origin gFrontEnd )
				)
				( attribute "PART_NUMBER" "A36096-030"
					( Origin gFrontEnd )
				)
				( attribute "PHYS_PAGE" "185"
					( Origin gFrontEnd )
				)
				( attribute "ROOM" "M_2"
					( Origin gFrontEnd )
				)
				( attribute "ROT" "0"
					( Origin gFrontEnd )
				)
				( attribute "SEC" "1"
					( Origin gFrontEnd )
				)
				( attribute "SEC_TYPE" "0402V"
					( Origin gFrontEnd )
				)
				( attribute "TOLERANCE" "10%"
					( Origin gFrontEnd )
				)
				( attribute "VALUE" "0.1UF"
					( Origin gFrontEnd )
				)
				( attribute "VER" "1"
					( Origin gFrontEnd )
				)
				( attribute "VOLTAGE" "16V"
					( Units "uVoltage" "V" 1.000000)
					( Origin gFrontEnd )
				)
				( attribute "XY" "(-4000,4575)"
					( Origin gFrontEnd )
				)
				( attribute "CHIPS_PART_NAME" "CAP_A"
					( Origin gPackager )
				)
				( attribute "CDS_PART_NAME" "CAP_A_0402V-0.1UF,16V,10%,X7R,A"
					( Origin gPackager )
				)
				( objectStatus "C2T26" )
			)
			( gate "@baseboard_fab2_lib.baseboard_fab2(sch_1):page185_i124"
				( attribute "BOM_COST" "SD_FLASH"
					( Origin gFrontEnd )
				)
				( attribute "CDS_LIB" "dev_discrete"
					( Origin gPackager )
				)
				( attribute "CDS_LOCATION" "C2T21"
					( Origin gPackager )
				)
				( attribute "CDS_SEC" "1"
					( Origin gPackager )
				)
				( attribute "LOCATION" "C2T21"
					( Origin gFrontEnd )
				)
				( attribute "MATERIAL" "X7R"
					( Origin gFrontEnd )
				)
				( attribute "PACK_TYPE" "0402V"
					( Origin gFrontEnd )
				)
				( attribute "PART_NUMBER" "A36096-030"
					( Origin gFrontEnd )
				)
				( attribute "PHYS_PAGE" "185"
					( Origin gFrontEnd )
				)
				( attribute "ROOM" "M_2"
					( Origin gFrontEnd )
				)
				( attribute "ROT" "0"
					( Origin gFrontEnd )
				)
				( attribute "SEC" "1"
					( Origin gFrontEnd )
				)
				( attribute "SEC_TYPE" "0402V"
					( Origin gFrontEnd )
				)
				( attribute "TOLERANCE" "10%"
					( Origin gFrontEnd )
				)
				( attribute "VALUE" "0.1UF"
					( Origin gFrontEnd )
				)
				( attribute "VER" "1"
					( Origin gFrontEnd )
				)
				( attribute "VOLTAGE" "16V"
					( Units "uVoltage" "V" 1.000000)
					( Origin gFrontEnd )
				)
				( attribute "XY" "(-3750,4575)"
					( Origin gFrontEnd )
				)
				( attribute "CHIPS_PART_NAME" "CAP_A"
					( Origin gPackager )
				)
				( attribute "CDS_PART_NAME" "CAP_A_0402V-0.1UF,16V,10%,X7R,A"
					( Origin gPackager )
				)
				( objectStatus "C2T21" )
			)
			( gate "@baseboard_fab2_lib.baseboard_fab2(sch_1):page185_i126"
				( attribute "BOM_COST" "SD_FLASH"
					( Origin gFrontEnd )
				)
				( attribute "CDS_LIB" "dev_discrete"
					( Origin gPackager )
				)
				( attribute "CDS_LOCATION" "C2T16"
					( Origin gPackager )
				)
				( attribute "CDS_SEC" "1"
					( Origin gPackager )
				)
				( attribute "LOCATION" "C2T16"
					( Origin gFrontEnd )
				)
				( attribute "MATERIAL" "X7R"
					( Origin gFrontEnd )
				)
				( attribute "PACK_TYPE" "0402V"
					( Origin gFrontEnd )
				)
				( attribute "PART_NUMBER" "A36096-030"
					( Origin gFrontEnd )
				)
				( attribute "PHYS_PAGE" "185"
					( Origin gFrontEnd )
				)
				( attribute "ROOM" "M_2"
					( Origin gFrontEnd )
				)
				( attribute "ROT" "0"
					( Origin gFrontEnd )
				)
				( attribute "SEC" "1"
					( Origin gFrontEnd )
				)
				( attribute "SEC_TYPE" "0402V"
					( Origin gFrontEnd )
				)
				( attribute "TOLERANCE" "10%"
					( Origin gFrontEnd )
				)
				( attribute "VALUE" "0.1UF"
					( Origin gFrontEnd )
				)
				( attribute "VER" "1"
					( Origin gFrontEnd )
				)
				( attribute "VOLTAGE" "16V"
					( Units "uVoltage" "V" 1.000000)
					( Origin gFrontEnd )
				)
				( attribute "XY" "(-2425,4575)"
					( Origin gFrontEnd )
				)
				( attribute "CHIPS_PART_NAME" "CAP_A"
					( Origin gPackager )
				)
				( attribute "CDS_PART_NAME" "CAP_A_0402V-0.1UF,16V,10%,X7R,A"
					( Origin gPackager )
				)
				( objectStatus "C2T16" )
			)
			( gate "@baseboard_fab2_lib.baseboard_fab2(sch_1):page185_i127"
				( attribute "BOM_COST" "SD_FLASH"
					( Origin gFrontEnd )
				)
				( attribute "CDS_LIB" "dev_discrete"
					( Origin gPackager )
				)
				( attribute "CDS_LOCATION" "C2T15"
					( Origin gPackager )
				)
				( attribute "CDS_SEC" "1"
					( Origin gPackager )
				)
				( attribute "LOCATION" "C2T15"
					( Origin gFrontEnd )
				)
				( attribute "MATERIAL" "X7R"
					( Origin gFrontEnd )
				)
				( attribute "PACK_TYPE" "0402V"
					( Origin gFrontEnd )
				)
				( attribute "PART_NUMBER" "A36096-030"
					( Origin gFrontEnd )
				)
				( attribute "PHYS_PAGE" "185"
					( Origin gFrontEnd )
				)
				( attribute "ROOM" "M_2"
					( Origin gFrontEnd )
				)
				( attribute "ROT" "0"
					( Origin gFrontEnd )
				)
				( attribute "SEC" "1"
					( Origin gFrontEnd )
				)
				( attribute "SEC_TYPE" "0402V"
					( Origin gFrontEnd )
				)
				( attribute "TOLERANCE" "10%"
					( Origin gFrontEnd )
				)
				( attribute "VALUE" "0.1UF"
					( Origin gFrontEnd )
				)
				( attribute "VER" "1"
					( Origin gFrontEnd )
				)
				( attribute "VOLTAGE" "16V"
					( Units "uVoltage" "V" 1.000000)
					( Origin gFrontEnd )
				)
				( attribute "XY" "(-2675,4575)"
					( Origin gFrontEnd )
				)
				( attribute "CHIPS_PART_NAME" "CAP_A"
					( Origin gPackager )
				)
				( attribute "CDS_PART_NAME" "CAP_A_0402V-0.1UF,16V,10%,X7R,A"
					( Origin gPackager )
				)
				( objectStatus "C2T15" )
			)
			( gate "@baseboard_fab2_lib.baseboard_fab2(sch_1):page185_i129"
				( attribute "BOM_COST" "SD_FLASH"
					( Origin gFrontEnd )
				)
				( attribute "CDS_LIB" "dev_discrete"
					( Origin gPackager )
				)
				( attribute "CDS_LOCATION" "C2T24"
					( Origin gPackager )
				)
				( attribute "CDS_SEC" "1"
					( Origin gPackager )
				)
				( attribute "LOCATION" "C2T24"
					( Origin gFrontEnd )
				)
				( attribute "MATERIAL" "X7R"
					( Origin gFrontEnd )
				)
				( attribute "PACK_TYPE" "0402V"
					( Origin gFrontEnd )
				)
				( attribute "PART_NUMBER" "A36096-030"
					( Origin gFrontEnd )
				)
				( attribute "PHYS_PAGE" "185"
					( Origin gFrontEnd )
				)
				( attribute "ROOM" "M_2"
					( Origin gFrontEnd )
				)
				( attribute "ROT" "0"
					( Origin gFrontEnd )
				)
				( attribute "SEC" "1"
					( Origin gFrontEnd )
				)
				( attribute "SEC_TYPE" "0402V"
					( Origin gFrontEnd )
				)
				( attribute "TOLERANCE" "10%"
					( Origin gFrontEnd )
				)
				( attribute "VALUE" "0.1UF"
					( Origin gFrontEnd )
				)
				( attribute "VER" "1"
					( Origin gFrontEnd )
				)
				( attribute "VOLTAGE" "16V"
					( Units "uVoltage" "V" 1.000000)
					( Origin gFrontEnd )
				)
				( attribute "XY" "(-2925,4575)"
					( Origin gFrontEnd )
				)
				( attribute "CHIPS_PART_NAME" "CAP_A"
					( Origin gPackager )
				)
				( attribute "CDS_PART_NAME" "CAP_A_0402V-0.1UF,16V,10%,X7R,A"
					( Origin gPackager )
				)
				( objectStatus "C2T24" )
			)
			( gate "@baseboard_fab2_lib.baseboard_fab2(sch_1):page185_i131"
				( attribute "BOM_COST" "SD_FLASH"
					( Origin gFrontEnd )
				)
				( attribute "CDS_LIB" "dev_discrete"
					( Origin gPackager )
				)
				( attribute "CDS_LOCATION" "C2T2"
					( Origin gPackager )
				)
				( attribute "CDS_SEC" "1"
					( Origin gPackager )
				)
				( attribute "LOCATION" "C2T2"
					( Origin gFrontEnd )
				)
				( attribute "MATERIAL" "X7R"
					( Origin gFrontEnd )
				)
				( attribute "PACK_TYPE" "0402V"
					( Origin gFrontEnd )
				)
				( attribute "PART_NUMBER" "A36096-030"
					( Origin gFrontEnd )
				)
				( attribute "PHYS_PAGE" "185"
					( Origin gFrontEnd )
				)
				( attribute "ROOM" "M_2"
					( Origin gFrontEnd )
				)
				( attribute "ROT" "0"
					( Origin gFrontEnd )
				)
				( attribute "SEC" "1"
					( Origin gFrontEnd )
				)
				( attribute "SEC_TYPE" "0402V"
					( Origin gFrontEnd )
				)
				( attribute "TOLERANCE" "10%"
					( Origin gFrontEnd )
				)
				( attribute "VALUE" "0.1UF"
					( Origin gFrontEnd )
				)
				( attribute "VER" "1"
					( Origin gFrontEnd )
				)
				( attribute "VOLTAGE" "16V"
					( Units "uVoltage" "V" 1.000000)
					( Origin gFrontEnd )
				)
				( attribute "XY" "(-950,4575)"
					( Origin gFrontEnd )
				)
				( attribute "CHIPS_PART_NAME" "CAP_A"
					( Origin gPackager )
				)
				( attribute "CDS_PART_NAME" "CAP_A_0402V-0.1UF,16V,10%,X7R,A"
					( Origin gPackager )
				)
				( objectStatus "C2T2" )
			)
			( gate "@baseboard_fab2_lib.baseboard_fab2(sch_1):page185_i132"
				( attribute "BOM_COST" "SD_FLASH"
					( Origin gFrontEnd )
				)
				( attribute "CDS_LIB" "dev_discrete"
					( Origin gPackager )
				)
				( attribute "CDS_LOCATION" "C2T4"
					( Origin gPackager )
				)
				( attribute "CDS_SEC" "1"
					( Origin gPackager )
				)
				( attribute "LOCATION" "C2T4"
					( Origin gFrontEnd )
				)
				( attribute "MATERIAL" "X7R"
					( Origin gFrontEnd )
				)
				( attribute "PACK_TYPE" "0402V"
					( Origin gFrontEnd )
				)
				( attribute "PART_NUMBER" "A36096-030"
					( Origin gFrontEnd )
				)
				( attribute "PHYS_PAGE" "185"
					( Origin gFrontEnd )
				)
				( attribute "ROOM" "M_2"
					( Origin gFrontEnd )
				)
				( attribute "ROT" "0"
					( Origin gFrontEnd )
				)
				( attribute "SEC" "1"
					( Origin gFrontEnd )
				)
				( attribute "SEC_TYPE" "0402V"
					( Origin gFrontEnd )
				)
				( attribute "TOLERANCE" "10%"
					( Origin gFrontEnd )
				)
				( attribute "VALUE" "0.1UF"
					( Origin gFrontEnd )
				)
				( attribute "VER" "1"
					( Origin gFrontEnd )
				)
				( attribute "VOLTAGE" "16V"
					( Units "uVoltage" "V" 1.000000)
					( Origin gFrontEnd )
				)
				( attribute "XY" "(-1200,4575)"
					( Origin gFrontEnd )
				)
				( attribute "CHIPS_PART_NAME" "CAP_A"
					( Origin gPackager )
				)
				( attribute "CDS_PART_NAME" "CAP_A_0402V-0.1UF,16V,10%,X7R,A"
					( Origin gPackager )
				)
				( objectStatus "C2T4" )
			)
			( gate "@baseboard_fab2_lib.baseboard_fab2(sch_1):page185_i135"
				( attribute "BOM_COST" "SD_FLASH"
					( Origin gFrontEnd )
				)
				( attribute "CDS_LIB" "dev_discrete"
					( Origin gPackager )
				)
				( attribute "CDS_LOCATION" "C2T5"
					( Origin gPackager )
				)
				( attribute "CDS_SEC" "1"
					( Origin gPackager )
				)
				( attribute "LOCATION" "C2T5"
					( Origin gFrontEnd )
				)
				( attribute "MATERIAL" "X7R"
					( Origin gFrontEnd )
				)
				( attribute "PACK_TYPE" "0402V"
					( Origin gFrontEnd )
				)
				( attribute "PART_NUMBER" "A36096-030"
					( Origin gFrontEnd )
				)
				( attribute "PHYS_PAGE" "185"
					( Origin gFrontEnd )
				)
				( attribute "ROOM" "M_2"
					( Origin gFrontEnd )
				)
				( attribute "ROT" "0"
					( Origin gFrontEnd )
				)
				( attribute "SEC" "1"
					( Origin gFrontEnd )
				)
				( attribute "SEC_TYPE" "0402V"
					( Origin gFrontEnd )
				)
				( attribute "TOLERANCE" "10%"
					( Origin gFrontEnd )
				)
				( attribute "VALUE" "0.1UF"
					( Origin gFrontEnd )
				)
				( attribute "VER" "1"
					( Origin gFrontEnd )
				)
				( attribute "VOLTAGE" "16V"
					( Units "uVoltage" "V" 1.000000)
					( Origin gFrontEnd )
				)
				( attribute "XY" "(-1450,4575)"
					( Origin gFrontEnd )
				)
				( attribute "CHIPS_PART_NAME" "CAP_A"
					( Origin gPackager )
				)
				( attribute "CDS_PART_NAME" "CAP_A_0402V-0.1UF,16V,10%,X7R,A"
					( Origin gPackager )
				)
				( objectStatus "C2T5" )
			)
			( gate "@baseboard_fab2_lib.baseboard_fab2(sch_1):page185_i136"
				( attribute "BOM_COST" "ST_FLASH"
					( Origin gFrontEnd )
				)
				( attribute "CDS_LIB" "mstr_discrete"
					( Origin gPackager )
				)
				( attribute "LOCATION" "R8F36"
					( Origin gFrontEnd )
				)
				( attribute "MATERIAL" "CHIP"
					( Origin gFrontEnd )
				)
				( attribute "PACK_TYPE" "0402"
					( Origin gFrontEnd )
				)
				( attribute "PART_NUMBER" "G21796-016"
					( Origin gFrontEnd )
				)
				( attribute "PHYS_PAGE" "185"
					( Origin gFrontEnd )
				)
				( attribute "ROOM" "M_2"
					( Origin gFrontEnd )
				)
				( attribute "ROT" "0"
					( Origin gFrontEnd )
				)
				( attribute "SEC" "1"
					( Origin gFrontEnd )
				)
				( attribute "SEC_TYPE" "0402"
					( Origin gFrontEnd )
				)
				( attribute "TOLERANCE" "1%"
					( Origin gFrontEnd )
				)
				( attribute "VALUE" "10.0K"
					( Origin gFrontEnd )
				)
				( attribute "VER" "2"
					( Origin gFrontEnd )
				)
				( attribute "WATTAGE" "1/16W"
					( Origin gFrontEnd )
				)
				( attribute "XY" "(-8000,3500)"
					( Origin gFrontEnd )
				)
				( attribute "CHIPS_PART_NAME" "RES"
					( Origin gPackager )
				)
				( attribute "CDS_PART_NAME" "RES_0402-10.0K,1%,1/16W,CHIP,GA"
					( Origin gPackager )
				)
				( attribute "CDS_LOCATION" "R8F36"
					( Origin gPackager )
				)
				( attribute "CDS_SEC" "1"
					( Origin gPackager )
				)
				( objectStatus "R8F36" )
			)
			( gate "@baseboard_fab2_lib.baseboard_fab2(sch_1):page186_i3"
				( attribute "CDS_LIB" "mstr_discrete"
					( Origin gPackager )
				)
				( attribute "CDS_LOCATION" "C1M27"
					( Origin gPackager )
				)
				( attribute "CDS_SEC" "1"
					( Origin gPackager )
				)
				( attribute "LOCATION" "C1M27"
					( Origin gFrontEnd )
				)
				( attribute "MATERIAL" "X6S"
					( Origin gFrontEnd )
				)
				( attribute "PACK_TYPE" "0805"
					( Origin gFrontEnd )
				)
				( attribute "PART_NUMBER" "C95333-007"
					( Origin gFrontEnd )
				)
				( attribute "PHYS_PAGE" "186"
					( Origin gFrontEnd )
				)
				( attribute "ROOM" "IO_SLOT"
					( Origin gFrontEnd )
				)
				( attribute "ROT" "0"
					( Origin gFrontEnd )
				)
				( attribute "SEC" "1"
					( Origin gFrontEnd )
				)
				( attribute "SEC_TYPE" "0805"
					( Origin gFrontEnd )
				)
				( attribute "TOLERANCE" "10%"
					( Origin gFrontEnd )
				)
				( attribute "VALUE" "10UF"
					( Origin gFrontEnd )
				)
				( attribute "VER" "1"
					( Origin gFrontEnd )
				)
				( attribute "VOLTAGE" "16V"
					( Units "uVoltage" "V" 1.000000)
					( Origin gFrontEnd )
				)
				( attribute "XY" "(10450,3975)"
					( Origin gFrontEnd )
				)
				( attribute "CHIPS_PART_NAME" "CAP"
					( Origin gPackager )
				)
				( attribute "CDS_PART_NAME" "CAP_0805-10UF,16V,10%,X6S,C953A"
					( Origin gPackager )
				)
				( objectStatus "C1M27" )
			)
			( gate "@baseboard_fab2_lib.baseboard_fab2(sch_1):page186_i6"
				( attribute "CDS_LIB" "mstr_discrete"
					( Origin gPackager )
				)
				( attribute "CDS_LOCATION" "C1M26"
					( Origin gPackager )
				)
				( attribute "CDS_SEC" "1"
					( Origin gPackager )
				)
				( attribute "LOCATION" "C1M26"
					( Origin gFrontEnd )
				)
				( attribute "MATERIAL" "X6S"
					( Origin gFrontEnd )
				)
				( attribute "PACK_TYPE" "0805"
					( Origin gFrontEnd )
				)
				( attribute "PART_NUMBER" "C95333-007"
					( Origin gFrontEnd )
				)
				( attribute "PHYS_PAGE" "186"
					( Origin gFrontEnd )
				)
				( attribute "ROOM" "IO_SLOT"
					( Origin gFrontEnd )
				)
				( attribute "ROT" "0"
					( Origin gFrontEnd )
				)
				( attribute "SEC" "1"
					( Origin gFrontEnd )
				)
				( attribute "SEC_TYPE" "0805"
					( Origin gFrontEnd )
				)
				( attribute "TOLERANCE" "10%"
					( Origin gFrontEnd )
				)
				( attribute "VALUE" "10UF"
					( Origin gFrontEnd )
				)
				( attribute "VER" "1"
					( Origin gFrontEnd )
				)
				( attribute "VOLTAGE" "16V"
					( Units "uVoltage" "V" 1.000000)
					( Origin gFrontEnd )
				)
				( attribute "XY" "(10850,3950)"
					( Origin gFrontEnd )
				)
				( attribute "CHIPS_PART_NAME" "CAP"
					( Origin gPackager )
				)
				( attribute "CDS_PART_NAME" "CAP_0805-10UF,16V,10%,X6S,C953A"
					( Origin gPackager )
				)
				( objectStatus "C1M26" )
			)
			( gate "@baseboard_fab2_lib.baseboard_fab2(sch_1):page186_i7"
				( attribute "CDS_LIB" "dev_discrete"
					( Origin gPackager )
				)
				( attribute "CDS_LOCATION" "C1M23"
					( Origin gPackager )
				)
				( attribute "CDS_SEC" "1"
					( Origin gPackager )
				)
				( attribute "LOCATION" "C1M23"
					( Origin gFrontEnd )
				)
				( attribute "MATERIAL" "X7R"
					( Origin gFrontEnd )
				)
				( attribute "PACK_TYPE" "0402V"
					( Origin gFrontEnd )
				)
				( attribute "PART_NUMBER" "A36096-030"
					( Origin gFrontEnd )
				)
				( attribute "PHYS_PAGE" "186"
					( Origin gFrontEnd )
				)
				( attribute "ROOM" "IO_SLOT"
					( Origin gFrontEnd )
				)
				( attribute "ROT" "0"
					( Origin gFrontEnd )
				)
				( attribute "SEC" "1"
					( Origin gFrontEnd )
				)
				( attribute "SEC_TYPE" "0402V"
					( Origin gFrontEnd )
				)
				( attribute "TOLERANCE" "10%"
					( Origin gFrontEnd )
				)
				( attribute "VALUE" "0.1UF"
					( Origin gFrontEnd )
				)
				( attribute "VER" "1"
					( Origin gFrontEnd )
				)
				( attribute "VOLTAGE" "16V"
					( Units "uVoltage" "V" 1.000000)
					( Origin gFrontEnd )
				)
				( attribute "XY" "(11225,3950)"
					( Origin gFrontEnd )
				)
				( attribute "CHIPS_PART_NAME" "CAP_A"
					( Origin gPackager )
				)
				( attribute "CDS_PART_NAME" "CAP_A_0402V-0.1UF,16V,10%,X7R,A"
					( Origin gPackager )
				)
				( objectStatus "C1M23" )
			)
			( gate "@baseboard_fab2_lib.baseboard_fab2(sch_1):page186_i8"
				( attribute "CDS_LIB" "dev_discrete"
					( Origin gPackager )
				)
				( attribute "CDS_LOCATION" "C1M22"
					( Origin gPackager )
				)
				( attribute "CDS_SEC" "1"
					( Origin gPackager )
				)
				( attribute "LOCATION" "C1M22"
					( Origin gFrontEnd )
				)
				( attribute "MATERIAL" "X7R"
					( Origin gFrontEnd )
				)
				( attribute "PACK_TYPE" "0402V"
					( Origin gFrontEnd )
				)
				( attribute "PART_NUMBER" "A36096-030"
					( Origin gFrontEnd )
				)
				( attribute "PHYS_PAGE" "186"
					( Origin gFrontEnd )
				)
				( attribute "ROOM" "IO_SLOT"
					( Origin gFrontEnd )
				)
				( attribute "ROT" "0"
					( Origin gFrontEnd )
				)
				( attribute "SEC" "1"
					( Origin gFrontEnd )
				)
				( attribute "SEC_TYPE" "0402V"
					( Origin gFrontEnd )
				)
				( attribute "TOLERANCE" "10%"
					( Origin gFrontEnd )
				)
				( attribute "VALUE" "0.1UF"
					( Origin gFrontEnd )
				)
				( attribute "VER" "1"
					( Origin gFrontEnd )
				)
				( attribute "VOLTAGE" "16V"
					( Units "uVoltage" "V" 1.000000)
					( Origin gFrontEnd )
				)
				( attribute "XY" "(11650,3950)"
					( Origin gFrontEnd )
				)
				( attribute "CHIPS_PART_NAME" "CAP_A"
					( Origin gPackager )
				)
				( attribute "CDS_PART_NAME" "CAP_A_0402V-0.1UF,16V,10%,X7R,A"
					( Origin gPackager )
				)
				( objectStatus "C1M22" )
			)
			( gate "@baseboard_fab2_lib.baseboard_fab2(sch_1):page186_i10"
				( attribute "CDS_LIB" "dev_discrete"
					( Origin gPackager )
				)
				( attribute "CDS_LOCATION" "C1M24"
					( Origin gPackager )
				)
				( attribute "CDS_SEC" "1"
					( Origin gPackager )
				)
				( attribute "LOCATION" "C1M24"
					( Origin gFrontEnd )
				)
				( attribute "MATERIAL" "X7R"
					( Origin gFrontEnd )
				)
				( attribute "PACK_TYPE" "0402V"
					( Origin gFrontEnd )
				)
				( attribute "PART_NUMBER" "A36096-030"
					( Origin gFrontEnd )
				)
				( attribute "PHYS_PAGE" "186"
					( Origin gFrontEnd )
				)
				( attribute "ROOM" "IO_SLOT"
					( Origin gFrontEnd )
				)
				( attribute "ROT" "0"
					( Origin gFrontEnd )
				)
				( attribute "SEC" "1"
					( Origin gFrontEnd )
				)
				( attribute "SEC_TYPE" "0402V"
					( Origin gFrontEnd )
				)
				( attribute "TOLERANCE" "10%"
					( Origin gFrontEnd )
				)
				( attribute "VALUE" "0.1UF"
					( Origin gFrontEnd )
				)
				( attribute "VER" "1"
					( Origin gFrontEnd )
				)
				( attribute "VOLTAGE" "16V"
					( Units "uVoltage" "V" 1.000000)
					( Origin gFrontEnd )
				)
				( attribute "XY" "(10850,4675)"
					( Origin gFrontEnd )
				)
				( attribute "CHIPS_PART_NAME" "CAP_A"
					( Origin gPackager )
				)
				( attribute "CDS_PART_NAME" "CAP_A_0402V-0.1UF,16V,10%,X7R,A"
					( Origin gPackager )
				)
				( objectStatus "C1M24" )
			)
			( gate "@baseboard_fab2_lib.baseboard_fab2(sch_1):page186_i220"
				( attribute "CDS_LIB" "mstr_discrete"
					( Origin gPackager )
				)
				( attribute "CDS_LOCATION" "R1M14"
					( Origin gPackager )
				)
				( attribute "CDS_SEC" "1"
					( Origin gPackager )
				)
				( attribute "LOCATION" "R1M14"
					( Origin gFrontEnd )
				)
				( attribute "MATERIAL" "CHIP"
					( Origin gFrontEnd )
				)
				( attribute "PACK_TYPE" "0402"
					( Origin gFrontEnd )
				)
				( attribute "PART_NUMBER" "G21796-004"
					( Origin gFrontEnd )
				)
				( attribute "PHYS_PAGE" "186"
					( Origin gFrontEnd )
				)
				( attribute "ROOM" "IO_SLOT"
					( Origin gFrontEnd )
				)
				( attribute "ROT" "0"
					( Origin gFrontEnd )
				)
				( attribute "SEC" "1"
					( Origin gFrontEnd )
				)
				( attribute "SEC_TYPE" "0402"
					( Origin gFrontEnd )
				)
				( attribute "TOLERANCE" "1%"
					( Origin gFrontEnd )
				)
				( attribute "VALUE" "200.0"
					( Origin gFrontEnd )
				)
				( attribute "VER" "1"
					( Origin gFrontEnd )
				)
				( attribute "WATTAGE" "1/16W"
					( Origin gFrontEnd )
				)
				( attribute "XY" "(6000,3050)"
					( Origin gFrontEnd )
				)
				( attribute "CHIPS_PART_NAME" "RES"
					( Origin gPackager )
				)
				( attribute "CDS_PART_NAME" "RES_0402-200.0,1%,1/16W,CHIP,GA"
					( Origin gPackager )
				)
				( objectStatus "R1M14" )
			)
			( gate "@baseboard_fab2_lib.baseboard_fab2(sch_1):page202_i114"
				( attribute "ATTRIBUTE" "1 OHM"
					( Origin gFrontEnd )
				)
				( attribute "CDS_LIB" "w_hdl"
					( Origin gPackager )
				)
				( attribute "CDS_LMAN_SYM_OUTLINE" "-50,75,50,-75"
					( Origin gPackager )
				)
				( attribute "LOCATION" "RT2"
					( Origin gFrontEnd )
				)
				( attribute "PACK_TYPE" "RCL_GP"
					( Origin gFrontEnd )
				)
				( attribute "PART_NUMBER" "64.1R005.55L"
					( Origin gFrontEnd )
				)
				( attribute "PHYS_PAGE" "202"
					( Origin gFrontEnd )
				)
				( attribute "POP" "NOPOP"
					( Origin gFrontEnd )
				)
				( attribute "RATED" "1/10W"
					( Origin gFrontEnd )
				)
				( attribute "ROT" "0"
					( Origin gFrontEnd )
				)
				( attribute "SEC" "1"
					( Origin gFrontEnd )
				)
				( attribute "SEC_TYPE" "RCL_GP"
					( Origin gFrontEnd )
				)
				( attribute "TOLERANCE" "1%"
					( Origin gFrontEnd )
				)
				( attribute "VALUE" "1R3F-GP"
					( Origin gFrontEnd )
				)
				( attribute "VER" "1"
					( Origin gFrontEnd )
				)
				( attribute "XY" "(-2550,2950)"
					( Origin gFrontEnd )
				)
				( attribute "CHIPS_PART_NAME" "1R3F-GP"
					( Origin gPackager )
				)
				( attribute "CDS_PART_NAME" "1R3F-GP_RCL_GP-1R3F-GP,64.1R00A"
					( Origin gPackager )
				)
				( attribute "PACK_SIZE" "0603"
					( Origin gFrontEnd )
				)
				( attribute "CDS_LOCATION" "RT2"
					( Origin gPackager )
				)
				( attribute "CDS_SEC" "1"
					( Origin gPackager )
				)
				( objectStatus "RT2" )
			)
			( gate "@baseboard_fab2_lib.baseboard_fab2(sch_1):page186_i270"
				( attribute "CDS_LIB" "dev_discrete"
					( Origin gPackager )
				)
				( attribute "CDS_LOCATION" "C1M20"
					( Origin gPackager )
				)
				( attribute "LOCATION" "C1M20"
					( Origin gFrontEnd )
				)
				( attribute "MATERIAL" "X7R"
					( Origin gFrontEnd )
				)
				( attribute "PACK_TYPE" "0402V"
					( Origin gFrontEnd )
				)
				( attribute "PART_NUMBER" "A36096-030"
					( Origin gFrontEnd )
				)
				( attribute "PHYS_PAGE" "186"
					( Origin gFrontEnd )
				)
				( attribute "ROOM" "IO_SLOT"
					( Origin gFrontEnd )
				)
				( attribute "ROT" "0"
					( Origin gFrontEnd )
				)
				( attribute "SEC" "1"
					( Origin gFrontEnd )
				)
				( attribute "TOLERANCE" "10%"
					( Origin gFrontEnd )
				)
				( attribute "VALUE" "0.1UF"
					( Origin gFrontEnd )
				)
				( attribute "VER" "1"
					( Origin gFrontEnd )
				)
				( attribute "VOLTAGE" "16V"
					( Units "uVoltage" "V" 1.000000)
					( Origin gFrontEnd )
				)
				( attribute "XY" "(11650,4675)"
					( Origin gFrontEnd )
				)
				( attribute "CHIPS_PART_NAME" "CAP_A"
					( Origin gPackager )
				)
				( attribute "CDS_PART_NAME" "CAP_A_0402V-0.1UF,16V,10%,X7R,A"
					( Origin gPackager )
				)
				( attribute "SEC_TYPE" "0402V"
					( Origin gFrontEnd )
				)
				( attribute "CDS_SEC" "1"
					( Origin gPackager )
				)
				( objectStatus "C1M20" )
			)
			( gate "@baseboard_fab2_lib.baseboard_fab2(sch_1):page186_i334"
				( attribute "CDS_LIB" "dev_discrete"
					( Origin gPackager )
				)
				( attribute "CDS_LOCATION" "C1M21"
					( Origin gPackager )
				)
				( attribute "CDS_SEC" "1"
					( Origin gPackager )
				)
				( attribute "LOCATION" "C1M21"
					( Origin gFrontEnd )
				)
				( attribute "MATERIAL" "X6S"
					( Origin gFrontEnd )
				)
				( attribute "PACK_TYPE" "0402V"
					( Origin gFrontEnd )
				)
				( attribute "PART_NUMBER" "D97712-004"
					( Origin gFrontEnd )
				)
				( attribute "PHYS_PAGE" "186"
					( Origin gFrontEnd )
				)
				( attribute "ROOM" "IO_SLOT"
					( Origin gFrontEnd )
				)
				( attribute "ROT" "0"
					( Origin gFrontEnd )
				)
				( attribute "SEC" "1"
					( Origin gFrontEnd )
				)
				( attribute "SEC_TYPE" "0402V"
					( Origin gFrontEnd )
				)
				( attribute "TOLERANCE" "10%"
					( Origin gFrontEnd )
				)
				( attribute "VALUE" "1.0UF"
					( Origin gFrontEnd )
				)
				( attribute "VER" "1"
					( Origin gFrontEnd )
				)
				( attribute "VOLTAGE" "6.3V"
					( Units "uVoltage" "V" 1.000000)
					( Origin gFrontEnd )
				)
				( attribute "XY" "(10450,4700)"
					( Origin gFrontEnd )
				)
				( attribute "CHIPS_PART_NAME" "CAP_A"
					( Origin gPackager )
				)
				( attribute "CDS_PART_NAME" "CAP_A_0402V-1.0UF,6.3V,10%,X6SA"
					( Origin gPackager )
				)
				( objectStatus "C1M21" )
			)
			( gate "@baseboard_fab2_lib.baseboard_fab2(sch_1):page186_i335"
				( attribute "CDS_LIB" "dev_discrete"
					( Origin gPackager )
				)
				( attribute "CDS_LOCATION" "C1M25"
					( Origin gPackager )
				)
				( attribute "CDS_SEC" "1"
					( Origin gPackager )
				)
				( attribute "LOCATION" "C1M25"
					( Origin gFrontEnd )
				)
				( attribute "MATERIAL" "X6S"
					( Origin gFrontEnd )
				)
				( attribute "PACK_TYPE" "0402V"
					( Origin gFrontEnd )
				)
				( attribute "PART_NUMBER" "D97712-004"
					( Origin gFrontEnd )
				)
				( attribute "PHYS_PAGE" "186"
					( Origin gFrontEnd )
				)
				( attribute "ROOM" "IO_SLOT"
					( Origin gFrontEnd )
				)
				( attribute "ROT" "0"
					( Origin gFrontEnd )
				)
				( attribute "SEC" "1"
					( Origin gFrontEnd )
				)
				( attribute "SEC_TYPE" "0402V"
					( Origin gFrontEnd )
				)
				( attribute "TOLERANCE" "10%"
					( Origin gFrontEnd )
				)
				( attribute "VALUE" "1.0UF"
					( Origin gFrontEnd )
				)
				( attribute "VER" "1"
					( Origin gFrontEnd )
				)
				( attribute "VOLTAGE" "6.3V"
					( Units "uVoltage" "V" 1.000000)
					( Origin gFrontEnd )
				)
				( attribute "XY" "(11250,4700)"
					( Origin gFrontEnd )
				)
				( attribute "CHIPS_PART_NAME" "CAP_A"
					( Origin gPackager )
				)
				( attribute "CDS_PART_NAME" "CAP_A_0402V-1.0UF,6.3V,10%,X6SA"
					( Origin gPackager )
				)
				( objectStatus "C1M25" )
			)
			( gate "@baseboard_fab2_lib.baseboard_fab2(sch_1):page186_i336"
				( attribute "CDS_LIB" "mstr_sconn"
					( Origin gPackager )
				)
				( attribute "CDS_LOCATION" "J9B3"
					( Origin gPackager )
				)
				( attribute "CDS_SEC" "1"
					( Origin gPackager )
				)
				( attribute "LOCATION" "J9B3"
					( Origin gFrontEnd )
				)
				( attribute "MATERIAL" "SCONN"
					( Origin gFrontEnd )
				)
				( attribute "PACK_TYPE" "SM"
					( Origin gFrontEnd )
				)
				( attribute "PART_NUMBER" "A28699-018"
					( Origin gFrontEnd )
				)
				( attribute "PHYS_PAGE" "186"
					( Origin gFrontEnd )
				)
				( attribute "ROOM" "IO_SLOT"
					( Origin gFrontEnd )
				)
				( attribute "ROT" "0"
					( Origin gFrontEnd )
				)
				( attribute "SEC" "1"
					( Origin gFrontEnd )
				)
				( attribute "SEC_TYPE" "SM"
					( Origin gFrontEnd )
				)
				( attribute "VER" "1"
					( Origin gFrontEnd )
				)
				( attribute "XY" "(8250,2350)"
					( Origin gFrontEnd )
				)
				( attribute "CHIPS_PART_NAME" "SCONN120_A28699018"
					( Origin gPackager )
				)
				( attribute "CDS_PART_NAME" "SCONN120_A28699018_SM-SCONN,A2A"
					( Origin gPackager )
				)
				( attribute "GROUP" "NO_KR"
					( Origin gFrontEnd )
				)
				( objectStatus "J9B3" )
			)
			( gate "@baseboard_fab2_lib.baseboard_fab2(sch_1):page186_i337"
				( attribute "CDS_LIB" "mstr_discrete"
					( Origin gPackager )
				)
				( attribute "CDS_LOCATION" "R1M16"
					( Origin gPackager )
				)
				( attribute "CDS_SEC" "1"
					( Origin gPackager )
				)
				( attribute "LOCATION" "R1M16"
					( Origin gFrontEnd )
				)
				( attribute "MATERIAL" "CHIP"
					( Origin gFrontEnd )
				)
				( attribute "PACK_TYPE" "0402"
					( Origin gFrontEnd )
				)
				( attribute "PART_NUMBER" "G21497-005"
					( Origin gFrontEnd )
				)
				( attribute "PHYS_PAGE" "186"
					( Origin gFrontEnd )
				)
				( attribute "ROOM" "IO_SLOT"
					( Origin gFrontEnd )
				)
				( attribute "ROT" "0"
					( Origin gFrontEnd )
				)
				( attribute "SEC" "1"
					( Origin gFrontEnd )
				)
				( attribute "SEC_TYPE" "0402"
					( Origin gFrontEnd )
				)
				( attribute "TOLERANCE" "5%"
					( Origin gFrontEnd )
				)
				( attribute "VALUE" "0.0"
					( Origin gFrontEnd )
				)
				( attribute "VER" "1"
					( Origin gFrontEnd )
				)
				( attribute "WATTAGE" "1/16W"
					( Origin gFrontEnd )
				)
				( attribute "XY" "(6700,2750)"
					( Origin gFrontEnd )
				)
				( attribute "CHIPS_PART_NAME" "RES"
					( Origin gPackager )
				)
				( attribute "CDS_PART_NAME" "RES_0402-0.0,5%,1/16W,CHIP,G21A"
					( Origin gPackager )
				)
				( objectStatus "R1M16" )
			)
			( gate "@baseboard_fab2_lib.baseboard_fab2(sch_1):page186_i338"
				( attribute "CDS_LIB" "mstr_discrete"
					( Origin gPackager )
				)
				( attribute "CDS_LOCATION" "R1M17"
					( Origin gPackager )
				)
				( attribute "CDS_SEC" "1"
					( Origin gPackager )
				)
				( attribute "LOCATION" "R1M17"
					( Origin gFrontEnd )
				)
				( attribute "MATERIAL" "CHIP"
					( Origin gFrontEnd )
				)
				( attribute "PACK_TYPE" "0402"
					( Origin gFrontEnd )
				)
				( attribute "PART_NUMBER" "G21497-005"
					( Origin gFrontEnd )
				)
				( attribute "PHYS_PAGE" "186"
					( Origin gFrontEnd )
				)
				( attribute "ROOM" "IO_SLOT"
					( Origin gFrontEnd )
				)
				( attribute "ROT" "0"
					( Origin gFrontEnd )
				)
				( attribute "SEC" "1"
					( Origin gFrontEnd )
				)
				( attribute "SEC_TYPE" "0402"
					( Origin gFrontEnd )
				)
				( attribute "TOLERANCE" "5%"
					( Origin gFrontEnd )
				)
				( attribute "VALUE" "0.0"
					( Origin gFrontEnd )
				)
				( attribute "VER" "1"
					( Origin gFrontEnd )
				)
				( attribute "WATTAGE" "1/16W"
					( Origin gFrontEnd )
				)
				( attribute "XY" "(6375,2800)"
					( Origin gFrontEnd )
				)
				( attribute "CHIPS_PART_NAME" "RES"
					( Origin gPackager )
				)
				( attribute "CDS_PART_NAME" "RES_0402-0.0,5%,1/16W,CHIP,G21A"
					( Origin gPackager )
				)
				( objectStatus "R1M17" )
			)
			( gate "@baseboard_fab2_lib.baseboard_fab2(sch_1):page186_i339"
				( attribute "CDS_LIB" "mstr_discrete"
					( Origin gPackager )
				)
				( attribute "CDS_LOCATION" "R1M15"
					( Origin gPackager )
				)
				( attribute "CDS_SEC" "1"
					( Origin gPackager )
				)
				( attribute "LOCATION" "R1M15"
					( Origin gFrontEnd )
				)
				( attribute "MATERIAL" "CHIP"
					( Origin gFrontEnd )
				)
				( attribute "PACK_TYPE" "0402"
					( Origin gFrontEnd )
				)
				( attribute "PART_NUMBER" "G21497-005"
					( Origin gFrontEnd )
				)
				( attribute "PHYS_PAGE" "186"
					( Origin gFrontEnd )
				)
				( attribute "ROOM" "IO_SLOT"
					( Origin gFrontEnd )
				)
				( attribute "ROT" "0"
					( Origin gFrontEnd )
				)
				( attribute "SEC" "1"
					( Origin gFrontEnd )
				)
				( attribute "SEC_TYPE" "0402"
					( Origin gFrontEnd )
				)
				( attribute "TOLERANCE" "5%"
					( Origin gFrontEnd )
				)
				( attribute "VALUE" "0.0"
					( Origin gFrontEnd )
				)
				( attribute "VER" "1"
					( Origin gFrontEnd )
				)
				( attribute "WATTAGE" "1/16W"
					( Origin gFrontEnd )
				)
				( attribute "XY" "(6375,3200)"
					( Origin gFrontEnd )
				)
				( attribute "CHIPS_PART_NAME" "RES"
					( Origin gPackager )
				)
				( attribute "CDS_PART_NAME" "RES_0402-0.0,5%,1/16W,CHIP,G21A"
					( Origin gPackager )
				)
				( objectStatus "R1M15" )
			)
			( gate "@baseboard_fab2_lib.baseboard_fab2(sch_1):page186_i340"
				( attribute "CDS_LIB" "mstr_discrete"
					( Origin gPackager )
				)
				( attribute "CDS_LOCATION" "R1M18"
					( Origin gPackager )
				)
				( attribute "CDS_SEC" "1"
					( Origin gPackager )
				)
				( attribute "LOCATION" "R1M18"
					( Origin gFrontEnd )
				)
				( attribute "MATERIAL" "CHIP"
					( Origin gFrontEnd )
				)
				( attribute "PACK_TYPE" "0402"
					( Origin gFrontEnd )
				)
				( attribute "PART_NUMBER" "G21497-005"
					( Origin gFrontEnd )
				)
				( attribute "PHYS_PAGE" "186"
					( Origin gFrontEnd )
				)
				( attribute "ROOM" "IO_SLOT"
					( Origin gFrontEnd )
				)
				( attribute "ROT" "0"
					( Origin gFrontEnd )
				)
				( attribute "SEC" "1"
					( Origin gFrontEnd )
				)
				( attribute "SEC_TYPE" "0402"
					( Origin gFrontEnd )
				)
				( attribute "TOLERANCE" "5%"
					( Origin gFrontEnd )
				)
				( attribute "VALUE" "0.0"
					( Origin gFrontEnd )
				)
				( attribute "VER" "1"
					( Origin gFrontEnd )
				)
				( attribute "WATTAGE" "1/16W"
					( Origin gFrontEnd )
				)
				( attribute "XY" "(10250,3000)"
					( Origin gFrontEnd )
				)
				( attribute "CHIPS_PART_NAME" "RES"
					( Origin gPackager )
				)
				( attribute "CDS_PART_NAME" "RES_0402-0.0,5%,1/16W,CHIP,G21A"
					( Origin gPackager )
				)
				( objectStatus "R1M18" )
			)
			( gate "@baseboard_fab2_lib.baseboard_fab2(sch_1):page186_i345"
				( attribute "CDS_LIB" "dev_discrete"
					( Origin gPackager )
				)
				( attribute "CDS_LOCATION" "C9B10"
					( Origin gPackager )
				)
				( attribute "CDS_SEC" "1"
					( Origin gPackager )
				)
				( attribute "LOCATION" "C9B10"
					( Origin gFrontEnd )
				)
				( attribute "MATERIAL" "X7R"
					( Origin gFrontEnd )
				)
				( attribute "PACK_TYPE" "0402V"
					( Origin gFrontEnd )
				)
				( attribute "PART_NUMBER" "A36096-030"
					( Origin gFrontEnd )
				)
				( attribute "PHYS_PAGE" "186"
					( Origin gFrontEnd )
				)
				( attribute "ROOM" "IO_SLOT"
					( Origin gFrontEnd )
				)
				( attribute "ROT" "0"
					( Origin gFrontEnd )
				)
				( attribute "SEC" "1"
					( Origin gFrontEnd )
				)
				( attribute "SEC_TYPE" "0402V"
					( Origin gFrontEnd )
				)
				( attribute "TOLERANCE" "10%"
					( Origin gFrontEnd )
				)
				( attribute "VALUE" "0.1UF"
					( Origin gFrontEnd )
				)
				( attribute "VER" "1"
					( Origin gFrontEnd )
				)
				( attribute "VOLTAGE" "16V"
					( Units "uVoltage" "V" 1.000000)
					( Origin gFrontEnd )
				)
				( attribute "XY" "(10050,3950)"
					( Origin gFrontEnd )
				)
				( attribute "CHIPS_PART_NAME" "CAP_A"
					( Origin gPackager )
				)
				( attribute "CDS_PART_NAME" "CAP_A_0402V-0.1UF,16V,10%,X7R,A"
					( Origin gPackager )
				)
				( objectStatus "C9B10" )
			)
			( gate "@baseboard_fab2_lib.baseboard_fab2(sch_1):page209_i89"
				( attribute "CDS_LIB" "w_hdl"
					( Origin gPackager )
				)
				( attribute "CDS_LMAN_SYM_OUTLINE" "-50,25,50,-25"
					( Origin gPackager )
				)
				( attribute "LOCATION" "C1C18"
					( Origin gFrontEnd )
				)
				( attribute "PACK_TYPE" "SMD-BCG6"
					( Origin gFrontEnd )
				)
				( attribute "PART_NUMBER" "78.10523.8FL"
					( Origin gFrontEnd )
				)
				( attribute "PHYS_PAGE" "209"
					( Origin gFrontEnd )
				)
				( attribute "ROT" "0"
					( Origin gFrontEnd )
				)
				( attribute "SEC" "1"
					( Origin gFrontEnd )
				)
				( attribute "SEC_TYPE" "SMD-BCG6"
					( Origin gFrontEnd )
				)
				( attribute "VALUE" "SC1U10V2KX-4-GP"
					( Origin gFrontEnd )
				)
				( attribute "VER" "1"
					( Origin gFrontEnd )
				)
				( attribute "XY" "(-5125,4025)"
					( Origin gFrontEnd )
				)
				( attribute "CHIPS_PART_NAME" "SC1U10V2KX-4-GP"
					( Origin gPackager )
				)
				( attribute "CDS_PART_NAME" "SC1U10V2KX-4-GP_SMD-BCG6-SC1U1A"
					( Origin gPackager )
				)
				( attribute "ATTRIBUTE" "1UF"
					( Origin gFrontEnd )
				)
				( attribute "PACK_SIZE" "0402"
					( Origin gFrontEnd )
				)
				( attribute "RATED" "10V"
					( Origin gFrontEnd )
				)
				( attribute "TOLERANCE" "10%"
					( Origin gFrontEnd )
				)
				( attribute "CDS_LOCATION" "C1C18"
					( Origin gPackager )
				)
				( attribute "CDS_SEC" "1"
					( Origin gPackager )
				)
				( objectStatus "C1C18" )
			)
			( gate "@baseboard_fab2_lib.baseboard_fab2(sch_1):page187_i119"
				( attribute "CDS_LIB" "mstr_sconn"
					( Origin gPackager )
				)
				( attribute "CDS_LMAN_SYM_OUTLINE" "-250,1100,250,-1100"
					( Origin gPackager )
				)
				( attribute "CDS_LOCATION" "J8E3"
					( Origin gPackager )
				)
				( attribute "CDS_SEC" "1"
					( Origin gPackager )
				)
				( attribute "LOCATION" "J8E3"
					( Origin gFrontEnd )
				)
				( attribute "MATERIAL" "CONN"
					( Origin gFrontEnd )
				)
				( attribute "PACK_TYPE" "SM"
					( Origin gFrontEnd )
				)
				( attribute "PART_NUMBER" "E67482-007"
					( Origin gFrontEnd )
				)
				( attribute "PHYS_PAGE" "187"
					( Origin gFrontEnd )
				)
				( attribute "ROOM" "IO_SLOT"
					( Origin gFrontEnd )
				)
				( attribute "ROT" "2"
					( Origin gFrontEnd )
				)
				( attribute "SEC" "1"
					( Origin gFrontEnd )
				)
				( attribute "SEC_TYPE" "SM"
					( Origin gFrontEnd )
				)
				( attribute "VER" "1"
					( Origin gFrontEnd )
				)
				( attribute "XY" "(-50,3100)"
					( Origin gFrontEnd )
				)
				( attribute "CHIPS_PART_NAME" "SCONN80_E67482007"
					( Origin gPackager )
				)
				( attribute "CDS_PART_NAME" "SCONN80_E67482007_SM-CONN,E674A"
					( Origin gPackager )
				)
				( attribute "GROUP" "NO_KR"
					( Origin gFrontEnd )
				)
				( objectStatus "J8E3" )
			)
			( gate "@baseboard_fab2_lib.baseboard_fab2(sch_1):page187_i145"
				( attribute "CDS_LIB" "mstr_discrete"
					( Origin gPackager )
				)
				( attribute "CDS_LOCATION" "R9E10"
					( Origin gPackager )
				)
				( attribute "CDS_SEC" "1"
					( Origin gPackager )
				)
				( attribute "LOCATION" "R9E10"
					( Origin gFrontEnd )
				)
				( attribute "MATERIAL" "CHIP"
					( Origin gFrontEnd )
				)
				( attribute "PACK_TYPE" "0402"
					( Origin gFrontEnd )
				)
				( attribute "PART_NUMBER" "G21796-004"
					( Origin gFrontEnd )
				)
				( attribute "PHYS_PAGE" "187"
					( Origin gFrontEnd )
				)
				( attribute "ROOM" "IO_SLOT"
					( Origin gFrontEnd )
				)
				( attribute "ROT" "0"
					( Origin gFrontEnd )
				)
				( attribute "SEC" "1"
					( Origin gFrontEnd )
				)
				( attribute "SEC_TYPE" "0402"
					( Origin gFrontEnd )
				)
				( attribute "TOLERANCE" "1%"
					( Origin gFrontEnd )
				)
				( attribute "VALUE" "200.0"
					( Origin gFrontEnd )
				)
				( attribute "VER" "1"
					( Origin gFrontEnd )
				)
				( attribute "WATTAGE" "1/16W"
					( Origin gFrontEnd )
				)
				( attribute "XY" "(2275,2200)"
					( Origin gFrontEnd )
				)
				( attribute "CHIPS_PART_NAME" "RES"
					( Origin gPackager )
				)
				( attribute "CDS_PART_NAME" "RES_0402-200.0,1%,1/16W,CHIP,GA"
					( Origin gPackager )
				)
				( objectStatus "R9E10" )
			)
			( gate "@baseboard_fab2_lib.baseboard_fab2(sch_1):page187_i150"
				( attribute "CDS_LIB" "mstr_discrete"
					( Origin gPackager )
				)
				( attribute "CDS_LOCATION" "R9E11"
					( Origin gPackager )
				)
				( attribute "CDS_SEC" "1"
					( Origin gPackager )
				)
				( attribute "LOCATION" "R9E11"
					( Origin gFrontEnd )
				)
				( attribute "MATERIAL" "CHIP"
					( Origin gFrontEnd )
				)
				( attribute "PACK_TYPE" "0402"
					( Origin gFrontEnd )
				)
				( attribute "PART_NUMBER" "G21796-004"
					( Origin gFrontEnd )
				)
				( attribute "PHYS_PAGE" "187"
					( Origin gFrontEnd )
				)
				( attribute "ROOM" "IO_SLOT"
					( Origin gFrontEnd )
				)
				( attribute "ROT" "0"
					( Origin gFrontEnd )
				)
				( attribute "SEC" "1"
					( Origin gFrontEnd )
				)
				( attribute "SEC_TYPE" "0402"
					( Origin gFrontEnd )
				)
				( attribute "TOLERANCE" "1%"
					( Origin gFrontEnd )
				)
				( attribute "VALUE" "200.0"
					( Origin gFrontEnd )
				)
				( attribute "VER" "1"
					( Origin gFrontEnd )
				)
				( attribute "WATTAGE" "1/16W"
					( Origin gFrontEnd )
				)
				( attribute "XY" "(1725,2150)"
					( Origin gFrontEnd )
				)
				( attribute "CHIPS_PART_NAME" "RES"
					( Origin gPackager )
				)
				( attribute "CDS_PART_NAME" "RES_0402-200.0,1%,1/16W,CHIP,GA"
					( Origin gPackager )
				)
				( objectStatus "R9E11" )
			)
			( gate "@baseboard_fab2_lib.baseboard_fab2(sch_1):page187_i153"
				( attribute "CDS_LIB" "mstr_discrete"
					( Origin gPackager )
				)
				( attribute "CDS_LOCATION" "R9E12"
					( Origin gPackager )
				)
				( attribute "CDS_SEC" "1"
					( Origin gPackager )
				)
				( attribute "LOCATION" "R9E12"
					( Origin gFrontEnd )
				)
				( attribute "MATERIAL" "CHIP"
					( Origin gFrontEnd )
				)
				( attribute "PACK_TYPE" "0402"
					( Origin gFrontEnd )
				)
				( attribute "PART_NUMBER" "G21796-004"
					( Origin gFrontEnd )
				)
				( attribute "PHYS_PAGE" "187"
					( Origin gFrontEnd )
				)
				( attribute "ROOM" "IO_SLOT"
					( Origin gFrontEnd )
				)
				( attribute "ROT" "0"
					( Origin gFrontEnd )
				)
				( attribute "SEC" "1"
					( Origin gFrontEnd )
				)
				( attribute "SEC_TYPE" "0402"
					( Origin gFrontEnd )
				)
				( attribute "TOLERANCE" "1%"
					( Origin gFrontEnd )
				)
				( attribute "VALUE" "200.0"
					( Origin gFrontEnd )
				)
				( attribute "VER" "1"
					( Origin gFrontEnd )
				)
				( attribute "WATTAGE" "1/16W"
					( Origin gFrontEnd )
				)
				( attribute "XY" "(1275,2100)"
					( Origin gFrontEnd )
				)
				( attribute "CHIPS_PART_NAME" "RES"
					( Origin gPackager )
				)
				( attribute "CDS_PART_NAME" "RES_0402-200.0,1%,1/16W,CHIP,GA"
					( Origin gPackager )
				)
				( objectStatus "R9E12" )
			)
			( gate "@baseboard_fab2_lib.baseboard_fab2(sch_1):page188_i2"
				( attribute "BOM_COST" "IO_MODULE"
					( Origin gFrontEnd )
				)
				( attribute "CDS_LIB" "dev_discrete"
					( Origin gPackager )
				)
				( attribute "CDS_LOCATION" "C2R15"
					( Origin gPackager )
				)
				( attribute "CDS_SEC" "1"
					( Origin gPackager )
				)
				( attribute "LOCATION" "C2R15"
					( Origin gFrontEnd )
				)
				( attribute "MATERIAL" "X7R"
					( Origin gFrontEnd )
				)
				( attribute "PACK_TYPE" "0402V"
					( Origin gFrontEnd )
				)
				( attribute "PART_NUMBER" "A36096-030"
					( Origin gFrontEnd )
				)
				( attribute "PHYS_PAGE" "188"
					( Origin gFrontEnd )
				)
				( attribute "ROOM" "IO_MODULE"
					( Origin gFrontEnd )
				)
				( attribute "ROT" "0"
					( Origin gFrontEnd )
				)
				( attribute "SEC" "1"
					( Origin gFrontEnd )
				)
				( attribute "SEC_TYPE" "0402V"
					( Origin gFrontEnd )
				)
				( attribute "TOLERANCE" "10%"
					( Origin gFrontEnd )
				)
				( attribute "VALUE" "0.1UF"
					( Origin gFrontEnd )
				)
				( attribute "VER" "1"
					( Origin gFrontEnd )
				)
				( attribute "VOLTAGE" "16V"
					( Units "uVoltage" "V" 1.000000)
					( Origin gFrontEnd )
				)
				( attribute "XY" "(3300,1300)"
					( Origin gFrontEnd )
				)
				( attribute "CHIPS_PART_NAME" "CAP_A"
					( Origin gPackager )
				)
				( attribute "CDS_PART_NAME" "CAP_A_0402V-0.1UF,16V,10%,X7R,A"
					( Origin gPackager )
				)
				( objectStatus "C2R15" )
			)
			( gate "@baseboard_fab2_lib.baseboard_fab2(sch_1):page188_i3"
				( attribute "BOM_COST" "IO_MODULE"
					( Origin gFrontEnd )
				)
				( attribute "CDS_LIB" "dev_discrete"
					( Origin gPackager )
				)
				( attribute "CDS_LOCATION" "C2R18"
					( Origin gPackager )
				)
				( attribute "CDS_SEC" "1"
					( Origin gPackager )
				)
				( attribute "LOCATION" "C2R18"
					( Origin gFrontEnd )
				)
				( attribute "MATERIAL" "X7R"
					( Origin gFrontEnd )
				)
				( attribute "PACK_TYPE" "0402V"
					( Origin gFrontEnd )
				)
				( attribute "PART_NUMBER" "A36096-030"
					( Origin gFrontEnd )
				)
				( attribute "PHYS_PAGE" "188"
					( Origin gFrontEnd )
				)
				( attribute "ROOM" "IO_MODULE"
					( Origin gFrontEnd )
				)
				( attribute "ROT" "0"
					( Origin gFrontEnd )
				)
				( attribute "SEC" "1"
					( Origin gPackager )
				)
				( attribute "TOLERANCE" "10%"
					( Origin gFrontEnd )
				)
				( attribute "VALUE" "0.1UF"
					( Origin gFrontEnd )
				)
				( attribute "VER" "1"
					( Origin gFrontEnd )
				)
				( attribute "VOLTAGE" "16V"
					( Units "uVoltage" "V" 1.000000)
					( Origin gFrontEnd )
				)
				( attribute "XY" "(2925,1300)"
					( Origin gFrontEnd )
				)
				( attribute "CHIPS_PART_NAME" "CAP_A"
					( Origin gPackager )
				)
				( attribute "CDS_PART_NAME" "CAP_A_0402V-0.1UF,16V,10%,X7R,A"
					( Origin gPackager )
				)
				( objectStatus "C2R18" )
			)
			( gate "@baseboard_fab2_lib.baseboard_fab2(sch_1):page188_i21"
				( attribute "BOM_COST" "IO_MODULE"
					( Origin gFrontEnd )
				)
				( attribute "CDS_LIB" "dev_discrete"
					( Origin gPackager )
				)
				( attribute "CDS_LOCATION" "C2P11"
					( Origin gPackager )
				)
				( attribute "CDS_SEC" "1"
					( Origin gPackager )
				)
				( attribute "LOCATION" "C2P11"
					( Origin gFrontEnd )
				)
				( attribute "MATERIAL" "X7R"
					( Origin gFrontEnd )
				)
				( attribute "PACK_TYPE" "0402V"
					( Origin gFrontEnd )
				)
				( attribute "PART_NUMBER" "A36096-030"
					( Origin gFrontEnd )
				)
				( attribute "PHYS_PAGE" "188"
					( Origin gFrontEnd )
				)
				( attribute "ROOM" "IO_MODULE"
					( Origin gFrontEnd )
				)
				( attribute "ROT" "0"
					( Origin gFrontEnd )
				)
				( attribute "SEC" "1"
					( Origin gFrontEnd )
				)
				( attribute "SEC_TYPE" "0402V"
					( Origin gFrontEnd )
				)
				( attribute "TOLERANCE" "10%"
					( Origin gFrontEnd )
				)
				( attribute "VALUE" "0.1UF"
					( Origin gFrontEnd )
				)
				( attribute "VER" "1"
					( Origin gFrontEnd )
				)
				( attribute "VOLTAGE" "16V"
					( Units "uVoltage" "V" 1.000000)
					( Origin gFrontEnd )
				)
				( attribute "XY" "(2400,1300)"
					( Origin gFrontEnd )
				)
				( attribute "CHIPS_PART_NAME" "CAP_A"
					( Origin gPackager )
				)
				( attribute "CDS_PART_NAME" "CAP_A_0402V-0.1UF,16V,10%,X7R,A"
					( Origin gPackager )
				)
				( objectStatus "C2P11" )
			)
			( gate "@baseboard_fab2_lib.baseboard_fab2(sch_1):page188_i23"
				( attribute "BOM_COST" "IO_MODULE"
					( Origin gFrontEnd )
				)
				( attribute "CDS_LIB" "dev_discrete"
					( Origin gPackager )
				)
				( attribute "CDS_LOCATION" "C2P12"
					( Origin gPackager )
				)
				( attribute "CDS_SEC" "1"
					( Origin gPackager )
				)
				( attribute "LOCATION" "C2P12"
					( Origin gFrontEnd )
				)
				( attribute "MATERIAL" "X7R"
					( Origin gFrontEnd )
				)
				( attribute "PACK_TYPE" "0402V"
					( Origin gFrontEnd )
				)
				( attribute "PART_NUMBER" "A36096-030"
					( Origin gFrontEnd )
				)
				( attribute "PHYS_PAGE" "188"
					( Origin gFrontEnd )
				)
				( attribute "ROOM" "IO_MODULE"
					( Origin gFrontEnd )
				)
				( attribute "ROT" "0"
					( Origin gFrontEnd )
				)
				( attribute "SEC" "1"
					( Origin gFrontEnd )
				)
				( attribute "SEC_TYPE" "0402V"
					( Origin gFrontEnd )
				)
				( attribute "TOLERANCE" "10%"
					( Origin gFrontEnd )
				)
				( attribute "VALUE" "0.1UF"
					( Origin gFrontEnd )
				)
				( attribute "VER" "1"
					( Origin gFrontEnd )
				)
				( attribute "VOLTAGE" "16V"
					( Units "uVoltage" "V" 1.000000)
					( Origin gFrontEnd )
				)
				( attribute "XY" "(2050,1300)"
					( Origin gFrontEnd )
				)
				( attribute "CHIPS_PART_NAME" "CAP_A"
					( Origin gPackager )
				)
				( attribute "CDS_PART_NAME" "CAP_A_0402V-0.1UF,16V,10%,X7R,A"
					( Origin gPackager )
				)
				( objectStatus "C2P12" )
			)
			( gate "@baseboard_fab2_lib.baseboard_fab2(sch_1):page188_i25"
				( attribute "BOM_COST" "IO_MODULE"
					( Origin gFrontEnd )
				)
				( attribute "CDS_LIB" "dev_discrete"
					( Origin gPackager )
				)
				( attribute "CDS_LOCATION" "C2R17"
					( Origin gPackager )
				)
				( attribute "CDS_SEC" "1"
					( Origin gPackager )
				)
				( attribute "LOCATION" "C2R17"
					( Origin gFrontEnd )
				)
				( attribute "MATERIAL" "X7R"
					( Origin gFrontEnd )
				)
				( attribute "PACK_TYPE" "0402V"
					( Origin gFrontEnd )
				)
				( attribute "PART_NUMBER" "A36096-030"
					( Origin gFrontEnd )
				)
				( attribute "PHYS_PAGE" "188"
					( Origin gFrontEnd )
				)
				( attribute "ROOM" "IO_MODULE"
					( Origin gFrontEnd )
				)
				( attribute "ROT" "0"
					( Origin gFrontEnd )
				)
				( attribute "SEC" "1"
					( Origin gPackager )
				)
				( attribute "TOLERANCE" "10%"
					( Origin gFrontEnd )
				)
				( attribute "VALUE" "0.1UF"
					( Origin gFrontEnd )
				)
				( attribute "VER" "1"
					( Origin gFrontEnd )
				)
				( attribute "VOLTAGE" "16V"
					( Units "uVoltage" "V" 1.000000)
					( Origin gFrontEnd )
				)
				( attribute "XY" "(1000,1300)"
					( Origin gFrontEnd )
				)
				( attribute "CHIPS_PART_NAME" "CAP_A"
					( Origin gPackager )
				)
				( attribute "CDS_PART_NAME" "CAP_A_0402V-0.1UF,16V,10%,X7R,A"
					( Origin gPackager )
				)
				( objectStatus "C2R17" )
			)
			( gate "@baseboard_fab2_lib.baseboard_fab2(sch_1):page188_i27"
				( attribute "CDS_LIB" "mstr_sconn"
					( Origin gPackager )
				)
				( attribute "LOCATION" "J8E4"
					( Origin gFrontEnd )
				)
				( attribute "MATERIAL" "CONN"
					( Origin gFrontEnd )
				)
				( attribute "PACK_TYPE" "SMT"
					( Origin gFrontEnd )
				)
				( attribute "PART_NUMBER" "H87568-002"
					( Origin gFrontEnd )
				)
				( attribute "PHYS_PAGE" "188"
					( Origin gFrontEnd )
				)
				( attribute "ROOM" "IO_MODULE"
					( Origin gFrontEnd )
				)
				( attribute "ROT" "0"
					( Origin gFrontEnd )
				)
				( attribute "SEC" "1"
					( Origin gFrontEnd )
				)
				( attribute "SEC_TYPE" "SMT"
					( Origin gFrontEnd )
				)
				( attribute "VER" "1"
					( Origin gFrontEnd )
				)
				( attribute "XY" "(150,3025)"
					( Origin gFrontEnd )
				)
				( attribute "CHIPS_PART_NAME" "SCONN64_H87568002_A"
					( Origin gPackager )
				)
				( attribute "CDS_PART_NAME" "SCONN64_H87568002_A_SMT-CONN,HA"
					( Origin gPackager )
				)
				( attribute "GROUP" "KR"
					( Origin gFrontEnd )
				)
				( attribute "CDS_LOCATION" "J8E4"
					( Origin gPackager )
				)
				( attribute "CDS_SEC" "1"
					( Origin gPackager )
				)
				( objectStatus "J8E4" )
			)
			( gate "@baseboard_fab2_lib.baseboard_fab2(sch_1):page188_i40"
				( attribute "BOM_COST" "IO_MODULE"
					( Origin gFrontEnd )
				)
				( attribute "CDS_LIB" "dev_discrete"
					( Origin gPackager )
				)
				( attribute "CDS_LOCATION" "C2R16"
					( Origin gPackager )
				)
				( attribute "CDS_SEC" "1"
					( Origin gPackager )
				)
				( attribute "LOCATION" "C2R16"
					( Origin gFrontEnd )
				)
				( attribute "MATERIAL" "X7R"
					( Origin gFrontEnd )
				)
				( attribute "PACK_TYPE" "0402V"
					( Origin gFrontEnd )
				)
				( attribute "PART_NUMBER" "A36096-030"
					( Origin gFrontEnd )
				)
				( attribute "PHYS_PAGE" "188"
					( Origin gFrontEnd )
				)
				( attribute "ROOM" "IO_MODULE"
					( Origin gFrontEnd )
				)
				( attribute "ROT" "0"
					( Origin gFrontEnd )
				)
				( attribute "SEC" "1"
					( Origin gPackager )
				)
				( attribute "TOLERANCE" "10%"
					( Origin gFrontEnd )
				)
				( attribute "VALUE" "0.1UF"
					( Origin gFrontEnd )
				)
				( attribute "VER" "1"
					( Origin gFrontEnd )
				)
				( attribute "VOLTAGE" "16V"
					( Units "uVoltage" "V" 1.000000)
					( Origin gFrontEnd )
				)
				( attribute "XY" "(475,1300)"
					( Origin gFrontEnd )
				)
				( attribute "CHIPS_PART_NAME" "CAP_A"
					( Origin gPackager )
				)
				( attribute "CDS_PART_NAME" "CAP_A_0402V-0.1UF,16V,10%,X7R,A"
					( Origin gPackager )
				)
				( objectStatus "C2R16" )
			)
			( gate "@baseboard_fab2_lib.baseboard_fab2(sch_1):page188_i41"
				( attribute "BOM_COST" "IO_MODULE"
					( Origin gFrontEnd )
				)
				( attribute "CDS_LIB" "mstr_discrete"
					( Origin gPackager )
				)
				( attribute "CDS_LOCATION" "C2P10"
					( Origin gPackager )
				)
				( attribute "CDS_SEC" "1"
					( Origin gPackager )
				)
				( attribute "LOCATION" "C2P10"
					( Origin gFrontEnd )
				)
				( attribute "MATERIAL" "X6S"
					( Origin gFrontEnd )
				)
				( attribute "PACK_TYPE" "1206LF"
					( Origin gFrontEnd )
				)
				( attribute "PART_NUMBER" "D38464-005"
					( Origin gFrontEnd )
				)
				( attribute "PHYS_PAGE" "188"
					( Origin gFrontEnd )
				)
				( attribute "ROOM" "IO_MODULE"
					( Origin gFrontEnd )
				)
				( attribute "ROT" "0"
					( Origin gFrontEnd )
				)
				( attribute "SEC" "1"
					( Origin gFrontEnd )
				)
				( attribute "SEC_TYPE" "1206LF"
					( Origin gFrontEnd )
				)
				( attribute "TOLERANCE" "10%"
					( Origin gFrontEnd )
				)
				( attribute "VALUE" "22UF"
					( Origin gFrontEnd )
				)
				( attribute "VER" "1"
					( Origin gFrontEnd )
				)
				( attribute "VOLTAGE" "16V"
					( Units "uVoltage" "V" 1.000000)
					( Origin gFrontEnd )
				)
				( attribute "XY" "(-75,1300)"
					( Origin gFrontEnd )
				)
				( attribute "CHIPS_PART_NAME" "CAP"
					( Origin gPackager )
				)
				( attribute "CDS_PART_NAME" "CAP_1206LF-22UF,16V,10%,X6S,D3A"
					( Origin gPackager )
				)
				( objectStatus "C2P10" )
			)
			( gate "@baseboard_fab2_lib.baseboard_fab2(sch_1):page188_i53"
				( attribute "BOM_COST" "IO_MODULE"
					( Origin gFrontEnd )
				)
				( attribute "CDS_LIB" "dev_discrete"
					( Origin gPackager )
				)
				( attribute "CDS_LOCATION" "C2P16"
					( Origin gPackager )
				)
				( attribute "CDS_SEC" "1"
					( Origin gPackager )
				)
				( attribute "LOCATION" "C2P16"
					( Origin gFrontEnd )
				)
				( attribute "MATERIAL" "X7R"
					( Origin gFrontEnd )
				)
				( attribute "PACK_TYPE" "0402V"
					( Origin gFrontEnd )
				)
				( attribute "PART_NUMBER" "A36096-030"
					( Origin gFrontEnd )
				)
				( attribute "PHYS_PAGE" "188"
					( Origin gFrontEnd )
				)
				( attribute "ROOM" "IO_MODULE"
					( Origin gFrontEnd )
				)
				( attribute "ROT" "0"
					( Origin gFrontEnd )
				)
				( attribute "SEC" "1"
					( Origin gPackager )
				)
				( attribute "TOLERANCE" "10%"
					( Origin gFrontEnd )
				)
				( attribute "VALUE" "0.1UF"
					( Origin gFrontEnd )
				)
				( attribute "VER" "1"
					( Origin gFrontEnd )
				)
				( attribute "VOLTAGE" "16V"
					( Units "uVoltage" "V" 1.000000)
					( Origin gFrontEnd )
				)
				( attribute "XY" "(-525,1300)"
					( Origin gFrontEnd )
				)
				( attribute "CHIPS_PART_NAME" "CAP_A"
					( Origin gPackager )
				)
				( attribute "CDS_PART_NAME" "CAP_A_0402V-0.1UF,16V,10%,X7R,A"
					( Origin gPackager )
				)
				( objectStatus "C2P16" )
			)
			( gate "@baseboard_fab2_lib.baseboard_fab2(sch_1):page188_i55"
				( attribute "BOM_COST" "IO_MODULE"
					( Origin gFrontEnd )
				)
				( attribute "CDS_LIB" "dev_discrete"
					( Origin gPackager )
				)
				( attribute "CDS_LOCATION" "C2P15"
					( Origin gPackager )
				)
				( attribute "CDS_SEC" "1"
					( Origin gPackager )
				)
				( attribute "LOCATION" "C2P15"
					( Origin gFrontEnd )
				)
				( attribute "MATERIAL" "X7R"
					( Origin gFrontEnd )
				)
				( attribute "PACK_TYPE" "0402V"
					( Origin gFrontEnd )
				)
				( attribute "PART_NUMBER" "A36096-030"
					( Origin gFrontEnd )
				)
				( attribute "PHYS_PAGE" "188"
					( Origin gFrontEnd )
				)
				( attribute "ROOM" "IO_MODULE"
					( Origin gFrontEnd )
				)
				( attribute "ROT" "0"
					( Origin gFrontEnd )
				)
				( attribute "SEC" "1"
					( Origin gPackager )
				)
				( attribute "TOLERANCE" "10%"
					( Origin gFrontEnd )
				)
				( attribute "VALUE" "0.1UF"
					( Origin gFrontEnd )
				)
				( attribute "VER" "1"
					( Origin gFrontEnd )
				)
				( attribute "VOLTAGE" "16V"
					( Units "uVoltage" "V" 1.000000)
					( Origin gFrontEnd )
				)
				( attribute "XY" "(-950,1300)"
					( Origin gFrontEnd )
				)
				( attribute "CHIPS_PART_NAME" "CAP_A"
					( Origin gPackager )
				)
				( attribute "CDS_PART_NAME" "CAP_A_0402V-0.1UF,16V,10%,X7R,A"
					( Origin gPackager )
				)
				( objectStatus "C2P15" )
			)
			( gate "@baseboard_fab2_lib.baseboard_fab2(sch_1):page188_i56"
				( attribute "BOM_COST" "IO_MODULE"
					( Origin gFrontEnd )
				)
				( attribute "CDS_LIB" "dev_discrete"
					( Origin gPackager )
				)
				( attribute "CDS_LOCATION" "C2P14"
					( Origin gPackager )
				)
				( attribute "CDS_SEC" "1"
					( Origin gPackager )
				)
				( attribute "LOCATION" "C2P14"
					( Origin gFrontEnd )
				)
				( attribute "MATERIAL" "X7R"
					( Origin gFrontEnd )
				)
				( attribute "PACK_TYPE" "0402V"
					( Origin gFrontEnd )
				)
				( attribute "PART_NUMBER" "A36096-030"
					( Origin gFrontEnd )
				)
				( attribute "PHYS_PAGE" "188"
					( Origin gFrontEnd )
				)
				( attribute "ROOM" "IO_MODULE"
					( Origin gFrontEnd )
				)
				( attribute "ROT" "0"
					( Origin gFrontEnd )
				)
				( attribute "SEC" "1"
					( Origin gPackager )
				)
				( attribute "TOLERANCE" "10%"
					( Origin gFrontEnd )
				)
				( attribute "VALUE" "0.1UF"
					( Origin gFrontEnd )
				)
				( attribute "VER" "1"
					( Origin gFrontEnd )
				)
				( attribute "VOLTAGE" "16V"
					( Units "uVoltage" "V" 1.000000)
					( Origin gFrontEnd )
				)
				( attribute "XY" "(-1400,1300)"
					( Origin gFrontEnd )
				)
				( attribute "CHIPS_PART_NAME" "CAP_A"
					( Origin gPackager )
				)
				( attribute "CDS_PART_NAME" "CAP_A_0402V-0.1UF,16V,10%,X7R,A"
					( Origin gPackager )
				)
				( objectStatus "C2P14" )
			)
			( gate "@baseboard_fab2_lib.baseboard_fab2(sch_1):page188_i57"
				( attribute "BOM_COST" "IO_MODULE"
					( Origin gFrontEnd )
				)
				( attribute "CDS_LIB" "dev_discrete"
					( Origin gPackager )
				)
				( attribute "CDS_LOCATION" "C2P13"
					( Origin gPackager )
				)
				( attribute "CDS_SEC" "1"
					( Origin gPackager )
				)
				( attribute "LOCATION" "C2P13"
					( Origin gFrontEnd )
				)
				( attribute "MATERIAL" "X7R"
					( Origin gFrontEnd )
				)
				( attribute "PACK_TYPE" "0402V"
					( Origin gFrontEnd )
				)
				( attribute "PART_NUMBER" "A36096-030"
					( Origin gFrontEnd )
				)
				( attribute "PHYS_PAGE" "188"
					( Origin gFrontEnd )
				)
				( attribute "ROOM" "IO_MODULE"
					( Origin gFrontEnd )
				)
				( attribute "ROT" "0"
					( Origin gFrontEnd )
				)
				( attribute "SEC" "1"
					( Origin gPackager )
				)
				( attribute "TOLERANCE" "10%"
					( Origin gFrontEnd )
				)
				( attribute "VALUE" "0.1UF"
					( Origin gFrontEnd )
				)
				( attribute "VER" "1"
					( Origin gFrontEnd )
				)
				( attribute "VOLTAGE" "16V"
					( Units "uVoltage" "V" 1.000000)
					( Origin gFrontEnd )
				)
				( attribute "XY" "(-1825,1300)"
					( Origin gFrontEnd )
				)
				( attribute "CHIPS_PART_NAME" "CAP_A"
					( Origin gPackager )
				)
				( attribute "CDS_PART_NAME" "CAP_A_0402V-0.1UF,16V,10%,X7R,A"
					( Origin gPackager )
				)
				( objectStatus "C2P13" )
			)
			( gate "@baseboard_fab2_lib.baseboard_fab2(sch_1):page188_i82"
				( attribute "CDS_LIB" "dev_discrete"
					( Origin gPackager )
				)
				( attribute "CDS_LOCATION" "C8C15"
					( Origin gPackager )
				)
				( attribute "CDS_SEC" "1"
					( Origin gPackager )
				)
				( attribute "LOCATION" "C8C15"
					( Origin gFrontEnd )
				)
				( attribute "MATERIAL" "X7R"
					( Origin gFrontEnd )
				)
				( attribute "PACK_TYPE" "0402V"
					( Origin gFrontEnd )
				)
				( attribute "PART_NUMBER" "A36096-030"
					( Origin gFrontEnd )
				)
				( attribute "PHYS_PAGE" "188"
					( Origin gFrontEnd )
				)
				( attribute "ROT" "0"
					( Origin gFrontEnd )
				)
				( attribute "SEC" "1"
					( Origin gFrontEnd )
				)
				( attribute "SEC_TYPE" "0402V"
					( Origin gFrontEnd )
				)
				( attribute "TOLERANCE" "10%"
					( Origin gFrontEnd )
				)
				( attribute "VALUE" "0.1UF"
					( Origin gFrontEnd )
				)
				( attribute "VER" "2"
					( Origin gFrontEnd )
				)
				( attribute "VOLTAGE" "16V"
					( Units "uVoltage" "V" 1.000000)
					( Origin gFrontEnd )
				)
				( attribute "XY" "(3075,2925)"
					( Origin gFrontEnd )
				)
				( attribute "CHIPS_PART_NAME" "CAP_A"
					( Origin gPackager )
				)
				( attribute "CDS_PART_NAME" "CAP_A_0402V-0.1UF,16V,10%,X7R,A"
					( Origin gPackager )
				)
				( objectStatus "C8C15" )
			)
			( gate "@baseboard_fab2_lib.baseboard_fab2(sch_1):page188_i86"
				( attribute "CDS_LIB" "dev_discrete"
					( Origin gPackager )
				)
				( attribute "CDS_LOCATION" "C8C14"
					( Origin gPackager )
				)
				( attribute "CDS_SEC" "1"
					( Origin gPackager )
				)
				( attribute "LOCATION" "C8C14"
					( Origin gFrontEnd )
				)
				( attribute "MATERIAL" "X7R"
					( Origin gFrontEnd )
				)
				( attribute "PACK_TYPE" "0402V"
					( Origin gFrontEnd )
				)
				( attribute "PART_NUMBER" "A36096-030"
					( Origin gFrontEnd )
				)
				( attribute "PHYS_PAGE" "188"
					( Origin gFrontEnd )
				)
				( attribute "ROT" "0"
					( Origin gFrontEnd )
				)
				( attribute "SEC" "1"
					( Origin gFrontEnd )
				)
				( attribute "SEC_TYPE" "0402V"
					( Origin gFrontEnd )
				)
				( attribute "TOLERANCE" "10%"
					( Origin gFrontEnd )
				)
				( attribute "VALUE" "0.1UF"
					( Origin gFrontEnd )
				)
				( attribute "VER" "2"
					( Origin gFrontEnd )
				)
				( attribute "VOLTAGE" "16V"
					( Units "uVoltage" "V" 1.000000)
					( Origin gFrontEnd )
				)
				( attribute "XY" "(3075,2600)"
					( Origin gFrontEnd )
				)
				( attribute "CHIPS_PART_NAME" "CAP_A"
					( Origin gPackager )
				)
				( attribute "CDS_PART_NAME" "CAP_A_0402V-0.1UF,16V,10%,X7R,A"
					( Origin gPackager )
				)
				( objectStatus "C8C14" )
			)
			( gate "@baseboard_fab2_lib.baseboard_fab2(sch_1):page188_i88"
				( attribute "CDS_LIB" "mstr_discrete"
					( Origin gPackager )
				)
				( attribute "CDS_LOCATION" "R1R18"
					( Origin gPackager )
				)
				( attribute "CDS_SEC" "1"
					( Origin gPackager )
				)
				( attribute "LOCATION" "R1R18"
					( Origin gFrontEnd )
				)
				( attribute "MATERIAL" "CHIP"
					( Origin gFrontEnd )
				)
				( attribute "PACK_TYPE" "0402"
					( Origin gFrontEnd )
				)
				( attribute "PART_NUMBER" "G21796-112"
					( Origin gFrontEnd )
				)
				( attribute "PHYS_PAGE" "188"
					( Origin gFrontEnd )
				)
				( attribute "ROT" "0"
					( Origin gFrontEnd )
				)
				( attribute "SEC" "1"
					( Origin gFrontEnd )
				)
				( attribute "SEC_TYPE" "0402"
					( Origin gFrontEnd )
				)
				( attribute "TOLERANCE" "1%"
					( Origin gFrontEnd )
				)
				( attribute "VALUE" "2.21K"
					( Origin gFrontEnd )
				)
				( attribute "VER" "1"
					( Origin gFrontEnd )
				)
				( attribute "WATTAGE" "1/16W"
					( Origin gFrontEnd )
				)
				( attribute "XY" "(-3250,3950)"
					( Origin gFrontEnd )
				)
				( attribute "CHIPS_PART_NAME" "RES"
					( Origin gPackager )
				)
				( attribute "CDS_PART_NAME" "RES_0402-2.21K,1%,1/16W,CHIP,GA"
					( Origin gPackager )
				)
				( objectStatus "R1R18" )
			)
			( gate "@baseboard_fab2_lib.baseboard_fab2(sch_1):page188_i89"
				( attribute "CDS_LIB" "mstr_discrete"
					( Origin gPackager )
				)
				( attribute "CDS_LOCATION" "R1R19"
					( Origin gPackager )
				)
				( attribute "CDS_SEC" "1"
					( Origin gPackager )
				)
				( attribute "LOCATION" "R1R19"
					( Origin gFrontEnd )
				)
				( attribute "MATERIAL" "CHIP"
					( Origin gFrontEnd )
				)
				( attribute "PACK_TYPE" "0402"
					( Origin gFrontEnd )
				)
				( attribute "PART_NUMBER" "G21796-112"
					( Origin gFrontEnd )
				)
				( attribute "PHYS_PAGE" "188"
					( Origin gFrontEnd )
				)
				( attribute "ROT" "0"
					( Origin gFrontEnd )
				)
				( attribute "SEC" "1"
					( Origin gFrontEnd )
				)
				( attribute "SEC_TYPE" "0402"
					( Origin gFrontEnd )
				)
				( attribute "TOLERANCE" "1%"
					( Origin gFrontEnd )
				)
				( attribute "VALUE" "2.21K"
					( Origin gFrontEnd )
				)
				( attribute "VER" "1"
					( Origin gFrontEnd )
				)
				( attribute "WATTAGE" "1/16W"
					( Origin gFrontEnd )
				)
				( attribute "XY" "(-3250,3800)"
					( Origin gFrontEnd )
				)
				( attribute "CHIPS_PART_NAME" "RES"
					( Origin gPackager )
				)
				( attribute "CDS_PART_NAME" "RES_0402-2.21K,1%,1/16W,CHIP,GA"
					( Origin gPackager )
				)
				( objectStatus "R1R19" )
			)
			( gate "@baseboard_fab2_lib.baseboard_fab2(sch_1):page188_i90"
				( attribute "CDS_LIB" "mstr_discrete"
					( Origin gPackager )
				)
				( attribute "CDS_LOCATION" "R1R21"
					( Origin gPackager )
				)
				( attribute "CDS_SEC" "1"
					( Origin gPackager )
				)
				( attribute "LOCATION" "R1R21"
					( Origin gFrontEnd )
				)
				( attribute "MATERIAL" "CHIP"
					( Origin gFrontEnd )
				)
				( attribute "PACK_TYPE" "0402"
					( Origin gFrontEnd )
				)
				( attribute "PART_NUMBER" "G21796-112"
					( Origin gFrontEnd )
				)
				( attribute "PHYS_PAGE" "188"
					( Origin gFrontEnd )
				)
				( attribute "ROT" "0"
					( Origin gFrontEnd )
				)
				( attribute "SEC" "1"
					( Origin gFrontEnd )
				)
				( attribute "SEC_TYPE" "0402"
					( Origin gFrontEnd )
				)
				( attribute "TOLERANCE" "1%"
					( Origin gFrontEnd )
				)
				( attribute "VALUE" "2.21K"
					( Origin gFrontEnd )
				)
				( attribute "VER" "1"
					( Origin gFrontEnd )
				)
				( attribute "WATTAGE" "1/16W"
					( Origin gFrontEnd )
				)
				( attribute "XY" "(-3250,3500)"
					( Origin gFrontEnd )
				)
				( attribute "CHIPS_PART_NAME" "RES"
					( Origin gPackager )
				)
				( attribute "CDS_PART_NAME" "RES_0402-2.21K,1%,1/16W,CHIP,GA"
					( Origin gPackager )
				)
				( objectStatus "R1R21" )
			)
			( gate "@baseboard_fab2_lib.baseboard_fab2(sch_1):page188_i91"
				( attribute "CDS_LIB" "mstr_discrete"
					( Origin gPackager )
				)
				( attribute "CDS_LOCATION" "R1R20"
					( Origin gPackager )
				)
				( attribute "CDS_SEC" "1"
					( Origin gPackager )
				)
				( attribute "LOCATION" "R1R20"
					( Origin gFrontEnd )
				)
				( attribute "MATERIAL" "CHIP"
					( Origin gFrontEnd )
				)
				( attribute "PACK_TYPE" "0402"
					( Origin gFrontEnd )
				)
				( attribute "PART_NUMBER" "G21796-112"
					( Origin gFrontEnd )
				)
				( attribute "PHYS_PAGE" "188"
					( Origin gFrontEnd )
				)
				( attribute "ROT" "0"
					( Origin gFrontEnd )
				)
				( attribute "SEC" "1"
					( Origin gFrontEnd )
				)
				( attribute "SEC_TYPE" "0402"
					( Origin gFrontEnd )
				)
				( attribute "TOLERANCE" "1%"
					( Origin gFrontEnd )
				)
				( attribute "VALUE" "2.21K"
					( Origin gFrontEnd )
				)
				( attribute "VER" "1"
					( Origin gFrontEnd )
				)
				( attribute "WATTAGE" "1/16W"
					( Origin gFrontEnd )
				)
				( attribute "XY" "(-3250,3650)"
					( Origin gFrontEnd )
				)
				( attribute "CHIPS_PART_NAME" "RES"
					( Origin gPackager )
				)
				( attribute "CDS_PART_NAME" "RES_0402-2.21K,1%,1/16W,CHIP,GA"
					( Origin gPackager )
				)
				( objectStatus "R1R20" )
			)
			( gate "@baseboard_fab2_lib.baseboard_fab2(sch_1):page188_i92"
				( attribute "CDS_LIB" "mstr_discrete"
					( Origin gPackager )
				)
				( attribute "CDS_LOCATION" "R1R22"
					( Origin gPackager )
				)
				( attribute "CDS_SEC" "1"
					( Origin gPackager )
				)
				( attribute "LOCATION" "R1R22"
					( Origin gFrontEnd )
				)
				( attribute "MATERIAL" "CHIP"
					( Origin gFrontEnd )
				)
				( attribute "PACK_TYPE" "0402"
					( Origin gFrontEnd )
				)
				( attribute "PART_NUMBER" "G21796-112"
					( Origin gFrontEnd )
				)
				( attribute "PHYS_PAGE" "188"
					( Origin gFrontEnd )
				)
				( attribute "ROT" "0"
					( Origin gFrontEnd )
				)
				( attribute "SEC" "1"
					( Origin gFrontEnd )
				)
				( attribute "SEC_TYPE" "0402"
					( Origin gFrontEnd )
				)
				( attribute "TOLERANCE" "1%"
					( Origin gFrontEnd )
				)
				( attribute "VALUE" "2.21K"
					( Origin gFrontEnd )
				)
				( attribute "VER" "1"
					( Origin gFrontEnd )
				)
				( attribute "WATTAGE" "1/16W"
					( Origin gFrontEnd )
				)
				( attribute "XY" "(-3250,2900)"
					( Origin gFrontEnd )
				)
				( attribute "CHIPS_PART_NAME" "RES"
					( Origin gPackager )
				)
				( attribute "CDS_PART_NAME" "RES_0402-2.21K,1%,1/16W,CHIP,GA"
					( Origin gPackager )
				)
				( objectStatus "R1R22" )
			)
			( gate "@baseboard_fab2_lib.baseboard_fab2(sch_1):page188_i93"
				( attribute "CDS_LIB" "mstr_discrete"
					( Origin gPackager )
				)
				( attribute "CDS_LOCATION" "R1R16"
					( Origin gPackager )
				)
				( attribute "CDS_SEC" "1"
					( Origin gPackager )
				)
				( attribute "LOCATION" "R1R16"
					( Origin gFrontEnd )
				)
				( attribute "MATERIAL" "CHIP"
					( Origin gFrontEnd )
				)
				( attribute "PACK_TYPE" "0402"
					( Origin gFrontEnd )
				)
				( attribute "PART_NUMBER" "G21796-112"
					( Origin gFrontEnd )
				)
				( attribute "PHYS_PAGE" "188"
					( Origin gFrontEnd )
				)
				( attribute "ROT" "0"
					( Origin gFrontEnd )
				)
				( attribute "SEC" "1"
					( Origin gFrontEnd )
				)
				( attribute "SEC_TYPE" "0402"
					( Origin gFrontEnd )
				)
				( attribute "TOLERANCE" "1%"
					( Origin gFrontEnd )
				)
				( attribute "VALUE" "2.21K"
					( Origin gFrontEnd )
				)
				( attribute "VER" "1"
					( Origin gFrontEnd )
				)
				( attribute "WATTAGE" "1/16W"
					( Origin gFrontEnd )
				)
				( attribute "XY" "(-3250,3350)"
					( Origin gFrontEnd )
				)
				( attribute "CHIPS_PART_NAME" "RES"
					( Origin gPackager )
				)
				( attribute "CDS_PART_NAME" "RES_0402-2.21K,1%,1/16W,CHIP,GA"
					( Origin gPackager )
				)
				( objectStatus "R1R16" )
			)
			( gate "@baseboard_fab2_lib.baseboard_fab2(sch_1):page188_i94"
				( attribute "CDS_LIB" "mstr_discrete"
					( Origin gPackager )
				)
				( attribute "LOCATION" "R1R17"
					( Origin gFrontEnd )
				)
				( attribute "MATERIAL" "CHIP"
					( Origin gFrontEnd )
				)
				( attribute "PACK_TYPE" "0402"
					( Origin gFrontEnd )
				)
				( attribute "PART_NUMBER" "G21796-112"
					( Origin gFrontEnd )
				)
				( attribute "PHYS_PAGE" "188"
					( Origin gFrontEnd )
				)
				( attribute "ROT" "0"
					( Origin gFrontEnd )
				)
				( attribute "SEC" "1"
					( Origin gFrontEnd )
				)
				( attribute "SEC_TYPE" "0402"
					( Origin gFrontEnd )
				)
				( attribute "TOLERANCE" "1%"
					( Origin gFrontEnd )
				)
				( attribute "VALUE" "2.21K"
					( Origin gFrontEnd )
				)
				( attribute "VER" "1"
					( Origin gFrontEnd )
				)
				( attribute "WATTAGE" "1/16W"
					( Origin gFrontEnd )
				)
				( attribute "XY" "(-3250,3200)"
					( Origin gFrontEnd )
				)
				( attribute "CHIPS_PART_NAME" "RES"
					( Origin gPackager )
				)
				( attribute "CDS_PART_NAME" "RES_0402-2.21K,1%,1/16W,CHIP,GA"
					( Origin gPackager )
				)
				( attribute "CDS_LOCATION" "R1R17"
					( Origin gPackager )
				)
				( attribute "CDS_SEC" "1"
					( Origin gPackager )
				)
				( objectStatus "R1R17" )
			)
			( gate "@baseboard_fab2_lib.baseboard_fab2(sch_1):page188_i95"
				( attribute "CDS_LIB" "mstr_discrete"
					( Origin gPackager )
				)
				( attribute "CDS_LOCATION" "R1R23"
					( Origin gPackager )
				)
				( attribute "CDS_SEC" "1"
					( Origin gPackager )
				)
				( attribute "LOCATION" "R1R23"
					( Origin gFrontEnd )
				)
				( attribute "MATERIAL" "CHIP"
					( Origin gFrontEnd )
				)
				( attribute "PACK_TYPE" "0402"
					( Origin gFrontEnd )
				)
				( attribute "PART_NUMBER" "G21796-112"
					( Origin gFrontEnd )
				)
				( attribute "PHYS_PAGE" "188"
					( Origin gFrontEnd )
				)
				( attribute "ROT" "0"
					( Origin gFrontEnd )
				)
				( attribute "SEC" "1"
					( Origin gFrontEnd )
				)
				( attribute "SEC_TYPE" "0402"
					( Origin gFrontEnd )
				)
				( attribute "TOLERANCE" "1%"
					( Origin gFrontEnd )
				)
				( attribute "VALUE" "2.21K"
					( Origin gFrontEnd )
				)
				( attribute "VER" "1"
					( Origin gFrontEnd )
				)
				( attribute "WATTAGE" "1/16W"
					( Origin gFrontEnd )
				)
				( attribute "XY" "(-3250,3050)"
					( Origin gFrontEnd )
				)
				( attribute "CHIPS_PART_NAME" "RES"
					( Origin gPackager )
				)
				( attribute "CDS_PART_NAME" "RES_0402-2.21K,1%,1/16W,CHIP,GA"
					( Origin gPackager )
				)
				( objectStatus "R1R23" )
			)
			( gate "@baseboard_fab2_lib.baseboard_fab2(sch_1):page189_i7"
				( attribute "BOM_COST" "DEBUG"
					( Origin gFrontEnd )
				)
				( attribute "CDS_LIB" "mstr_discrete"
					( Origin gPackager )
				)
				( attribute "CDS_LOCATION" "R8G10"
					( Origin gPackager )
				)
				( attribute "CDS_SEC" "1"
					( Origin gPackager )
				)
				( attribute "LOCATION" "R8G10"
					( Origin gFrontEnd )
				)
				( attribute "MATERIAL" "CHIP"
					( Origin gFrontEnd )
				)
				( attribute "PACK_TYPE" "0402"
					( Origin gFrontEnd )
				)
				( attribute "PART_NUMBER" "G21497-005"
					( Origin gFrontEnd )
				)
				( attribute "PHYS_PAGE" "189"
					( Origin gFrontEnd )
				)
				( attribute "ROOM" "BMC_DEBUG_HEADER"
					( Origin gFrontEnd )
				)
				( attribute "ROT" "0"
					( Origin gFrontEnd )
				)
				( attribute "SEC" "1"
					( Origin gFrontEnd )
				)
				( attribute "SEC_TYPE" "0402"
					( Origin gFrontEnd )
				)
				( attribute "TOLERANCE" "5%"
					( Origin gFrontEnd )
				)
				( attribute "VALUE" "0.0"
					( Origin gFrontEnd )
				)
				( attribute "VER" "1"
					( Origin gFrontEnd )
				)
				( attribute "WATTAGE" "1/16W"
					( Origin gFrontEnd )
				)
				( attribute "XY" "(-2100,4775)"
					( Origin gFrontEnd )
				)
				( attribute "CHIPS_PART_NAME" "RES"
					( Origin gPackager )
				)
				( attribute "CDS_PART_NAME" "RES_0402-0.0,5%,1/16W,CHIP,G21A"
					( Origin gPackager )
				)
				( objectStatus "R8G10" )
			)
			( gate "@baseboard_fab2_lib.baseboard_fab2(sch_1):page189_i8"
				( attribute "BOM_COST" "DEBUG"
					( Origin gFrontEnd )
				)
				( attribute "CDS_LIB" "mstr_discrete"
					( Origin gPackager )
				)
				( attribute "CDS_LOCATION" "R7G19"
					( Origin gPackager )
				)
				( attribute "CDS_SEC" "1"
					( Origin gPackager )
				)
				( attribute "LOCATION" "R7G19"
					( Origin gFrontEnd )
				)
				( attribute "MATERIAL" "EMPTY"
					( Origin gFrontEnd )
				)
				( attribute "PACK_TYPE" "0402"
					( Origin gFrontEnd )
				)
				( attribute "PART_NUMBER" "G21497-005"
					( Origin gFrontEnd )
				)
				( attribute "PHYS_PAGE" "189"
					( Origin gFrontEnd )
				)
				( attribute "ROOM" "BMC_DEBUG_HEADER"
					( Origin gFrontEnd )
				)
				( attribute "ROT" "0"
					( Origin gFrontEnd )
				)
				( attribute "SEC" "1"
					( Origin gFrontEnd )
				)
				( attribute "SEC_TYPE" "0402"
					( Origin gFrontEnd )
				)
				( attribute "TOLERANCE" "5%"
					( Origin gFrontEnd )
				)
				( attribute "VALUE" "0.0"
					( Origin gFrontEnd )
				)
				( attribute "VER" "1"
					( Origin gFrontEnd )
				)
				( attribute "WATTAGE" "1/16W"
					( Origin gFrontEnd )
				)
				( attribute "XY" "(-2100,4400)"
					( Origin gFrontEnd )
				)
				( attribute "CHIPS_PART_NAME" "RES"
					( Origin gPackager )
				)
				( attribute "CDS_PART_NAME" "RES_0402-0.0,5%,1/16W,EMPTY,G2A"
					( Origin gPackager )
				)
				( objectStatus "R7G19" )
			)
			( gate "@baseboard_fab2_lib.baseboard_fab2(sch_1):page189_i9"
				( attribute "BOM_COST" "DEBUG"
					( Origin gFrontEnd )
				)
				( attribute "CDS_LIB" "mstr_discrete"
					( Origin gPackager )
				)
				( attribute "CDS_LOCATION" "R8G9"
					( Origin gPackager )
				)
				( attribute "CDS_SEC" "1"
					( Origin gPackager )
				)
				( attribute "LOCATION" "R8G9"
					( Origin gFrontEnd )
				)
				( attribute "MATERIAL" "EMPTY"
					( Origin gFrontEnd )
				)
				( attribute "PACK_TYPE" "0402"
					( Origin gFrontEnd )
				)
				( attribute "PART_NUMBER" "G21497-005"
					( Origin gFrontEnd )
				)
				( attribute "PHYS_PAGE" "189"
					( Origin gFrontEnd )
				)
				( attribute "ROOM" "BMC_DEBUG_HEADER"
					( Origin gFrontEnd )
				)
				( attribute "ROT" "0"
					( Origin gFrontEnd )
				)
				( attribute "SEC" "1"
					( Origin gPackager )
				)
				( attribute "TOLERANCE" "5%"
					( Origin gFrontEnd )
				)
				( attribute "VALUE" "0.0"
					( Origin gFrontEnd )
				)
				( attribute "VER" "1"
					( Origin gFrontEnd )
				)
				( attribute "WATTAGE" "1/16W"
					( Origin gFrontEnd )
				)
				( attribute "XY" "(-2100,4600)"
					( Origin gFrontEnd )
				)
				( attribute "CHIPS_PART_NAME" "RES"
					( Origin gPackager )
				)
				( attribute "CDS_PART_NAME" "RES_0402-0.0,5%,1/16W,EMPTY,G2A"
					( Origin gPackager )
				)
				( objectStatus "R8G9" )
			)
			( gate "@baseboard_fab2_lib.baseboard_fab2(sch_1):page189_i13"
				( attribute "BOM_COST" "DEBUG"
					( Origin gFrontEnd )
				)
				( attribute "CDS_LIB" "mstr_discrete"
					( Origin gPackager )
				)
				( attribute "CDS_LOCATION" "R7G18"
					( Origin gPackager )
				)
				( attribute "CDS_SEC" "1"
					( Origin gPackager )
				)
				( attribute "LOCATION" "R7G18"
					( Origin gFrontEnd )
				)
				( attribute "MATERIAL" "EMPTY"
					( Origin gFrontEnd )
				)
				( attribute "PACK_TYPE" "0402"
					( Origin gFrontEnd )
				)
				( attribute "PART_NUMBER" "G21497-005"
					( Origin gFrontEnd )
				)
				( attribute "PHYS_PAGE" "189"
					( Origin gFrontEnd )
				)
				( attribute "ROOM" "BMC_DEBUG_HEADER"
					( Origin gFrontEnd )
				)
				( attribute "ROT" "0"
					( Origin gFrontEnd )
				)
				( attribute "SEC" "1"
					( Origin gFrontEnd )
				)
				( attribute "SEC_TYPE" "0402"
					( Origin gFrontEnd )
				)
				( attribute "TOLERANCE" "5%"
					( Origin gFrontEnd )
				)
				( attribute "VALUE" "0.0"
					( Origin gFrontEnd )
				)
				( attribute "VER" "1"
					( Origin gFrontEnd )
				)
				( attribute "WATTAGE" "1/16W"
					( Origin gFrontEnd )
				)
				( attribute "XY" "(-2100,4225)"
					( Origin gFrontEnd )
				)
				( attribute "CHIPS_PART_NAME" "RES"
					( Origin gPackager )
				)
				( attribute "CDS_PART_NAME" "RES_0402-0.0,5%,1/16W,EMPTY,G2A"
					( Origin gPackager )
				)
				( objectStatus "R7G18" )
			)
			( gate "@baseboard_fab2_lib.baseboard_fab2(sch_1):page189_i17"
				( attribute "BOM_COST" "DEBUG"
					( Origin gFrontEnd )
				)
				( attribute "CDS_LIB" "mstr_discrete"
					( Origin gPackager )
				)
				( attribute "CDS_LOCATION" "R8G8"
					( Origin gPackager )
				)
				( attribute "CDS_SEC" "1"
					( Origin gPackager )
				)
				( attribute "LOCATION" "R8G8"
					( Origin gFrontEnd )
				)
				( attribute "MATERIAL" "CHIP"
					( Origin gFrontEnd )
				)
				( attribute "PACK_TYPE" "0402"
					( Origin gFrontEnd )
				)
				( attribute "PART_NUMBER" "G21497-005"
					( Origin gFrontEnd )
				)
				( attribute "PHYS_PAGE" "189"
					( Origin gFrontEnd )
				)
				( attribute "ROOM" "BMC_DEBUG_HEADER"
					( Origin gFrontEnd )
				)
				( attribute "ROT" "0"
					( Origin gFrontEnd )
				)
				( attribute "SEC" "1"
					( Origin gFrontEnd )
				)
				( attribute "SEC_TYPE" "0402"
					( Origin gFrontEnd )
				)
				( attribute "TOLERANCE" "5%"
					( Origin gFrontEnd )
				)
				( attribute "VALUE" "0.0"
					( Origin gFrontEnd )
				)
				( attribute "VER" "1"
					( Origin gFrontEnd )
				)
				( attribute "WATTAGE" "1/16W"
					( Origin gFrontEnd )
				)
				( attribute "XY" "(-2100,4050)"
					( Origin gFrontEnd )
				)
				( attribute "CHIPS_PART_NAME" "RES"
					( Origin gPackager )
				)
				( attribute "CDS_PART_NAME" "RES_0402-0.0,5%,1/16W,CHIP,G21A"
					( Origin gPackager )
				)
				( objectStatus "R8G8" )
			)
			( gate "@baseboard_fab2_lib.baseboard_fab2(sch_1):page189_i18"
				( attribute "BOM_COST" "DEBUG"
					( Origin gFrontEnd )
				)
				( attribute "CDS_LIB" "mstr_discrete"
					( Origin gPackager )
				)
				( attribute "CDS_LOCATION" "R8G7"
					( Origin gPackager )
				)
				( attribute "CDS_SEC" "1"
					( Origin gPackager )
				)
				( attribute "LOCATION" "R8G7"
					( Origin gFrontEnd )
				)
				( attribute "MATERIAL" "CHIP"
					( Origin gFrontEnd )
				)
				( attribute "PACK_TYPE" "0402"
					( Origin gFrontEnd )
				)
				( attribute "PART_NUMBER" "G21497-005"
					( Origin gFrontEnd )
				)
				( attribute "PHYS_PAGE" "189"
					( Origin gFrontEnd )
				)
				( attribute "ROOM" "BMC_DEBUG_HEADER"
					( Origin gFrontEnd )
				)
				( attribute "ROT" "0"
					( Origin gFrontEnd )
				)
				( attribute "SEC" "1"
					( Origin gFrontEnd )
				)
				( attribute "SEC_TYPE" "0402"
					( Origin gFrontEnd )
				)
				( attribute "TOLERANCE" "5%"
					( Origin gFrontEnd )
				)
				( attribute "VALUE" "0.0"
					( Origin gFrontEnd )
				)
				( attribute "VER" "1"
					( Origin gFrontEnd )
				)
				( attribute "WATTAGE" "1/16W"
					( Origin gFrontEnd )
				)
				( attribute "XY" "(-125,4650)"
					( Origin gFrontEnd )
				)
				( attribute "CHIPS_PART_NAME" "RES"
					( Origin gPackager )
				)
				( attribute "CDS_PART_NAME" "RES_0402-0.0,5%,1/16W,CHIP,G21A"
					( Origin gPackager )
				)
				( objectStatus "R8G7" )
			)
			( gate "@baseboard_fab2_lib.baseboard_fab2(sch_1):page189_i19"
				( attribute "BOM_COST" "DEBUG"
					( Origin gFrontEnd )
				)
				( attribute "CDS_LIB" "mstr_discrete"
					( Origin gPackager )
				)
				( attribute "CDS_LOCATION" "R8G11"
					( Origin gPackager )
				)
				( attribute "CDS_SEC" "1"
					( Origin gPackager )
				)
				( attribute "LOCATION" "R8G11"
					( Origin gFrontEnd )
				)
				( attribute "MATERIAL" "EMPTY"
					( Origin gFrontEnd )
				)
				( attribute "PACK_TYPE" "0402"
					( Origin gFrontEnd )
				)
				( attribute "PART_NUMBER" "G21497-005"
					( Origin gFrontEnd )
				)
				( attribute "PHYS_PAGE" "189"
					( Origin gFrontEnd )
				)
				( attribute "ROOM" "BMC_DEBUG_HEADER"
					( Origin gFrontEnd )
				)
				( attribute "ROT" "0"
					( Origin gFrontEnd )
				)
				( attribute "SEC" "1"
					( Origin gFrontEnd )
				)
				( attribute "SEC_TYPE" "0402"
					( Origin gFrontEnd )
				)
				( attribute "TOLERANCE" "5%"
					( Origin gFrontEnd )
				)
				( attribute "VALUE" "0.0"
					( Origin gFrontEnd )
				)
				( attribute "VER" "1"
					( Origin gFrontEnd )
				)
				( attribute "WATTAGE" "1/16W"
					( Origin gFrontEnd )
				)
				( attribute "XY" "(-2100,3500)"
					( Origin gFrontEnd )
				)
				( attribute "CHIPS_PART_NAME" "RES"
					( Origin gPackager )
				)
				( attribute "CDS_PART_NAME" "RES_0402-0.0,5%,1/16W,EMPTY,G2A"
					( Origin gPackager )
				)
				( objectStatus "R8G11" )
			)
			( gate "@baseboard_fab2_lib.baseboard_fab2(sch_1):page189_i20"
				( attribute "BOM_COST" "DEBUG"
					( Origin gFrontEnd )
				)
				( attribute "CDS_LIB" "mstr_discrete"
					( Origin gPackager )
				)
				( attribute "CDS_LOCATION" "R8G14"
					( Origin gPackager )
				)
				( attribute "CDS_SEC" "1"
					( Origin gPackager )
				)
				( attribute "LOCATION" "R8G14"
					( Origin gFrontEnd )
				)
				( attribute "MATERIAL" "CHIP"
					( Origin gFrontEnd )
				)
				( attribute "PACK_TYPE" "0402"
					( Origin gFrontEnd )
				)
				( attribute "PART_NUMBER" "G21497-005"
					( Origin gFrontEnd )
				)
				( attribute "PHYS_PAGE" "189"
					( Origin gFrontEnd )
				)
				( attribute "ROOM" "BMC_DEBUG_HEADER"
					( Origin gFrontEnd )
				)
				( attribute "ROT" "0"
					( Origin gFrontEnd )
				)
				( attribute "SEC" "1"
					( Origin gFrontEnd )
				)
				( attribute "SEC_TYPE" "0402"
					( Origin gFrontEnd )
				)
				( attribute "TOLERANCE" "5%"
					( Origin gFrontEnd )
				)
				( attribute "VALUE" "0.0"
					( Origin gFrontEnd )
				)
				( attribute "VER" "1"
					( Origin gFrontEnd )
				)
				( attribute "WATTAGE" "1/16W"
					( Origin gFrontEnd )
				)
				( attribute "XY" "(-2100,3350)"
					( Origin gFrontEnd )
				)
				( attribute "CHIPS_PART_NAME" "RES"
					( Origin gPackager )
				)
				( attribute "CDS_PART_NAME" "RES_0402-0.0,5%,1/16W,CHIP,G21A"
					( Origin gPackager )
				)
				( objectStatus "R8G14" )
			)
			( gate "@baseboard_fab2_lib.baseboard_fab2(sch_1):page189_i21"
				( attribute "BOM_COST" "DEBUG"
					( Origin gFrontEnd )
				)
				( attribute "CDS_LIB" "mstr_discrete"
					( Origin gPackager )
				)
				( attribute "CDS_LOCATION" "R8G12"
					( Origin gPackager )
				)
				( attribute "CDS_SEC" "1"
					( Origin gPackager )
				)
				( attribute "LOCATION" "R8G12"
					( Origin gFrontEnd )
				)
				( attribute "MATERIAL" "EMPTY"
					( Origin gFrontEnd )
				)
				( attribute "PACK_TYPE" "0402"
					( Origin gFrontEnd )
				)
				( attribute "PART_NUMBER" "G21497-005"
					( Origin gFrontEnd )
				)
				( attribute "PHYS_PAGE" "189"
					( Origin gFrontEnd )
				)
				( attribute "ROOM" "BMC_DEBUG_HEADER"
					( Origin gFrontEnd )
				)
				( attribute "ROT" "0"
					( Origin gFrontEnd )
				)
				( attribute "SEC" "1"
					( Origin gFrontEnd )
				)
				( attribute "SEC_TYPE" "0402"
					( Origin gFrontEnd )
				)
				( attribute "TOLERANCE" "5%"
					( Origin gFrontEnd )
				)
				( attribute "VALUE" "0.0"
					( Origin gFrontEnd )
				)
				( attribute "VER" "1"
					( Origin gFrontEnd )
				)
				( attribute "WATTAGE" "1/16W"
					( Origin gFrontEnd )
				)
				( attribute "XY" "(-2100,3675)"
					( Origin gFrontEnd )
				)
				( attribute "CHIPS_PART_NAME" "RES"
					( Origin gPackager )
				)
				( attribute "CDS_PART_NAME" "RES_0402-0.0,5%,1/16W,EMPTY,G2A"
					( Origin gPackager )
				)
				( objectStatus "R8G12" )
			)
			( gate "@baseboard_fab2_lib.baseboard_fab2(sch_1):page189_i22"
				( attribute "BOM_COST" "DEBUG"
					( Origin gFrontEnd )
				)
				( attribute "CDS_LIB" "mstr_discrete"
					( Origin gPackager )
				)
				( attribute "CDS_LOCATION" "R8G16"
					( Origin gPackager )
				)
				( attribute "CDS_SEC" "1"
					( Origin gPackager )
				)
				( attribute "LOCATION" "R8G16"
					( Origin gFrontEnd )
				)
				( attribute "MATERIAL" "EMPTY"
					( Origin gFrontEnd )
				)
				( attribute "PACK_TYPE" "0402"
					( Origin gFrontEnd )
				)
				( attribute "PART_NUMBER" "G21497-005"
					( Origin gFrontEnd )
				)
				( attribute "PHYS_PAGE" "189"
					( Origin gFrontEnd )
				)
				( attribute "ROOM" "BMC_DEBUG_HEADER"
					( Origin gFrontEnd )
				)
				( attribute "ROT" "0"
					( Origin gFrontEnd )
				)
				( attribute "SEC" "1"
					( Origin gFrontEnd )
				)
				( attribute "SEC_TYPE" "0402"
					( Origin gFrontEnd )
				)
				( attribute "TOLERANCE" "5%"
					( Origin gFrontEnd )
				)
				( attribute "VALUE" "0.0"
					( Origin gFrontEnd )
				)
				( attribute "VER" "1"
					( Origin gFrontEnd )
				)
				( attribute "WATTAGE" "1/16W"
					( Origin gFrontEnd )
				)
				( attribute "XY" "(-2100,2800)"
					( Origin gFrontEnd )
				)
				( attribute "CHIPS_PART_NAME" "RES"
					( Origin gPackager )
				)
				( attribute "CDS_PART_NAME" "RES_0402-0.0,5%,1/16W,EMPTY,G2A"
					( Origin gPackager )
				)
				( objectStatus "R8G16" )
			)
			( gate "@baseboard_fab2_lib.baseboard_fab2(sch_1):page189_i23"
				( attribute "BOM_COST" "DEBUG"
					( Origin gFrontEnd )
				)
				( attribute "CDS_LIB" "mstr_discrete"
					( Origin gPackager )
				)
				( attribute "CDS_LOCATION" "R8G13"
					( Origin gPackager )
				)
				( attribute "LOCATION" "R8G13"
					( Origin gFrontEnd )
				)
				( attribute "MATERIAL" "CHIP"
					( Origin gFrontEnd )
				)
				( attribute "PACK_TYPE" "0402"
					( Origin gFrontEnd )
				)
				( attribute "PART_NUMBER" "G21497-005"
					( Origin gFrontEnd )
				)
				( attribute "PHYS_PAGE" "189"
					( Origin gFrontEnd )
				)
				( attribute "ROOM" "BMC_DEBUG_HEADER"
					( Origin gFrontEnd )
				)
				( attribute "ROT" "0"
					( Origin gFrontEnd )
				)
				( attribute "SEC" "1"
					( Origin gFrontEnd )
				)
				( attribute "SEC_TYPE" "0402"
					( Origin gFrontEnd )
				)
				( attribute "TOLERANCE" "5%"
					( Origin gFrontEnd )
				)
				( attribute "VALUE" "0.0"
					( Origin gFrontEnd )
				)
				( attribute "VER" "1"
					( Origin gFrontEnd )
				)
				( attribute "WATTAGE" "1/16W"
					( Origin gFrontEnd )
				)
				( attribute "XY" "(-125,4450)"
					( Origin gFrontEnd )
				)
				( attribute "CHIPS_PART_NAME" "RES"
					( Origin gPackager )
				)
				( attribute "CDS_PART_NAME" "RES_0402-0.0,5%,1/16W,CHIP,G21A"
					( Origin gPackager )
				)
				( attribute "CDS_SEC" "1"
					( Origin gPackager )
				)
				( objectStatus "R8G13" )
			)
			( gate "@baseboard_fab2_lib.baseboard_fab2(sch_1):page189_i24"
				( attribute "BOM_COST" "DEBUG"
					( Origin gFrontEnd )
				)
				( attribute "CDS_LIB" "mstr_discrete"
					( Origin gPackager )
				)
				( attribute "CDS_LOCATION" "R8G15"
					( Origin gPackager )
				)
				( attribute "CDS_SEC" "1"
					( Origin gPackager )
				)
				( attribute "LOCATION" "R8G15"
					( Origin gFrontEnd )
				)
				( attribute "MATERIAL" "EMPTY"
					( Origin gFrontEnd )
				)
				( attribute "PACK_TYPE" "0402"
					( Origin gFrontEnd )
				)
				( attribute "PART_NUMBER" "G21497-005"
					( Origin gFrontEnd )
				)
				( attribute "PHYS_PAGE" "189"
					( Origin gFrontEnd )
				)
				( attribute "ROOM" "BMC_DEBUG_HEADER"
					( Origin gFrontEnd )
				)
				( attribute "ROT" "0"
					( Origin gFrontEnd )
				)
				( attribute "SEC" "1"
					( Origin gFrontEnd )
				)
				( attribute "SEC_TYPE" "0402"
					( Origin gFrontEnd )
				)
				( attribute "TOLERANCE" "5%"
					( Origin gFrontEnd )
				)
				( attribute "VALUE" "0.0"
					( Origin gFrontEnd )
				)
				( attribute "VER" "1"
					( Origin gFrontEnd )
				)
				( attribute "WATTAGE" "1/16W"
					( Origin gFrontEnd )
				)
				( attribute "XY" "(-2100,2975)"
					( Origin gFrontEnd )
				)
				( attribute "CHIPS_PART_NAME" "RES"
					( Origin gPackager )
				)
				( attribute "CDS_PART_NAME" "RES_0402-0.0,5%,1/16W,EMPTY,G2A"
					( Origin gPackager )
				)
				( objectStatus "R8G15" )
			)
			( gate "@baseboard_fab2_lib.baseboard_fab2(sch_1):page189_i25"
				( attribute "BOM_COST" "DEBUG"
					( Origin gFrontEnd )
				)
				( attribute "CDS_LIB" "mstr_discrete"
					( Origin gPackager )
				)
				( attribute "CDS_LOCATION" "R8G17"
					( Origin gPackager )
				)
				( attribute "CDS_SEC" "1"
					( Origin gPackager )
				)
				( attribute "LOCATION" "R8G17"
					( Origin gFrontEnd )
				)
				( attribute "MATERIAL" "CHIP"
					( Origin gFrontEnd )
				)
				( attribute "PACK_TYPE" "0402"
					( Origin gFrontEnd )
				)
				( attribute "PART_NUMBER" "G21497-005"
					( Origin gFrontEnd )
				)
				( attribute "PHYS_PAGE" "189"
					( Origin gFrontEnd )
				)
				( attribute "ROOM" "BMC_DEBUG_HEADER"
					( Origin gFrontEnd )
				)
				( attribute "ROT" "0"
					( Origin gFrontEnd )
				)
				( attribute "SEC" "1"
					( Origin gFrontEnd )
				)
				( attribute "SEC_TYPE" "0402"
					( Origin gFrontEnd )
				)
				( attribute "TOLERANCE" "5%"
					( Origin gFrontEnd )
				)
				( attribute "VALUE" "0.0"
					( Origin gFrontEnd )
				)
				( attribute "VER" "1"
					( Origin gFrontEnd )
				)
				( attribute "WATTAGE" "1/16W"
					( Origin gFrontEnd )
				)
				( attribute "XY" "(-2100,2625)"
					( Origin gFrontEnd )
				)
				( attribute "CHIPS_PART_NAME" "RES"
					( Origin gPackager )
				)
				( attribute "CDS_PART_NAME" "RES_0402-0.0,5%,1/16W,CHIP,G21A"
					( Origin gPackager )
				)
				( objectStatus "R8G17" )
			)
			( gate "@baseboard_fab2_lib.baseboard_fab2(sch_1):page189_i26"
				( attribute "BOM_COST" "DEBUG"
					( Origin gFrontEnd )
				)
				( attribute "CDS_LIB" "mstr_discrete"
					( Origin gPackager )
				)
				( attribute "CDS_LOCATION" "R8G18"
					( Origin gPackager )
				)
				( attribute "CDS_SEC" "1"
					( Origin gPackager )
				)
				( attribute "LOCATION" "R8G18"
					( Origin gFrontEnd )
				)
				( attribute "MATERIAL" "CHIP"
					( Origin gFrontEnd )
				)
				( attribute "PACK_TYPE" "0402"
					( Origin gFrontEnd )
				)
				( attribute "PART_NUMBER" "G21497-005"
					( Origin gFrontEnd )
				)
				( attribute "PHYS_PAGE" "189"
					( Origin gFrontEnd )
				)
				( attribute "ROOM" "BMC_DEBUG_HEADER"
					( Origin gFrontEnd )
				)
				( attribute "ROT" "0"
					( Origin gFrontEnd )
				)
				( attribute "SEC" "1"
					( Origin gFrontEnd )
				)
				( attribute "SEC_TYPE" "0402"
					( Origin gFrontEnd )
				)
				( attribute "TOLERANCE" "5%"
					( Origin gFrontEnd )
				)
				( attribute "VALUE" "0.0"
					( Origin gFrontEnd )
				)
				( attribute "VER" "1"
					( Origin gFrontEnd )
				)
				( attribute "WATTAGE" "1/16W"
					( Origin gFrontEnd )
				)
				( attribute "XY" "(-125,4250)"
					( Origin gFrontEnd )
				)
				( attribute "CHIPS_PART_NAME" "RES"
					( Origin gPackager )
				)
				( attribute "CDS_PART_NAME" "RES_0402-0.0,5%,1/16W,CHIP,G21A"
					( Origin gPackager )
				)
				( objectStatus "R8G18" )
			)
			( gate "@baseboard_fab2_lib.baseboard_fab2(sch_1):page189_i27"
				( attribute "BOM_COST" "DEBUG"
					( Origin gFrontEnd )
				)
				( attribute "CDS_LIB" "mstr_discrete"
					( Origin gPackager )
				)
				( attribute "CDS_LOCATION" "R7G16"
					( Origin gPackager )
				)
				( attribute "CDS_SEC" "1"
					( Origin gPackager )
				)
				( attribute "LOCATION" "R7G16"
					( Origin gFrontEnd )
				)
				( attribute "MATERIAL" "EMPTY"
					( Origin gFrontEnd )
				)
				( attribute "PACK_TYPE" "0402"
					( Origin gFrontEnd )
				)
				( attribute "PART_NUMBER" "G21497-005"
					( Origin gFrontEnd )
				)
				( attribute "PHYS_PAGE" "189"
					( Origin gFrontEnd )
				)
				( attribute "ROOM" "BMC_DEBUG_HEADER"
					( Origin gFrontEnd )
				)
				( attribute "ROT" "0"
					( Origin gFrontEnd )
				)
				( attribute "SEC" "1"
					( Origin gFrontEnd )
				)
				( attribute "SEC_TYPE" "0402"
					( Origin gFrontEnd )
				)
				( attribute "TOLERANCE" "5%"
					( Origin gFrontEnd )
				)
				( attribute "VALUE" "0.0"
					( Origin gFrontEnd )
				)
				( attribute "VER" "1"
					( Origin gFrontEnd )
				)
				( attribute "WATTAGE" "1/16W"
					( Origin gFrontEnd )
				)
				( attribute "XY" "(-2100,2250)"
					( Origin gFrontEnd )
				)
				( attribute "CHIPS_PART_NAME" "RES"
					( Origin gPackager )
				)
				( attribute "CDS_PART_NAME" "RES_0402-0.0,5%,1/16W,EMPTY,G2A"
					( Origin gPackager )
				)
				( objectStatus "R7G16" )
			)
			( gate "@baseboard_fab2_lib.baseboard_fab2(sch_1):page189_i36"
				( attribute "BOM_COST" "DEBUG"
					( Origin gFrontEnd )
				)
				( attribute "CDS_LIB" "mstr_discrete"
					( Origin gPackager )
				)
				( attribute "CDS_LOCATION" "R7G15"
					( Origin gPackager )
				)
				( attribute "CDS_SEC" "1"
					( Origin gPackager )
				)
				( attribute "LOCATION" "R7G15"
					( Origin gFrontEnd )
				)
				( attribute "MATERIAL" "EMPTY"
					( Origin gFrontEnd )
				)
				( attribute "PACK_TYPE" "0402"
					( Origin gFrontEnd )
				)
				( attribute "PART_NUMBER" "G21497-005"
					( Origin gFrontEnd )
				)
				( attribute "PHYS_PAGE" "189"
					( Origin gFrontEnd )
				)
				( attribute "ROOM" "BMC_DEBUG_HEADER"
					( Origin gFrontEnd )
				)
				( attribute "ROT" "0"
					( Origin gFrontEnd )
				)
				( attribute "SEC" "1"
					( Origin gFrontEnd )
				)
				( attribute "SEC_TYPE" "0402"
					( Origin gFrontEnd )
				)
				( attribute "TOLERANCE" "5%"
					( Origin gFrontEnd )
				)
				( attribute "VALUE" "0.0"
					( Origin gFrontEnd )
				)
				( attribute "VER" "1"
					( Origin gFrontEnd )
				)
				( attribute "WATTAGE" "1/16W"
					( Origin gFrontEnd )
				)
				( attribute "XY" "(-2100,2075)"
					( Origin gFrontEnd )
				)
				( attribute "CHIPS_PART_NAME" "RES"
					( Origin gPackager )
				)
				( attribute "CDS_PART_NAME" "RES_0402-0.0,5%,1/16W,EMPTY,G2A"
					( Origin gPackager )
				)
				( objectStatus "R7G15" )
			)
			( gate "@baseboard_fab2_lib.baseboard_fab2(sch_1):page189_i37"
				( attribute "BOM_COST" "DEBUG"
					( Origin gFrontEnd )
				)
				( attribute "CDS_LIB" "mstr_discrete"
					( Origin gPackager )
				)
				( attribute "CDS_LOCATION" "R7G17"
					( Origin gPackager )
				)
				( attribute "CDS_SEC" "1"
					( Origin gPackager )
				)
				( attribute "LOCATION" "R7G17"
					( Origin gFrontEnd )
				)
				( attribute "MATERIAL" "CHIP"
					( Origin gFrontEnd )
				)
				( attribute "PACK_TYPE" "0402"
					( Origin gFrontEnd )
				)
				( attribute "PART_NUMBER" "G21497-005"
					( Origin gFrontEnd )
				)
				( attribute "PHYS_PAGE" "189"
					( Origin gFrontEnd )
				)
				( attribute "ROOM" "BMC_DEBUG_HEADER"
					( Origin gFrontEnd )
				)
				( attribute "ROT" "0"
					( Origin gFrontEnd )
				)
				( attribute "SEC" "1"
					( Origin gFrontEnd )
				)
				( attribute "SEC_TYPE" "0402"
					( Origin gFrontEnd )
				)
				( attribute "TOLERANCE" "5%"
					( Origin gFrontEnd )
				)
				( attribute "VALUE" "0.0"
					( Origin gFrontEnd )
				)
				( attribute "VER" "1"
					( Origin gFrontEnd )
				)
				( attribute "WATTAGE" "1/16W"
					( Origin gFrontEnd )
				)
				( attribute "XY" "(-2100,1900)"
					( Origin gFrontEnd )
				)
				( attribute "CHIPS_PART_NAME" "RES"
					( Origin gPackager )
				)
				( attribute "CDS_PART_NAME" "RES_0402-0.0,5%,1/16W,CHIP,G21A"
					( Origin gPackager )
				)
				( objectStatus "R7G17" )
			)
			( gate "@baseboard_fab2_lib.baseboard_fab2(sch_1):page189_i38"
				( attribute "BOM_COST" "DEBUG"
					( Origin gFrontEnd )
				)
				( attribute "CDS_LIB" "mstr_discrete"
					( Origin gPackager )
				)
				( attribute "CDS_LOCATION" "R7G14"
					( Origin gPackager )
				)
				( attribute "CDS_SEC" "1"
					( Origin gPackager )
				)
				( attribute "LOCATION" "R7G14"
					( Origin gFrontEnd )
				)
				( attribute "MATERIAL" "CHIP"
					( Origin gFrontEnd )
				)
				( attribute "PACK_TYPE" "0402"
					( Origin gFrontEnd )
				)
				( attribute "PART_NUMBER" "G21497-005"
					( Origin gFrontEnd )
				)
				( attribute "PHYS_PAGE" "189"
					( Origin gFrontEnd )
				)
				( attribute "ROOM" "BMC_DEBUG_HEADER"
					( Origin gFrontEnd )
				)
				( attribute "ROT" "0"
					( Origin gFrontEnd )
				)
				( attribute "SEC" "1"
					( Origin gFrontEnd )
				)
				( attribute "SEC_TYPE" "0402"
					( Origin gFrontEnd )
				)
				( attribute "TOLERANCE" "5%"
					( Origin gFrontEnd )
				)
				( attribute "VALUE" "0.0"
					( Origin gFrontEnd )
				)
				( attribute "VER" "1"
					( Origin gFrontEnd )
				)
				( attribute "WATTAGE" "1/16W"
					( Origin gFrontEnd )
				)
				( attribute "XY" "(-125,4050)"
					( Origin gFrontEnd )
				)
				( attribute "CHIPS_PART_NAME" "RES"
					( Origin gPackager )
				)
				( attribute "CDS_PART_NAME" "RES_0402-0.0,5%,1/16W,CHIP,G21A"
					( Origin gPackager )
				)
				( objectStatus "R7G14" )
			)
			( gate "@baseboard_fab2_lib.baseboard_fab2(sch_1):page189_i44"
				( attribute "CDS_LIB" "mstr_discrete"
					( Origin gPackager )
				)
				( attribute "CDS_LOCATION" "R3R15"
					( Origin gPackager )
				)
				( attribute "LOCATION" "R3R15"
					( Origin gFrontEnd )
				)
				( attribute "MATERIAL" "CHIP"
					( Origin gFrontEnd )
				)
				( attribute "PACK_TYPE" "0402"
					( Origin gFrontEnd )
				)
				( attribute "PART_NUMBER" "G21796-026"
					( Origin gFrontEnd )
				)
				( attribute "PHYS_PAGE" "189"
					( Origin gFrontEnd )
				)
				( attribute "ROOM" "BMC_DEBUG_HEADER"
					( Origin gFrontEnd )
				)
				( attribute "ROT" "0"
					( Origin gFrontEnd )
				)
				( attribute "SEC" "1"
					( Origin gFrontEnd )
				)
				( attribute "SEC_TYPE" "0402"
					( Origin gFrontEnd )
				)
				( attribute "TOLERANCE" "1%"
					( Origin gFrontEnd )
				)
				( attribute "VALUE" "1.00K"
					( Origin gFrontEnd )
				)
				( attribute "VER" "2"
					( Origin gFrontEnd )
				)
				( attribute "WATTAGE" "1/16W"
					( Origin gFrontEnd )
				)
				( attribute "XY" "(175,2000)"
					( Origin gFrontEnd )
				)
				( attribute "CHIPS_PART_NAME" "RES"
					( Origin gPackager )
				)
				( attribute "CDS_PART_NAME" "RES_0402-1.00K,1%,1/16W,CHIP,GA"
					( Origin gPackager )
				)
				( attribute "CDS_SEC" "1"
					( Origin gPackager )
				)
				( objectStatus "R3R15" )
			)
			( gate "@baseboard_fab2_lib.baseboard_fab2(sch_1):page189_i45"
				( attribute "CDS_LIB" "mstr_discrete"
					( Origin gPackager )
				)
				( attribute "CDS_LOCATION" "R3R11"
					( Origin gPackager )
				)
				( attribute "CDS_SEC" "1"
					( Origin gPackager )
				)
				( attribute "LOCATION" "R3R11"
					( Origin gFrontEnd )
				)
				( attribute "MATERIAL" "EMPTY"
					( Origin gFrontEnd )
				)
				( attribute "PACK_TYPE" "0402"
					( Origin gFrontEnd )
				)
				( attribute "PART_NUMBER" "G21796-016"
					( Origin gFrontEnd )
				)
				( attribute "PHYS_PAGE" "189"
					( Origin gFrontEnd )
				)
				( attribute "ROOM" "BMC_DEBUG_HEADER"
					( Origin gFrontEnd )
				)
				( attribute "ROT" "0"
					( Origin gFrontEnd )
				)
				( attribute "SEC" "1"
					( Origin gFrontEnd )
				)
				( attribute "SEC_TYPE" "0402"
					( Origin gFrontEnd )
				)
				( attribute "TOLERANCE" "1%"
					( Origin gFrontEnd )
				)
				( attribute "VALUE" "10.0K"
					( Origin gFrontEnd )
				)
				( attribute "VER" "2"
					( Origin gFrontEnd )
				)
				( attribute "WATTAGE" "1/16W"
					( Origin gFrontEnd )
				)
				( attribute "XY" "(175,1600)"
					( Origin gFrontEnd )
				)
				( attribute "CHIPS_PART_NAME" "RES"
					( Origin gPackager )
				)
				( attribute "CDS_PART_NAME" "RES_0402-10.0K,1%,1/16W,EMPTY,A"
					( Origin gPackager )
				)
				( objectStatus "R3R11" )
			)
			( gate "@baseboard_fab2_lib.baseboard_fab2(sch_1):page189_i47"
				( attribute "BOM_COST" "DEBUG"
					( Origin gFrontEnd )
				)
				( attribute "CDS_LIB" "mstr_conn"
					( Origin gPackager )
				)
				( attribute "CDS_LOCATION" "J7G2"
					( Origin gPackager )
				)
				( attribute "CDS_SEC" "1"
					( Origin gPackager )
				)
				( attribute "LOCATION" "J7G2"
					( Origin gFrontEnd )
				)
				( attribute "MATERIAL" "CONN"
					( Origin gFrontEnd )
				)
				( attribute "PACK_TYPE" "PIP"
					( Origin gFrontEnd )
				)
				( attribute "PART_NUMBER" "C77962-004"
					( Origin gFrontEnd )
				)
				( attribute "PHYS_PAGE" "189"
					( Origin gFrontEnd )
				)
				( attribute "ROOM" "BMC_DEBUG_HEADER"
					( Origin gFrontEnd )
				)
				( attribute "ROT" "2"
					( Origin gFrontEnd )
				)
				( attribute "SEC" "1"
					( Origin gFrontEnd )
				)
				( attribute "SEC_TYPE" "PIP"
					( Origin gFrontEnd )
				)
				( attribute "VER" "1"
					( Origin gFrontEnd )
				)
				( attribute "XY" "(4000,3125)"
					( Origin gFrontEnd )
				)
				( attribute "CHIPS_PART_NAME" "CONN8_C77962004"
					( Origin gPackager )
				)
				( attribute "CDS_PART_NAME" "CONN8_C77962004_PIP-CONN,C7796A"
					( Origin gPackager )
				)
				( objectStatus "J7G2" )
			)
			( gate "@baseboard_fab2_lib.baseboard_fab2(sch_1):page189_i49"
				( attribute "BOM_COST" "DEBUG"
					( Origin gFrontEnd )
				)
				( attribute "CDS_LIB" "mstr_discrete"
					( Origin gPackager )
				)
				( attribute "CDS_LOCATION" "CR3U1"
					( Origin gPackager )
				)
				( attribute "CDS_SEC" "1"
					( Origin gPackager )
				)
				( attribute "LOCATION" "CR3U1"
					( Origin gFrontEnd )
				)
				( attribute "MATERIAL" "IC"
					( Origin gFrontEnd )
				)
				( attribute "PACK_TYPE" "SMLF"
					( Origin gFrontEnd )
				)
				( attribute "PART_NUMBER" "D55839-001"
					( Origin gFrontEnd )
				)
				( attribute "PHYS_PAGE" "189"
					( Origin gFrontEnd )
				)
				( attribute "ROOM" "BMC_DEBUG_HEADER"
					( Origin gFrontEnd )
				)
				( attribute "ROT" "0"
					( Origin gFrontEnd )
				)
				( attribute "SEC" "1"
					( Origin gFrontEnd )
				)
				( attribute "SEC_TYPE" "SMLF"
					( Origin gFrontEnd )
				)
				( attribute "VALUE" "1N5819HW"
					( Origin gFrontEnd )
				)
				( attribute "VER" "1"
					( Origin gFrontEnd )
				)
				( attribute "XY" "(3500,3525)"
					( Origin gFrontEnd )
				)
				( attribute "CHIPS_PART_NAME" "DIODE"
					( Origin gPackager )
				)
				( attribute "CDS_PART_NAME" "DIODE_SMLF-1N5819HW,IC,D55839-A"
					( Origin gPackager )
				)
				( objectStatus "CR3U1" )
			)
			( gate "@baseboard_fab2_lib.baseboard_fab2(sch_1):page189_i50"
				( attribute "CDS_LIB" "mstr_discrete"
					( Origin gPackager )
				)
				( attribute "CDS_LOCATION" "R8G20"
					( Origin gPackager )
				)
				( attribute "CDS_SEC" "1"
					( Origin gPackager )
				)
				( attribute "LOCATION" "R8G20"
					( Origin gFrontEnd )
				)
				( attribute "MATERIAL" "CHIP"
					( Origin gFrontEnd )
				)
				( attribute "PACK_TYPE" "0402"
					( Origin gFrontEnd )
				)
				( attribute "PART_NUMBER" "G21796-016"
					( Origin gFrontEnd )
				)
				( attribute "PHYS_PAGE" "189"
					( Origin gFrontEnd )
				)
				( attribute "ROOM" "BMC_DEBUG_HEADER"
					( Origin gFrontEnd )
				)
				( attribute "ROT" "0"
					( Origin gFrontEnd )
				)
				( attribute "SEC" "1"
					( Origin gPackager )
				)
				( attribute "TOLERANCE" "1%"
					( Origin gFrontEnd )
				)
				( attribute "VALUE" "10.0K"
					( Origin gFrontEnd )
				)
				( attribute "VER" "2"
					( Origin gFrontEnd )
				)
				( attribute "WATTAGE" "1/16W"
					( Origin gFrontEnd )
				)
				( attribute "XY" "(3200,3500)"
					( Origin gFrontEnd )
				)
				( attribute "CHIPS_PART_NAME" "RES"
					( Origin gPackager )
				)
				( attribute "CDS_PART_NAME" "RES_0402-10.0K,1%,1/16W,CHIP,GA"
					( Origin gPackager )
				)
				( objectStatus "R8G20" )
			)
			( gate "@baseboard_fab2_lib.baseboard_fab2(sch_1):page189_i51"
				( attribute "CDS_LIB" "mstr_discrete"
					( Origin gPackager )
				)
				( attribute "CDS_LOCATION" "R7G23"
					( Origin gPackager )
				)
				( attribute "CDS_SEC" "1"
					( Origin gPackager )
				)
				( attribute "LOCATION" "R7G23"
					( Origin gFrontEnd )
				)
				( attribute "MATERIAL" "CHIP"
					( Origin gFrontEnd )
				)
				( attribute "PACK_TYPE" "0402"
					( Origin gFrontEnd )
				)
				( attribute "PART_NUMBER" "G21796-016"
					( Origin gFrontEnd )
				)
				( attribute "PHYS_PAGE" "189"
					( Origin gFrontEnd )
				)
				( attribute "ROOM" "BMC_DEBUG_HEADER"
					( Origin gFrontEnd )
				)
				( attribute "ROT" "0"
					( Origin gFrontEnd )
				)
				( attribute "SEC" "1"
					( Origin gPackager )
				)
				( attribute "TOLERANCE" "1%"
					( Origin gFrontEnd )
				)
				( attribute "VALUE" "10.0K"
					( Origin gFrontEnd )
				)
				( attribute "VER" "2"
					( Origin gFrontEnd )
				)
				( attribute "WATTAGE" "1/16W"
					( Origin gFrontEnd )
				)
				( attribute "XY" "(2900,3500)"
					( Origin gFrontEnd )
				)
				( attribute "CHIPS_PART_NAME" "RES"
					( Origin gPackager )
				)
				( attribute "CDS_PART_NAME" "RES_0402-10.0K,1%,1/16W,CHIP,GA"
					( Origin gPackager )
				)
				( objectStatus "R7G23" )
			)
			( gate "@baseboard_fab2_lib.baseboard_fab2(sch_1):page189_i53"
				( attribute "CDS_LIB" "mstr_discrete"
					( Origin gPackager )
				)
				( attribute "CDS_LOCATION" "R7G22"
					( Origin gPackager )
				)
				( attribute "CDS_SEC" "1"
					( Origin gPackager )
				)
				( attribute "LOCATION" "R7G22"
					( Origin gFrontEnd )
				)
				( attribute "MATERIAL" "CHIP"
					( Origin gFrontEnd )
				)
				( attribute "PACK_TYPE" "0402"
					( Origin gFrontEnd )
				)
				( attribute "PART_NUMBER" "G21796-016"
					( Origin gFrontEnd )
				)
				( attribute "PHYS_PAGE" "189"
					( Origin gFrontEnd )
				)
				( attribute "ROOM" "BMC_DEBUG_HEADER"
					( Origin gFrontEnd )
				)
				( attribute "ROT" "0"
					( Origin gFrontEnd )
				)
				( attribute "SEC" "1"
					( Origin gPackager )
				)
				( attribute "TOLERANCE" "1%"
					( Origin gFrontEnd )
				)
				( attribute "VALUE" "10.0K"
					( Origin gFrontEnd )
				)
				( attribute "VER" "2"
					( Origin gFrontEnd )
				)
				( attribute "WATTAGE" "1/16W"
					( Origin gFrontEnd )
				)
				( attribute "XY" "(2600,3500)"
					( Origin gFrontEnd )
				)
				( attribute "CHIPS_PART_NAME" "RES"
					( Origin gPackager )
				)
				( attribute "CDS_PART_NAME" "RES_0402-10.0K,1%,1/16W,CHIP,GA"
					( Origin gPackager )
				)
				( objectStatus "R7G22" )
			)
			( gate "@baseboard_fab2_lib.baseboard_fab2(sch_1):page189_i56"
				( attribute "CDS_LIB" "mstr_discrete"
					( Origin gPackager )
				)
				( attribute "CDS_LOCATION" "R8G23"
					( Origin gPackager )
				)
				( attribute "CDS_SEC" "1"
					( Origin gPackager )
				)
				( attribute "LOCATION" "R8G23"
					( Origin gFrontEnd )
				)
				( attribute "MATERIAL" "CHIP"
					( Origin gFrontEnd )
				)
				( attribute "PACK_TYPE" "0402"
					( Origin gFrontEnd )
				)
				( attribute "PART_NUMBER" "G21796-072"
					( Origin gFrontEnd )
				)
				( attribute "PHYS_PAGE" "189"
					( Origin gFrontEnd )
				)
				( attribute "ROOM" "BMC_DEBUG_HEADER"
					( Origin gFrontEnd )
				)
				( attribute "ROT" "0"
					( Origin gFrontEnd )
				)
				( attribute "SEC" "1"
					( Origin gFrontEnd )
				)
				( attribute "SEC_TYPE" "0402"
					( Origin gFrontEnd )
				)
				( attribute "TOLERANCE" "1%"
					( Origin gFrontEnd )
				)
				( attribute "VALUE" "4.75K"
					( Origin gFrontEnd )
				)
				( attribute "VER" "2"
					( Origin gFrontEnd )
				)
				( attribute "WATTAGE" "1/16W"
					( Origin gFrontEnd )
				)
				( attribute "XY" "(3200,2700)"
					( Origin gFrontEnd )
				)
				( attribute "CHIPS_PART_NAME" "RES"
					( Origin gPackager )
				)
				( attribute "CDS_PART_NAME" "RES_0402-4.75K,1%,1/16W,CHIP,GA"
					( Origin gPackager )
				)
				( objectStatus "R8G23" )
			)
			( gate "@baseboard_fab2_lib.baseboard_fab2(sch_1):page189_i63"
				( attribute "BOM_COST" "DEBUG"
					( Origin gFrontEnd )
				)
				( attribute "CDS_LIB" "mstr_discrete"
					( Origin gPackager )
				)
				( attribute "CDS_LOCATION" "R7G21"
					( Origin gPackager )
				)
				( attribute "CDS_SEC" "1"
					( Origin gPackager )
				)
				( attribute "LOCATION" "R7G21"
					( Origin gFrontEnd )
				)
				( attribute "MATERIAL" "CHIP"
					( Origin gFrontEnd )
				)
				( attribute "PACK_TYPE" "0402"
					( Origin gFrontEnd )
				)
				( attribute "PART_NUMBER" "G21497-005"
					( Origin gFrontEnd )
				)
				( attribute "PHYS_PAGE" "189"
					( Origin gFrontEnd )
				)
				( attribute "ROOM" "BMC_DEBUG_HEADER"
					( Origin gFrontEnd )
				)
				( attribute "ROT" "0"
					( Origin gFrontEnd )
				)
				( attribute "SEC" "1"
					( Origin gFrontEnd )
				)
				( attribute "SEC_TYPE" "0402"
					( Origin gFrontEnd )
				)
				( attribute "TOLERANCE" "5%"
					( Origin gFrontEnd )
				)
				( attribute "VALUE" "0.0"
					( Origin gFrontEnd )
				)
				( attribute "VER" "1"
					( Origin gFrontEnd )
				)
				( attribute "WATTAGE" "1/16W"
					( Origin gFrontEnd )
				)
				( attribute "XY" "(2050,3225)"
					( Origin gFrontEnd )
				)
				( attribute "CHIPS_PART_NAME" "RES"
					( Origin gPackager )
				)
				( attribute "CDS_PART_NAME" "RES_0402-0.0,5%,1/16W,CHIP,G21A"
					( Origin gPackager )
				)
				( objectStatus "R7G21" )
			)
			( gate "@baseboard_fab2_lib.baseboard_fab2(sch_1):page189_i64"
				( attribute "BOM_COST" "DEBUG"
					( Origin gFrontEnd )
				)
				( attribute "CDS_LIB" "mstr_discrete"
					( Origin gPackager )
				)
				( attribute "CDS_LOCATION" "R8G19"
					( Origin gPackager )
				)
				( attribute "CDS_SEC" "1"
					( Origin gPackager )
				)
				( attribute "LOCATION" "R8G19"
					( Origin gFrontEnd )
				)
				( attribute "MATERIAL" "CHIP"
					( Origin gFrontEnd )
				)
				( attribute "PACK_TYPE" "0402"
					( Origin gFrontEnd )
				)
				( attribute "PART_NUMBER" "G21497-005"
					( Origin gFrontEnd )
				)
				( attribute "PHYS_PAGE" "189"
					( Origin gFrontEnd )
				)
				( attribute "ROOM" "BMC_DEBUG_HEADER"
					( Origin gFrontEnd )
				)
				( attribute "ROT" "0"
					( Origin gFrontEnd )
				)
				( attribute "SEC" "1"
					( Origin gFrontEnd )
				)
				( attribute "SEC_TYPE" "0402"
					( Origin gFrontEnd )
				)
				( attribute "TOLERANCE" "5%"
					( Origin gFrontEnd )
				)
				( attribute "VALUE" "0.0"
					( Origin gFrontEnd )
				)
				( attribute "VER" "1"
					( Origin gFrontEnd )
				)
				( attribute "WATTAGE" "1/16W"
					( Origin gFrontEnd )
				)
				( attribute "XY" "(2425,3175)"
					( Origin gFrontEnd )
				)
				( attribute "CHIPS_PART_NAME" "RES"
					( Origin gPackager )
				)
				( attribute "CDS_PART_NAME" "RES_0402-0.0,5%,1/16W,CHIP,G21A"
					( Origin gPackager )
				)
				( objectStatus "R8G19" )
			)
			( gate "@baseboard_fab2_lib.baseboard_fab2(sch_1):page189_i65"
				( attribute "BOM_COST" "DEBUG"
					( Origin gFrontEnd )
				)
				( attribute "CDS_LIB" "mstr_discrete"
					( Origin gPackager )
				)
				( attribute "CDS_LOCATION" "R8G21"
					( Origin gPackager )
				)
				( attribute "CDS_SEC" "1"
					( Origin gPackager )
				)
				( attribute "LOCATION" "R8G21"
					( Origin gFrontEnd )
				)
				( attribute "MATERIAL" "CHIP"
					( Origin gFrontEnd )
				)
				( attribute "PACK_TYPE" "0402"
					( Origin gFrontEnd )
				)
				( attribute "PART_NUMBER" "G21497-005"
					( Origin gFrontEnd )
				)
				( attribute "PHYS_PAGE" "189"
					( Origin gFrontEnd )
				)
				( attribute "ROOM" "BMC_DEBUG_HEADER"
					( Origin gFrontEnd )
				)
				( attribute "ROT" "0"
					( Origin gFrontEnd )
				)
				( attribute "SEC" "1"
					( Origin gFrontEnd )
				)
				( attribute "SEC_TYPE" "0402"
					( Origin gFrontEnd )
				)
				( attribute "TOLERANCE" "5%"
					( Origin gFrontEnd )
				)
				( attribute "VALUE" "0.0"
					( Origin gFrontEnd )
				)
				( attribute "VER" "1"
					( Origin gFrontEnd )
				)
				( attribute "WATTAGE" "1/16W"
					( Origin gFrontEnd )
				)
				( attribute "XY" "(2525,3025)"
					( Origin gFrontEnd )
				)
				( attribute "CHIPS_PART_NAME" "RES"
					( Origin gPackager )
				)
				( attribute "CDS_PART_NAME" "RES_0402-0.0,5%,1/16W,CHIP,G21A"
					( Origin gPackager )
				)
				( objectStatus "R8G21" )
			)
			( gate "@baseboard_fab2_lib.baseboard_fab2(sch_1):page189_i66"
				( attribute "BOM_COST" "DEBUG"
					( Origin gFrontEnd )
				)
				( attribute "CDS_LIB" "mstr_discrete"
					( Origin gPackager )
				)
				( attribute "CDS_LOCATION" "R8G22"
					( Origin gPackager )
				)
				( attribute "CDS_SEC" "1"
					( Origin gPackager )
				)
				( attribute "LOCATION" "R8G22"
					( Origin gFrontEnd )
				)
				( attribute "MATERIAL" "CHIP"
					( Origin gFrontEnd )
				)
				( attribute "PACK_TYPE" "0402"
					( Origin gFrontEnd )
				)
				( attribute "PART_NUMBER" "G21497-005"
					( Origin gFrontEnd )
				)
				( attribute "PHYS_PAGE" "189"
					( Origin gFrontEnd )
				)
				( attribute "ROOM" "BMC_DEBUG_HEADER"
					( Origin gFrontEnd )
				)
				( attribute "ROT" "0"
					( Origin gFrontEnd )
				)
				( attribute "SEC" "1"
					( Origin gFrontEnd )
				)
				( attribute "SEC_TYPE" "0402"
					( Origin gFrontEnd )
				)
				( attribute "TOLERANCE" "5%"
					( Origin gFrontEnd )
				)
				( attribute "VALUE" "0.0"
					( Origin gFrontEnd )
				)
				( attribute "VER" "1"
					( Origin gFrontEnd )
				)
				( attribute "WATTAGE" "1/16W"
					( Origin gFrontEnd )
				)
				( attribute "XY" "(2850,2925)"
					( Origin gFrontEnd )
				)
				( attribute "CHIPS_PART_NAME" "RES"
					( Origin gPackager )
				)
				( attribute "CDS_PART_NAME" "RES_0402-0.0,5%,1/16W,CHIP,G21A"
					( Origin gPackager )
				)
				( objectStatus "R8G22" )
			)
			( gate "@baseboard_fab2_lib.baseboard_fab2(sch_1):page190_i116"
				( attribute "BOM_COST" "CPLD"
					( Origin gFrontEnd )
				)
				( attribute "CDS_LIB" "mstr_discrete"
					( Origin gPackager )
				)
				( attribute "CDS_LOCATION" "R3P34"
					( Origin gPackager )
				)
				( attribute "CDS_SEC" "1"
					( Origin gPackager )
				)
				( attribute "LOCATION" "R3P34"
					( Origin gFrontEnd )
				)
				( attribute "MATERIAL" "CHIP"
					( Origin gFrontEnd )
				)
				( attribute "PACK_TYPE" "0402"
					( Origin gFrontEnd )
				)
				( attribute "PART_NUMBER" "G21497-005"
					( Origin gFrontEnd )
				)
				( attribute "PHYS_PAGE" "190"
					( Origin gFrontEnd )
				)
				( attribute "ROOM" "CPLD"
					( Origin gFrontEnd )
				)
				( attribute "ROT" "0"
					( Origin gFrontEnd )
				)
				( attribute "SEC" "1"
					( Origin gFrontEnd )
				)
				( attribute "SEC_TYPE" "0402"
					( Origin gFrontEnd )
				)
				( attribute "TOLERANCE" "5%"
					( Origin gFrontEnd )
				)
				( attribute "VALUE" "0.0"
					( Origin gFrontEnd )
				)
				( attribute "VER" "1"
					( Origin gFrontEnd )
				)
				( attribute "WATTAGE" "1/16W"
					( Origin gFrontEnd )
				)
				( attribute "XY" "(-4150,5200)"
					( Origin gFrontEnd )
				)
				( attribute "CHIPS_PART_NAME" "RES"
					( Origin gPackager )
				)
				( attribute "CDS_PART_NAME" "RES_0402-0.0,5%,1/16W,CHIP,G21A"
					( Origin gPackager )
				)
				( objectStatus "R3P34" )
			)
			( gate "@baseboard_fab2_lib.baseboard_fab2(sch_1):page190_i117"
				( attribute "BOM_COST" "CPLD"
					( Origin gFrontEnd )
				)
				( attribute "CDS_LIB" "mstr_discrete"
					( Origin gPackager )
				)
				( attribute "CDS_LOCATION" "R3P35"
					( Origin gPackager )
				)
				( attribute "CDS_SEC" "1"
					( Origin gPackager )
				)
				( attribute "LOCATION" "R3P35"
					( Origin gFrontEnd )
				)
				( attribute "MATERIAL" "CHIP"
					( Origin gFrontEnd )
				)
				( attribute "PACK_TYPE" "0402"
					( Origin gFrontEnd )
				)
				( attribute "PART_NUMBER" "G21497-005"
					( Origin gFrontEnd )
				)
				( attribute "PHYS_PAGE" "190"
					( Origin gFrontEnd )
				)
				( attribute "ROOM" "CPLD"
					( Origin gFrontEnd )
				)
				( attribute "ROT" "0"
					( Origin gFrontEnd )
				)
				( attribute "SEC" "1"
					( Origin gFrontEnd )
				)
				( attribute "SEC_TYPE" "0402"
					( Origin gFrontEnd )
				)
				( attribute "TOLERANCE" "5%"
					( Origin gFrontEnd )
				)
				( attribute "VALUE" "0.0"
					( Origin gFrontEnd )
				)
				( attribute "VER" "1"
					( Origin gFrontEnd )
				)
				( attribute "WATTAGE" "1/16W"
					( Origin gFrontEnd )
				)
				( attribute "XY" "(-4150,5000)"
					( Origin gFrontEnd )
				)
				( attribute "CHIPS_PART_NAME" "RES"
					( Origin gPackager )
				)
				( attribute "CDS_PART_NAME" "RES_0402-0.0,5%,1/16W,CHIP,G21A"
					( Origin gPackager )
				)
				( objectStatus "R3P35" )
			)
			( gate "@baseboard_fab2_lib.baseboard_fab2(sch_1):page190_i179"
				( attribute "BOM_COST" "CPLD"
					( Origin gFrontEnd )
				)
				( attribute "CDS_LIB" "mstr_memory"
					( Origin gPackager )
				)
				( attribute "CDS_LMAN_SYM_OUTLINE" "-550,1750,550,-1750"
					( Origin gPackager )
				)
				( attribute "CDS_LOCATION" "U8D7"
					( Origin gPackager )
				)
				( attribute "LOCATION" "U8D7"
					( Origin gFrontEnd )
				)
				( attribute "MATERIAL" "IC"
					( Origin gFrontEnd )
				)
				( attribute "PACK_TYPE" "256BGA"
					( Origin gFrontEnd )
				)
				( attribute "PART_NUMBER" "H63395-001"
					( Origin gFrontEnd )
				)
				( attribute "PHYS_PAGE" "190"
					( Origin gFrontEnd )
				)
				( attribute "ROOM" "CPLD"
					( Origin gFrontEnd )
				)
				( attribute "ROT" "0"
					( Origin gFrontEnd )
				)
				( attribute "SEC" "1"
					( Origin gFrontEnd )
				)
				( attribute "SEC_TYPE" "256BGA"
					( Origin gFrontEnd )
				)
				( attribute "VER" "4"
					( Origin gFrontEnd )
				)
				( attribute "XY" "(-1950,2950)"
					( Origin gFrontEnd )
				)
				( attribute "CHIPS_PART_NAME" "LCMXO2_A"
					( Origin gPackager )
				)
				( attribute "CDS_PART_NAME" "LCMXO2_A_256BGA-IC,H63395-001"
					( Origin gPackager )
				)
				( attribute "CDS_SEC" "1"
					( Origin gPackager )
				)
				( objectStatus "U8D7" )
			)
			( gate "@baseboard_fab2_lib.baseboard_fab2(sch_1):page190_i338"
				( attribute "BOM_COST" "CPLD"
					( Origin gFrontEnd )
				)
				( attribute "CDS_LIB" "mstr_discrete"
					( Origin gPackager )
				)
				( attribute "CDS_LOCATION" "R2R2"
					( Origin gPackager )
				)
				( attribute "CDS_SEC" "1"
					( Origin gPackager )
				)
				( attribute "LOCATION" "R2R2"
					( Origin gFrontEnd )
				)
				( attribute "MATERIAL" "CHIP"
					( Origin gFrontEnd )
				)
				( attribute "PACK_TYPE" "0402"
					( Origin gFrontEnd )
				)
				( attribute "PART_NUMBER" "G21796-074"
					( Origin gFrontEnd )
				)
				( attribute "PHYS_PAGE" "190"
					( Origin gFrontEnd )
				)
				( attribute "ROOM" "CPLD"
					( Origin gFrontEnd )
				)
				( attribute "ROT" "0"
					( Origin gFrontEnd )
				)
				( attribute "SEC" "1"
					( Origin gPackager )
				)
				( attribute "TOLERANCE" "1%"
					( Origin gFrontEnd )
				)
				( attribute "VALUE" "33.2"
					( Origin gFrontEnd )
				)
				( attribute "VER" "1"
					( Origin gFrontEnd )
				)
				( attribute "WATTAGE" "1/16W"
					( Origin gFrontEnd )
				)
				( attribute "XY" "(-1350,5200)"
					( Origin gFrontEnd )
				)
				( attribute "CHIPS_PART_NAME" "RES"
					( Origin gPackager )
				)
				( attribute "CDS_PART_NAME" "RES_0402-33.2,1%,1/16W,CHIP,G2A"
					( Origin gPackager )
				)
				( objectStatus "R2R2" )
			)
			( gate "@baseboard_fab2_lib.baseboard_fab2(sch_1):page191_i59"
				( attribute "BOM_COST" "CPLD"
					( Origin gFrontEnd )
				)
				( attribute "CDS_LIB" "mstr_memory"
					( Origin gPackager )
				)
				( attribute "CDS_LMAN_SYM_OUTLINE" "-550,1700,550,-1700"
					( Origin gPackager )
				)
				( attribute "CDS_LOCATION" "U8D7"
					( Origin gPackager )
				)
				( attribute "LOCATION" "U8D7"
					( Origin gFrontEnd )
				)
				( attribute "MATERIAL" "IC"
					( Origin gFrontEnd )
				)
				( attribute "PACK_TYPE" "256BGA"
					( Origin gFrontEnd )
				)
				( attribute "PART_NUMBER" "H63395-001"
					( Origin gFrontEnd )
				)
				( attribute "PHYS_PAGE" "191"
					( Origin gFrontEnd )
				)
				( attribute "ROOM" "CPLD"
					( Origin gFrontEnd )
				)
				( attribute "ROT" "0"
					( Origin gFrontEnd )
				)
				( attribute "SEC" "2"
					( Origin gFrontEnd )
				)
				( attribute "SEC_TYPE" "256BGA"
					( Origin gFrontEnd )
				)
				( attribute "VER" "5"
					( Origin gFrontEnd )
				)
				( attribute "XY" "(-4475,2725)"
					( Origin gFrontEnd )
				)
				( attribute "CHIPS_PART_NAME" "LCMXO2_A"
					( Origin gPackager )
				)
				( attribute "CDS_PART_NAME" "LCMXO2_A_256BGA-IC,H63395-001"
					( Origin gPackager )
				)
				( attribute "CDS_SEC" "2"
					( Origin gPackager )
				)
				( objectStatus "U8D7" )
			)
			( gate "@baseboard_fab2_lib.baseboard_fab2(sch_1):page191_i166"
				( attribute "CDS_LIB" "mstr_discrete"
					( Origin gPackager )
				)
				( attribute "CDS_LOCATION" "R2R6"
					( Origin gPackager )
				)
				( attribute "LOCATION" "R2R6"
					( Origin gFrontEnd )
				)
				( attribute "MATERIAL" "CHIP"
					( Origin gFrontEnd )
				)
				( attribute "PACK_TYPE" "0402"
					( Origin gFrontEnd )
				)
				( attribute "PART_NUMBER" "G21497-048"
					( Origin gFrontEnd )
				)
				( attribute "PHYS_PAGE" "191"
					( Origin gFrontEnd )
				)
				( attribute "ROOM" "CPLD"
					( Origin gFrontEnd )
				)
				( attribute "ROT" "0"
					( Origin gFrontEnd )
				)
				( attribute "SEC" "1"
					( Origin gFrontEnd )
				)
				( attribute "SEC_TYPE" "0402"
					( Origin gFrontEnd )
				)
				( attribute "TOLERANCE" "5.0%"
					( Origin gFrontEnd )
				)
				( attribute "VALUE" "51"
					( Origin gFrontEnd )
				)
				( attribute "VER" "1"
					( Origin gFrontEnd )
				)
				( attribute "WATTAGE" "1/16W"
					( Origin gFrontEnd )
				)
				( attribute "XY" "(-1425,2675)"
					( Origin gFrontEnd )
				)
				( attribute "CHIPS_PART_NAME" "RES"
					( Origin gPackager )
				)
				( attribute "CDS_PART_NAME" "RES_0402-51,5.0%,1/16W,CHIP,G2A"
					( Origin gPackager )
				)
				( attribute "CDS_SEC" "1"
					( Origin gPackager )
				)
				( objectStatus "R2R6" )
			)
			( gate "@baseboard_fab2_lib.baseboard_fab2(sch_1):page191_i172"
				( attribute "BOM_COST" "CPLD"
					( Origin gFrontEnd )
				)
				( attribute "CDS_LIB" "mstr_discrete"
					( Origin gPackager )
				)
				( attribute "CDS_LOCATION" "R2R7"
					( Origin gPackager )
				)
				( attribute "LOCATION" "R2R7"
					( Origin gFrontEnd )
				)
				( attribute "MATERIAL" "CHIP"
					( Origin gFrontEnd )
				)
				( attribute "PACK_TYPE" "0402"
					( Origin gFrontEnd )
				)
				( attribute "PART_NUMBER" "G21796-072"
					( Origin gFrontEnd )
				)
				( attribute "PHYS_PAGE" "191"
					( Origin gFrontEnd )
				)
				( attribute "ROOM" "CPLD"
					( Origin gFrontEnd )
				)
				( attribute "ROT" "2"
					( Origin gFrontEnd )
				)
				( attribute "SEC" "1"
					( Origin gFrontEnd )
				)
				( attribute "SEC_TYPE" "0402"
					( Origin gFrontEnd )
				)
				( attribute "SIGNAL_MODEL" "DEFAULT_RESISTOR_47000OHM_2_1"
					( Origin gFrontEnd )
				)
				( attribute "TOLERANCE" "1%"
					( Origin gFrontEnd )
				)
				( attribute "VALUE" "4.75K"
					( Origin gFrontEnd )
				)
				( attribute "VER" "2"
					( Origin gFrontEnd )
				)
				( attribute "WATTAGE" "1/16W"
					( Origin gFrontEnd )
				)
				( attribute "XY" "(-1375,3550)"
					( Origin gFrontEnd )
				)
				( attribute "CHIPS_PART_NAME" "RES"
					( Origin gPackager )
				)
				( attribute "CDS_PART_NAME" "RES_0402-4.75K,1%,1/16W,CHIP,GA"
					( Origin gPackager )
				)
				( attribute "CDS_SEC" "1"
					( Origin gPackager )
				)
				( objectStatus "R2R7" )
			)
			( gate "@baseboard_fab2_lib.baseboard_fab2(sch_1):page191_i184"
				( attribute "BOM_COST" "CPLD"
					( Origin gFrontEnd )
				)
				( attribute "CDS_LIB" "mstr_discrete"
					( Origin gPackager )
				)
				( attribute "CDS_LOCATION" "R2R4"
					( Origin gPackager )
				)
				( attribute "CDS_SEC" "1"
					( Origin gPackager )
				)
				( attribute "LOCATION" "R2R4"
					( Origin gFrontEnd )
				)
				( attribute "MATERIAL" "CHIP"
					( Origin gFrontEnd )
				)
				( attribute "PACK_TYPE" "0402"
					( Origin gFrontEnd )
				)
				( attribute "PART_NUMBER" "G21497-005"
					( Origin gFrontEnd )
				)
				( attribute "PHYS_PAGE" "191"
					( Origin gFrontEnd )
				)
				( attribute "ROOM" "CPLD"
					( Origin gFrontEnd )
				)
				( attribute "ROT" "0"
					( Origin gFrontEnd )
				)
				( attribute "SEC" "1"
					( Origin gPackager )
				)
				( attribute "TOLERANCE" "5%"
					( Origin gFrontEnd )
				)
				( attribute "VALUE" "0.0"
					( Origin gFrontEnd )
				)
				( attribute "VER" "1"
					( Origin gFrontEnd )
				)
				( attribute "WATTAGE" "1/16W"
					( Origin gFrontEnd )
				)
				( attribute "XY" "(-3175,4325)"
					( Origin gFrontEnd )
				)
				( attribute "CHIPS_PART_NAME" "RES"
					( Origin gPackager )
				)
				( attribute "CDS_PART_NAME" "RES_0402-0.0,5%,1/16W,CHIP,G21A"
					( Origin gPackager )
				)
				( objectStatus "R2R4" )
			)
			( gate "@baseboard_fab2_lib.baseboard_fab2(sch_1):page191_i193"
				( attribute "CDS_LIB" "mstr_discrete"
					( Origin gPackager )
				)
				( attribute "CDS_LOCATION" "R7D42"
					( Origin gPackager )
				)
				( attribute "CDS_SEC" "1"
					( Origin gPackager )
				)
				( attribute "LOCATION" "R7D42"
					( Origin gFrontEnd )
				)
				( attribute "MATERIAL" "CHIP"
					( Origin gFrontEnd )
				)
				( attribute "PACK_TYPE" "0402"
					( Origin gFrontEnd )
				)
				( attribute "PART_NUMBER" "G21796-072"
					( Origin gFrontEnd )
				)
				( attribute "PHYS_PAGE" "191"
					( Origin gFrontEnd )
				)
				( attribute "ROOM" "CPLD"
					( Origin gFrontEnd )
				)
				( attribute "ROT" "0"
					( Origin gFrontEnd )
				)
				( attribute "SEC" "1"
					( Origin gFrontEnd )
				)
				( attribute "SEC_TYPE" "0402"
					( Origin gFrontEnd )
				)
				( attribute "TOLERANCE" "1%"
					( Origin gFrontEnd )
				)
				( attribute "VALUE" "4.75K"
					( Origin gFrontEnd )
				)
				( attribute "VER" "2"
					( Origin gFrontEnd )
				)
				( attribute "WATTAGE" "1/16W"
					( Origin gFrontEnd )
				)
				( attribute "XY" "(-7225,2675)"
					( Origin gFrontEnd )
				)
				( attribute "CHIPS_PART_NAME" "RES"
					( Origin gPackager )
				)
				( attribute "CDS_PART_NAME" "RES_0402-4.75K,1%,1/16W,CHIP,GA"
					( Origin gPackager )
				)
				( objectStatus "R7D42" )
			)
			( gate "@baseboard_fab2_lib.baseboard_fab2(sch_1):page192_i1"
				( attribute "BOM_COST" "CPLD"
					( Origin gFrontEnd )
				)
				( attribute "CDS_LIB" "dev_discrete"
					( Origin gPackager )
				)
				( attribute "CDS_LOCATION" "C2P8"
					( Origin gPackager )
				)
				( attribute "CDS_SEC" "1"
					( Origin gPackager )
				)
				( attribute "LOCATION" "C2P8"
					( Origin gFrontEnd )
				)
				( attribute "MATERIAL" "X7R"
					( Origin gFrontEnd )
				)
				( attribute "PACK_TYPE" "0402V"
					( Origin gFrontEnd )
				)
				( attribute "PART_NUMBER" "A36096-045"
					( Origin gFrontEnd )
				)
				( attribute "PHYS_PAGE" "192"
					( Origin gFrontEnd )
				)
				( attribute "ROOM" "CPLD"
					( Origin gFrontEnd )
				)
				( attribute "ROT" "0"
					( Origin gFrontEnd )
				)
				( attribute "SEC" "1"
					( Origin gPackager )
				)
				( attribute "SIGNAL_MODEL" "DEFAULT_CAPACITOR_10000pF_2_1"
					( Origin gFrontEnd )
				)
				( attribute "TOLERANCE" "10%"
					( Origin gFrontEnd )
				)
				( attribute "VALUE" "0.01UF"
					( Origin gFrontEnd )
				)
				( attribute "VER" "1"
					( Origin gFrontEnd )
				)
				( attribute "VOLTAGE" "25V"
					( Units "uVoltage" "V" 1.000000)
					( Origin gFrontEnd )
				)
				( attribute "XY" "(-1225,1975)"
					( Origin gFrontEnd )
				)
				( attribute "CHIPS_PART_NAME" "CAP_A"
					( Origin gPackager )
				)
				( attribute "CDS_PART_NAME" "CAP_A_0402V-0.01UF,25V,10%,X7RA"
					( Origin gPackager )
				)
				( objectStatus "C2P8" )
			)
			( gate "@baseboard_fab2_lib.baseboard_fab2(sch_1):page192_i3"
				( attribute "BOM_COST" "CPLD"
					( Origin gFrontEnd )
				)
				( attribute "CDS_LIB" "dev_discrete"
					( Origin gPackager )
				)
				( attribute "CDS_LOCATION" "C2P5"
					( Origin gPackager )
				)
				( attribute "CDS_SEC" "1"
					( Origin gPackager )
				)
				( attribute "LOCATION" "C2P5"
					( Origin gFrontEnd )
				)
				( attribute "MATERIAL" "X7R"
					( Origin gFrontEnd )
				)
				( attribute "PACK_TYPE" "0402V"
					( Origin gFrontEnd )
				)
				( attribute "PART_NUMBER" "A36096-030"
					( Origin gFrontEnd )
				)
				( attribute "PHYS_PAGE" "192"
					( Origin gFrontEnd )
				)
				( attribute "ROOM" "CPLD"
					( Origin gFrontEnd )
				)
				( attribute "ROT" "0"
					( Origin gFrontEnd )
				)
				( attribute "SEC" "1"
					( Origin gPackager )
				)
				( attribute "SIGNAL_MODEL" "DEFAULT_CAPACITOR_100000pF_2_1"
					( Origin gFrontEnd )
				)
				( attribute "TOLERANCE" "10%"
					( Origin gFrontEnd )
				)
				( attribute "VALUE" "0.1UF"
					( Origin gFrontEnd )
				)
				( attribute "VER" "1"
					( Origin gFrontEnd )
				)
				( attribute "VOLTAGE" "16V"
					( Units "uVoltage" "V" 1.000000)
					( Origin gFrontEnd )
				)
				( attribute "XY" "(-1700,1975)"
					( Origin gFrontEnd )
				)
				( attribute "CHIPS_PART_NAME" "CAP_A"
					( Origin gPackager )
				)
				( attribute "CDS_PART_NAME" "CAP_A_0402V-0.1UF,16V,10%,X7R,A"
					( Origin gPackager )
				)
				( objectStatus "C2P5" )
			)
			( gate "@baseboard_fab2_lib.baseboard_fab2(sch_1):page192_i4"
				( attribute "BOM_COST" "CPLD"
					( Origin gFrontEnd )
				)
				( attribute "CDS_LIB" "dev_discrete"
					( Origin gPackager )
				)
				( attribute "CDS_LOCATION" "C3R1"
					( Origin gPackager )
				)
				( attribute "CDS_SEC" "1"
					( Origin gPackager )
				)
				( attribute "LOCATION" "C3R1"
					( Origin gFrontEnd )
				)
				( attribute "MATERIAL" "X7R"
					( Origin gFrontEnd )
				)
				( attribute "PACK_TYPE" "0402V"
					( Origin gFrontEnd )
				)
				( attribute "PART_NUMBER" "A36096-030"
					( Origin gFrontEnd )
				)
				( attribute "PHYS_PAGE" "192"
					( Origin gFrontEnd )
				)
				( attribute "ROOM" "CPLD"
					( Origin gFrontEnd )
				)
				( attribute "ROT" "0"
					( Origin gFrontEnd )
				)
				( attribute "SEC" "1"
					( Origin gPackager )
				)
				( attribute "SIGNAL_MODEL" "DEFAULT_CAPACITOR_100000pF_2_1"
					( Origin gFrontEnd )
				)
				( attribute "TOLERANCE" "10%"
					( Origin gFrontEnd )
				)
				( attribute "VALUE" "0.1UF"
					( Origin gFrontEnd )
				)
				( attribute "VER" "1"
					( Origin gFrontEnd )
				)
				( attribute "VOLTAGE" "16V"
					( Units "uVoltage" "V" 1.000000)
					( Origin gFrontEnd )
				)
				( attribute "XY" "(-2175,1975)"
					( Origin gFrontEnd )
				)
				( attribute "CHIPS_PART_NAME" "CAP_A"
					( Origin gPackager )
				)
				( attribute "CDS_PART_NAME" "CAP_A_0402V-0.1UF,16V,10%,X7R,A"
					( Origin gPackager )
				)
				( objectStatus "C3R1" )
			)
			( gate "@baseboard_fab2_lib.baseboard_fab2(sch_1):page192_i6"
				( attribute "BOM_COST" "CPLD"
					( Origin gFrontEnd )
				)
				( attribute "CDS_LIB" "dev_discrete"
					( Origin gPackager )
				)
				( attribute "CDS_LOCATION" "C3P43"
					( Origin gPackager )
				)
				( attribute "CDS_SEC" "1"
					( Origin gPackager )
				)
				( attribute "LOCATION" "C3P43"
					( Origin gFrontEnd )
				)
				( attribute "MATERIAL" "X7R"
					( Origin gFrontEnd )
				)
				( attribute "PACK_TYPE" "0402V"
					( Origin gFrontEnd )
				)
				( attribute "PART_NUMBER" "A36096-030"
					( Origin gFrontEnd )
				)
				( attribute "PHYS_PAGE" "192"
					( Origin gFrontEnd )
				)
				( attribute "ROOM" "CPLD"
					( Origin gFrontEnd )
				)
				( attribute "ROT" "0"
					( Origin gFrontEnd )
				)
				( attribute "SEC" "1"
					( Origin gPackager )
				)
				( attribute "SIGNAL_MODEL" "DEFAULT_CAPACITOR_100000pF_2_1"
					( Origin gFrontEnd )
				)
				( attribute "TOLERANCE" "10%"
					( Origin gFrontEnd )
				)
				( attribute "VALUE" "0.1UF"
					( Origin gFrontEnd )
				)
				( attribute "VER" "1"
					( Origin gFrontEnd )
				)
				( attribute "VOLTAGE" "16V"
					( Units "uVoltage" "V" 1.000000)
					( Origin gFrontEnd )
				)
				( attribute "XY" "(-2650,1975)"
					( Origin gFrontEnd )
				)
				( attribute "CHIPS_PART_NAME" "CAP_A"
					( Origin gPackager )
				)
				( attribute "CDS_PART_NAME" "CAP_A_0402V-0.1UF,16V,10%,X7R,A"
					( Origin gPackager )
				)
				( objectStatus "C3P43" )
			)
			( gate "@baseboard_fab2_lib.baseboard_fab2(sch_1):page192_i7"
				( attribute "BOM_COST" "CPLD"
					( Origin gFrontEnd )
				)
				( attribute "CDS_LIB" "dev_discrete"
					( Origin gPackager )
				)
				( attribute "CDS_LOCATION" "C3R3"
					( Origin gPackager )
				)
				( attribute "CDS_SEC" "1"
					( Origin gPackager )
				)
				( attribute "LOCATION" "C3R3"
					( Origin gFrontEnd )
				)
				( attribute "MATERIAL" "X7R"
					( Origin gFrontEnd )
				)
				( attribute "PACK_TYPE" "0402V"
					( Origin gFrontEnd )
				)
				( attribute "PART_NUMBER" "A36096-030"
					( Origin gFrontEnd )
				)
				( attribute "PHYS_PAGE" "192"
					( Origin gFrontEnd )
				)
				( attribute "ROOM" "CPLD"
					( Origin gFrontEnd )
				)
				( attribute "ROT" "0"
					( Origin gFrontEnd )
				)
				( attribute "SEC" "1"
					( Origin gPackager )
				)
				( attribute "SIGNAL_MODEL" "DEFAULT_CAPACITOR_100000pF_2_1"
					( Origin gFrontEnd )
				)
				( attribute "TOLERANCE" "10%"
					( Origin gFrontEnd )
				)
				( attribute "VALUE" "0.1UF"
					( Origin gFrontEnd )
				)
				( attribute "VER" "1"
					( Origin gFrontEnd )
				)
				( attribute "VOLTAGE" "16V"
					( Units "uVoltage" "V" 1.000000)
					( Origin gFrontEnd )
				)
				( attribute "XY" "(-3125,1975)"
					( Origin gFrontEnd )
				)
				( attribute "CHIPS_PART_NAME" "CAP_A"
					( Origin gPackager )
				)
				( attribute "CDS_PART_NAME" "CAP_A_0402V-0.1UF,16V,10%,X7R,A"
					( Origin gPackager )
				)
				( objectStatus "C3R3" )
			)
			( gate "@baseboard_fab2_lib.baseboard_fab2(sch_1):page192_i8"
				( attribute "BOM_COST" "CPLD"
					( Origin gFrontEnd )
				)
				( attribute "CDS_LIB" "dev_discrete"
					( Origin gPackager )
				)
				( attribute "CDS_LOCATION" "C2R1"
					( Origin gPackager )
				)
				( attribute "CDS_SEC" "1"
					( Origin gPackager )
				)
				( attribute "LOCATION" "C2R1"
					( Origin gFrontEnd )
				)
				( attribute "MATERIAL" "X7R"
					( Origin gFrontEnd )
				)
				( attribute "PACK_TYPE" "0402V"
					( Origin gFrontEnd )
				)
				( attribute "PART_NUMBER" "A36096-030"
					( Origin gFrontEnd )
				)
				( attribute "PHYS_PAGE" "192"
					( Origin gFrontEnd )
				)
				( attribute "ROOM" "CPLD"
					( Origin gFrontEnd )
				)
				( attribute "ROT" "0"
					( Origin gFrontEnd )
				)
				( attribute "SEC" "1"
					( Origin gPackager )
				)
				( attribute "SIGNAL_MODEL" "DEFAULT_CAPACITOR_100000pF_2_1"
					( Origin gFrontEnd )
				)
				( attribute "TOLERANCE" "10%"
					( Origin gFrontEnd )
				)
				( attribute "VALUE" "0.1UF"
					( Origin gFrontEnd )
				)
				( attribute "VER" "1"
					( Origin gFrontEnd )
				)
				( attribute "VOLTAGE" "16V"
					( Units "uVoltage" "V" 1.000000)
					( Origin gFrontEnd )
				)
				( attribute "XY" "(-3150,1300)"
					( Origin gFrontEnd )
				)
				( attribute "CHIPS_PART_NAME" "CAP_A"
					( Origin gPackager )
				)
				( attribute "CDS_PART_NAME" "CAP_A_0402V-0.1UF,16V,10%,X7R,A"
					( Origin gPackager )
				)
				( objectStatus "C2R1" )
			)
			( gate "@baseboard_fab2_lib.baseboard_fab2(sch_1):page192_i9"
				( attribute "BOM_COST" "CPLD"
					( Origin gFrontEnd )
				)
				( attribute "CDS_LIB" "dev_discrete"
					( Origin gPackager )
				)
				( attribute "CDS_LOCATION" "C2P2"
					( Origin gPackager )
				)
				( attribute "CDS_SEC" "1"
					( Origin gPackager )
				)
				( attribute "LOCATION" "C2P2"
					( Origin gFrontEnd )
				)
				( attribute "MATERIAL" "X7R"
					( Origin gFrontEnd )
				)
				( attribute "PACK_TYPE" "0402V"
					( Origin gFrontEnd )
				)
				( attribute "PART_NUMBER" "A36096-030"
					( Origin gFrontEnd )
				)
				( attribute "PHYS_PAGE" "192"
					( Origin gFrontEnd )
				)
				( attribute "ROOM" "CPLD"
					( Origin gFrontEnd )
				)
				( attribute "ROT" "0"
					( Origin gFrontEnd )
				)
				( attribute "SEC" "1"
					( Origin gPackager )
				)
				( attribute "SIGNAL_MODEL" "DEFAULT_CAPACITOR_100000pF_2_1"
					( Origin gFrontEnd )
				)
				( attribute "TOLERANCE" "10%"
					( Origin gFrontEnd )
				)
				( attribute "VALUE" "0.1UF"
					( Origin gFrontEnd )
				)
				( attribute "VER" "1"
					( Origin gFrontEnd )
				)
				( attribute "VOLTAGE" "16V"
					( Units "uVoltage" "V" 1.000000)
					( Origin gFrontEnd )
				)
				( attribute "XY" "(-3600,1975)"
					( Origin gFrontEnd )
				)
				( attribute "CHIPS_PART_NAME" "CAP_A"
					( Origin gPackager )
				)
				( attribute "CDS_PART_NAME" "CAP_A_0402V-0.1UF,16V,10%,X7R,A"
					( Origin gPackager )
				)
				( objectStatus "C2P2" )
			)
			( gate "@baseboard_fab2_lib.baseboard_fab2(sch_1):page192_i10"
				( attribute "BOM_COST" "CPLD"
					( Origin gFrontEnd )
				)
				( attribute "CDS_LIB" "dev_discrete"
					( Origin gPackager )
				)
				( attribute "CDS_LOCATION" "C3R2"
					( Origin gPackager )
				)
				( attribute "CDS_SEC" "1"
					( Origin gPackager )
				)
				( attribute "LOCATION" "C3R2"
					( Origin gFrontEnd )
				)
				( attribute "MATERIAL" "X7R"
					( Origin gFrontEnd )
				)
				( attribute "PACK_TYPE" "0402V"
					( Origin gFrontEnd )
				)
				( attribute "PART_NUMBER" "A36096-030"
					( Origin gFrontEnd )
				)
				( attribute "PHYS_PAGE" "192"
					( Origin gFrontEnd )
				)
				( attribute "ROOM" "CPLD"
					( Origin gFrontEnd )
				)
				( attribute "ROT" "0"
					( Origin gFrontEnd )
				)
				( attribute "SEC" "1"
					( Origin gPackager )
				)
				( attribute "SIGNAL_MODEL" "DEFAULT_CAPACITOR_100000pF_2_1"
					( Origin gFrontEnd )
				)
				( attribute "TOLERANCE" "10%"
					( Origin gFrontEnd )
				)
				( attribute "VALUE" "0.1UF"
					( Origin gFrontEnd )
				)
				( attribute "VER" "1"
					( Origin gFrontEnd )
				)
				( attribute "VOLTAGE" "16V"
					( Units "uVoltage" "V" 1.000000)
					( Origin gFrontEnd )
				)
				( attribute "XY" "(-4075,1975)"
					( Origin gFrontEnd )
				)
				( attribute "CHIPS_PART_NAME" "CAP_A"
					( Origin gPackager )
				)
				( attribute "CDS_PART_NAME" "CAP_A_0402V-0.1UF,16V,10%,X7R,A"
					( Origin gPackager )
				)
				( objectStatus "C3R2" )
			)
			( gate "@baseboard_fab2_lib.baseboard_fab2(sch_1):page192_i11"
				( attribute "BOM_COST" "CPLD"
					( Origin gFrontEnd )
				)
				( attribute "CDS_LIB" "dev_discrete"
					( Origin gPackager )
				)
				( attribute "CDS_LOCATION" "C3P51"
					( Origin gPackager )
				)
				( attribute "CDS_SEC" "1"
					( Origin gPackager )
				)
				( attribute "LOCATION" "C3P51"
					( Origin gFrontEnd )
				)
				( attribute "MATERIAL" "X7R"
					( Origin gFrontEnd )
				)
				( attribute "PACK_TYPE" "0402V"
					( Origin gFrontEnd )
				)
				( attribute "PART_NUMBER" "A36096-030"
					( Origin gFrontEnd )
				)
				( attribute "PHYS_PAGE" "192"
					( Origin gFrontEnd )
				)
				( attribute "ROOM" "CPLD"
					( Origin gFrontEnd )
				)
				( attribute "ROT" "0"
					( Origin gFrontEnd )
				)
				( attribute "SEC" "1"
					( Origin gPackager )
				)
				( attribute "SIGNAL_MODEL" "DEFAULT_CAPACITOR_100000pF_2_1"
					( Origin gFrontEnd )
				)
				( attribute "TOLERANCE" "10%"
					( Origin gFrontEnd )
				)
				( attribute "VALUE" "0.1UF"
					( Origin gFrontEnd )
				)
				( attribute "VER" "1"
					( Origin gFrontEnd )
				)
				( attribute "VOLTAGE" "16V"
					( Units "uVoltage" "V" 1.000000)
					( Origin gFrontEnd )
				)
				( attribute "XY" "(-3700,1300)"
					( Origin gFrontEnd )
				)
				( attribute "CHIPS_PART_NAME" "CAP_A"
					( Origin gPackager )
				)
				( attribute "CDS_PART_NAME" "CAP_A_0402V-0.1UF,16V,10%,X7R,A"
					( Origin gPackager )
				)
				( objectStatus "C3P51" )
			)
			( gate "@baseboard_fab2_lib.baseboard_fab2(sch_1):page192_i12"
				( attribute "BOM_COST" "CPLD"
					( Origin gFrontEnd )
				)
				( attribute "CDS_LIB" "dev_discrete"
					( Origin gPackager )
				)
				( attribute "CDS_LOCATION" "C3P47"
					( Origin gPackager )
				)
				( attribute "CDS_SEC" "1"
					( Origin gPackager )
				)
				( attribute "LOCATION" "C3P47"
					( Origin gFrontEnd )
				)
				( attribute "MATERIAL" "X7R"
					( Origin gFrontEnd )
				)
				( attribute "PACK_TYPE" "0402V"
					( Origin gFrontEnd )
				)
				( attribute "PART_NUMBER" "A36096-030"
					( Origin gFrontEnd )
				)
				( attribute "PHYS_PAGE" "192"
					( Origin gFrontEnd )
				)
				( attribute "ROOM" "CPLD"
					( Origin gFrontEnd )
				)
				( attribute "ROT" "0"
					( Origin gFrontEnd )
				)
				( attribute "SEC" "1"
					( Origin gPackager )
				)
				( attribute "SIGNAL_MODEL" "DEFAULT_CAPACITOR_100000pF_2_1"
					( Origin gFrontEnd )
				)
				( attribute "TOLERANCE" "10%"
					( Origin gFrontEnd )
				)
				( attribute "VALUE" "0.1UF"
					( Origin gFrontEnd )
				)
				( attribute "VER" "1"
					( Origin gFrontEnd )
				)
				( attribute "VOLTAGE" "16V"
					( Units "uVoltage" "V" 1.000000)
					( Origin gFrontEnd )
				)
				( attribute "XY" "(-4200,1300)"
					( Origin gFrontEnd )
				)
				( attribute "CHIPS_PART_NAME" "CAP_A"
					( Origin gPackager )
				)
				( attribute "CDS_PART_NAME" "CAP_A_0402V-0.1UF,16V,10%,X7R,A"
					( Origin gPackager )
				)
				( objectStatus "C3P47" )
			)
			( gate "@baseboard_fab2_lib.baseboard_fab2(sch_1):page192_i14"
				( attribute "BOM_COST" "CPLD"
					( Origin gFrontEnd )
				)
				( attribute "CDS_LIB" "mstr_memory"
					( Origin gPackager )
				)
				( attribute "CDS_LMAN_SYM_OUTLINE" "-400,750,400,-750"
					( Origin gPackager )
				)
				( attribute "CDS_LOCATION" "U8D7"
					( Origin gPackager )
				)
				( attribute "LOCATION" "U8D7"
					( Origin gFrontEnd )
				)
				( attribute "MATERIAL" "IC"
					( Origin gFrontEnd )
				)
				( attribute "PACK_TYPE" "256BGA"
					( Origin gFrontEnd )
				)
				( attribute "PART_NUMBER" "H63395-001"
					( Origin gFrontEnd )
				)
				( attribute "PHYS_PAGE" "192"
					( Origin gFrontEnd )
				)
				( attribute "ROOM" "CPLD"
					( Origin gFrontEnd )
				)
				( attribute "ROT" "0"
					( Origin gFrontEnd )
				)
				( attribute "SEC" "3"
					( Origin gFrontEnd )
				)
				( attribute "SEC_TYPE" "256BGA"
					( Origin gFrontEnd )
				)
				( attribute "VER" "6"
					( Origin gFrontEnd )
				)
				( attribute "XY" "(-1850,3900)"
					( Origin gFrontEnd )
				)
				( attribute "CHIPS_PART_NAME" "LCMXO2_A"
					( Origin gPackager )
				)
				( attribute "CDS_PART_NAME" "LCMXO2_A_256BGA-IC,H63395-001"
					( Origin gPackager )
				)
				( attribute "CDS_SEC" "3"
					( Origin gPackager )
				)
				( objectStatus "U8D7" )
			)
			( gate "@baseboard_fab2_lib.baseboard_fab2(sch_1):page192_i15"
				( attribute "BOM_COST" "CPLD"
					( Origin gFrontEnd )
				)
				( attribute "CDS_LIB" "dev_discrete"
					( Origin gPackager )
				)
				( attribute "CDS_LOCATION" "C2R5"
					( Origin gPackager )
				)
				( attribute "CDS_SEC" "1"
					( Origin gPackager )
				)
				( attribute "LOCATION" "C2R5"
					( Origin gFrontEnd )
				)
				( attribute "MATERIAL" "X7R"
					( Origin gFrontEnd )
				)
				( attribute "PACK_TYPE" "0402V"
					( Origin gFrontEnd )
				)
				( attribute "PART_NUMBER" "A36096-030"
					( Origin gFrontEnd )
				)
				( attribute "PHYS_PAGE" "192"
					( Origin gFrontEnd )
				)
				( attribute "ROOM" "CPLD"
					( Origin gFrontEnd )
				)
				( attribute "ROT" "0"
					( Origin gFrontEnd )
				)
				( attribute "SEC" "1"
					( Origin gPackager )
				)
				( attribute "SIGNAL_MODEL" "DEFAULT_CAPACITOR_100000pF_2_1"
					( Origin gFrontEnd )
				)
				( attribute "TOLERANCE" "10%"
					( Origin gFrontEnd )
				)
				( attribute "VALUE" "0.1UF"
					( Origin gFrontEnd )
				)
				( attribute "VER" "1"
					( Origin gFrontEnd )
				)
				( attribute "VOLTAGE" "16V"
					( Units "uVoltage" "V" 1.000000)
					( Origin gFrontEnd )
				)
				( attribute "XY" "(-4550,1975)"
					( Origin gFrontEnd )
				)
				( attribute "CHIPS_PART_NAME" "CAP_A"
					( Origin gPackager )
				)
				( attribute "CDS_PART_NAME" "CAP_A_0402V-0.1UF,16V,10%,X7R,A"
					( Origin gPackager )
				)
				( objectStatus "C2R5" )
			)
			( gate "@baseboard_fab2_lib.baseboard_fab2(sch_1):page192_i16"
				( attribute "BOM_COST" "CPLD"
					( Origin gFrontEnd )
				)
				( attribute "CDS_LIB" "dev_discrete"
					( Origin gPackager )
				)
				( attribute "CDS_LOCATION" "C2P4"
					( Origin gPackager )
				)
				( attribute "CDS_SEC" "1"
					( Origin gPackager )
				)
				( attribute "LOCATION" "C2P4"
					( Origin gFrontEnd )
				)
				( attribute "MATERIAL" "X7R"
					( Origin gFrontEnd )
				)
				( attribute "PACK_TYPE" "0402V"
					( Origin gFrontEnd )
				)
				( attribute "PART_NUMBER" "A36096-030"
					( Origin gFrontEnd )
				)
				( attribute "PHYS_PAGE" "192"
					( Origin gFrontEnd )
				)
				( attribute "ROOM" "CPLD"
					( Origin gFrontEnd )
				)
				( attribute "ROT" "0"
					( Origin gFrontEnd )
				)
				( attribute "SEC" "1"
					( Origin gPackager )
				)
				( attribute "SIGNAL_MODEL" "DEFAULT_CAPACITOR_100000pF_2_1"
					( Origin gFrontEnd )
				)
				( attribute "TOLERANCE" "10%"
					( Origin gFrontEnd )
				)
				( attribute "VALUE" "0.1UF"
					( Origin gFrontEnd )
				)
				( attribute "VER" "1"
					( Origin gFrontEnd )
				)
				( attribute "VOLTAGE" "16V"
					( Units "uVoltage" "V" 1.000000)
					( Origin gFrontEnd )
				)
				( attribute "XY" "(-5025,1975)"
					( Origin gFrontEnd )
				)
				( attribute "CHIPS_PART_NAME" "CAP_A"
					( Origin gPackager )
				)
				( attribute "CDS_PART_NAME" "CAP_A_0402V-0.1UF,16V,10%,X7R,A"
					( Origin gPackager )
				)
				( objectStatus "C2P4" )
			)
			( gate "@baseboard_fab2_lib.baseboard_fab2(sch_1):page192_i17"
				( attribute "BOM_COST" "CPLD"
					( Origin gFrontEnd )
				)
				( attribute "CDS_LIB" "dev_discrete"
					( Origin gPackager )
				)
				( attribute "CDS_LOCATION" "C3P52"
					( Origin gPackager )
				)
				( attribute "CDS_SEC" "1"
					( Origin gPackager )
				)
				( attribute "LOCATION" "C3P52"
					( Origin gFrontEnd )
				)
				( attribute "MATERIAL" "X7R"
					( Origin gFrontEnd )
				)
				( attribute "PACK_TYPE" "0402V"
					( Origin gFrontEnd )
				)
				( attribute "PART_NUMBER" "A36096-030"
					( Origin gFrontEnd )
				)
				( attribute "PHYS_PAGE" "192"
					( Origin gFrontEnd )
				)
				( attribute "ROOM" "CPLD"
					( Origin gFrontEnd )
				)
				( attribute "ROT" "0"
					( Origin gFrontEnd )
				)
				( attribute "SEC" "1"
					( Origin gPackager )
				)
				( attribute "SIGNAL_MODEL" "DEFAULT_CAPACITOR_100000pF_2_1"
					( Origin gFrontEnd )
				)
				( attribute "TOLERANCE" "10%"
					( Origin gFrontEnd )
				)
				( attribute "VALUE" "0.1UF"
					( Origin gFrontEnd )
				)
				( attribute "VER" "1"
					( Origin gFrontEnd )
				)
				( attribute "VOLTAGE" "16V"
					( Units "uVoltage" "V" 1.000000)
					( Origin gFrontEnd )
				)
				( attribute "XY" "(-4725,1300)"
					( Origin gFrontEnd )
				)
				( attribute "CHIPS_PART_NAME" "CAP_A"
					( Origin gPackager )
				)
				( attribute "CDS_PART_NAME" "CAP_A_0402V-0.1UF,16V,10%,X7R,A"
					( Origin gPackager )
				)
				( objectStatus "C3P52" )
			)
			( gate "@baseboard_fab2_lib.baseboard_fab2(sch_1):page192_i18"
				( attribute "BOM_COST" "CPLD"
					( Origin gFrontEnd )
				)
				( attribute "CDS_LIB" "dev_discrete"
					( Origin gPackager )
				)
				( attribute "CDS_LOCATION" "C2P6"
					( Origin gPackager )
				)
				( attribute "CDS_SEC" "1"
					( Origin gPackager )
				)
				( attribute "LOCATION" "C2P6"
					( Origin gFrontEnd )
				)
				( attribute "MATERIAL" "X7R"
					( Origin gFrontEnd )
				)
				( attribute "PACK_TYPE" "0402V"
					( Origin gFrontEnd )
				)
				( attribute "PART_NUMBER" "A36096-030"
					( Origin gFrontEnd )
				)
				( attribute "PHYS_PAGE" "192"
					( Origin gFrontEnd )
				)
				( attribute "ROOM" "CPLD"
					( Origin gFrontEnd )
				)
				( attribute "ROT" "0"
					( Origin gFrontEnd )
				)
				( attribute "SEC" "1"
					( Origin gPackager )
				)
				( attribute "SIGNAL_MODEL" "DEFAULT_CAPACITOR_100000pF_2_1"
					( Origin gFrontEnd )
				)
				( attribute "TOLERANCE" "10%"
					( Origin gFrontEnd )
				)
				( attribute "VALUE" "0.1UF"
					( Origin gFrontEnd )
				)
				( attribute "VER" "1"
					( Origin gFrontEnd )
				)
				( attribute "VOLTAGE" "16V"
					( Units "uVoltage" "V" 1.000000)
					( Origin gFrontEnd )
				)
				( attribute "XY" "(-5225,1300)"
					( Origin gFrontEnd )
				)
				( attribute "CHIPS_PART_NAME" "CAP_A"
					( Origin gPackager )
				)
				( attribute "CDS_PART_NAME" "CAP_A_0402V-0.1UF,16V,10%,X7R,A"
					( Origin gPackager )
				)
				( objectStatus "C2P6" )
			)
			( gate "@baseboard_fab2_lib.baseboard_fab2(sch_1):page192_i19"
				( attribute "BOM_COST" "CPLD"
					( Origin gFrontEnd )
				)
				( attribute "CDS_LIB" "dev_discrete"
					( Origin gPackager )
				)
				( attribute "CDS_LOCATION" "C2R3"
					( Origin gPackager )
				)
				( attribute "CDS_SEC" "1"
					( Origin gPackager )
				)
				( attribute "LOCATION" "C2R3"
					( Origin gFrontEnd )
				)
				( attribute "MATERIAL" "X7R"
					( Origin gFrontEnd )
				)
				( attribute "PACK_TYPE" "0402V"
					( Origin gFrontEnd )
				)
				( attribute "PART_NUMBER" "A36096-030"
					( Origin gFrontEnd )
				)
				( attribute "PHYS_PAGE" "192"
					( Origin gFrontEnd )
				)
				( attribute "ROOM" "CPLD"
					( Origin gFrontEnd )
				)
				( attribute "ROT" "0"
					( Origin gFrontEnd )
				)
				( attribute "SEC" "1"
					( Origin gPackager )
				)
				( attribute "SIGNAL_MODEL" "DEFAULT_CAPACITOR_100000pF_2_1"
					( Origin gFrontEnd )
				)
				( attribute "TOLERANCE" "10%"
					( Origin gFrontEnd )
				)
				( attribute "VALUE" "0.1UF"
					( Origin gFrontEnd )
				)
				( attribute "VER" "1"
					( Origin gFrontEnd )
				)
				( attribute "VOLTAGE" "16V"
					( Units "uVoltage" "V" 1.000000)
					( Origin gFrontEnd )
				)
				( attribute "XY" "(-5500,1975)"
					( Origin gFrontEnd )
				)
				( attribute "CHIPS_PART_NAME" "CAP_A"
					( Origin gPackager )
				)
				( attribute "CDS_PART_NAME" "CAP_A_0402V-0.1UF,16V,10%,X7R,A"
					( Origin gPackager )
				)
				( objectStatus "C2R3" )
			)
			( gate "@baseboard_fab2_lib.baseboard_fab2(sch_1):page192_i20"
				( attribute "BOM_COST" "CPLD"
					( Origin gFrontEnd )
				)
				( attribute "CDS_LIB" "dev_discrete"
					( Origin gPackager )
				)
				( attribute "CDS_LOCATION" "C2P7"
					( Origin gPackager )
				)
				( attribute "CDS_SEC" "1"
					( Origin gPackager )
				)
				( attribute "LOCATION" "C2P7"
					( Origin gFrontEnd )
				)
				( attribute "MATERIAL" "X7R"
					( Origin gFrontEnd )
				)
				( attribute "PACK_TYPE" "0402V"
					( Origin gFrontEnd )
				)
				( attribute "PART_NUMBER" "A36096-030"
					( Origin gFrontEnd )
				)
				( attribute "PHYS_PAGE" "192"
					( Origin gFrontEnd )
				)
				( attribute "ROOM" "CPLD"
					( Origin gFrontEnd )
				)
				( attribute "ROT" "0"
					( Origin gFrontEnd )
				)
				( attribute "SEC" "1"
					( Origin gPackager )
				)
				( attribute "SIGNAL_MODEL" "DEFAULT_CAPACITOR_100000pF_2_1"
					( Origin gFrontEnd )
				)
				( attribute "TOLERANCE" "10%"
					( Origin gFrontEnd )
				)
				( attribute "VALUE" "0.1UF"
					( Origin gFrontEnd )
				)
				( attribute "VER" "1"
					( Origin gFrontEnd )
				)
				( attribute "VOLTAGE" "16V"
					( Units "uVoltage" "V" 1.000000)
					( Origin gFrontEnd )
				)
				( attribute "XY" "(-5975,1975)"
					( Origin gFrontEnd )
				)
				( attribute "CHIPS_PART_NAME" "CAP_A"
					( Origin gPackager )
				)
				( attribute "CDS_PART_NAME" "CAP_A_0402V-0.1UF,16V,10%,X7R,A"
					( Origin gPackager )
				)
				( objectStatus "C2P7" )
			)
			( gate "@baseboard_fab2_lib.baseboard_fab2(sch_1):page192_i21"
				( attribute "BOM_COST" "CPLD"
					( Origin gFrontEnd )
				)
				( attribute "CDS_LIB" "dev_discrete"
					( Origin gPackager )
				)
				( attribute "CDS_LOCATION" "C2R4"
					( Origin gPackager )
				)
				( attribute "CDS_SEC" "1"
					( Origin gPackager )
				)
				( attribute "LOCATION" "C2R4"
					( Origin gFrontEnd )
				)
				( attribute "MATERIAL" "X7R"
					( Origin gFrontEnd )
				)
				( attribute "PACK_TYPE" "0402V"
					( Origin gFrontEnd )
				)
				( attribute "PART_NUMBER" "A36096-030"
					( Origin gFrontEnd )
				)
				( attribute "PHYS_PAGE" "192"
					( Origin gFrontEnd )
				)
				( attribute "ROOM" "CPLD"
					( Origin gFrontEnd )
				)
				( attribute "ROT" "0"
					( Origin gFrontEnd )
				)
				( attribute "SEC" "1"
					( Origin gPackager )
				)
				( attribute "SIGNAL_MODEL" "DEFAULT_CAPACITOR_100000pF_2_1"
					( Origin gFrontEnd )
				)
				( attribute "TOLERANCE" "10%"
					( Origin gFrontEnd )
				)
				( attribute "VALUE" "0.1UF"
					( Origin gFrontEnd )
				)
				( attribute "VER" "1"
					( Origin gFrontEnd )
				)
				( attribute "VOLTAGE" "16V"
					( Units "uVoltage" "V" 1.000000)
					( Origin gFrontEnd )
				)
				( attribute "XY" "(-5700,1300)"
					( Origin gFrontEnd )
				)
				( attribute "CHIPS_PART_NAME" "CAP_A"
					( Origin gPackager )
				)
				( attribute "CDS_PART_NAME" "CAP_A_0402V-0.1UF,16V,10%,X7R,A"
					( Origin gPackager )
				)
				( objectStatus "C2R4" )
			)
			( gate "@baseboard_fab2_lib.baseboard_fab2(sch_1):page192_i22"
				( attribute "BOM_COST" "CPLD"
					( Origin gFrontEnd )
				)
				( attribute "CDS_LIB" "dev_discrete"
					( Origin gPackager )
				)
				( attribute "CDS_LOCATION" "C2P3"
					( Origin gPackager )
				)
				( attribute "CDS_SEC" "1"
					( Origin gPackager )
				)
				( attribute "LOCATION" "C2P3"
					( Origin gFrontEnd )
				)
				( attribute "MATERIAL" "X7R"
					( Origin gFrontEnd )
				)
				( attribute "PACK_TYPE" "0402V"
					( Origin gFrontEnd )
				)
				( attribute "PART_NUMBER" "A36096-030"
					( Origin gFrontEnd )
				)
				( attribute "PHYS_PAGE" "192"
					( Origin gFrontEnd )
				)
				( attribute "ROOM" "CPLD"
					( Origin gFrontEnd )
				)
				( attribute "ROT" "0"
					( Origin gFrontEnd )
				)
				( attribute "SEC" "1"
					( Origin gPackager )
				)
				( attribute "SIGNAL_MODEL" "DEFAULT_CAPACITOR_100000pF_2_1"
					( Origin gFrontEnd )
				)
				( attribute "TOLERANCE" "10%"
					( Origin gFrontEnd )
				)
				( attribute "VALUE" "0.1UF"
					( Origin gFrontEnd )
				)
				( attribute "VER" "1"
					( Origin gFrontEnd )
				)
				( attribute "VOLTAGE" "16V"
					( Units "uVoltage" "V" 1.000000)
					( Origin gFrontEnd )
				)
				( attribute "XY" "(-6250,1300)"
					( Origin gFrontEnd )
				)
				( attribute "CHIPS_PART_NAME" "CAP_A"
					( Origin gPackager )
				)
				( attribute "CDS_PART_NAME" "CAP_A_0402V-0.1UF,16V,10%,X7R,A"
					( Origin gPackager )
				)
				( objectStatus "C2P3" )
			)
			( gate "@baseboard_fab2_lib.baseboard_fab2(sch_1):page192_i23"
				( attribute "BOM_COST" "CPLD"
					( Origin gFrontEnd )
				)
				( attribute "CDS_LIB" "dev_discrete"
					( Origin gPackager )
				)
				( attribute "CDS_LOCATION" "C3P44"
					( Origin gPackager )
				)
				( attribute "CDS_SEC" "1"
					( Origin gPackager )
				)
				( attribute "LOCATION" "C3P44"
					( Origin gFrontEnd )
				)
				( attribute "MATERIAL" "X7R"
					( Origin gFrontEnd )
				)
				( attribute "PACK_TYPE" "0402V"
					( Origin gFrontEnd )
				)
				( attribute "PART_NUMBER" "A36096-030"
					( Origin gFrontEnd )
				)
				( attribute "PHYS_PAGE" "192"
					( Origin gFrontEnd )
				)
				( attribute "ROOM" "CPLD"
					( Origin gFrontEnd )
				)
				( attribute "ROT" "0"
					( Origin gFrontEnd )
				)
				( attribute "SEC" "1"
					( Origin gPackager )
				)
				( attribute "SIGNAL_MODEL" "DEFAULT_CAPACITOR_100000pF_2_1"
					( Origin gFrontEnd )
				)
				( attribute "TOLERANCE" "10%"
					( Origin gFrontEnd )
				)
				( attribute "VALUE" "0.1UF"
					( Origin gFrontEnd )
				)
				( attribute "VER" "1"
					( Origin gFrontEnd )
				)
				( attribute "VOLTAGE" "16V"
					( Units "uVoltage" "V" 1.000000)
					( Origin gFrontEnd )
				)
				( attribute "XY" "(-6450,1975)"
					( Origin gFrontEnd )
				)
				( attribute "CHIPS_PART_NAME" "CAP_A"
					( Origin gPackager )
				)
				( attribute "CDS_PART_NAME" "CAP_A_0402V-0.1UF,16V,10%,X7R,A"
					( Origin gPackager )
				)
				( objectStatus "C3P44" )
			)
			( gate "@baseboard_fab2_lib.baseboard_fab2(sch_1):page192_i25"
				( attribute "BOM_COST" "CPLD"
					( Origin gFrontEnd )
				)
				( attribute "CDS_LIB" "dev_discrete"
					( Origin gPackager )
				)
				( attribute "CDS_LOCATION" "C3P48"
					( Origin gPackager )
				)
				( attribute "CDS_SEC" "1"
					( Origin gPackager )
				)
				( attribute "LOCATION" "C3P48"
					( Origin gFrontEnd )
				)
				( attribute "MATERIAL" "X7R"
					( Origin gFrontEnd )
				)
				( attribute "PACK_TYPE" "0402V"
					( Origin gFrontEnd )
				)
				( attribute "PART_NUMBER" "A36096-030"
					( Origin gFrontEnd )
				)
				( attribute "PHYS_PAGE" "192"
					( Origin gFrontEnd )
				)
				( attribute "ROOM" "CPLD"
					( Origin gFrontEnd )
				)
				( attribute "ROT" "0"
					( Origin gFrontEnd )
				)
				( attribute "SEC" "1"
					( Origin gFrontEnd )
				)
				( attribute "SEC_TYPE" "0402V"
					( Origin gFrontEnd )
				)
				( attribute "SIGNAL_MODEL" "DEFAULT_CAPACITOR_100000pF_2_1"
					( Origin gFrontEnd )
				)
				( attribute "TOLERANCE" "10%"
					( Origin gFrontEnd )
				)
				( attribute "VALUE" "0.1UF"
					( Origin gFrontEnd )
				)
				( attribute "VER" "1"
					( Origin gFrontEnd )
				)
				( attribute "VOLTAGE" "16V"
					( Units "uVoltage" "V" 1.000000)
					( Origin gFrontEnd )
				)
				( attribute "XY" "(-6925,1975)"
					( Origin gFrontEnd )
				)
				( attribute "CHIPS_PART_NAME" "CAP_A"
					( Origin gPackager )
				)
				( attribute "CDS_PART_NAME" "CAP_A_0402V-0.1UF,16V,10%,X7R,A"
					( Origin gPackager )
				)
				( objectStatus "C3P48" )
			)
			( gate "@baseboard_fab2_lib.baseboard_fab2(sch_1):page192_i28"
				( attribute "BOM_COST" "CPLD"
					( Origin gFrontEnd )
				)
				( attribute "CDS_LIB" "dev_discrete"
					( Origin gPackager )
				)
				( attribute "CDS_LOCATION" "C2R2"
					( Origin gPackager )
				)
				( attribute "CDS_SEC" "1"
					( Origin gPackager )
				)
				( attribute "LOCATION" "C2R2"
					( Origin gFrontEnd )
				)
				( attribute "MATERIAL" "X7R"
					( Origin gFrontEnd )
				)
				( attribute "PACK_TYPE" "0402V"
					( Origin gFrontEnd )
				)
				( attribute "PART_NUMBER" "A36096-030"
					( Origin gFrontEnd )
				)
				( attribute "PHYS_PAGE" "192"
					( Origin gFrontEnd )
				)
				( attribute "ROOM" "CPLD"
					( Origin gFrontEnd )
				)
				( attribute "ROT" "0"
					( Origin gFrontEnd )
				)
				( attribute "SEC" "1"
					( Origin gPackager )
				)
				( attribute "SIGNAL_MODEL" "DEFAULT_CAPACITOR_100000pF_2_1"
					( Origin gFrontEnd )
				)
				( attribute "TOLERANCE" "10%"
					( Origin gFrontEnd )
				)
				( attribute "VALUE" "0.1UF"
					( Origin gFrontEnd )
				)
				( attribute "VER" "1"
					( Origin gFrontEnd )
				)
				( attribute "VOLTAGE" "16V"
					( Units "uVoltage" "V" 1.000000)
					( Origin gFrontEnd )
				)
				( attribute "XY" "(-6850,1300)"
					( Origin gFrontEnd )
				)
				( attribute "CHIPS_PART_NAME" "CAP_A"
					( Origin gPackager )
				)
				( attribute "CDS_PART_NAME" "CAP_A_0402V-0.1UF,16V,10%,X7R,A"
					( Origin gPackager )
				)
				( objectStatus "C2R2" )
			)
			( gate "@baseboard_fab2_lib.baseboard_fab2(sch_1):page192_i33"
				( attribute "BOM_COST" "CPLD"
					( Origin gFrontEnd )
				)
				( attribute "CDS_LIB" "mstr_discrete"
					( Origin gPackager )
				)
				( attribute "CDS_LOCATION" "R7E6"
					( Origin gPackager )
				)
				( attribute "LOCATION" "R7E6"
					( Origin gFrontEnd )
				)
				( attribute "MATERIAL" "CHIP"
					( Origin gFrontEnd )
				)
				( attribute "PACK_TYPE" "0402"
					( Origin gFrontEnd )
				)
				( attribute "PART_NUMBER" "G21796-016"
					( Origin gFrontEnd )
				)
				( attribute "PHYS_PAGE" "192"
					( Origin gFrontEnd )
				)
				( attribute "ROOM" "CPLD"
					( Origin gFrontEnd )
				)
				( attribute "ROT" "0"
					( Origin gFrontEnd )
				)
				( attribute "SEC" "1"
					( Origin gFrontEnd )
				)
				( attribute "TOLERANCE" "1%"
					( Origin gFrontEnd )
				)
				( attribute "VALUE" "10.0K"
					( Origin gFrontEnd )
				)
				( attribute "VER" "2"
					( Origin gFrontEnd )
				)
				( attribute "WATTAGE" "1/16W"
					( Origin gFrontEnd )
				)
				( attribute "XY" "(-6150,4400)"
					( Origin gFrontEnd )
				)
				( attribute "CHIPS_PART_NAME" "RES"
					( Origin gPackager )
				)
				( attribute "CDS_PART_NAME" "RES_0402-10.0K,1%,1/16W,CHIP,GA"
					( Origin gPackager )
				)
				( attribute "SEC_TYPE" "0402"
					( Origin gFrontEnd )
				)
				( attribute "CDS_SEC" "1"
					( Origin gPackager )
				)
				( objectStatus "R7E6" )
			)
			( gate "@baseboard_fab2_lib.baseboard_fab2(sch_1):page192_i34"
				( attribute "BOM_COST" "CPLD"
					( Origin gFrontEnd )
				)
				( attribute "CDS_LIB" "mstr_discrete"
					( Origin gPackager )
				)
				( attribute "CDS_LOCATION" "R2R1"
					( Origin gPackager )
				)
				( attribute "LOCATION" "R2R1"
					( Origin gFrontEnd )
				)
				( attribute "MATERIAL" "CHIP"
					( Origin gFrontEnd )
				)
				( attribute "PACK_TYPE" "0402"
					( Origin gFrontEnd )
				)
				( attribute "PART_NUMBER" "G21796-016"
					( Origin gFrontEnd )
				)
				( attribute "PHYS_PAGE" "192"
					( Origin gFrontEnd )
				)
				( attribute "ROOM" "CPLD"
					( Origin gFrontEnd )
				)
				( attribute "ROT" "0"
					( Origin gFrontEnd )
				)
				( attribute "SEC" "1"
					( Origin gFrontEnd )
				)
				( attribute "TOLERANCE" "1%"
					( Origin gFrontEnd )
				)
				( attribute "VALUE" "10.0K"
					( Origin gFrontEnd )
				)
				( attribute "VER" "2"
					( Origin gFrontEnd )
				)
				( attribute "WATTAGE" "1/16W"
					( Origin gFrontEnd )
				)
				( attribute "XY" "(-5750,4400)"
					( Origin gFrontEnd )
				)
				( attribute "CHIPS_PART_NAME" "RES"
					( Origin gPackager )
				)
				( attribute "CDS_PART_NAME" "RES_0402-10.0K,1%,1/16W,CHIP,GA"
					( Origin gPackager )
				)
				( attribute "SEC_TYPE" "0402"
					( Origin gFrontEnd )
				)
				( attribute "CDS_SEC" "1"
					( Origin gPackager )
				)
				( objectStatus "R2R1" )
			)
			( gate "@baseboard_fab2_lib.baseboard_fab2(sch_1):page192_i38"
				( attribute "BOM_COST" "CPLD"
					( Origin gFrontEnd )
				)
				( attribute "CDS_LIB" "mstr_discrete"
					( Origin gPackager )
				)
				( attribute "CDS_LOCATION" "R7E5"
					( Origin gPackager )
				)
				( attribute "CDS_SEC" "1"
					( Origin gPackager )
				)
				( attribute "LOCATION" "R7E5"
					( Origin gFrontEnd )
				)
				( attribute "MATERIAL" "CHIP"
					( Origin gFrontEnd )
				)
				( attribute "PACK_TYPE" "0402"
					( Origin gFrontEnd )
				)
				( attribute "PART_NUMBER" "G21796-016"
					( Origin gFrontEnd )
				)
				( attribute "PHYS_PAGE" "192"
					( Origin gFrontEnd )
				)
				( attribute "ROOM" "CPLD"
					( Origin gFrontEnd )
				)
				( attribute "ROT" "0"
					( Origin gFrontEnd )
				)
				( attribute "SEC" "1"
					( Origin gPackager )
				)
				( attribute "TOLERANCE" "1%"
					( Origin gFrontEnd )
				)
				( attribute "VALUE" "10.0K"
					( Origin gFrontEnd )
				)
				( attribute "VER" "2"
					( Origin gFrontEnd )
				)
				( attribute "WATTAGE" "1/16W"
					( Origin gFrontEnd )
				)
				( attribute "XY" "(-6550,4400)"
					( Origin gFrontEnd )
				)
				( attribute "CHIPS_PART_NAME" "RES"
					( Origin gPackager )
				)
				( attribute "CDS_PART_NAME" "RES_0402-10.0K,1%,1/16W,CHIP,GA"
					( Origin gPackager )
				)
				( objectStatus "R7E5" )
			)
			( gate "@baseboard_fab2_lib.baseboard_fab2(sch_1):page192_i41"
				( attribute "BOM_COST" "CPLD"
					( Origin gFrontEnd )
				)
				( attribute "CDS_LIB" "mstr_discrete"
					( Origin gPackager )
				)
				( attribute "CDS_LOCATION" "R2R3"
					( Origin gPackager )
				)
				( attribute "CDS_SEC" "1"
					( Origin gPackager )
				)
				( attribute "LOCATION" "R2R3"
					( Origin gFrontEnd )
				)
				( attribute "MATERIAL" "CHIP"
					( Origin gFrontEnd )
				)
				( attribute "PACK_TYPE" "0402"
					( Origin gFrontEnd )
				)
				( attribute "PART_NUMBER" "G21796-016"
					( Origin gFrontEnd )
				)
				( attribute "PHYS_PAGE" "192"
					( Origin gFrontEnd )
				)
				( attribute "ROOM" "CPLD"
					( Origin gFrontEnd )
				)
				( attribute "ROT" "0"
					( Origin gFrontEnd )
				)
				( attribute "SEC" "1"
					( Origin gPackager )
				)
				( attribute "TOLERANCE" "1%"
					( Origin gFrontEnd )
				)
				( attribute "VALUE" "10.0K"
					( Origin gFrontEnd )
				)
				( attribute "VER" "2"
					( Origin gFrontEnd )
				)
				( attribute "WATTAGE" "1/16W"
					( Origin gFrontEnd )
				)
				( attribute "XY" "(-6950,4400)"
					( Origin gFrontEnd )
				)
				( attribute "CHIPS_PART_NAME" "RES"
					( Origin gPackager )
				)
				( attribute "CDS_PART_NAME" "RES_0402-10.0K,1%,1/16W,CHIP,GA"
					( Origin gPackager )
				)
				( objectStatus "R2R3" )
			)
			( gate "@baseboard_fab2_lib.baseboard_fab2(sch_1):page192_i48"
				( attribute "BOM_COST" "CPLD"
					( Origin gFrontEnd )
				)
				( attribute "CDS_LIB" "mstr_discrete"
					( Origin gPackager )
				)
				( attribute "CDS_LOCATION" "R3R16"
					( Origin gPackager )
				)
				( attribute "CDS_SEC" "1"
					( Origin gPackager )
				)
				( attribute "LOCATION" "R3R16"
					( Origin gFrontEnd )
				)
				( attribute "MATERIAL" "CHIP"
					( Origin gFrontEnd )
				)
				( attribute "PACK_TYPE" "0402"
					( Origin gFrontEnd )
				)
				( attribute "PART_NUMBER" "G21796-072"
					( Origin gFrontEnd )
				)
				( attribute "PHYS_PAGE" "192"
					( Origin gFrontEnd )
				)
				( attribute "ROOM" "CPLD"
					( Origin gFrontEnd )
				)
				( attribute "ROT" "0"
					( Origin gFrontEnd )
				)
				( attribute "SEC" "1"
					( Origin gFrontEnd )
				)
				( attribute "SEC_TYPE" "0402"
					( Origin gFrontEnd )
				)
				( attribute "TOLERANCE" "1%"
					( Origin gFrontEnd )
				)
				( attribute "VALUE" "4.75K"
					( Origin gFrontEnd )
				)
				( attribute "VER" "2"
					( Origin gFrontEnd )
				)
				( attribute "WATTAGE" "1/16W"
					( Origin gFrontEnd )
				)
				( attribute "XY" "(-6150,2800)"
					( Origin gFrontEnd )
				)
				( attribute "CHIPS_PART_NAME" "RES"
					( Origin gPackager )
				)
				( attribute "CDS_PART_NAME" "RES_0402-4.75K,1%,1/16W,CHIP,GA"
					( Origin gPackager )
				)
				( objectStatus "R3R16" )
			)
			( gate "@baseboard_fab2_lib.baseboard_fab2(sch_1):page192_i49"
				( attribute "BOM_COST" "CPLD"
					( Origin gFrontEnd )
				)
				( attribute "CDS_LIB" "mstr_discrete"
					( Origin gPackager )
				)
				( attribute "CDS_LOCATION" "R6M9"
					( Origin gPackager )
				)
				( attribute "CDS_SEC" "1"
					( Origin gPackager )
				)
				( attribute "LOCATION" "R6M9"
					( Origin gFrontEnd )
				)
				( attribute "MATERIAL" "CHIP"
					( Origin gFrontEnd )
				)
				( attribute "PACK_TYPE" "0402"
					( Origin gFrontEnd )
				)
				( attribute "PART_NUMBER" "G21796-072"
					( Origin gFrontEnd )
				)
				( attribute "PHYS_PAGE" "192"
					( Origin gFrontEnd )
				)
				( attribute "ROOM" "CPLD"
					( Origin gFrontEnd )
				)
				( attribute "ROT" "0"
					( Origin gFrontEnd )
				)
				( attribute "SEC" "1"
					( Origin gFrontEnd )
				)
				( attribute "SEC_TYPE" "0402"
					( Origin gFrontEnd )
				)
				( attribute "TOLERANCE" "1%"
					( Origin gFrontEnd )
				)
				( attribute "VALUE" "4.75K"
					( Origin gFrontEnd )
				)
				( attribute "VER" "2"
					( Origin gFrontEnd )
				)
				( attribute "WATTAGE" "1/16W"
					( Origin gFrontEnd )
				)
				( attribute "XY" "(-5750,2800)"
					( Origin gFrontEnd )
				)
				( attribute "CHIPS_PART_NAME" "RES"
					( Origin gPackager )
				)
				( attribute "CDS_PART_NAME" "RES_0402-4.75K,1%,1/16W,CHIP,GA"
					( Origin gPackager )
				)
				( objectStatus "R6M9" )
			)
			( gate "@baseboard_fab2_lib.baseboard_fab2(sch_1):page192_i55"
				( attribute "BOM_COST" "CPLD"
					( Origin gFrontEnd )
				)
				( attribute "CDS_LIB" "mstr_discrete"
					( Origin gPackager )
				)
				( attribute "CDS_LOCATION" "R7E18"
					( Origin gPackager )
				)
				( attribute "LOCATION" "R7E18"
					( Origin gFrontEnd )
				)
				( attribute "MATERIAL" "CHIP"
					( Origin gFrontEnd )
				)
				( attribute "PACK_TYPE" "0402"
					( Origin gFrontEnd )
				)
				( attribute "PART_NUMBER" "G21796-072"
					( Origin gFrontEnd )
				)
				( attribute "PHYS_PAGE" "192"
					( Origin gFrontEnd )
				)
				( attribute "ROOM" "CPLD"
					( Origin gFrontEnd )
				)
				( attribute "ROT" "0"
					( Origin gFrontEnd )
				)
				( attribute "SEC" "1"
					( Origin gFrontEnd )
				)
				( attribute "TOLERANCE" "1%"
					( Origin gFrontEnd )
				)
				( attribute "VALUE" "4.75K"
					( Origin gFrontEnd )
				)
				( attribute "VER" "2"
					( Origin gFrontEnd )
				)
				( attribute "WATTAGE" "1/16W"
					( Origin gFrontEnd )
				)
				( attribute "XY" "(-7350,4400)"
					( Origin gFrontEnd )
				)
				( attribute "CHIPS_PART_NAME" "RES"
					( Origin gPackager )
				)
				( attribute "CDS_PART_NAME" "RES_0402-4.75K,1%,1/16W,CHIP,GA"
					( Origin gPackager )
				)
				( attribute "SEC_TYPE" "0402"
					( Origin gFrontEnd )
				)
				( attribute "CDS_SEC" "1"
					( Origin gPackager )
				)
				( attribute "POP" "NOPOP"
					( Origin gFrontEnd )
				)
				( objectStatus "R7E18" )
			)
			( gate "@baseboard_fab2_lib.baseboard_fab2(sch_1):page192_i57"
				( attribute "BOM_COST" "CPLD"
					( Origin gFrontEnd )
				)
				( attribute "CDS_LIB" "mstr_discrete"
					( Origin gPackager )
				)
				( attribute "CDS_LOCATION" "R7E19"
					( Origin gPackager )
				)
				( attribute "LOCATION" "R7E19"
					( Origin gFrontEnd )
				)
				( attribute "MATERIAL" "EMPTY"
					( Origin gFrontEnd )
				)
				( attribute "PACK_TYPE" "0402"
					( Origin gFrontEnd )
				)
				( attribute "PART_NUMBER" "G21796-026"
					( Origin gFrontEnd )
				)
				( attribute "PHYS_PAGE" "192"
					( Origin gFrontEnd )
				)
				( attribute "ROOM" "CPLD"
					( Origin gFrontEnd )
				)
				( attribute "ROT" "0"
					( Origin gFrontEnd )
				)
				( attribute "SEC" "1"
					( Origin gFrontEnd )
				)
				( attribute "TOLERANCE" "1%"
					( Origin gFrontEnd )
				)
				( attribute "VALUE" "1.00K"
					( Origin gFrontEnd )
				)
				( attribute "VER" "2"
					( Origin gFrontEnd )
				)
				( attribute "WATTAGE" "1/16W"
					( Origin gFrontEnd )
				)
				( attribute "XY" "(-7750,4400)"
					( Origin gFrontEnd )
				)
				( attribute "CHIPS_PART_NAME" "RES"
					( Origin gPackager )
				)
				( attribute "CDS_PART_NAME" "RES_0402-1.00K,1%,1/16W,EMPTY,A"
					( Origin gPackager )
				)
				( attribute "SEC_TYPE" "0402"
					( Origin gFrontEnd )
				)
				( attribute "CDS_SEC" "1"
					( Origin gPackager )
				)
				( objectStatus "R7E19" )
			)
			( gate "@baseboard_fab2_lib.baseboard_fab2(sch_1):page192_i59"
				( attribute "BOM_COST" "CPLD"
					( Origin gFrontEnd )
				)
				( attribute "CDS_LIB" "mstr_discrete"
					( Origin gPackager )
				)
				( attribute "CDS_LOCATION" "R7E20"
					( Origin gPackager )
				)
				( attribute "LOCATION" "R7E20"
					( Origin gFrontEnd )
				)
				( attribute "MATERIAL" "CHIP"
					( Origin gFrontEnd )
				)
				( attribute "PACK_TYPE" "0402"
					( Origin gFrontEnd )
				)
				( attribute "PART_NUMBER" "G21796-026"
					( Origin gFrontEnd )
				)
				( attribute "PHYS_PAGE" "192"
					( Origin gFrontEnd )
				)
				( attribute "ROOM" "CPLD"
					( Origin gFrontEnd )
				)
				( attribute "ROT" "0"
					( Origin gFrontEnd )
				)
				( attribute "SEC" "1"
					( Origin gFrontEnd )
				)
				( attribute "TOLERANCE" "1%"
					( Origin gFrontEnd )
				)
				( attribute "VALUE" "1.00K"
					( Origin gFrontEnd )
				)
				( attribute "VER" "2"
					( Origin gFrontEnd )
				)
				( attribute "WATTAGE" "1/16W"
					( Origin gFrontEnd )
				)
				( attribute "XY" "(-7750,3500)"
					( Origin gFrontEnd )
				)
				( attribute "CHIPS_PART_NAME" "RES"
					( Origin gPackager )
				)
				( attribute "CDS_PART_NAME" "RES_0402-1.00K,1%,1/16W,CHIP,GA"
					( Origin gPackager )
				)
				( attribute "SEC_TYPE" "0402"
					( Origin gFrontEnd )
				)
				( attribute "CDS_SEC" "1"
					( Origin gPackager )
				)
				( objectStatus "R7E20" )
			)
			( gate "@baseboard_fab2_lib.baseboard_fab2(sch_1):page193_i29"
				( attribute "BOM_COST" "PROC_VRD_VCCIN_CPU1"
					( Origin gFrontEnd )
				)
				( attribute "CDS_LIB" "mstr_discrete"
					( Origin gPackager )
				)
				( attribute "CDS_LOCATION" "C4C1"
					( Origin gPackager )
				)
				( attribute "CDS_SEC" "1"
					( Origin gPackager )
				)
				( attribute "LOCATION" "C4C1"
					( Origin gFrontEnd )
				)
				( attribute "MATERIAL" "ALUM"
					( Origin gFrontEnd )
				)
				( attribute "PACK_TYPE" "3018"
					( Origin gFrontEnd )
				)
				( attribute "PART_NUMBER" "699013-049"
					( Origin gFrontEnd )
				)
				( attribute "PHYS_PAGE" "193"
					( Origin gFrontEnd )
				)
				( attribute "ROOM" "P0V95_MCP_CPU1_DECAP_VR"
					( Origin gFrontEnd )
				)
				( attribute "ROT" "0"
					( Origin gFrontEnd )
				)
				( attribute "SEC" "1"
					( Origin gFrontEnd )
				)
				( attribute "SEC_TYPE" "3018"
					( Origin gFrontEnd )
				)
				( attribute "TOLERANCE" "20%"
					( Origin gFrontEnd )
				)
				( attribute "VALUE" "470UF"
					( Origin gFrontEnd )
				)
				( attribute "VER" "1"
					( Origin gFrontEnd )
				)
				( attribute "VOLTAGE" "2.5V"
					( Units "uVoltage" "V" 1.000000)
					( Origin gFrontEnd )
				)
				( attribute "XY" "(-1900,3950)"
					( Origin gFrontEnd )
				)
				( attribute "CHIPS_PART_NAME" "CAPP"
					( Origin gPackager )
				)
				( attribute "CDS_PART_NAME" "CAPP_3018-470UF,2.5V,20%,ALUM,A"
					( Origin gPackager )
				)
				( attribute "GROUP" "PWR_MCP_CAP"
					( Origin gFrontEnd )
				)
				( objectStatus "C4C1" )
			)
			( gate "@baseboard_fab2_lib.baseboard_fab2(sch_1):page193_i31"
				( attribute "CDS_LIB" "dev_discrete"
					( Origin gPackager )
				)
				( attribute "CDS_LOCATION" "C3C2"
					( Origin gPackager )
				)
				( attribute "CDS_SEC" "1"
					( Origin gPackager )
				)
				( attribute "LOCATION" "C3C2"
					( Origin gFrontEnd )
				)
				( attribute "MATERIAL" "X6S"
					( Origin gFrontEnd )
				)
				( attribute "PACK_TYPE" "0402V"
					( Origin gFrontEnd )
				)
				( attribute "PART_NUMBER" "D97712-004"
					( Origin gFrontEnd )
				)
				( attribute "PHYS_PAGE" "193"
					( Origin gFrontEnd )
				)
				( attribute "ROOM" "P0V95_FPGA_CPU1"
					( Origin gFrontEnd )
				)
				( attribute "ROT" "0"
					( Origin gFrontEnd )
				)
				( attribute "SEC" "1"
					( Origin gFrontEnd )
				)
				( attribute "SEC_TYPE" "0402V"
					( Origin gFrontEnd )
				)
				( attribute "TOLERANCE" "10%"
					( Origin gFrontEnd )
				)
				( attribute "VALUE" "1.0UF"
					( Origin gFrontEnd )
				)
				( attribute "VER" "1"
					( Origin gFrontEnd )
				)
				( attribute "VOLTAGE" "6.3V"
					( Units "uVoltage" "V" 1.000000)
					( Origin gFrontEnd )
				)
				( attribute "XY" "(-1300,3950)"
					( Origin gFrontEnd )
				)
				( attribute "CHIPS_PART_NAME" "CAP_A"
					( Origin gPackager )
				)
				( attribute "CDS_PART_NAME" "CAP_A_0402V-1.0UF,6.3V,10%,X6SA"
					( Origin gPackager )
				)
				( attribute "GROUP" "PWR_MCP_CAP"
					( Origin gFrontEnd )
				)
				( objectStatus "C3C2" )
			)
			( gate "@baseboard_fab2_lib.baseboard_fab2(sch_1):page193_i38"
				( attribute "CDS_LIB" "dev_discrete"
					( Origin gPackager )
				)
				( attribute "CDS_LOCATION" "C3C1"
					( Origin gPackager )
				)
				( attribute "CDS_SEC" "1"
					( Origin gPackager )
				)
				( attribute "LOCATION" "C3C1"
					( Origin gFrontEnd )
				)
				( attribute "MATERIAL" "X6S"
					( Origin gFrontEnd )
				)
				( attribute "PACK_TYPE" "0402V"
					( Origin gFrontEnd )
				)
				( attribute "PART_NUMBER" "D97712-004"
					( Origin gFrontEnd )
				)
				( attribute "PHYS_PAGE" "193"
					( Origin gFrontEnd )
				)
				( attribute "ROOM" "P0V95_FPGA_CPU1"
					( Origin gFrontEnd )
				)
				( attribute "ROT" "0"
					( Origin gFrontEnd )
				)
				( attribute "SEC" "1"
					( Origin gFrontEnd )
				)
				( attribute "SEC_TYPE" "0402V"
					( Origin gFrontEnd )
				)
				( attribute "TOLERANCE" "10%"
					( Origin gFrontEnd )
				)
				( attribute "VALUE" "1.0UF"
					( Origin gFrontEnd )
				)
				( attribute "VER" "1"
					( Origin gFrontEnd )
				)
				( attribute "VOLTAGE" "6.3V"
					( Units "uVoltage" "V" 1.000000)
					( Origin gFrontEnd )
				)
				( attribute "XY" "(-1600,3950)"
					( Origin gFrontEnd )
				)
				( attribute "CHIPS_PART_NAME" "CAP_A"
					( Origin gPackager )
				)
				( attribute "CDS_PART_NAME" "CAP_A_0402V-1.0UF,6.3V,10%,X6SA"
					( Origin gPackager )
				)
				( attribute "GROUP" "PWR_MCP_CAP"
					( Origin gFrontEnd )
				)
				( objectStatus "C3C1" )
			)
			( gate "@baseboard_fab2_lib.baseboard_fab2(sch_1):page193_i45"
				( attribute "CDS_LIB" "mstr_sconn"
					( Origin gPackager )
				)
				( attribute "CDS_LOCATION" "J4E1"
					( Origin gPackager )
				)
				( attribute "CDS_SEC" "1"
					( Origin gPackager )
				)
				( attribute "LOCATION" "J4E1"
					( Origin gFrontEnd )
				)
				( attribute "MATERIAL" "CONN"
					( Origin gFrontEnd )
				)
				( attribute "PACK_TYPE" "SM"
					( Origin gFrontEnd )
				)
				( attribute "PART_NUMBER" "H61426-002"
					( Origin gFrontEnd )
				)
				( attribute "PHYS_PAGE" "193"
					( Origin gFrontEnd )
				)
				( attribute "ROOM" "MCP VRM CPU1"
					( Origin gFrontEnd )
				)
				( attribute "ROT" "0"
					( Origin gFrontEnd )
				)
				( attribute "SEC" "1"
					( Origin gFrontEnd )
				)
				( attribute "SEC_TYPE" "SM"
					( Origin gFrontEnd )
				)
				( attribute "VER" "1"
					( Origin gFrontEnd )
				)
				( attribute "XY" "(-3150,2800)"
					( Origin gFrontEnd )
				)
				( attribute "CHIPS_PART_NAME" "SCONN120_H61426002"
					( Origin gPackager )
				)
				( attribute "CDS_PART_NAME" "SCONN120_H61426002_SM-CONN,H61A"
					( Origin gPackager )
				)
				( attribute "GROUP" "MCP"
					( Origin gFrontEnd )
				)
				( objectStatus "J4E1" )
			)
			( gate "@baseboard_fab2_lib.baseboard_fab2(sch_1):page193_i46"
				( attribute "CDS_LIB" "mstr_sconn"
					( Origin gPackager )
				)
				( attribute "CDS_LOCATION" "J4B2"
					( Origin gPackager )
				)
				( attribute "CDS_SEC" "1"
					( Origin gPackager )
				)
				( attribute "LOCATION" "J4B2"
					( Origin gFrontEnd )
				)
				( attribute "MATERIAL" "CONN"
					( Origin gFrontEnd )
				)
				( attribute "PACK_TYPE" "SM"
					( Origin gFrontEnd )
				)
				( attribute "PART_NUMBER" "H61426-002"
					( Origin gFrontEnd )
				)
				( attribute "PHYS_PAGE" "193"
					( Origin gFrontEnd )
				)
				( attribute "ROOM" "MCP VRM CPU1"
					( Origin gFrontEnd )
				)
				( attribute "ROT" "0"
					( Origin gFrontEnd )
				)
				( attribute "SEC" "1"
					( Origin gFrontEnd )
				)
				( attribute "SEC_TYPE" "SM"
					( Origin gFrontEnd )
				)
				( attribute "VER" "1"
					( Origin gFrontEnd )
				)
				( attribute "XY" "(-6325,2725)"
					( Origin gFrontEnd )
				)
				( attribute "CHIPS_PART_NAME" "SCONN120_H61426002"
					( Origin gPackager )
				)
				( attribute "CDS_PART_NAME" "SCONN120_H61426002_SM-CONN,H61A"
					( Origin gPackager )
				)
				( attribute "GROUP" "MCP"
					( Origin gFrontEnd )
				)
				( objectStatus "J4B2" )
			)
			( gate "@baseboard_fab2_lib.baseboard_fab2(sch_1):page193_i61"
				( attribute "BOM_COST" "PVMCP_MCP_CPU1_VR"
					( Origin gFrontEnd )
				)
				( attribute "CDS_LIB" "mstr_discrete"
					( Origin gPackager )
				)
				( attribute "CDS_LOCATION" "C4E24"
					( Origin gPackager )
				)
				( attribute "CDS_SEC" "1"
					( Origin gPackager )
				)
				( attribute "LOCATION" "C4E24"
					( Origin gFrontEnd )
				)
				( attribute "MATERIAL" "ALUM"
					( Origin gFrontEnd )
				)
				( attribute "PACK_TYPE" "3018"
					( Origin gFrontEnd )
				)
				( attribute "PART_NUMBER" "699013-049"
					( Origin gFrontEnd )
				)
				( attribute "PHYS_PAGE" "193"
					( Origin gFrontEnd )
				)
				( attribute "ROOM" "PVMCP_MCP_CPU1_VR"
					( Origin gFrontEnd )
				)
				( attribute "ROT" "0"
					( Origin gFrontEnd )
				)
				( attribute "SEC" "1"
					( Origin gPackager )
				)
				( attribute "TOLERANCE" "20%"
					( Origin gFrontEnd )
				)
				( attribute "VALUE" "470UF"
					( Origin gFrontEnd )
				)
				( attribute "VER" "1"
					( Origin gFrontEnd )
				)
				( attribute "VOLTAGE" "2.5V"
					( Units "uVoltage" "V" 1.000000)
					( Origin gFrontEnd )
				)
				( attribute "XY" "(-1900,3100)"
					( Origin gFrontEnd )
				)
				( attribute "CHIPS_PART_NAME" "CAPP"
					( Origin gPackager )
				)
				( attribute "CDS_PART_NAME" "CAPP_3018-470UF,2.5V,20%,ALUM,A"
					( Origin gPackager )
				)
				( attribute "GROUP" "PWR_MCP_CAP"
					( Origin gFrontEnd )
				)
				( objectStatus "C4E24" )
			)
			( gate "@baseboard_fab2_lib.baseboard_fab2(sch_1):page193_i62"
				( attribute "BOM_COST" "PVMCP_MCP_CPU1_VR"
					( Origin gFrontEnd )
				)
				( attribute "CDS_LIB" "mstr_discrete"
					( Origin gPackager )
				)
				( attribute "CDS_LOCATION" "C6R16"
					( Origin gPackager )
				)
				( attribute "CDS_SEC" "1"
					( Origin gPackager )
				)
				( attribute "LOCATION" "C6R16"
					( Origin gFrontEnd )
				)
				( attribute "MATERIAL" "ALUM"
					( Origin gFrontEnd )
				)
				( attribute "PACK_TYPE" "3018"
					( Origin gFrontEnd )
				)
				( attribute "PART_NUMBER" "699013-049"
					( Origin gFrontEnd )
				)
				( attribute "PHYS_PAGE" "193"
					( Origin gFrontEnd )
				)
				( attribute "ROOM" "PVMCP_MCP_CPU1_VR"
					( Origin gFrontEnd )
				)
				( attribute "ROT" "0"
					( Origin gFrontEnd )
				)
				( attribute "SEC" "1"
					( Origin gFrontEnd )
				)
				( attribute "SEC_TYPE" "3018"
					( Origin gFrontEnd )
				)
				( attribute "TOLERANCE" "20%"
					( Origin gFrontEnd )
				)
				( attribute "VALUE" "470UF"
					( Origin gFrontEnd )
				)
				( attribute "VER" "1"
					( Origin gFrontEnd )
				)
				( attribute "VOLTAGE" "2.5V"
					( Units "uVoltage" "V" 1.000000)
					( Origin gFrontEnd )
				)
				( attribute "XY" "(-1600,3100)"
					( Origin gFrontEnd )
				)
				( attribute "CHIPS_PART_NAME" "CAPP"
					( Origin gPackager )
				)
				( attribute "CDS_PART_NAME" "CAPP_3018-470UF,2.5V,20%,ALUM,A"
					( Origin gPackager )
				)
				( attribute "GROUP" "PWR_MCP_CAP"
					( Origin gFrontEnd )
				)
				( objectStatus "C6R16" )
			)
			( gate "@baseboard_fab2_lib.baseboard_fab2(sch_1):page193_i68"
				( attribute "CDS_LIB" "dev_discrete"
					( Origin gPackager )
				)
				( attribute "CDS_LOCATION" "C4F1"
					( Origin gPackager )
				)
				( attribute "CDS_SEC" "1"
					( Origin gPackager )
				)
				( attribute "LOCATION" "C4F1"
					( Origin gFrontEnd )
				)
				( attribute "MATERIAL" "X6S"
					( Origin gFrontEnd )
				)
				( attribute "PACK_TYPE" "0402V"
					( Origin gFrontEnd )
				)
				( attribute "PART_NUMBER" "D97712-004"
					( Origin gFrontEnd )
				)
				( attribute "PHYS_PAGE" "193"
					( Origin gFrontEnd )
				)
				( attribute "ROOM" "P1V8_MCP_CPU1"
					( Origin gFrontEnd )
				)
				( attribute "ROT" "0"
					( Origin gFrontEnd )
				)
				( attribute "SEC" "1"
					( Origin gFrontEnd )
				)
				( attribute "SEC_TYPE" "0402V"
					( Origin gFrontEnd )
				)
				( attribute "TOLERANCE" "10%"
					( Origin gFrontEnd )
				)
				( attribute "VALUE" "1.0UF"
					( Origin gFrontEnd )
				)
				( attribute "VER" "1"
					( Origin gFrontEnd )
				)
				( attribute "VOLTAGE" "6.3V"
					( Units "uVoltage" "V" 1.000000)
					( Origin gFrontEnd )
				)
				( attribute "XY" "(-1000,2450)"
					( Origin gFrontEnd )
				)
				( attribute "CHIPS_PART_NAME" "CAP_A"
					( Origin gPackager )
				)
				( attribute "CDS_PART_NAME" "CAP_A_0402V-1.0UF,6.3V,10%,X6SA"
					( Origin gPackager )
				)
				( attribute "GROUP" "PWR_MCP_CAP"
					( Origin gFrontEnd )
				)
				( objectStatus "C4F1" )
			)
			( gate "@baseboard_fab2_lib.baseboard_fab2(sch_1):page193_i70"
				( attribute "CDS_LIB" "dev_discrete"
					( Origin gPackager )
				)
				( attribute "CDS_LOCATION" "C4F3"
					( Origin gPackager )
				)
				( attribute "CDS_SEC" "1"
					( Origin gPackager )
				)
				( attribute "LOCATION" "C4F3"
					( Origin gFrontEnd )
				)
				( attribute "MATERIAL" "X6S"
					( Origin gFrontEnd )
				)
				( attribute "PACK_TYPE" "0402V"
					( Origin gFrontEnd )
				)
				( attribute "PART_NUMBER" "D97712-004"
					( Origin gFrontEnd )
				)
				( attribute "PHYS_PAGE" "193"
					( Origin gFrontEnd )
				)
				( attribute "ROOM" "P1V8_MCP_CPU1"
					( Origin gFrontEnd )
				)
				( attribute "ROT" "0"
					( Origin gFrontEnd )
				)
				( attribute "SEC" "1"
					( Origin gFrontEnd )
				)
				( attribute "SEC_TYPE" "0402V"
					( Origin gFrontEnd )
				)
				( attribute "TOLERANCE" "10%"
					( Origin gFrontEnd )
				)
				( attribute "VALUE" "1.0UF"
					( Origin gFrontEnd )
				)
				( attribute "VER" "1"
					( Origin gFrontEnd )
				)
				( attribute "VOLTAGE" "6.3V"
					( Units "uVoltage" "V" 1.000000)
					( Origin gFrontEnd )
				)
				( attribute "XY" "(-1300,2450)"
					( Origin gFrontEnd )
				)
				( attribute "CHIPS_PART_NAME" "CAP_A"
					( Origin gPackager )
				)
				( attribute "CDS_PART_NAME" "CAP_A_0402V-1.0UF,6.3V,10%,X6SA"
					( Origin gPackager )
				)
				( attribute "GROUP" "PWR_MCP_CAP"
					( Origin gFrontEnd )
				)
				( objectStatus "C4F3" )
			)
			( gate "@baseboard_fab2_lib.baseboard_fab2(sch_1):page193_i140"
				( attribute "CDS_LIB" "dev_discrete"
					( Origin gPackager )
				)
				( attribute "CDS_LOCATION" "C3F1"
					( Origin gPackager )
				)
				( attribute "CDS_SEC" "1"
					( Origin gPackager )
				)
				( attribute "LOCATION" "C3F1"
					( Origin gFrontEnd )
				)
				( attribute "MATERIAL" "X5R"
					( Origin gFrontEnd )
				)
				( attribute "PACK_TYPE" "0603V"
					( Origin gFrontEnd )
				)
				( attribute "PART_NUMBER" "602433-106"
					( Origin gFrontEnd )
				)
				( attribute "PHYS_PAGE" "193"
					( Origin gFrontEnd )
				)
				( attribute "ROT" "0"
					( Origin gFrontEnd )
				)
				( attribute "SEC" "1"
					( Origin gFrontEnd )
				)
				( attribute "SEC_TYPE" "0603V"
					( Origin gFrontEnd )
				)
				( attribute "TOLERANCE" "20%"
					( Origin gFrontEnd )
				)
				( attribute "VALUE" "47UF"
					( Origin gFrontEnd )
				)
				( attribute "VER" "1"
					( Origin gFrontEnd )
				)
				( attribute "VOLTAGE" "4V"
					( Units "uVoltage" "V" 1.000000)
					( Origin gFrontEnd )
				)
				( attribute "XY" "(-1900,2450)"
					( Origin gFrontEnd )
				)
				( attribute "CHIPS_PART_NAME" "CAP_A"
					( Origin gPackager )
				)
				( attribute "CDS_PART_NAME" "CAP_A_0603V-47UF,4V,20%,X5R,60A"
					( Origin gPackager )
				)
				( attribute "GROUP" "PWR_MCP_CAP"
					( Origin gFrontEnd )
				)
				( objectStatus "C3F1" )
			)
			( gate "@baseboard_fab2_lib.baseboard_fab2(sch_1):page193_i141"
				( attribute "CDS_LIB" "dev_discrete"
					( Origin gPackager )
				)
				( attribute "CDS_LOCATION" "C4F2"
					( Origin gPackager )
				)
				( attribute "CDS_SEC" "1"
					( Origin gPackager )
				)
				( attribute "LOCATION" "C4F2"
					( Origin gFrontEnd )
				)
				( attribute "MATERIAL" "X5R"
					( Origin gFrontEnd )
				)
				( attribute "PACK_TYPE" "0603V"
					( Origin gFrontEnd )
				)
				( attribute "PART_NUMBER" "602433-106"
					( Origin gFrontEnd )
				)
				( attribute "PHYS_PAGE" "193"
					( Origin gFrontEnd )
				)
				( attribute "ROT" "0"
					( Origin gFrontEnd )
				)
				( attribute "SEC" "1"
					( Origin gFrontEnd )
				)
				( attribute "SEC_TYPE" "0603V"
					( Origin gFrontEnd )
				)
				( attribute "TOLERANCE" "20%"
					( Origin gFrontEnd )
				)
				( attribute "VALUE" "47UF"
					( Origin gFrontEnd )
				)
				( attribute "VER" "1"
					( Origin gFrontEnd )
				)
				( attribute "VOLTAGE" "4V"
					( Units "uVoltage" "V" 1.000000)
					( Origin gFrontEnd )
				)
				( attribute "XY" "(-1600,2450)"
					( Origin gFrontEnd )
				)
				( attribute "CHIPS_PART_NAME" "CAP_A"
					( Origin gPackager )
				)
				( attribute "CDS_PART_NAME" "CAP_A_0603V-47UF,4V,20%,X5R,60A"
					( Origin gPackager )
				)
				( attribute "GROUP" "PWR_MCP_CAP"
					( Origin gFrontEnd )
				)
				( objectStatus "C4F2" )
			)
			( gate "@baseboard_fab2_lib.baseboard_fab2(sch_1):page193_i169"
				( attribute "CDS_LIB" "mstr_discrete"
					( Origin gPackager )
				)
				( attribute "CDS_LOCATION" "R4C12"
					( Origin gPackager )
				)
				( attribute "CDS_SEC" "1"
					( Origin gPackager )
				)
				( attribute "LOCATION" "R4C12"
					( Origin gFrontEnd )
				)
				( attribute "MATERIAL" "CHIP"
					( Origin gFrontEnd )
				)
				( attribute "PACK_TYPE" "0402"
					( Origin gFrontEnd )
				)
				( attribute "PART_NUMBER" "G21796-078"
					( Origin gFrontEnd )
				)
				( attribute "PHYS_PAGE" "193"
					( Origin gFrontEnd )
				)
				( attribute "ROOM" "PVCCIN_CPU0_VR"
					( Origin gFrontEnd )
				)
				( attribute "ROT" "0"
					( Origin gFrontEnd )
				)
				( attribute "SEC" "1"
					( Origin gFrontEnd )
				)
				( attribute "SEC_TYPE" "0402"
					( Origin gFrontEnd )
				)
				( attribute "TOLERANCE" "1%"
					( Origin gFrontEnd )
				)
				( attribute "VALUE" "8.06K"
					( Origin gFrontEnd )
				)
				( attribute "VER" "2"
					( Origin gFrontEnd )
				)
				( attribute "WATTAGE" "1/16W"
					( Origin gFrontEnd )
				)
				( attribute "XY" "(-7950,775)"
					( Origin gFrontEnd )
				)
				( attribute "CHIPS_PART_NAME" "RES"
					( Origin gPackager )
				)
				( attribute "CDS_PART_NAME" "RES_0402-8.06K,1%,1/16W,CHIP,GA"
					( Origin gPackager )
				)
				( attribute "GROUP" "MCP"
					( Origin gFrontEnd )
				)
				( objectStatus "R4C12" )
			)
			( gate "@baseboard_fab2_lib.baseboard_fab2(sch_1):page193_i170"
				( attribute "CDS_LIB" "mstr_discrete"
					( Origin gPackager )
				)
				( attribute "CDS_LOCATION" "R4C11"
					( Origin gPackager )
				)
				( attribute "CDS_SEC" "1"
					( Origin gPackager )
				)
				( attribute "LOCATION" "R4C11"
					( Origin gFrontEnd )
				)
				( attribute "MATERIAL" "CHIP"
					( Origin gFrontEnd )
				)
				( attribute "PACK_TYPE" "0402"
					( Origin gFrontEnd )
				)
				( attribute "PART_NUMBER" "G21796-043"
					( Origin gFrontEnd )
				)
				( attribute "PHYS_PAGE" "193"
					( Origin gFrontEnd )
				)
				( attribute "ROOM" "PVCCIN_CPU0_VR"
					( Origin gFrontEnd )
				)
				( attribute "ROT" "0"
					( Origin gFrontEnd )
				)
				( attribute "SEC" "1"
					( Origin gFrontEnd )
				)
				( attribute "SEC_TYPE" "0402"
					( Origin gFrontEnd )
				)
				( attribute "TOLERANCE" "1%"
					( Origin gFrontEnd )
				)
				( attribute "VALUE" "3.16K"
					( Origin gFrontEnd )
				)
				( attribute "VER" "2"
					( Origin gFrontEnd )
				)
				( attribute "WATTAGE" "1/16W"
					( Origin gFrontEnd )
				)
				( attribute "XY" "(-7600,750)"
					( Origin gFrontEnd )
				)
				( attribute "CHIPS_PART_NAME" "RES"
					( Origin gPackager )
				)
				( attribute "CDS_PART_NAME" "RES_0402-3.16K,1%,1/16W,CHIP,GA"
					( Origin gPackager )
				)
				( attribute "GROUP" "MCP"
					( Origin gFrontEnd )
				)
				( objectStatus "R4C11" )
			)
			( gate "@baseboard_fab2_lib.baseboard_fab2(sch_1):page194_i9"
				( attribute "CDS_LIB" "dev_discrete"
					( Origin gPackager )
				)
				( attribute "CDS_LOCATION" "C4T2"
					( Origin gPackager )
				)
				( attribute "CDS_SEC" "1"
					( Origin gPackager )
				)
				( attribute "LOCATION" "C4T2"
					( Origin gFrontEnd )
				)
				( attribute "MATERIAL" "X6S"
					( Origin gFrontEnd )
				)
				( attribute "PACK_TYPE" "0402V"
					( Origin gFrontEnd )
				)
				( attribute "PART_NUMBER" "D97712-004"
					( Origin gFrontEnd )
				)
				( attribute "PHYS_PAGE" "194"
					( Origin gFrontEnd )
				)
				( attribute "ROOM" "P1V8_MCP_CPU0"
					( Origin gFrontEnd )
				)
				( attribute "ROT" "0"
					( Origin gFrontEnd )
				)
				( attribute "SEC" "1"
					( Origin gFrontEnd )
				)
				( attribute "SEC_TYPE" "0402V"
					( Origin gFrontEnd )
				)
				( attribute "TOLERANCE" "10%"
					( Origin gFrontEnd )
				)
				( attribute "VALUE" "1.0UF"
					( Origin gFrontEnd )
				)
				( attribute "VER" "1"
					( Origin gFrontEnd )
				)
				( attribute "VOLTAGE" "6.3V"
					( Units "uVoltage" "V" 1.000000)
					( Origin gFrontEnd )
				)
				( attribute "XY" "(-1000,1850)"
					( Origin gFrontEnd )
				)
				( attribute "CHIPS_PART_NAME" "CAP_A"
					( Origin gPackager )
				)
				( attribute "CDS_PART_NAME" "CAP_A_0402V-1.0UF,6.3V,10%,X6SA"
					( Origin gPackager )
				)
				( attribute "GROUP" "PWR_MCP_CAP"
					( Origin gFrontEnd )
				)
				( objectStatus "C4T2" )
			)
			( gate "@baseboard_fab2_lib.baseboard_fab2(sch_1):page194_i16"
				( attribute "CDS_LIB" "dev_discrete"
					( Origin gPackager )
				)
				( attribute "CDS_LOCATION" "C4T1"
					( Origin gPackager )
				)
				( attribute "CDS_SEC" "1"
					( Origin gPackager )
				)
				( attribute "LOCATION" "C4T1"
					( Origin gFrontEnd )
				)
				( attribute "MATERIAL" "X6S"
					( Origin gFrontEnd )
				)
				( attribute "PACK_TYPE" "0402V"
					( Origin gFrontEnd )
				)
				( attribute "PART_NUMBER" "D97712-004"
					( Origin gFrontEnd )
				)
				( attribute "PHYS_PAGE" "194"
					( Origin gFrontEnd )
				)
				( attribute "ROOM" "P1V8_MCP_CPU0"
					( Origin gFrontEnd )
				)
				( attribute "ROT" "0"
					( Origin gFrontEnd )
				)
				( attribute "SEC" "1"
					( Origin gFrontEnd )
				)
				( attribute "SEC_TYPE" "0402V"
					( Origin gFrontEnd )
				)
				( attribute "TOLERANCE" "10%"
					( Origin gFrontEnd )
				)
				( attribute "VALUE" "1.0UF"
					( Origin gFrontEnd )
				)
				( attribute "VER" "1"
					( Origin gFrontEnd )
				)
				( attribute "VOLTAGE" "6.3V"
					( Units "uVoltage" "V" 1.000000)
					( Origin gFrontEnd )
				)
				( attribute "XY" "(-1300,1850)"
					( Origin gFrontEnd )
				)
				( attribute "CHIPS_PART_NAME" "CAP_A"
					( Origin gPackager )
				)
				( attribute "CDS_PART_NAME" "CAP_A_0402V-1.0UF,6.3V,10%,X6SA"
					( Origin gPackager )
				)
				( attribute "GROUP" "PWR_MCP_CAP"
					( Origin gFrontEnd )
				)
				( objectStatus "C4T1" )
			)
			( gate "@baseboard_fab2_lib.baseboard_fab2(sch_1):page194_i29"
				( attribute "BOM_COST" "PVMCP_MCP_CPU0_VR"
					( Origin gFrontEnd )
				)
				( attribute "CDS_LIB" "mstr_discrete"
					( Origin gPackager )
				)
				( attribute "CDS_LOCATION" "C4R1"
					( Origin gPackager )
				)
				( attribute "CDS_SEC" "1"
					( Origin gPackager )
				)
				( attribute "LOCATION" "C4R1"
					( Origin gFrontEnd )
				)
				( attribute "MATERIAL" "ALUM"
					( Origin gFrontEnd )
				)
				( attribute "PACK_TYPE" "3018"
					( Origin gFrontEnd )
				)
				( attribute "PART_NUMBER" "699013-049"
					( Origin gFrontEnd )
				)
				( attribute "PHYS_PAGE" "194"
					( Origin gFrontEnd )
				)
				( attribute "ROOM" "PVMCP_MCP_CPU0_VR"
					( Origin gFrontEnd )
				)
				( attribute "ROT" "0"
					( Origin gFrontEnd )
				)
				( attribute "SEC" "1"
					( Origin gFrontEnd )
				)
				( attribute "SEC_TYPE" "3018"
					( Origin gFrontEnd )
				)
				( attribute "TOLERANCE" "20%"
					( Origin gFrontEnd )
				)
				( attribute "VALUE" "470UF"
					( Origin gFrontEnd )
				)
				( attribute "VER" "1"
					( Origin gFrontEnd )
				)
				( attribute "VOLTAGE" "2.5V"
					( Units "uVoltage" "V" 1.000000)
					( Origin gFrontEnd )
				)
				( attribute "XY" "(-1600,2500)"
					( Origin gFrontEnd )
				)
				( attribute "CHIPS_PART_NAME" "CAPP"
					( Origin gPackager )
				)
				( attribute "CDS_PART_NAME" "CAPP_3018-470UF,2.5V,20%,ALUM,A"
					( Origin gPackager )
				)
				( attribute "GROUP" "PWR_MCP_CAP"
					( Origin gFrontEnd )
				)
				( objectStatus "C4R1" )
			)
			( gate "@baseboard_fab2_lib.baseboard_fab2(sch_1):page194_i31"
				( attribute "BOM_COST" "PVMCP_MCP_CPU0_VR"
					( Origin gFrontEnd )
				)
				( attribute "CDS_LIB" "mstr_discrete"
					( Origin gPackager )
				)
				( attribute "CDS_LOCATION" "C3R4"
					( Origin gPackager )
				)
				( attribute "CDS_SEC" "1"
					( Origin gPackager )
				)
				( attribute "LOCATION" "C3R4"
					( Origin gFrontEnd )
				)
				( attribute "MATERIAL" "ALUM"
					( Origin gFrontEnd )
				)
				( attribute "PACK_TYPE" "3018"
					( Origin gFrontEnd )
				)
				( attribute "PART_NUMBER" "699013-049"
					( Origin gFrontEnd )
				)
				( attribute "PHYS_PAGE" "194"
					( Origin gFrontEnd )
				)
				( attribute "ROOM" "PVMCP_MCP_CPU0_VR"
					( Origin gFrontEnd )
				)
				( attribute "ROT" "0"
					( Origin gFrontEnd )
				)
				( attribute "SEC" "1"
					( Origin gPackager )
				)
				( attribute "TOLERANCE" "20%"
					( Origin gFrontEnd )
				)
				( attribute "VALUE" "470UF"
					( Origin gFrontEnd )
				)
				( attribute "VER" "1"
					( Origin gFrontEnd )
				)
				( attribute "VOLTAGE" "2.5V"
					( Units "uVoltage" "V" 1.000000)
					( Origin gFrontEnd )
				)
				( attribute "XY" "(-1900,2500)"
					( Origin gFrontEnd )
				)
				( attribute "CHIPS_PART_NAME" "CAPP"
					( Origin gPackager )
				)
				( attribute "CDS_PART_NAME" "CAPP_3018-470UF,2.5V,20%,ALUM,A"
					( Origin gPackager )
				)
				( attribute "GROUP" "PWR_MCP_CAP"
					( Origin gFrontEnd )
				)
				( objectStatus "C3R4" )
			)
			( gate "@baseboard_fab2_lib.baseboard_fab2(sch_1):page194_i55"
				( attribute "CDS_LIB" "mstr_sconn"
					( Origin gPackager )
				)
				( attribute "CDS_LOCATION" "J6E1"
					( Origin gPackager )
				)
				( attribute "CDS_SEC" "1"
					( Origin gPackager )
				)
				( attribute "LOCATION" "J6E1"
					( Origin gFrontEnd )
				)
				( attribute "MATERIAL" "CONN"
					( Origin gFrontEnd )
				)
				( attribute "PACK_TYPE" "SM"
					( Origin gFrontEnd )
				)
				( attribute "PART_NUMBER" "H61426-002"
					( Origin gFrontEnd )
				)
				( attribute "PHYS_PAGE" "194"
					( Origin gFrontEnd )
				)
				( attribute "ROOM" "MCP VRM CPU0"
					( Origin gFrontEnd )
				)
				( attribute "ROT" "0"
					( Origin gFrontEnd )
				)
				( attribute "SEC" "1"
					( Origin gFrontEnd )
				)
				( attribute "SEC_TYPE" "SM"
					( Origin gFrontEnd )
				)
				( attribute "VER" "1"
					( Origin gFrontEnd )
				)
				( attribute "XY" "(-3150,2100)"
					( Origin gFrontEnd )
				)
				( attribute "CHIPS_PART_NAME" "SCONN120_H61426002"
					( Origin gPackager )
				)
				( attribute "CDS_PART_NAME" "SCONN120_H61426002_SM-CONN,H61A"
					( Origin gPackager )
				)
				( attribute "GROUP" "MCP"
					( Origin gFrontEnd )
				)
				( objectStatus "J6E1" )
			)
			( gate "@baseboard_fab2_lib.baseboard_fab2(sch_1):page194_i56"
				( attribute "CDS_LIB" "mstr_sconn"
					( Origin gPackager )
				)
				( attribute "CDS_LOCATION" "J6B1"
					( Origin gPackager )
				)
				( attribute "CDS_SEC" "1"
					( Origin gPackager )
				)
				( attribute "LOCATION" "J6B1"
					( Origin gFrontEnd )
				)
				( attribute "MATERIAL" "CONN"
					( Origin gFrontEnd )
				)
				( attribute "PACK_TYPE" "SM"
					( Origin gFrontEnd )
				)
				( attribute "PART_NUMBER" "H61426-002"
					( Origin gFrontEnd )
				)
				( attribute "PHYS_PAGE" "194"
					( Origin gFrontEnd )
				)
				( attribute "ROOM" "MCP VRM CPU0"
					( Origin gFrontEnd )
				)
				( attribute "ROT" "0"
					( Origin gFrontEnd )
				)
				( attribute "SEC" "1"
					( Origin gFrontEnd )
				)
				( attribute "SEC_TYPE" "SM"
					( Origin gFrontEnd )
				)
				( attribute "VER" "1"
					( Origin gFrontEnd )
				)
				( attribute "XY" "(-6550,2075)"
					( Origin gFrontEnd )
				)
				( attribute "CHIPS_PART_NAME" "SCONN120_H61426002"
					( Origin gPackager )
				)
				( attribute "CDS_PART_NAME" "SCONN120_H61426002_SM-CONN,H61A"
					( Origin gPackager )
				)
				( attribute "GROUP" "MCP"
					( Origin gFrontEnd )
				)
				( objectStatus "J6B1" )
			)
			( gate "@baseboard_fab2_lib.baseboard_fab2(sch_1):page194_i86"
				( attribute "CDS_LIB" "dev_discrete"
					( Origin gPackager )
				)
				( attribute "CDS_LOCATION" "C3N40"
					( Origin gPackager )
				)
				( attribute "CDS_SEC" "1"
					( Origin gPackager )
				)
				( attribute "LOCATION" "C3N40"
					( Origin gFrontEnd )
				)
				( attribute "MATERIAL" "X6S"
					( Origin gFrontEnd )
				)
				( attribute "PACK_TYPE" "0402V"
					( Origin gFrontEnd )
				)
				( attribute "PART_NUMBER" "D97712-004"
					( Origin gFrontEnd )
				)
				( attribute "PHYS_PAGE" "194"
					( Origin gFrontEnd )
				)
				( attribute "ROOM" "P0V95_MCP_CPU0"
					( Origin gFrontEnd )
				)
				( attribute "ROT" "0"
					( Origin gFrontEnd )
				)
				( attribute "SEC" "1"
					( Origin gFrontEnd )
				)
				( attribute "SEC_TYPE" "0402V"
					( Origin gFrontEnd )
				)
				( attribute "TOLERANCE" "10%"
					( Origin gFrontEnd )
				)
				( attribute "VALUE" "1.0UF"
					( Origin gFrontEnd )
				)
				( attribute "VER" "1"
					( Origin gFrontEnd )
				)
				( attribute "VOLTAGE" "6.3V"
					( Units "uVoltage" "V" 1.000000)
					( Origin gFrontEnd )
				)
				( attribute "XY" "(-1100,3100)"
					( Origin gFrontEnd )
				)
				( attribute "CHIPS_PART_NAME" "CAP_A"
					( Origin gPackager )
				)
				( attribute "CDS_PART_NAME" "CAP_A_0402V-1.0UF,6.3V,10%,X6SA"
					( Origin gPackager )
				)
				( attribute "GROUP" "PWR_MCP_CAP"
					( Origin gFrontEnd )
				)
				( objectStatus "C3N40" )
			)
			( gate "@baseboard_fab2_lib.baseboard_fab2(sch_1):page194_i99"
				( attribute "CDS_LIB" "dev_discrete"
					( Origin gPackager )
				)
				( attribute "CDS_SEC" "1"
					( Origin gPackager )
				)
				( attribute "LOCATION" "C3M46"
					( Origin gFrontEnd )
				)
				( attribute "MATERIAL" "X6S"
					( Origin gFrontEnd )
				)
				( attribute "PACK_TYPE" "0402V"
					( Origin gFrontEnd )
				)
				( attribute "PART_NUMBER" "D97712-004"
					( Origin gFrontEnd )
				)
				( attribute "PHYS_PAGE" "194"
					( Origin gFrontEnd )
				)
				( attribute "ROOM" "P0V95_MCP_CPU0"
					( Origin gFrontEnd )
				)
				( attribute "ROT" "0"
					( Origin gFrontEnd )
				)
				( attribute "SEC" "1"
					( Origin gFrontEnd )
				)
				( attribute "SEC_TYPE" "0402V"
					( Origin gFrontEnd )
				)
				( attribute "TOLERANCE" "10%"
					( Origin gFrontEnd )
				)
				( attribute "VALUE" "1.0UF"
					( Origin gFrontEnd )
				)
				( attribute "VER" "1"
					( Origin gFrontEnd )
				)
				( attribute "VOLTAGE" "6.3V"
					( Units "uVoltage" "V" 1.000000)
					( Origin gFrontEnd )
				)
				( attribute "XY" "(-1400,3100)"
					( Origin gFrontEnd )
				)
				( attribute "CHIPS_PART_NAME" "CAP_A"
					( Origin gPackager )
				)
				( attribute "CDS_PART_NAME" "CAP_A_0402V-1.0UF,6.3V,10%,X6SA"
					( Origin gPackager )
				)
				( attribute "GROUP" "PWR_MCP_CAP"
					( Origin gFrontEnd )
				)
				( attribute "CDS_LOCATION" "C3M46"
					( Origin gPackager )
				)
				( objectStatus "C3M46" )
			)
			( gate "@baseboard_fab2_lib.baseboard_fab2(sch_1):page194_i101"
				( attribute "BOM_COST" "PROC_VRD_VCCIN_CPU0"
					( Origin gFrontEnd )
				)
				( attribute "CDS_LIB" "mstr_discrete"
					( Origin gPackager )
				)
				( attribute "CDS_LOCATION" "C3N14"
					( Origin gPackager )
				)
				( attribute "CDS_SEC" "1"
					( Origin gPackager )
				)
				( attribute "LOCATION" "C3N14"
					( Origin gFrontEnd )
				)
				( attribute "MATERIAL" "ALUM"
					( Origin gFrontEnd )
				)
				( attribute "PACK_TYPE" "3018"
					( Origin gFrontEnd )
				)
				( attribute "PART_NUMBER" "699013-049"
					( Origin gFrontEnd )
				)
				( attribute "PHYS_PAGE" "194"
					( Origin gFrontEnd )
				)
				( attribute "ROOM" "P0V95_MCP_CPU0_DECAP_VR"
					( Origin gFrontEnd )
				)
				( attribute "ROT" "0"
					( Origin gFrontEnd )
				)
				( attribute "SEC" "1"
					( Origin gFrontEnd )
				)
				( attribute "SEC_TYPE" "3018"
					( Origin gFrontEnd )
				)
				( attribute "TOLERANCE" "20%"
					( Origin gFrontEnd )
				)
				( attribute "VALUE" "470UF"
					( Origin gFrontEnd )
				)
				( attribute "VER" "1"
					( Origin gFrontEnd )
				)
				( attribute "VOLTAGE" "2.5V"
					( Units "uVoltage" "V" 1.000000)
					( Origin gFrontEnd )
				)
				( attribute "XY" "(-1900,3100)"
					( Origin gFrontEnd )
				)
				( attribute "CHIPS_PART_NAME" "CAPP"
					( Origin gPackager )
				)
				( attribute "CDS_PART_NAME" "CAPP_3018-470UF,2.5V,20%,ALUM,A"
					( Origin gPackager )
				)
				( attribute "GROUP" "PWR_MCP_CAP"
					( Origin gFrontEnd )
				)
				( objectStatus "C3N14" )
			)
			( gate "@baseboard_fab2_lib.baseboard_fab2(sch_1):page194_i149"
				( attribute "CDS_LIB" "dev_discrete"
					( Origin gPackager )
				)
				( attribute "CDS_LOCATION" "C3T1"
					( Origin gPackager )
				)
				( attribute "CDS_SEC" "1"
					( Origin gPackager )
				)
				( attribute "LOCATION" "C3T1"
					( Origin gFrontEnd )
				)
				( attribute "MATERIAL" "X5R"
					( Origin gFrontEnd )
				)
				( attribute "PACK_TYPE" "0603V"
					( Origin gFrontEnd )
				)
				( attribute "PART_NUMBER" "602433-106"
					( Origin gFrontEnd )
				)
				( attribute "PHYS_PAGE" "194"
					( Origin gFrontEnd )
				)
				( attribute "ROT" "0"
					( Origin gFrontEnd )
				)
				( attribute "SEC" "1"
					( Origin gFrontEnd )
				)
				( attribute "SEC_TYPE" "0603V"
					( Origin gFrontEnd )
				)
				( attribute "TOLERANCE" "20%"
					( Origin gFrontEnd )
				)
				( attribute "VALUE" "47UF"
					( Origin gFrontEnd )
				)
				( attribute "VER" "1"
					( Origin gFrontEnd )
				)
				( attribute "VOLTAGE" "4V"
					( Units "uVoltage" "V" 1.000000)
					( Origin gFrontEnd )
				)
				( attribute "XY" "(-1600,1850)"
					( Origin gFrontEnd )
				)
				( attribute "CHIPS_PART_NAME" "CAP_A"
					( Origin gPackager )
				)
				( attribute "CDS_PART_NAME" "CAP_A_0603V-47UF,4V,20%,X5R,60A"
					( Origin gPackager )
				)
				( attribute "GROUP" "PWR_MCP_CAP"
					( Origin gFrontEnd )
				)
				( objectStatus "C3T1" )
			)
			( gate "@baseboard_fab2_lib.baseboard_fab2(sch_1):page194_i150"
				( attribute "CDS_LIB" "dev_discrete"
					( Origin gPackager )
				)
				( attribute "CDS_LOCATION" "C3T2"
					( Origin gPackager )
				)
				( attribute "CDS_SEC" "1"
					( Origin gPackager )
				)
				( attribute "LOCATION" "C3T2"
					( Origin gFrontEnd )
				)
				( attribute "MATERIAL" "X5R"
					( Origin gFrontEnd )
				)
				( attribute "PACK_TYPE" "0603V"
					( Origin gFrontEnd )
				)
				( attribute "PART_NUMBER" "602433-106"
					( Origin gFrontEnd )
				)
				( attribute "PHYS_PAGE" "194"
					( Origin gFrontEnd )
				)
				( attribute "ROT" "0"
					( Origin gFrontEnd )
				)
				( attribute "SEC" "1"
					( Origin gFrontEnd )
				)
				( attribute "SEC_TYPE" "0603V"
					( Origin gFrontEnd )
				)
				( attribute "TOLERANCE" "20%"
					( Origin gFrontEnd )
				)
				( attribute "VALUE" "47UF"
					( Origin gFrontEnd )
				)
				( attribute "VER" "1"
					( Origin gFrontEnd )
				)
				( attribute "VOLTAGE" "4V"
					( Units "uVoltage" "V" 1.000000)
					( Origin gFrontEnd )
				)
				( attribute "XY" "(-1900,1850)"
					( Origin gFrontEnd )
				)
				( attribute "CHIPS_PART_NAME" "CAP_A"
					( Origin gPackager )
				)
				( attribute "CDS_PART_NAME" "CAP_A_0603V-47UF,4V,20%,X5R,60A"
					( Origin gPackager )
				)
				( attribute "GROUP" "PWR_MCP_CAP"
					( Origin gFrontEnd )
				)
				( objectStatus "C3T2" )
			)
			( gate "@baseboard_fab2_lib.baseboard_fab2(sch_1):page194_i155"
				( attribute "CDS_LIB" "mstr_discrete"
					( Origin gPackager )
				)
				( attribute "CDS_LOCATION" "R7C24"
					( Origin gPackager )
				)
				( attribute "CDS_SEC" "1"
					( Origin gPackager )
				)
				( attribute "LOCATION" "R7C24"
					( Origin gFrontEnd )
				)
				( attribute "MATERIAL" "CHIP"
					( Origin gFrontEnd )
				)
				( attribute "PACK_TYPE" "0402"
					( Origin gFrontEnd )
				)
				( attribute "PART_NUMBER" "G21796-082"
					( Origin gFrontEnd )
				)
				( attribute "PHYS_PAGE" "194"
					( Origin gFrontEnd )
				)
				( attribute "ROOM" "PVCCIN_CPU1_VR"
					( Origin gFrontEnd )
				)
				( attribute "ROT" "0"
					( Origin gFrontEnd )
				)
				( attribute "SEC" "1"
					( Origin gFrontEnd )
				)
				( attribute "SEC_TYPE" "0402"
					( Origin gFrontEnd )
				)
				( attribute "TOLERANCE" "1%"
					( Origin gFrontEnd )
				)
				( attribute "VALUE" "4.02K"
					( Origin gFrontEnd )
				)
				( attribute "VER" "2"
					( Origin gFrontEnd )
				)
				( attribute "WATTAGE" "1/16W"
					( Origin gFrontEnd )
				)
				( attribute "XY" "(-7825,100)"
					( Origin gFrontEnd )
				)
				( attribute "CHIPS_PART_NAME" "RES"
					( Origin gPackager )
				)
				( attribute "CDS_PART_NAME" "RES_0402-4.02K,1%,1/16W,CHIP,GA"
					( Origin gPackager )
				)
				( attribute "GROUP" "MCP"
					( Origin gFrontEnd )
				)
				( objectStatus "R7C24" )
			)
			( gate "@baseboard_fab2_lib.baseboard_fab2(sch_1):page194_i156"
				( attribute "CDS_LIB" "mstr_discrete"
					( Origin gPackager )
				)
				( attribute "CDS_LOCATION" "R3N29"
					( Origin gPackager )
				)
				( attribute "CDS_SEC" "1"
					( Origin gPackager )
				)
				( attribute "LOCATION" "R3N29"
					( Origin gFrontEnd )
				)
				( attribute "MATERIAL" "CHIP"
					( Origin gFrontEnd )
				)
				( attribute "PACK_TYPE" "0402"
					( Origin gFrontEnd )
				)
				( attribute "PART_NUMBER" "G21796-317"
					( Origin gFrontEnd )
				)
				( attribute "PHYS_PAGE" "194"
					( Origin gFrontEnd )
				)
				( attribute "ROOM" "VDDQ_ABC_PWR_VR"
					( Origin gFrontEnd )
				)
				( attribute "ROT" "0"
					( Origin gFrontEnd )
				)
				( attribute "SEC" "1"
					( Origin gFrontEnd )
				)
				( attribute "SEC_TYPE" "0402"
					( Origin gFrontEnd )
				)
				( attribute "TOLERANCE" "1.0%"
					( Origin gFrontEnd )
				)
				( attribute "VALUE" "16K"
					( Origin gFrontEnd )
				)
				( attribute "VER" "2"
					( Origin gFrontEnd )
				)
				( attribute "WATTAGE" "1/16W"
					( Origin gFrontEnd )
				)
				( attribute "XY" "(-8175,125)"
					( Origin gFrontEnd )
				)
				( attribute "CHIPS_PART_NAME" "RES"
					( Origin gPackager )
				)
				( attribute "CDS_PART_NAME" "RES_0402-16K,1.0%,1/16W,CHIP,GA"
					( Origin gPackager )
				)
				( attribute "GROUP" "MCP"
					( Origin gFrontEnd )
				)
				( objectStatus "R3N29" )
			)
			( gate "@baseboard_fab2_lib.baseboard_fab2(sch_1):page195_i26"
				( attribute "CDS_LIB" "mstr_conn"
					( Origin gPackager )
				)
				( attribute "CDS_LMAN_SYM_OUTLINE" "-150,200,150,-200"
					( Origin gPackager )
				)
				( attribute "CDS_LOCATION" "RM1E1"
					( Origin gPackager )
				)
				( attribute "CDS_SEC" "1"
					( Origin gPackager )
				)
				( attribute "LOCATION" "RM1E1"
					( Origin gFrontEnd )
				)
				( attribute "MATERIAL" "CONN"
					( Origin gFrontEnd )
				)
				( attribute "PACK_TYPE" "PIP"
					( Origin gFrontEnd )
				)
				( attribute "PART_NUMBER" "G98259-001"
					( Origin gFrontEnd )
				)
				( attribute "PHYS_PAGE" "195"
					( Origin gFrontEnd )
				)
				( attribute "ROT" "0"
					( Origin gFrontEnd )
				)
				( attribute "SEC" "1"
					( Origin gPackager )
				)
				( attribute "VER" "1"
					( Origin gFrontEnd )
				)
				( attribute "XY" "(-925,3725)"
					( Origin gFrontEnd )
				)
				( attribute "CHIPS_PART_NAME" "CONN3_G98259001"
					( Origin gPackager )
				)
				( attribute "CDS_PART_NAME" "CONN3_G98259001_PIP-CONN,G9825A"
					( Origin gPackager )
				)
				( objectStatus "RM1E1" )
			)
			( gate "@baseboard_fab2_lib.baseboard_fab2(sch_1):page195_i31"
				( attribute "CDS_LIB" "mstr_discrete"
					( Origin gPackager )
				)
				( attribute "CDS_LOCATION" "C9R5"
					( Origin gPackager )
				)
				( attribute "CDS_SEC" "1"
					( Origin gPackager )
				)
				( attribute "LOCATION" "C9R5"
					( Origin gFrontEnd )
				)
				( attribute "MATERIAL" "X6S"
					( Origin gFrontEnd )
				)
				( attribute "PACK_TYPE" "0805"
					( Origin gFrontEnd )
				)
				( attribute "PART_NUMBER" "C95333-007"
					( Origin gFrontEnd )
				)
				( attribute "PHYS_PAGE" "195"
					( Origin gFrontEnd )
				)
				( attribute "ROOM" "HOT_SWAP"
					( Origin gFrontEnd )
				)
				( attribute "ROT" "0"
					( Origin gFrontEnd )
				)
				( attribute "SEC" "1"
					( Origin gFrontEnd )
				)
				( attribute "SEC_TYPE" "0805"
					( Origin gFrontEnd )
				)
				( attribute "TOLERANCE" "10%"
					( Origin gFrontEnd )
				)
				( attribute "VALUE" "10UF"
					( Origin gFrontEnd )
				)
				( attribute "VER" "1"
					( Origin gFrontEnd )
				)
				( attribute "VOLTAGE" "16V"
					( Units "uVoltage" "V" 1.000000)
					( Origin gFrontEnd )
				)
				( attribute "XY" "(-3700,3650)"
					( Origin gFrontEnd )
				)
				( attribute "CHIPS_PART_NAME" "CAP"
					( Origin gPackager )
				)
				( attribute "CDS_PART_NAME" "CAP_0805-10UF,16V,10%,X6S,C953A"
					( Origin gPackager )
				)
				( attribute "POP" "NOPOP"
					( Origin gFrontEnd )
				)
				( objectStatus "C9R5" )
			)
			( gate "@baseboard_fab2_lib.baseboard_fab2(sch_1):page195_i32"
				( attribute "CDS_LIB" "mstr_discrete"
					( Origin gPackager )
				)
				( attribute "CDS_LOCATION" "C1E12"
					( Origin gPackager )
				)
				( attribute "CDS_SEC" "1"
					( Origin gPackager )
				)
				( attribute "LOCATION" "C1E12"
					( Origin gFrontEnd )
				)
				( attribute "MATERIAL" "X6S"
					( Origin gFrontEnd )
				)
				( attribute "PACK_TYPE" "0805"
					( Origin gFrontEnd )
				)
				( attribute "PART_NUMBER" "C95333-007"
					( Origin gFrontEnd )
				)
				( attribute "PHYS_PAGE" "195"
					( Origin gFrontEnd )
				)
				( attribute "ROOM" "HOT_SWAP"
					( Origin gFrontEnd )
				)
				( attribute "ROT" "0"
					( Origin gFrontEnd )
				)
				( attribute "SEC" "1"
					( Origin gFrontEnd )
				)
				( attribute "SEC_TYPE" "0805"
					( Origin gFrontEnd )
				)
				( attribute "TOLERANCE" "10%"
					( Origin gFrontEnd )
				)
				( attribute "VALUE" "10UF"
					( Origin gFrontEnd )
				)
				( attribute "VER" "1"
					( Origin gFrontEnd )
				)
				( attribute "VOLTAGE" "16V"
					( Units "uVoltage" "V" 1.000000)
					( Origin gFrontEnd )
				)
				( attribute "XY" "(-3375,3650)"
					( Origin gFrontEnd )
				)
				( attribute "CHIPS_PART_NAME" "CAP"
					( Origin gPackager )
				)
				( attribute "CDS_PART_NAME" "CAP_0805-10UF,16V,10%,X6S,C953A"
					( Origin gPackager )
				)
				( attribute "POP" "NOPOP"
					( Origin gFrontEnd )
				)
				( objectStatus "C1E12" )
			)
			( gate "@baseboard_fab2_lib.baseboard_fab2(sch_1):page195_i35"
				( attribute "CDS_LIB" "mstr_discrete"
					( Origin gPackager )
				)
				( attribute "CDS_LOCATION" "C1E15"
					( Origin gPackager )
				)
				( attribute "CDS_SEC" "1"
					( Origin gPackager )
				)
				( attribute "LOCATION" "C1E15"
					( Origin gFrontEnd )
				)
				( attribute "MATERIAL" "X6S"
					( Origin gFrontEnd )
				)
				( attribute "PACK_TYPE" "0805"
					( Origin gFrontEnd )
				)
				( attribute "PART_NUMBER" "C95333-007"
					( Origin gFrontEnd )
				)
				( attribute "PHYS_PAGE" "195"
					( Origin gFrontEnd )
				)
				( attribute "ROOM" "HOT_SWAP"
					( Origin gFrontEnd )
				)
				( attribute "ROT" "0"
					( Origin gFrontEnd )
				)
				( attribute "SEC" "1"
					( Origin gFrontEnd )
				)
				( attribute "SEC_TYPE" "0805"
					( Origin gFrontEnd )
				)
				( attribute "TOLERANCE" "10%"
					( Origin gFrontEnd )
				)
				( attribute "VALUE" "10UF"
					( Origin gFrontEnd )
				)
				( attribute "VER" "1"
					( Origin gFrontEnd )
				)
				( attribute "VOLTAGE" "16V"
					( Units "uVoltage" "V" 1.000000)
					( Origin gFrontEnd )
				)
				( attribute "XY" "(-3025,3650)"
					( Origin gFrontEnd )
				)
				( attribute "CHIPS_PART_NAME" "CAP"
					( Origin gPackager )
				)
				( attribute "CDS_PART_NAME" "CAP_0805-10UF,16V,10%,X6S,C953A"
					( Origin gPackager )
				)
				( attribute "POP" "NOPOP"
					( Origin gFrontEnd )
				)
				( objectStatus "C1E15" )
			)
			( gate "@baseboard_fab2_lib.baseboard_fab2(sch_1):page195_i36"
				( attribute "BOM_COST" "HOT_SWAP"
					( Origin gFrontEnd )
				)
				( attribute "CDS_LIB" "dev_discrete"
					( Origin gPackager )
				)
				( attribute "CDS_LOCATION" "C9R12"
					( Origin gPackager )
				)
				( attribute "CDS_SEC" "1"
					( Origin gPackager )
				)
				( attribute "LOCATION" "C9R12"
					( Origin gFrontEnd )
				)
				( attribute "MATERIAL" "X7R"
					( Origin gFrontEnd )
				)
				( attribute "PACK_TYPE" "0402V"
					( Origin gFrontEnd )
				)
				( attribute "PART_NUMBER" "A36096-030"
					( Origin gFrontEnd )
				)
				( attribute "PHYS_PAGE" "195"
					( Origin gFrontEnd )
				)
				( attribute "ROOM" "HOT_SWAP"
					( Origin gFrontEnd )
				)
				( attribute "ROT" "0"
					( Origin gFrontEnd )
				)
				( attribute "SEC" "1"
					( Origin gFrontEnd )
				)
				( attribute "SEC_TYPE" "0402V"
					( Origin gFrontEnd )
				)
				( attribute "TOLERANCE" "10%"
					( Origin gFrontEnd )
				)
				( attribute "VALUE" "0.1UF"
					( Origin gFrontEnd )
				)
				( attribute "VER" "1"
					( Origin gFrontEnd )
				)
				( attribute "VOLTAGE" "16V"
					( Units "uVoltage" "V" 1.000000)
					( Origin gFrontEnd )
				)
				( attribute "XY" "(-2675,3650)"
					( Origin gFrontEnd )
				)
				( attribute "CHIPS_PART_NAME" "CAP_A"
					( Origin gPackager )
				)
				( attribute "CDS_PART_NAME" "CAP_A_0402V-0.1UF,16V,10%,X7R,A"
					( Origin gPackager )
				)
				( attribute "POP" "NOPOP"
					( Origin gFrontEnd )
				)
				( objectStatus "C9R12" )
			)
			( gate "@baseboard_fab2_lib.baseboard_fab2(sch_1):page195_i37"
				( attribute "BOM_COST" "HOT_SWAP"
					( Origin gFrontEnd )
				)
				( attribute "CDS_LIB" "dev_discrete"
					( Origin gPackager )
				)
				( attribute "CDS_LOCATION" "C9R6"
					( Origin gPackager )
				)
				( attribute "CDS_SEC" "1"
					( Origin gPackager )
				)
				( attribute "LOCATION" "C9R6"
					( Origin gFrontEnd )
				)
				( attribute "MATERIAL" "X7R"
					( Origin gFrontEnd )
				)
				( attribute "PACK_TYPE" "0402V"
					( Origin gFrontEnd )
				)
				( attribute "PART_NUMBER" "A36096-030"
					( Origin gFrontEnd )
				)
				( attribute "PHYS_PAGE" "195"
					( Origin gFrontEnd )
				)
				( attribute "ROOM" "HOT_SWAP"
					( Origin gFrontEnd )
				)
				( attribute "ROT" "0"
					( Origin gFrontEnd )
				)
				( attribute "SEC" "1"
					( Origin gFrontEnd )
				)
				( attribute "SEC_TYPE" "0402V"
					( Origin gFrontEnd )
				)
				( attribute "TOLERANCE" "10%"
					( Origin gFrontEnd )
				)
				( attribute "VALUE" "0.1UF"
					( Origin gFrontEnd )
				)
				( attribute "VER" "1"
					( Origin gFrontEnd )
				)
				( attribute "VOLTAGE" "16V"
					( Units "uVoltage" "V" 1.000000)
					( Origin gFrontEnd )
				)
				( attribute "XY" "(-2300,3650)"
					( Origin gFrontEnd )
				)
				( attribute "CHIPS_PART_NAME" "CAP_A"
					( Origin gPackager )
				)
				( attribute "CDS_PART_NAME" "CAP_A_0402V-0.1UF,16V,10%,X7R,A"
					( Origin gPackager )
				)
				( attribute "POP" "NOPOP"
					( Origin gFrontEnd )
				)
				( objectStatus "C9R6" )
			)
			( gate "@baseboard_fab2_lib.baseboard_fab2(sch_1):page195_i38"
				( attribute "BOM_COST" "HOT_SWAP"
					( Origin gFrontEnd )
				)
				( attribute "CDS_LIB" "dev_discrete"
					( Origin gPackager )
				)
				( attribute "CDS_LOCATION" "C1E17"
					( Origin gPackager )
				)
				( attribute "CDS_SEC" "1"
					( Origin gPackager )
				)
				( attribute "LOCATION" "C1E17"
					( Origin gFrontEnd )
				)
				( attribute "MATERIAL" "X7R"
					( Origin gFrontEnd )
				)
				( attribute "PACK_TYPE" "0402V"
					( Origin gFrontEnd )
				)
				( attribute "PART_NUMBER" "A36096-030"
					( Origin gFrontEnd )
				)
				( attribute "PHYS_PAGE" "195"
					( Origin gFrontEnd )
				)
				( attribute "ROOM" "HOT_SWAP"
					( Origin gFrontEnd )
				)
				( attribute "ROT" "0"
					( Origin gFrontEnd )
				)
				( attribute "SEC" "1"
					( Origin gFrontEnd )
				)
				( attribute "SEC_TYPE" "0402V"
					( Origin gFrontEnd )
				)
				( attribute "TOLERANCE" "10%"
					( Origin gFrontEnd )
				)
				( attribute "VALUE" "0.1UF"
					( Origin gFrontEnd )
				)
				( attribute "VER" "1"
					( Origin gFrontEnd )
				)
				( attribute "VOLTAGE" "16V"
					( Units "uVoltage" "V" 1.000000)
					( Origin gFrontEnd )
				)
				( attribute "XY" "(-1950,3650)"
					( Origin gFrontEnd )
				)
				( attribute "CHIPS_PART_NAME" "CAP_A"
					( Origin gPackager )
				)
				( attribute "CDS_PART_NAME" "CAP_A_0402V-0.1UF,16V,10%,X7R,A"
					( Origin gPackager )
				)
				( attribute "POP" "NOPOP"
					( Origin gFrontEnd )
				)
				( objectStatus "C1E17" )
			)
			( gate "@baseboard_fab2_lib.baseboard_fab2(sch_1):page195_i39"
				( attribute "BOM_COST" "HOT_SWAP"
					( Origin gFrontEnd )
				)
				( attribute "CDS_LIB" "dev_discrete"
					( Origin gPackager )
				)
				( attribute "CDS_LOCATION" "C1E16"
					( Origin gPackager )
				)
				( attribute "CDS_SEC" "1"
					( Origin gPackager )
				)
				( attribute "LOCATION" "C1E16"
					( Origin gFrontEnd )
				)
				( attribute "MATERIAL" "X7R"
					( Origin gFrontEnd )
				)
				( attribute "PACK_TYPE" "0402V"
					( Origin gFrontEnd )
				)
				( attribute "PART_NUMBER" "A36096-030"
					( Origin gFrontEnd )
				)
				( attribute "PHYS_PAGE" "195"
					( Origin gFrontEnd )
				)
				( attribute "ROOM" "HOT_SWAP"
					( Origin gFrontEnd )
				)
				( attribute "ROT" "0"
					( Origin gFrontEnd )
				)
				( attribute "SEC" "1"
					( Origin gFrontEnd )
				)
				( attribute "SEC_TYPE" "0402V"
					( Origin gFrontEnd )
				)
				( attribute "TOLERANCE" "10%"
					( Origin gFrontEnd )
				)
				( attribute "VALUE" "0.1UF"
					( Origin gFrontEnd )
				)
				( attribute "VER" "1"
					( Origin gFrontEnd )
				)
				( attribute "VOLTAGE" "16V"
					( Units "uVoltage" "V" 1.000000)
					( Origin gFrontEnd )
				)
				( attribute "XY" "(-1625,3650)"
					( Origin gFrontEnd )
				)
				( attribute "CHIPS_PART_NAME" "CAP_A"
					( Origin gPackager )
				)
				( attribute "CDS_PART_NAME" "CAP_A_0402V-0.1UF,16V,10%,X7R,A"
					( Origin gPackager )
				)
				( attribute "POP" "NOPOP"
					( Origin gFrontEnd )
				)
				( objectStatus "C1E16" )
			)
			( gate "@baseboard_fab2_lib.baseboard_fab2(sch_1):page195_i49"
				( attribute "BOM_COST" "TEST_MFG"
					( Origin gFrontEnd )
				)
				( attribute "CDS_LIB" "mstr_misc"
					( Origin gPackager )
				)
				( attribute "CDS_LOCATION" "TH4G1"
					( Origin gPackager )
				)
				( attribute "CDS_SEC" "1"
					( Origin gPackager )
				)
				( attribute "LOCATION" "TH4G1"
					( Origin gFrontEnd )
				)
				( attribute "MATERIAL" "EMPTY"
					( Origin gFrontEnd )
				)
				( attribute "PACK_TYPE" "TH"
					( Origin gFrontEnd )
				)
				( attribute "PART_NUMBER" "NA"
					( Origin gFrontEnd )
				)
				( attribute "PHYS_PAGE" "195"
					( Origin gFrontEnd )
				)
				( attribute "ROOM" "MOUNTING_HOLES"
					( Origin gFrontEnd )
				)
				( attribute "ROT" "0"
					( Origin gFrontEnd )
				)
				( attribute "SEC" "1"
					( Origin gPackager )
				)
				( attribute "VER" "1"
					( Origin gFrontEnd )
				)
				( attribute "XY" "(-6475,4725)"
					( Origin gFrontEnd )
				)
				( attribute "CHIPS_PART_NAME" "MTG_KEYHOLE"
					( Origin gPackager )
				)
				( attribute "CDS_PART_NAME" "MTG_KEYHOLE_TH-EMPTY,NA"
					( Origin gPackager )
				)
				( objectStatus "TH4G1" )
			)
			( gate "@baseboard_fab2_lib.baseboard_fab2(sch_1):page195_i52"
				( attribute "BOM_COST" "TEST_MFG"
					( Origin gFrontEnd )
				)
				( attribute "CDS_LIB" "mstr_misc"
					( Origin gPackager )
				)
				( attribute "CDS_LOCATION" "TH9G1"
					( Origin gPackager )
				)
				( attribute "CDS_SEC" "1"
					( Origin gPackager )
				)
				( attribute "LOCATION" "TH9G1"
					( Origin gFrontEnd )
				)
				( attribute "MATERIAL" "EMPTY"
					( Origin gFrontEnd )
				)
				( attribute "PACK_TYPE" "TH"
					( Origin gFrontEnd )
				)
				( attribute "PART_NUMBER" "NA"
					( Origin gFrontEnd )
				)
				( attribute "PHYS_PAGE" "195"
					( Origin gFrontEnd )
				)
				( attribute "ROOM" "MOUNTING_HOLES"
					( Origin gFrontEnd )
				)
				( attribute "ROT" "0"
					( Origin gFrontEnd )
				)
				( attribute "SEC" "1"
					( Origin gPackager )
				)
				( attribute "VER" "1"
					( Origin gFrontEnd )
				)
				( attribute "XY" "(-6425,4125)"
					( Origin gFrontEnd )
				)
				( attribute "CHIPS_PART_NAME" "MTG_KEYHOLE"
					( Origin gPackager )
				)
				( attribute "CDS_PART_NAME" "MTG_KEYHOLE_TH-EMPTY,NA"
					( Origin gPackager )
				)
				( objectStatus "TH9G1" )
			)
			( gate "@baseboard_fab2_lib.baseboard_fab2(sch_1):page195_i54"
				( attribute "BOM_COST" "TEST_MFG"
					( Origin gFrontEnd )
				)
				( attribute "CDS_LIB" "mstr_misc"
					( Origin gPackager )
				)
				( attribute "CDS_LOCATION" "TH9A1"
					( Origin gPackager )
				)
				( attribute "CDS_SEC" "1"
					( Origin gPackager )
				)
				( attribute "LOCATION" "TH9A1"
					( Origin gFrontEnd )
				)
				( attribute "MATERIAL" "EMPTY"
					( Origin gFrontEnd )
				)
				( attribute "PACK_TYPE" "TH"
					( Origin gFrontEnd )
				)
				( attribute "PART_NUMBER" "NA"
					( Origin gFrontEnd )
				)
				( attribute "PHYS_PAGE" "195"
					( Origin gFrontEnd )
				)
				( attribute "ROOM" "MOUNTING_HOLES"
					( Origin gFrontEnd )
				)
				( attribute "ROT" "0"
					( Origin gFrontEnd )
				)
				( attribute "SEC" "1"
					( Origin gPackager )
				)
				( attribute "VER" "1"
					( Origin gFrontEnd )
				)
				( attribute "XY" "(-4600,4725)"
					( Origin gFrontEnd )
				)
				( attribute "CHIPS_PART_NAME" "MTG_KEYHOLE"
					( Origin gPackager )
				)
				( attribute "CDS_PART_NAME" "MTG_KEYHOLE_TH-EMPTY,NA"
					( Origin gPackager )
				)
				( objectStatus "TH9A1" )
			)
			( gate "@baseboard_fab2_lib.baseboard_fab2(sch_1):page195_i56"
				( attribute "BOM_COST" "TEST_MFG"
					( Origin gFrontEnd )
				)
				( attribute "CDS_LIB" "mstr_misc"
					( Origin gPackager )
				)
				( attribute "CDS_LOCATION" "TH1A1"
					( Origin gPackager )
				)
				( attribute "CDS_SEC" "1"
					( Origin gPackager )
				)
				( attribute "LOCATION" "TH1A1"
					( Origin gFrontEnd )
				)
				( attribute "MATERIAL" "EMPTY"
					( Origin gFrontEnd )
				)
				( attribute "PACK_TYPE" "TH"
					( Origin gFrontEnd )
				)
				( attribute "PART_NUMBER" "NA"
					( Origin gFrontEnd )
				)
				( attribute "PHYS_PAGE" "195"
					( Origin gFrontEnd )
				)
				( attribute "ROOM" "MOUNTING_HOLES"
					( Origin gFrontEnd )
				)
				( attribute "ROT" "0"
					( Origin gFrontEnd )
				)
				( attribute "SEC" "1"
					( Origin gPackager )
				)
				( attribute "VER" "1"
					( Origin gFrontEnd )
				)
				( attribute "XY" "(-5525,4725)"
					( Origin gFrontEnd )
				)
				( attribute "CHIPS_PART_NAME" "MTG_KEYHOLE"
					( Origin gPackager )
				)
				( attribute "CDS_PART_NAME" "MTG_KEYHOLE_TH-EMPTY,NA"
					( Origin gPackager )
				)
				( objectStatus "TH1A1" )
			)
			( gate "@baseboard_fab2_lib.baseboard_fab2(sch_1):page195_i62"
				( attribute "BOM_COST" "TEST_MFG"
					( Origin gFrontEnd )
				)
				( attribute "CDS_LIB" "mstr_misc"
					( Origin gPackager )
				)
				( attribute "CDS_LOCATION" "TH4A1"
					( Origin gPackager )
				)
				( attribute "CDS_SEC" "1"
					( Origin gPackager )
				)
				( attribute "LOCATION" "TH4A1"
					( Origin gFrontEnd )
				)
				( attribute "MATERIAL" "EMPTY"
					( Origin gFrontEnd )
				)
				( attribute "PACK_TYPE" "TH"
					( Origin gFrontEnd )
				)
				( attribute "PART_NUMBER" "NA"
					( Origin gFrontEnd )
				)
				( attribute "PHYS_PAGE" "195"
					( Origin gFrontEnd )
				)
				( attribute "ROOM" "MOUNTING_HOLES"
					( Origin gFrontEnd )
				)
				( attribute "ROT" "0"
					( Origin gFrontEnd )
				)
				( attribute "SEC" "1"
					( Origin gPackager )
				)
				( attribute "VER" "1"
					( Origin gFrontEnd )
				)
				( attribute "XY" "(-7350,4125)"
					( Origin gFrontEnd )
				)
				( attribute "CHIPS_PART_NAME" "MTG_KEYHOLE"
					( Origin gPackager )
				)
				( attribute "CDS_PART_NAME" "MTG_KEYHOLE_TH-EMPTY,NA"
					( Origin gPackager )
				)
				( objectStatus "TH4A1" )
			)
			( gate "@baseboard_fab2_lib.baseboard_fab2(sch_1):page195_i65"
				( attribute "BOM_COST" "TEST_MFG"
					( Origin gFrontEnd )
				)
				( attribute "CDS_LIB" "mstr_misc"
					( Origin gPackager )
				)
				( attribute "CDS_LOCATION" "TH7A1"
					( Origin gPackager )
				)
				( attribute "CDS_SEC" "1"
					( Origin gPackager )
				)
				( attribute "LOCATION" "TH7A1"
					( Origin gFrontEnd )
				)
				( attribute "MATERIAL" "EMPTY"
					( Origin gFrontEnd )
				)
				( attribute "PACK_TYPE" "TH"
					( Origin gFrontEnd )
				)
				( attribute "PART_NUMBER" "NA"
					( Origin gFrontEnd )
				)
				( attribute "PHYS_PAGE" "195"
					( Origin gFrontEnd )
				)
				( attribute "ROOM" "MOUNTING_HOLES"
					( Origin gFrontEnd )
				)
				( attribute "ROT" "0"
					( Origin gFrontEnd )
				)
				( attribute "SEC" "1"
					( Origin gPackager )
				)
				( attribute "VER" "1"
					( Origin gFrontEnd )
				)
				( attribute "XY" "(-5525,4150)"
					( Origin gFrontEnd )
				)
				( attribute "CHIPS_PART_NAME" "MTG_KEYHOLE"
					( Origin gPackager )
				)
				( attribute "CDS_PART_NAME" "MTG_KEYHOLE_TH-EMPTY,NA"
					( Origin gPackager )
				)
				( objectStatus "TH7A1" )
			)
			( gate "@baseboard_fab2_lib.baseboard_fab2(sch_1):page195_i67"
				( attribute "BOM_COST" "TEST_MFG"
					( Origin gFrontEnd )
				)
				( attribute "CDS_LIB" "mstr_misc"
					( Origin gPackager )
				)
				( attribute "CDS_LOCATION" "TH7G1"
					( Origin gPackager )
				)
				( attribute "CDS_SEC" "1"
					( Origin gPackager )
				)
				( attribute "LOCATION" "TH7G1"
					( Origin gFrontEnd )
				)
				( attribute "MATERIAL" "EMPTY"
					( Origin gFrontEnd )
				)
				( attribute "PACK_TYPE" "TH"
					( Origin gFrontEnd )
				)
				( attribute "PART_NUMBER" "NA"
					( Origin gFrontEnd )
				)
				( attribute "PHYS_PAGE" "195"
					( Origin gFrontEnd )
				)
				( attribute "ROOM" "MOUNTING_HOLES"
					( Origin gFrontEnd )
				)
				( attribute "ROT" "0"
					( Origin gFrontEnd )
				)
				( attribute "SEC" "1"
					( Origin gPackager )
				)
				( attribute "VER" "1"
					( Origin gFrontEnd )
				)
				( attribute "XY" "(-4600,4150)"
					( Origin gFrontEnd )
				)
				( attribute "CHIPS_PART_NAME" "MTG_KEYHOLE"
					( Origin gPackager )
				)
				( attribute "CDS_PART_NAME" "MTG_KEYHOLE_TH-EMPTY,NA"
					( Origin gPackager )
				)
				( objectStatus "TH7G1" )
			)
			( gate "@baseboard_fab2_lib.baseboard_fab2(sch_1):page195_i82"
				( attribute "CDS_LIB" "mstr_discrete"
					( Origin gPackager )
				)
				( attribute "CDS_LOCATION" "C4F6"
					( Origin gPackager )
				)
				( attribute "CDS_SEC" "1"
					( Origin gPackager )
				)
				( attribute "LOCATION" "C4F6"
					( Origin gFrontEnd )
				)
				( attribute "MATERIAL" "ALUM"
					( Origin gFrontEnd )
				)
				( attribute "PACK_TYPE" "4040LF"
					( Origin gFrontEnd )
				)
				( attribute "PART_NUMBER" "A93539-036"
					( Origin gFrontEnd )
				)
				( attribute "PHYS_PAGE" "195"
					( Origin gFrontEnd )
				)
				( attribute "ROT" "0"
					( Origin gFrontEnd )
				)
				( attribute "SEC" "1"
					( Origin gPackager )
				)
				( attribute "TOLERANCE" "20%"
					( Origin gFrontEnd )
				)
				( attribute "VALUE" "470UF"
					( Origin gFrontEnd )
				)
				( attribute "VER" "1"
					( Origin gFrontEnd )
				)
				( attribute "VOLTAGE" "16V"
					( Units "uVoltage" "V" 1.000000)
					( Origin gFrontEnd )
				)
				( attribute "XY" "(-7175,2950)"
					( Origin gFrontEnd )
				)
				( attribute "CHIPS_PART_NAME" "CAPP"
					( Origin gPackager )
				)
				( attribute "CDS_PART_NAME" "CAPP_4040LF-470UF,16V,20%,ALUMA"
					( Origin gPackager )
				)
				( objectStatus "C4F6" )
			)
			( gate "@baseboard_fab2_lib.baseboard_fab2(sch_1):page195_i83"
				( attribute "CDS_LIB" "mstr_discrete"
					( Origin gPackager )
				)
				( attribute "CDS_LOCATION" "C4B13"
					( Origin gPackager )
				)
				( attribute "CDS_SEC" "1"
					( Origin gPackager )
				)
				( attribute "LOCATION" "C4B13"
					( Origin gFrontEnd )
				)
				( attribute "MATERIAL" "ALUM"
					( Origin gFrontEnd )
				)
				( attribute "PACK_TYPE" "4040LF"
					( Origin gFrontEnd )
				)
				( attribute "PART_NUMBER" "A93539-036"
					( Origin gFrontEnd )
				)
				( attribute "PHYS_PAGE" "195"
					( Origin gFrontEnd )
				)
				( attribute "ROT" "0"
					( Origin gFrontEnd )
				)
				( attribute "SEC" "1"
					( Origin gPackager )
				)
				( attribute "TOLERANCE" "20%"
					( Origin gFrontEnd )
				)
				( attribute "VALUE" "470UF"
					( Origin gFrontEnd )
				)
				( attribute "VER" "1"
					( Origin gFrontEnd )
				)
				( attribute "VOLTAGE" "16V"
					( Units "uVoltage" "V" 1.000000)
					( Origin gFrontEnd )
				)
				( attribute "XY" "(-6675,2950)"
					( Origin gFrontEnd )
				)
				( attribute "CHIPS_PART_NAME" "CAPP"
					( Origin gPackager )
				)
				( attribute "CDS_PART_NAME" "CAPP_4040LF-470UF,16V,20%,ALUMA"
					( Origin gPackager )
				)
				( objectStatus "C4B13" )
			)
			( gate "@baseboard_fab2_lib.baseboard_fab2(sch_1):page195_i84"
				( attribute "CDS_LIB" "mstr_discrete"
					( Origin gPackager )
				)
				( attribute "CDS_LOCATION" "C1B14"
					( Origin gPackager )
				)
				( attribute "CDS_SEC" "1"
					( Origin gPackager )
				)
				( attribute "LOCATION" "C1B14"
					( Origin gFrontEnd )
				)
				( attribute "MATERIAL" "ALUM"
					( Origin gFrontEnd )
				)
				( attribute "PACK_TYPE" "4040LF"
					( Origin gFrontEnd )
				)
				( attribute "PART_NUMBER" "A93539-036"
					( Origin gFrontEnd )
				)
				( attribute "PHYS_PAGE" "195"
					( Origin gFrontEnd )
				)
				( attribute "ROT" "0"
					( Origin gFrontEnd )
				)
				( attribute "SEC" "1"
					( Origin gPackager )
				)
				( attribute "TOLERANCE" "20%"
					( Origin gFrontEnd )
				)
				( attribute "VALUE" "470UF"
					( Origin gFrontEnd )
				)
				( attribute "VER" "1"
					( Origin gFrontEnd )
				)
				( attribute "VOLTAGE" "16V"
					( Units "uVoltage" "V" 1.000000)
					( Origin gFrontEnd )
				)
				( attribute "XY" "(-6150,2925)"
					( Origin gFrontEnd )
				)
				( attribute "CHIPS_PART_NAME" "CAPP"
					( Origin gPackager )
				)
				( attribute "CDS_PART_NAME" "CAPP_4040LF-470UF,16V,20%,ALUMA"
					( Origin gPackager )
				)
				( objectStatus "C1B14" )
			)
			( gate "@baseboard_fab2_lib.baseboard_fab2(sch_1):page195_i85"
				( attribute "CDS_LIB" "mstr_discrete"
					( Origin gPackager )
				)
				( attribute "CDS_LOCATION" "C1F7"
					( Origin gPackager )
				)
				( attribute "CDS_SEC" "1"
					( Origin gPackager )
				)
				( attribute "LOCATION" "C1F7"
					( Origin gFrontEnd )
				)
				( attribute "MATERIAL" "ALUM"
					( Origin gFrontEnd )
				)
				( attribute "PACK_TYPE" "4040LF"
					( Origin gFrontEnd )
				)
				( attribute "PART_NUMBER" "A93539-036"
					( Origin gFrontEnd )
				)
				( attribute "PHYS_PAGE" "195"
					( Origin gFrontEnd )
				)
				( attribute "ROT" "0"
					( Origin gFrontEnd )
				)
				( attribute "SEC" "1"
					( Origin gPackager )
				)
				( attribute "TOLERANCE" "20%"
					( Origin gFrontEnd )
				)
				( attribute "VALUE" "470UF"
					( Origin gFrontEnd )
				)
				( attribute "VER" "1"
					( Origin gFrontEnd )
				)
				( attribute "VOLTAGE" "16V"
					( Units "uVoltage" "V" 1.000000)
					( Origin gFrontEnd )
				)
				( attribute "XY" "(-5650,2900)"
					( Origin gFrontEnd )
				)
				( attribute "CHIPS_PART_NAME" "CAPP"
					( Origin gPackager )
				)
				( attribute "CDS_PART_NAME" "CAPP_4040LF-470UF,16V,20%,ALUMA"
					( Origin gPackager )
				)
				( objectStatus "C1F7" )
			)
			( gate "@baseboard_fab2_lib.baseboard_fab2(sch_1):page195_i96"
				( attribute "CDS_LIB" "mstr_discrete"
					( Origin gPackager )
				)
				( attribute "CDS_LOCATION" "C4F5"
					( Origin gPackager )
				)
				( attribute "LOCATION" "C4F5"
					( Origin gFrontEnd )
				)
				( attribute "MATERIAL" "TANT"
					( Origin gFrontEnd )
				)
				( attribute "PACK_TYPE" "3018"
					( Origin gFrontEnd )
				)
				( attribute "PART_NUMBER" "724613-112"
					( Origin gFrontEnd )
				)
				( attribute "PHYS_PAGE" "195"
					( Origin gFrontEnd )
				)
				( attribute "ROT" "0"
					( Origin gFrontEnd )
				)
				( attribute "SEC" "1"
					( Origin gFrontEnd )
				)
				( attribute "TOLERANCE" "20%"
					( Origin gFrontEnd )
				)
				( attribute "VALUE" "68UF"
					( Origin gFrontEnd )
				)
				( attribute "VER" "1"
					( Origin gFrontEnd )
				)
				( attribute "VOLTAGE" "16V"
					( Units "uVoltage" "V" 1.000000)
					( Origin gFrontEnd )
				)
				( attribute "XY" "(-7275,775)"
					( Origin gFrontEnd )
				)
				( attribute "CHIPS_PART_NAME" "CAPP"
					( Origin gPackager )
				)
				( attribute "CDS_PART_NAME" "CAPP_3018-68UF,16V,20%,TANT,72A"
					( Origin gPackager )
				)
				( attribute "SEC_TYPE" "3018"
					( Origin gFrontEnd )
				)
				( attribute "CDS_SEC" "1"
					( Origin gPackager )
				)
				( objectStatus "C4F5" )
			)
			( gate "@baseboard_fab2_lib.baseboard_fab2(sch_1):page195_i97"
				( attribute "CDS_LIB" "mstr_discrete"
					( Origin gPackager )
				)
				( attribute "CDS_LOCATION" "C4B14"
					( Origin gPackager )
				)
				( attribute "LOCATION" "C4B14"
					( Origin gFrontEnd )
				)
				( attribute "MATERIAL" "TANT"
					( Origin gFrontEnd )
				)
				( attribute "PACK_TYPE" "3018"
					( Origin gFrontEnd )
				)
				( attribute "PART_NUMBER" "724613-112"
					( Origin gFrontEnd )
				)
				( attribute "PHYS_PAGE" "195"
					( Origin gFrontEnd )
				)
				( attribute "ROT" "0"
					( Origin gFrontEnd )
				)
				( attribute "SEC" "1"
					( Origin gFrontEnd )
				)
				( attribute "TOLERANCE" "20%"
					( Origin gFrontEnd )
				)
				( attribute "VALUE" "68UF"
					( Origin gFrontEnd )
				)
				( attribute "VER" "1"
					( Origin gFrontEnd )
				)
				( attribute "VOLTAGE" "16V"
					( Units "uVoltage" "V" 1.000000)
					( Origin gFrontEnd )
				)
				( attribute "XY" "(-6900,775)"
					( Origin gFrontEnd )
				)
				( attribute "CHIPS_PART_NAME" "CAPP"
					( Origin gPackager )
				)
				( attribute "CDS_PART_NAME" "CAPP_3018-68UF,16V,20%,TANT,72A"
					( Origin gPackager )
				)
				( attribute "SEC_TYPE" "3018"
					( Origin gFrontEnd )
				)
				( attribute "CDS_SEC" "1"
					( Origin gPackager )
				)
				( objectStatus "C4B14" )
			)
			( gate "@baseboard_fab2_lib.baseboard_fab2(sch_1):page195_i98"
				( attribute "CDS_LIB" "mstr_discrete"
					( Origin gPackager )
				)
				( attribute "CDS_LOCATION" "C3T6"
					( Origin gPackager )
				)
				( attribute "LOCATION" "C3T6"
					( Origin gFrontEnd )
				)
				( attribute "MATERIAL" "TANT"
					( Origin gFrontEnd )
				)
				( attribute "PACK_TYPE" "3018"
					( Origin gFrontEnd )
				)
				( attribute "PART_NUMBER" "724613-112"
					( Origin gFrontEnd )
				)
				( attribute "PHYS_PAGE" "195"
					( Origin gFrontEnd )
				)
				( attribute "ROT" "0"
					( Origin gFrontEnd )
				)
				( attribute "SEC" "1"
					( Origin gFrontEnd )
				)
				( attribute "TOLERANCE" "20%"
					( Origin gFrontEnd )
				)
				( attribute "VALUE" "68UF"
					( Origin gFrontEnd )
				)
				( attribute "VER" "1"
					( Origin gFrontEnd )
				)
				( attribute "VOLTAGE" "16V"
					( Units "uVoltage" "V" 1.000000)
					( Origin gFrontEnd )
				)
				( attribute "XY" "(-5300,750)"
					( Origin gFrontEnd )
				)
				( attribute "CHIPS_PART_NAME" "CAPP"
					( Origin gPackager )
				)
				( attribute "CDS_PART_NAME" "CAPP_3018-68UF,16V,20%,TANT,72A"
					( Origin gPackager )
				)
				( attribute "SEC_TYPE" "3018"
					( Origin gFrontEnd )
				)
				( attribute "CDS_SEC" "1"
					( Origin gPackager )
				)
				( objectStatus "C3T6" )
			)
			( gate "@baseboard_fab2_lib.baseboard_fab2(sch_1):page195_i99"
				( attribute "CDS_LIB" "mstr_discrete"
					( Origin gPackager )
				)
				( attribute "CDS_LOCATION" "C9M3"
					( Origin gPackager )
				)
				( attribute "LOCATION" "C9M3"
					( Origin gFrontEnd )
				)
				( attribute "MATERIAL" "TANT"
					( Origin gFrontEnd )
				)
				( attribute "PACK_TYPE" "3018"
					( Origin gFrontEnd )
				)
				( attribute "PART_NUMBER" "724613-112"
					( Origin gFrontEnd )
				)
				( attribute "PHYS_PAGE" "195"
					( Origin gFrontEnd )
				)
				( attribute "ROT" "0"
					( Origin gFrontEnd )
				)
				( attribute "SEC" "1"
					( Origin gFrontEnd )
				)
				( attribute "TOLERANCE" "20%"
					( Origin gFrontEnd )
				)
				( attribute "VALUE" "68UF"
					( Origin gFrontEnd )
				)
				( attribute "VER" "1"
					( Origin gFrontEnd )
				)
				( attribute "VOLTAGE" "16V"
					( Units "uVoltage" "V" 1.000000)
					( Origin gFrontEnd )
				)
				( attribute "XY" "(-5750,775)"
					( Origin gFrontEnd )
				)
				( attribute "CHIPS_PART_NAME" "CAPP"
					( Origin gPackager )
				)
				( attribute "CDS_PART_NAME" "CAPP_3018-68UF,16V,20%,TANT,72A"
					( Origin gPackager )
				)
				( attribute "SEC_TYPE" "3018"
					( Origin gFrontEnd )
				)
				( attribute "CDS_SEC" "1"
					( Origin gPackager )
				)
				( objectStatus "C9M3" )
			)
			( gate "@baseboard_fab2_lib.baseboard_fab2(sch_1):page195_i100"
				( attribute "CDS_LIB" "mstr_discrete"
					( Origin gPackager )
				)
				( attribute "CDS_LOCATION" "C3B6"
					( Origin gPackager )
				)
				( attribute "LOCATION" "C3B6"
					( Origin gFrontEnd )
				)
				( attribute "MATERIAL" "TANT"
					( Origin gFrontEnd )
				)
				( attribute "PACK_TYPE" "3018"
					( Origin gFrontEnd )
				)
				( attribute "PART_NUMBER" "724613-112"
					( Origin gFrontEnd )
				)
				( attribute "PHYS_PAGE" "195"
					( Origin gFrontEnd )
				)
				( attribute "ROT" "0"
					( Origin gFrontEnd )
				)
				( attribute "SEC" "1"
					( Origin gFrontEnd )
				)
				( attribute "TOLERANCE" "20%"
					( Origin gFrontEnd )
				)
				( attribute "VALUE" "68UF"
					( Origin gFrontEnd )
				)
				( attribute "VER" "1"
					( Origin gFrontEnd )
				)
				( attribute "VOLTAGE" "16V"
					( Units "uVoltage" "V" 1.000000)
					( Origin gFrontEnd )
				)
				( attribute "XY" "(-7700,775)"
					( Origin gFrontEnd )
				)
				( attribute "CHIPS_PART_NAME" "CAPP"
					( Origin gPackager )
				)
				( attribute "CDS_PART_NAME" "CAPP_3018-68UF,16V,20%,TANT,72A"
					( Origin gPackager )
				)
				( attribute "SEC_TYPE" "3018"
					( Origin gFrontEnd )
				)
				( attribute "CDS_SEC" "1"
					( Origin gPackager )
				)
				( objectStatus "C3B6" )
			)
			( gate "@baseboard_fab2_lib.baseboard_fab2(sch_1):page195_i101"
				( attribute "CDS_LIB" "mstr_discrete"
					( Origin gPackager )
				)
				( attribute "CDS_LOCATION" "C1R23"
					( Origin gPackager )
				)
				( attribute "LOCATION" "C1R23"
					( Origin gFrontEnd )
				)
				( attribute "MATERIAL" "TANT"
					( Origin gFrontEnd )
				)
				( attribute "PACK_TYPE" "3018"
					( Origin gFrontEnd )
				)
				( attribute "PART_NUMBER" "724613-112"
					( Origin gFrontEnd )
				)
				( attribute "PHYS_PAGE" "195"
					( Origin gFrontEnd )
				)
				( attribute "ROT" "0"
					( Origin gFrontEnd )
				)
				( attribute "SEC" "1"
					( Origin gFrontEnd )
				)
				( attribute "TOLERANCE" "20%"
					( Origin gFrontEnd )
				)
				( attribute "VALUE" "68UF"
					( Origin gFrontEnd )
				)
				( attribute "VER" "1"
					( Origin gFrontEnd )
				)
				( attribute "VOLTAGE" "16V"
					( Units "uVoltage" "V" 1.000000)
					( Origin gFrontEnd )
				)
				( attribute "XY" "(-6175,775)"
					( Origin gFrontEnd )
				)
				( attribute "CHIPS_PART_NAME" "CAPP"
					( Origin gPackager )
				)
				( attribute "CDS_PART_NAME" "CAPP_3018-68UF,16V,20%,TANT,72A"
					( Origin gPackager )
				)
				( attribute "SEC_TYPE" "3018"
					( Origin gFrontEnd )
				)
				( attribute "CDS_SEC" "1"
					( Origin gPackager )
				)
				( objectStatus "C1R23" )
			)
			( gate "@baseboard_fab2_lib.baseboard_fab2(sch_1):page195_i102"
				( attribute "CDS_LIB" "mstr_discrete"
					( Origin gPackager )
				)
				( attribute "CDS_LOCATION" "C4M6"
					( Origin gPackager )
				)
				( attribute "LOCATION" "C4M6"
					( Origin gFrontEnd )
				)
				( attribute "MATERIAL" "TANT"
					( Origin gFrontEnd )
				)
				( attribute "PACK_TYPE" "3018"
					( Origin gFrontEnd )
				)
				( attribute "PART_NUMBER" "724613-112"
					( Origin gFrontEnd )
				)
				( attribute "PHYS_PAGE" "195"
					( Origin gFrontEnd )
				)
				( attribute "ROT" "0"
					( Origin gFrontEnd )
				)
				( attribute "SEC" "1"
					( Origin gFrontEnd )
				)
				( attribute "TOLERANCE" "20%"
					( Origin gFrontEnd )
				)
				( attribute "VALUE" "68UF"
					( Origin gFrontEnd )
				)
				( attribute "VER" "1"
					( Origin gFrontEnd )
				)
				( attribute "VOLTAGE" "16V"
					( Units "uVoltage" "V" 1.000000)
					( Origin gFrontEnd )
				)
				( attribute "XY" "(-4875,775)"
					( Origin gFrontEnd )
				)
				( attribute "CHIPS_PART_NAME" "CAPP"
					( Origin gPackager )
				)
				( attribute "CDS_PART_NAME" "CAPP_3018-68UF,16V,20%,TANT,72A"
					( Origin gPackager )
				)
				( attribute "SEC_TYPE" "3018"
					( Origin gFrontEnd )
				)
				( attribute "CDS_SEC" "1"
					( Origin gPackager )
				)
				( objectStatus "C4M6" )
			)
			( gate "@baseboard_fab2_lib.baseboard_fab2(sch_1):page195_i103"
				( attribute "CDS_LIB" "mstr_discrete"
					( Origin gPackager )
				)
				( attribute "CDS_LOCATION" "C1M5"
					( Origin gPackager )
				)
				( attribute "LOCATION" "C1M5"
					( Origin gFrontEnd )
				)
				( attribute "MATERIAL" "TANT"
					( Origin gFrontEnd )
				)
				( attribute "PACK_TYPE" "3018"
					( Origin gFrontEnd )
				)
				( attribute "PART_NUMBER" "724613-112"
					( Origin gFrontEnd )
				)
				( attribute "PHYS_PAGE" "195"
					( Origin gFrontEnd )
				)
				( attribute "ROT" "0"
					( Origin gFrontEnd )
				)
				( attribute "SEC" "1"
					( Origin gFrontEnd )
				)
				( attribute "TOLERANCE" "20%"
					( Origin gFrontEnd )
				)
				( attribute "VALUE" "68UF"
					( Origin gFrontEnd )
				)
				( attribute "VER" "1"
					( Origin gFrontEnd )
				)
				( attribute "VOLTAGE" "16V"
					( Units "uVoltage" "V" 1.000000)
					( Origin gFrontEnd )
				)
				( attribute "XY" "(-6550,775)"
					( Origin gFrontEnd )
				)
				( attribute "CHIPS_PART_NAME" "CAPP"
					( Origin gPackager )
				)
				( attribute "CDS_PART_NAME" "CAPP_3018-68UF,16V,20%,TANT,72A"
					( Origin gPackager )
				)
				( attribute "SEC_TYPE" "3018"
					( Origin gFrontEnd )
				)
				( attribute "CDS_SEC" "1"
					( Origin gPackager )
				)
				( objectStatus "C1M5" )
			)
			( gate "@baseboard_fab2_lib.baseboard_fab2(sch_1):page195_i104"
				( attribute "CDS_LIB" "mstr_discrete"
					( Origin gPackager )
				)
				( attribute "CDS_LOCATION" "C3T13"
					( Origin gPackager )
				)
				( attribute "LOCATION" "C3T13"
					( Origin gFrontEnd )
				)
				( attribute "MATERIAL" "TANT"
					( Origin gFrontEnd )
				)
				( attribute "PACK_TYPE" "3018"
					( Origin gFrontEnd )
				)
				( attribute "PART_NUMBER" "724613-112"
					( Origin gFrontEnd )
				)
				( attribute "PHYS_PAGE" "195"
					( Origin gFrontEnd )
				)
				( attribute "ROT" "0"
					( Origin gFrontEnd )
				)
				( attribute "SEC" "1"
					( Origin gFrontEnd )
				)
				( attribute "TOLERANCE" "20%"
					( Origin gFrontEnd )
				)
				( attribute "VALUE" "68UF"
					( Origin gFrontEnd )
				)
				( attribute "VER" "1"
					( Origin gFrontEnd )
				)
				( attribute "VOLTAGE" "16V"
					( Units "uVoltage" "V" 1.000000)
					( Origin gFrontEnd )
				)
				( attribute "XY" "(-5725,1950)"
					( Origin gFrontEnd )
				)
				( attribute "CHIPS_PART_NAME" "CAPP"
					( Origin gPackager )
				)
				( attribute "CDS_PART_NAME" "CAPP_3018-68UF,16V,20%,TANT,72A"
					( Origin gPackager )
				)
				( attribute "SEC_TYPE" "3018"
					( Origin gFrontEnd )
				)
				( attribute "CDS_SEC" "1"
					( Origin gPackager )
				)
				( objectStatus "C3T13" )
			)
			( gate "@baseboard_fab2_lib.baseboard_fab2(sch_1):page195_i105"
				( attribute "CDS_LIB" "mstr_discrete"
					( Origin gPackager )
				)
				( attribute "CDS_LOCATION" "C4M7"
					( Origin gPackager )
				)
				( attribute "LOCATION" "C4M7"
					( Origin gFrontEnd )
				)
				( attribute "MATERIAL" "TANT"
					( Origin gFrontEnd )
				)
				( attribute "PACK_TYPE" "3018"
					( Origin gFrontEnd )
				)
				( attribute "PART_NUMBER" "724613-112"
					( Origin gFrontEnd )
				)
				( attribute "PHYS_PAGE" "195"
					( Origin gFrontEnd )
				)
				( attribute "ROT" "0"
					( Origin gFrontEnd )
				)
				( attribute "SEC" "1"
					( Origin gFrontEnd )
				)
				( attribute "TOLERANCE" "20%"
					( Origin gFrontEnd )
				)
				( attribute "VALUE" "68UF"
					( Origin gFrontEnd )
				)
				( attribute "VER" "1"
					( Origin gFrontEnd )
				)
				( attribute "VOLTAGE" "16V"
					( Units "uVoltage" "V" 1.000000)
					( Origin gFrontEnd )
				)
				( attribute "XY" "(-4850,1950)"
					( Origin gFrontEnd )
				)
				( attribute "CHIPS_PART_NAME" "CAPP"
					( Origin gPackager )
				)
				( attribute "CDS_PART_NAME" "CAPP_3018-68UF,16V,20%,TANT,72A"
					( Origin gPackager )
				)
				( attribute "SEC_TYPE" "3018"
					( Origin gFrontEnd )
				)
				( attribute "CDS_SEC" "1"
					( Origin gPackager )
				)
				( objectStatus "C4M7" )
			)
			( gate "@baseboard_fab2_lib.baseboard_fab2(sch_1):page195_i106"
				( attribute "CDS_LIB" "mstr_discrete"
					( Origin gPackager )
				)
				( attribute "CDS_LOCATION" "C3T15"
					( Origin gPackager )
				)
				( attribute "LOCATION" "C3T15"
					( Origin gFrontEnd )
				)
				( attribute "MATERIAL" "TANT"
					( Origin gFrontEnd )
				)
				( attribute "PACK_TYPE" "3018"
					( Origin gFrontEnd )
				)
				( attribute "PART_NUMBER" "724613-112"
					( Origin gFrontEnd )
				)
				( attribute "PHYS_PAGE" "195"
					( Origin gFrontEnd )
				)
				( attribute "ROT" "0"
					( Origin gFrontEnd )
				)
				( attribute "SEC" "1"
					( Origin gFrontEnd )
				)
				( attribute "TOLERANCE" "20%"
					( Origin gFrontEnd )
				)
				( attribute "VALUE" "68UF"
					( Origin gFrontEnd )
				)
				( attribute "VER" "1"
					( Origin gFrontEnd )
				)
				( attribute "VOLTAGE" "16V"
					( Units "uVoltage" "V" 1.000000)
					( Origin gFrontEnd )
				)
				( attribute "XY" "(-5275,1925)"
					( Origin gFrontEnd )
				)
				( attribute "CHIPS_PART_NAME" "CAPP"
					( Origin gPackager )
				)
				( attribute "CDS_PART_NAME" "CAPP_3018-68UF,16V,20%,TANT,72A"
					( Origin gPackager )
				)
				( attribute "SEC_TYPE" "3018"
					( Origin gFrontEnd )
				)
				( attribute "CDS_SEC" "1"
					( Origin gPackager )
				)
				( objectStatus "C3T15" )
			)
			( gate "@baseboard_fab2_lib.baseboard_fab2(sch_1):page195_i108"
				( attribute "CDS_LIB" "mstr_discrete"
					( Origin gPackager )
				)
				( attribute "CDS_LOCATION" "C7M6"
					( Origin gPackager )
				)
				( attribute "LOCATION" "C7M6"
					( Origin gFrontEnd )
				)
				( attribute "MATERIAL" "TANT"
					( Origin gFrontEnd )
				)
				( attribute "PACK_TYPE" "3018"
					( Origin gFrontEnd )
				)
				( attribute "PART_NUMBER" "724613-112"
					( Origin gFrontEnd )
				)
				( attribute "PHYS_PAGE" "195"
					( Origin gFrontEnd )
				)
				( attribute "ROT" "0"
					( Origin gFrontEnd )
				)
				( attribute "SEC" "1"
					( Origin gFrontEnd )
				)
				( attribute "TOLERANCE" "20%"
					( Origin gFrontEnd )
				)
				( attribute "VALUE" "68UF"
					( Origin gFrontEnd )
				)
				( attribute "VER" "1"
					( Origin gFrontEnd )
				)
				( attribute "VOLTAGE" "16V"
					( Units "uVoltage" "V" 1.000000)
					( Origin gFrontEnd )
				)
				( attribute "XY" "(-6150,1950)"
					( Origin gFrontEnd )
				)
				( attribute "CHIPS_PART_NAME" "CAPP"
					( Origin gPackager )
				)
				( attribute "CDS_PART_NAME" "CAPP_3018-68UF,16V,20%,TANT,72A"
					( Origin gPackager )
				)
				( attribute "SEC_TYPE" "3018"
					( Origin gFrontEnd )
				)
				( attribute "CDS_SEC" "1"
					( Origin gPackager )
				)
				( objectStatus "C7M6" )
			)
			( gate "@baseboard_fab2_lib.baseboard_fab2(sch_1):page195_i109"
				( attribute "CDS_LIB" "mstr_discrete"
					( Origin gPackager )
				)
				( attribute "CDS_LOCATION" "C6N5"
					( Origin gPackager )
				)
				( attribute "LOCATION" "C6N5"
					( Origin gFrontEnd )
				)
				( attribute "MATERIAL" "TANT"
					( Origin gFrontEnd )
				)
				( attribute "PACK_TYPE" "3018"
					( Origin gFrontEnd )
				)
				( attribute "PART_NUMBER" "724613-112"
					( Origin gFrontEnd )
				)
				( attribute "PHYS_PAGE" "195"
					( Origin gFrontEnd )
				)
				( attribute "ROT" "0"
					( Origin gFrontEnd )
				)
				( attribute "SEC" "1"
					( Origin gFrontEnd )
				)
				( attribute "TOLERANCE" "20%"
					( Origin gFrontEnd )
				)
				( attribute "VALUE" "68UF"
					( Origin gFrontEnd )
				)
				( attribute "VER" "1"
					( Origin gFrontEnd )
				)
				( attribute "VOLTAGE" "16V"
					( Units "uVoltage" "V" 1.000000)
					( Origin gFrontEnd )
				)
				( attribute "XY" "(-6525,1950)"
					( Origin gFrontEnd )
				)
				( attribute "CHIPS_PART_NAME" "CAPP"
					( Origin gPackager )
				)
				( attribute "CDS_PART_NAME" "CAPP_3018-68UF,16V,20%,TANT,72A"
					( Origin gPackager )
				)
				( attribute "SEC_TYPE" "3018"
					( Origin gFrontEnd )
				)
				( attribute "CDS_SEC" "1"
					( Origin gPackager )
				)
				( objectStatus "C6N5" )
			)
			( gate "@baseboard_fab2_lib.baseboard_fab2(sch_1):page195_i111"
				( attribute "CDS_LIB" "mstr_discrete"
					( Origin gPackager )
				)
				( attribute "CDS_LOCATION" "C9T3"
					( Origin gPackager )
				)
				( attribute "LOCATION" "C9T3"
					( Origin gFrontEnd )
				)
				( attribute "MATERIAL" "TANT"
					( Origin gFrontEnd )
				)
				( attribute "PACK_TYPE" "3018"
					( Origin gFrontEnd )
				)
				( attribute "PART_NUMBER" "724613-112"
					( Origin gFrontEnd )
				)
				( attribute "PHYS_PAGE" "195"
					( Origin gFrontEnd )
				)
				( attribute "ROT" "0"
					( Origin gFrontEnd )
				)
				( attribute "SEC" "1"
					( Origin gFrontEnd )
				)
				( attribute "TOLERANCE" "20%"
					( Origin gFrontEnd )
				)
				( attribute "VALUE" "68UF"
					( Origin gFrontEnd )
				)
				( attribute "VER" "1"
					( Origin gFrontEnd )
				)
				( attribute "VOLTAGE" "16V"
					( Units "uVoltage" "V" 1.000000)
					( Origin gFrontEnd )
				)
				( attribute "XY" "(-6875,1950)"
					( Origin gFrontEnd )
				)
				( attribute "CHIPS_PART_NAME" "CAPP"
					( Origin gPackager )
				)
				( attribute "CDS_PART_NAME" "CAPP_3018-68UF,16V,20%,TANT,72A"
					( Origin gPackager )
				)
				( attribute "SEC_TYPE" "3018"
					( Origin gFrontEnd )
				)
				( attribute "CDS_SEC" "1"
					( Origin gPackager )
				)
				( objectStatus "C9T3" )
			)
			( gate "@baseboard_fab2_lib.baseboard_fab2(sch_1):page195_i112"
				( attribute "CDS_LIB" "mstr_discrete"
					( Origin gPackager )
				)
				( attribute "CDS_LOCATION" "C4F4"
					( Origin gPackager )
				)
				( attribute "LOCATION" "C4F4"
					( Origin gFrontEnd )
				)
				( attribute "MATERIAL" "TANT"
					( Origin gFrontEnd )
				)
				( attribute "PACK_TYPE" "3018"
					( Origin gFrontEnd )
				)
				( attribute "PART_NUMBER" "724613-112"
					( Origin gFrontEnd )
				)
				( attribute "PHYS_PAGE" "195"
					( Origin gFrontEnd )
				)
				( attribute "ROT" "0"
					( Origin gFrontEnd )
				)
				( attribute "SEC" "1"
					( Origin gFrontEnd )
				)
				( attribute "TOLERANCE" "20%"
					( Origin gFrontEnd )
				)
				( attribute "VALUE" "68UF"
					( Origin gFrontEnd )
				)
				( attribute "VER" "1"
					( Origin gFrontEnd )
				)
				( attribute "VOLTAGE" "16V"
					( Units "uVoltage" "V" 1.000000)
					( Origin gFrontEnd )
				)
				( attribute "XY" "(-7250,1950)"
					( Origin gFrontEnd )
				)
				( attribute "CHIPS_PART_NAME" "CAPP"
					( Origin gPackager )
				)
				( attribute "CDS_PART_NAME" "CAPP_3018-68UF,16V,20%,TANT,72A"
					( Origin gPackager )
				)
				( attribute "SEC_TYPE" "3018"
					( Origin gFrontEnd )
				)
				( attribute "CDS_SEC" "1"
					( Origin gPackager )
				)
				( objectStatus "C4F4" )
			)
			( gate "@baseboard_fab2_lib.baseboard_fab2(sch_1):page195_i113"
				( attribute "CDS_LIB" "mstr_discrete"
					( Origin gPackager )
				)
				( attribute "CDS_LOCATION" "C3T3"
					( Origin gPackager )
				)
				( attribute "LOCATION" "C3T3"
					( Origin gFrontEnd )
				)
				( attribute "MATERIAL" "TANT"
					( Origin gFrontEnd )
				)
				( attribute "PACK_TYPE" "3018"
					( Origin gFrontEnd )
				)
				( attribute "PART_NUMBER" "724613-112"
					( Origin gFrontEnd )
				)
				( attribute "PHYS_PAGE" "195"
					( Origin gFrontEnd )
				)
				( attribute "ROT" "0"
					( Origin gFrontEnd )
				)
				( attribute "SEC" "1"
					( Origin gFrontEnd )
				)
				( attribute "TOLERANCE" "20%"
					( Origin gFrontEnd )
				)
				( attribute "VALUE" "68UF"
					( Origin gFrontEnd )
				)
				( attribute "VER" "1"
					( Origin gFrontEnd )
				)
				( attribute "VOLTAGE" "16V"
					( Units "uVoltage" "V" 1.000000)
					( Origin gFrontEnd )
				)
				( attribute "XY" "(-7675,1950)"
					( Origin gFrontEnd )
				)
				( attribute "CHIPS_PART_NAME" "CAPP"
					( Origin gPackager )
				)
				( attribute "CDS_PART_NAME" "CAPP_3018-68UF,16V,20%,TANT,72A"
					( Origin gPackager )
				)
				( attribute "SEC_TYPE" "3018"
					( Origin gFrontEnd )
				)
				( attribute "CDS_SEC" "1"
					( Origin gPackager )
				)
				( objectStatus "C3T3" )
			)
			( gate "@baseboard_fab2_lib.baseboard_fab2(sch_1):page196_i46"
				( attribute "BOM_COST" "SB"
					( Origin gFrontEnd )
				)
				( attribute "CDS_LIB" "mstr_discrete"
					( Origin gPackager )
				)
				( attribute "CDS_LOCATION" "R2U43"
					( Origin gPackager )
				)
				( attribute "CDS_SEC" "1"
					( Origin gPackager )
				)
				( attribute "LOCATION" "R2U43"
					( Origin gFrontEnd )
				)
				( attribute "MATERIAL" "CHIP"
					( Origin gFrontEnd )
				)
				( attribute "PACK_TYPE" "0402"
					( Origin gFrontEnd )
				)
				( attribute "PART_NUMBER" "G21796-026"
					( Origin gFrontEnd )
				)
				( attribute "PHYS_PAGE" "196"
					( Origin gFrontEnd )
				)
				( attribute "ROOM" "SB_VRD"
					( Origin gFrontEnd )
				)
				( attribute "ROT" "0"
					( Origin gFrontEnd )
				)
				( attribute "SEC" "1"
					( Origin gFrontEnd )
				)
				( attribute "SEC_TYPE" "0402"
					( Origin gFrontEnd )
				)
				( attribute "TOLERANCE" "1%"
					( Origin gFrontEnd )
				)
				( attribute "VALUE" "1.00K"
					( Origin gFrontEnd )
				)
				( attribute "VER" "1"
					( Origin gFrontEnd )
				)
				( attribute "WATTAGE" "1/16W"
					( Origin gFrontEnd )
				)
				( attribute "XY" "(-3650,4550)"
					( Origin gFrontEnd )
				)
				( attribute "CHIPS_PART_NAME" "RES"
					( Origin gPackager )
				)
				( attribute "CDS_PART_NAME" "RES_0402-1.00K,1%,1/16W,CHIP,GA"
					( Origin gPackager )
				)
				( objectStatus "R2U43" )
			)
			( gate "@baseboard_fab2_lib.baseboard_fab2(sch_1):page196_i47"
				( attribute "BOM_COST" "SB"
					( Origin gFrontEnd )
				)
				( attribute "CDS_LIB" "mstr_misc"
					( Origin gPackager )
				)
				( attribute "CDS_LOCATION" "BT8G1"
					( Origin gPackager )
				)
				( attribute "LOCATION" "BT8G1"
					( Origin gFrontEnd )
				)
				( attribute "PACK_TYPE" "PLCLF"
					( Origin gFrontEnd )
				)
				( attribute "PART_NUMBER" "202168-001"
					( Origin gFrontEnd )
				)
				( attribute "PHYS_PAGE" "196"
					( Origin gFrontEnd )
				)
				( attribute "ROOM" "SB_VRD"
					( Origin gFrontEnd )
				)
				( attribute "ROT" "0"
					( Origin gFrontEnd )
				)
				( attribute "VER" "1"
					( Origin gFrontEnd )
				)
				( attribute "XY" "(-4375,4200)"
					( Origin gFrontEnd )
				)
				( attribute "CHIPS_PART_NAME" "BATTERY"
					( Origin gPackager )
				)
				( attribute "CDS_PART_NAME" "BATTERY_PLCLF-202168-001"
					( Origin gPackager )
				)
				( objectStatus "BT8G1" )
			)
			( gate "@baseboard_fab2_lib.baseboard_fab2(sch_1):page196_i51"
				( attribute "CDS_LIB" "mstr_discrete"
					( Origin gPackager )
				)
				( attribute "CDS_LOCATION" "XBT8G1"
					( Origin gPackager )
				)
				( attribute "CDS_SEC" "1"
					( Origin gPackager )
				)
				( attribute "LOCATION" "XBT8G1"
					( Origin gFrontEnd )
				)
				( attribute "MATERIAL" "3PVERT"
					( Origin gFrontEnd )
				)
				( attribute "PACK_TYPE" "PIP"
					( Origin gFrontEnd )
				)
				( attribute "PART_NUMBER" "C68619-005"
					( Origin gFrontEnd )
				)
				( attribute "PHYS_PAGE" "196"
					( Origin gFrontEnd )
				)
				( attribute "ROOM" "SB_VRD"
					( Origin gFrontEnd )
				)
				( attribute "ROT" "0"
					( Origin gFrontEnd )
				)
				( attribute "SEC" "1"
					( Origin gFrontEnd )
				)
				( attribute "SEC_TYPE" "PIP"
					( Origin gFrontEnd )
				)
				( attribute "VER" "1"
					( Origin gFrontEnd )
				)
				( attribute "XY" "(-4800,4550)"
					( Origin gFrontEnd )
				)
				( attribute "CHIPS_PART_NAME" "VERT_BATT_3PIN"
					( Origin gPackager )
				)
				( attribute "CDS_PART_NAME" "VERT_BATT_3PIN_PIP-3PVERT,C686A"
					( Origin gPackager )
				)
				( objectStatus "XBT8G1" )
			)
			( gate "@baseboard_fab2_lib.baseboard_fab2(sch_1):page196_i53"
				( attribute "CDS_LIB" "mstr_discrete"
					( Origin gPackager )
				)
				( attribute "CDS_LOCATION" "CR2U1"
					( Origin gPackager )
				)
				( attribute "CDS_SEC" "1"
					( Origin gPackager )
				)
				( attribute "LOCATION" "CR2U1"
					( Origin gFrontEnd )
				)
				( attribute "MATERIAL" "DIO"
					( Origin gFrontEnd )
				)
				( attribute "PACK_TYPE" "SMLF"
					( Origin gFrontEnd )
				)
				( attribute "PART_NUMBER" "C90169-001"
					( Origin gFrontEnd )
				)
				( attribute "PHYS_PAGE" "196"
					( Origin gFrontEnd )
				)
				( attribute "ROOM" "SB_VRD"
					( Origin gFrontEnd )
				)
				( attribute "ROT" "0"
					( Origin gFrontEnd )
				)
				( attribute "SEC" "1"
					( Origin gFrontEnd )
				)
				( attribute "SEC_TYPE" "SMLF"
					( Origin gFrontEnd )
				)
				( attribute "VALUE" "BAS70-05"
					( Origin gFrontEnd )
				)
				( attribute "VER" "1"
					( Origin gFrontEnd )
				)
				( attribute "XY" "(-2700,4650)"
					( Origin gFrontEnd )
				)
				( attribute "CHIPS_PART_NAME" "DIODE2A_DUAL"
					( Origin gPackager )
				)
				( attribute "CDS_PART_NAME" "DIODE2A_DUAL_SMLF-BAS70-05,DIOA"
					( Origin gPackager )
				)
				( objectStatus "CR2U1" )
			)
			( gate "@baseboard_fab2_lib.baseboard_fab2(sch_1):page196_i59"
				( attribute "CDS_LIB" "mstr_discrete"
					( Origin gPackager )
				)
				( attribute "CDS_LOCATION" "R3P44"
					( Origin gPackager )
				)
				( attribute "CDS_SEC" "1"
					( Origin gPackager )
				)
				( attribute "LOCATION" "R3P44"
					( Origin gFrontEnd )
				)
				( attribute "MATERIAL" "CHIP"
					( Origin gFrontEnd )
				)
				( attribute "PACK_TYPE" "0402"
					( Origin gFrontEnd )
				)
				( attribute "PART_NUMBER" "G21796-072"
					( Origin gFrontEnd )
				)
				( attribute "PHYS_PAGE" "196"
					( Origin gFrontEnd )
				)
				( attribute "ROOM" "V_SUPER"
					( Origin gFrontEnd )
				)
				( attribute "ROT" "0"
					( Origin gFrontEnd )
				)
				( attribute "SEC" "1"
					( Origin gFrontEnd )
				)
				( attribute "SEC_TYPE" "0402"
					( Origin gFrontEnd )
				)
				( attribute "TOLERANCE" "1%"
					( Origin gFrontEnd )
				)
				( attribute "VALUE" "4.75K"
					( Origin gFrontEnd )
				)
				( attribute "VER" "2"
					( Origin gFrontEnd )
				)
				( attribute "WATTAGE" "1/16W"
					( Origin gFrontEnd )
				)
				( attribute "XY" "(1325,4650)"
					( Origin gFrontEnd )
				)
				( attribute "CHIPS_PART_NAME" "RES"
					( Origin gPackager )
				)
				( attribute "CDS_PART_NAME" "RES_0402-4.75K,1%,1/16W,CHIP,GA"
					( Origin gPackager )
				)
				( objectStatus "R3P44" )
			)
			( gate "@baseboard_fab2_lib.baseboard_fab2(sch_1):page196_i60"
				( attribute "CDS_LIB" "mstr_discrete"
					( Origin gPackager )
				)
				( attribute "CDS_LOCATION" "C3P45"
					( Origin gPackager )
				)
				( attribute "CDS_SEC" "1"
					( Origin gPackager )
				)
				( attribute "LOCATION" "C3P45"
					( Origin gFrontEnd )
				)
				( attribute "MATERIAL" "X7R"
					( Origin gFrontEnd )
				)
				( attribute "PACK_TYPE" "0402"
					( Origin gFrontEnd )
				)
				( attribute "PART_NUMBER" "A36096-090"
					( Origin gFrontEnd )
				)
				( attribute "PHYS_PAGE" "196"
					( Origin gFrontEnd )
				)
				( attribute "ROOM" "V_SUPER"
					( Origin gFrontEnd )
				)
				( attribute "ROT" "0"
					( Origin gFrontEnd )
				)
				( attribute "SEC" "1"
					( Origin gFrontEnd )
				)
				( attribute "SEC_TYPE" "0402"
					( Origin gFrontEnd )
				)
				( attribute "TOLERANCE" "10%"
					( Origin gFrontEnd )
				)
				( attribute "VALUE" "0.047UF"
					( Origin gFrontEnd )
				)
				( attribute "VER" "1"
					( Origin gFrontEnd )
				)
				( attribute "VOLTAGE" "25V"
					( Units "uVoltage" "V" 1.000000)
					( Origin gFrontEnd )
				)
				( attribute "XY" "(1225,4050)"
					( Origin gFrontEnd )
				)
				( attribute "CHIPS_PART_NAME" "CAP"
					( Origin gPackager )
				)
				( attribute "CDS_PART_NAME" "CAP_0402-0.047UF,25V,10%,X7R,AA"
					( Origin gPackager )
				)
				( objectStatus "C3P45" )
			)
			( gate "@baseboard_fab2_lib.baseboard_fab2(sch_1):page196_i65"
				( attribute "CDS_LIB" "mstr_discrete"
					( Origin gPackager )
				)
				( attribute "CDS_LOCATION" "R2P20"
					( Origin gPackager )
				)
				( attribute "CDS_SEC" "1"
					( Origin gPackager )
				)
				( attribute "LOCATION" "R2P20"
					( Origin gFrontEnd )
				)
				( attribute "MATERIAL" "CHIP"
					( Origin gFrontEnd )
				)
				( attribute "PACK_TYPE" "0402"
					( Origin gFrontEnd )
				)
				( attribute "PART_NUMBER" "G21796-017"
					( Origin gFrontEnd )
				)
				( attribute "PHYS_PAGE" "196"
					( Origin gFrontEnd )
				)
				( attribute "ROOM" "V_SUPER"
					( Origin gFrontEnd )
				)
				( attribute "ROT" "0"
					( Origin gFrontEnd )
				)
				( attribute "SEC" "1"
					( Origin gFrontEnd )
				)
				( attribute "SEC_TYPE" "0402"
					( Origin gFrontEnd )
				)
				( attribute "TOLERANCE" "1%"
					( Origin gFrontEnd )
				)
				( attribute "VALUE" "100.0"
					( Origin gFrontEnd )
				)
				( attribute "VER" "1"
					( Origin gFrontEnd )
				)
				( attribute "WATTAGE" "1/16W"
					( Origin gFrontEnd )
				)
				( attribute "XY" "(1350,2000)"
					( Origin gFrontEnd )
				)
				( attribute "CHIPS_PART_NAME" "RES"
					( Origin gPackager )
				)
				( attribute "CDS_PART_NAME" "RES_0402-100.0,1%,1/16W,CHIP,GA"
					( Origin gPackager )
				)
				( objectStatus "R2P20" )
			)
			( gate "@baseboard_fab2_lib.baseboard_fab2(sch_1):page196_i68"
				( attribute "CDS_LIB" "mstr_discrete"
					( Origin gPackager )
				)
				( attribute "CDS_LOCATION" "R1L16"
					( Origin gPackager )
				)
				( attribute "CDS_SEC" "1"
					( Origin gPackager )
				)
				( attribute "LOCATION" "R1L16"
					( Origin gFrontEnd )
				)
				( attribute "MATERIAL" "CHIP"
					( Origin gFrontEnd )
				)
				( attribute "PACK_TYPE" "0402"
					( Origin gFrontEnd )
				)
				( attribute "PART_NUMBER" "G21796-047"
					( Origin gFrontEnd )
				)
				( attribute "PHYS_PAGE" "196"
					( Origin gFrontEnd )
				)
				( attribute "ROOM" "V_SUPER"
					( Origin gFrontEnd )
				)
				( attribute "ROT" "0"
					( Origin gFrontEnd )
				)
				( attribute "SEC" "1"
					( Origin gFrontEnd )
				)
				( attribute "SEC_TYPE" "0402"
					( Origin gFrontEnd )
				)
				( attribute "TOLERANCE" "1%"
					( Origin gFrontEnd )
				)
				( attribute "VALUE" "49.9"
					( Origin gFrontEnd )
				)
				( attribute "VER" "1"
					( Origin gFrontEnd )
				)
				( attribute "WATTAGE" "1/16W"
					( Origin gFrontEnd )
				)
				( attribute "XY" "(1300,1250)"
					( Origin gFrontEnd )
				)
				( attribute "CHIPS_PART_NAME" "RES"
					( Origin gPackager )
				)
				( attribute "CDS_PART_NAME" "RES_0402-49.9,1%,1/16W,CHIP,G2A"
					( Origin gPackager )
				)
				( objectStatus "R1L16" )
			)
			( gate "@baseboard_fab2_lib.baseboard_fab2(sch_1):page196_i70"
				( attribute "CDS_LIB" "mstr_analog"
					( Origin gPackager )
				)
				( attribute "CDS_LOCATION" "U7D3"
					( Origin gPackager )
				)
				( attribute "CDS_SEC" "1"
					( Origin gPackager )
				)
				( attribute "LOCATION" "U7D3"
					( Origin gFrontEnd )
				)
				( attribute "MATERIAL" "IC"
					( Origin gFrontEnd )
				)
				( attribute "PACK_TYPE" "SMT"
					( Origin gFrontEnd )
				)
				( attribute "PART_NUMBER" "H46130-001"
					( Origin gFrontEnd )
				)
				( attribute "PHYS_PAGE" "196"
					( Origin gFrontEnd )
				)
				( attribute "ROOM" "V_SUPER"
					( Origin gFrontEnd )
				)
				( attribute "ROT" "0"
					( Origin gFrontEnd )
				)
				( attribute "SEC" "1"
					( Origin gFrontEnd )
				)
				( attribute "SEC_TYPE" "SMT"
					( Origin gFrontEnd )
				)
				( attribute "VER" "1"
					( Origin gFrontEnd )
				)
				( attribute "XY" "(725,4400)"
					( Origin gFrontEnd )
				)
				( attribute "CHIPS_PART_NAME" "ADM1085"
					( Origin gPackager )
				)
				( attribute "CDS_PART_NAME" "ADM1085_SMT-IC,H46130-001"
					( Origin gPackager )
				)
				( objectStatus "U7D3" )
			)
			( gate "@baseboard_fab2_lib.baseboard_fab2(sch_1):page196_i71"
				( attribute "CDS_LIB" "mstr_discrete"
					( Origin gPackager )
				)
				( attribute "CDS_LOCATION" "R3P50"
					( Origin gPackager )
				)
				( attribute "CDS_SEC" "1"
					( Origin gPackager )
				)
				( attribute "LOCATION" "R3P50"
					( Origin gFrontEnd )
				)
				( attribute "MATERIAL" "EMPTY"
					( Origin gFrontEnd )
				)
				( attribute "PACK_TYPE" "0402"
					( Origin gFrontEnd )
				)
				( attribute "PART_NUMBER" "G21796-016"
					( Origin gFrontEnd )
				)
				( attribute "PHYS_PAGE" "196"
					( Origin gFrontEnd )
				)
				( attribute "ROOM" "V_SUPER"
					( Origin gFrontEnd )
				)
				( attribute "ROT" "0"
					( Origin gFrontEnd )
				)
				( attribute "SEC" "1"
					( Origin gFrontEnd )
				)
				( attribute "SEC_TYPE" "0402"
					( Origin gFrontEnd )
				)
				( attribute "TOLERANCE" "1%"
					( Origin gFrontEnd )
				)
				( attribute "VALUE" "10.0K"
					( Origin gFrontEnd )
				)
				( attribute "VER" "2"
					( Origin gFrontEnd )
				)
				( attribute "WATTAGE" "1/16W"
					( Origin gFrontEnd )
				)
				( attribute "XY" "(-25,4750)"
					( Origin gFrontEnd )
				)
				( attribute "CHIPS_PART_NAME" "RES"
					( Origin gPackager )
				)
				( attribute "CDS_PART_NAME" "RES_0402-10.0K,1%,1/16W,EMPTY,A"
					( Origin gPackager )
				)
				( objectStatus "R3P50" )
			)
			( gate "@baseboard_fab2_lib.baseboard_fab2(sch_1):page196_i72"
				( attribute "CDS_LIB" "dev_discrete"
					( Origin gPackager )
				)
				( attribute "CDS_LOCATION" "C3P46"
					( Origin gPackager )
				)
				( attribute "CDS_SEC" "1"
					( Origin gPackager )
				)
				( attribute "LOCATION" "C3P46"
					( Origin gFrontEnd )
				)
				( attribute "MATERIAL" "X7R"
					( Origin gFrontEnd )
				)
				( attribute "PACK_TYPE" "0402V"
					( Origin gFrontEnd )
				)
				( attribute "PART_NUMBER" "A36096-030"
					( Origin gFrontEnd )
				)
				( attribute "PHYS_PAGE" "196"
					( Origin gFrontEnd )
				)
				( attribute "ROOM" "V_SUPER"
					( Origin gFrontEnd )
				)
				( attribute "ROT" "0"
					( Origin gFrontEnd )
				)
				( attribute "SEC" "1"
					( Origin gFrontEnd )
				)
				( attribute "SEC_TYPE" "0402V"
					( Origin gFrontEnd )
				)
				( attribute "TOLERANCE" "10%"
					( Origin gFrontEnd )
				)
				( attribute "VALUE" "0.1UF"
					( Origin gFrontEnd )
				)
				( attribute "VER" "1"
					( Origin gFrontEnd )
				)
				( attribute "VOLTAGE" "16V"
					( Units "uVoltage" "V" 1.000000)
					( Origin gFrontEnd )
				)
				( attribute "XY" "(275,3950)"
					( Origin gFrontEnd )
				)
				( attribute "CHIPS_PART_NAME" "CAP_A"
					( Origin gPackager )
				)
				( attribute "CDS_PART_NAME" "CAP_A_0402V-0.1UF,16V,10%,X7R,A"
					( Origin gPackager )
				)
				( objectStatus "C3P46" )
			)
			( gate "@baseboard_fab2_lib.baseboard_fab2(sch_1):page196_i74"
				( attribute "CDS_LIB" "mstr_discrete"
					( Origin gPackager )
				)
				( attribute "CDS_LOCATION" "R3P48"
					( Origin gPackager )
				)
				( attribute "CDS_SEC" "1"
					( Origin gPackager )
				)
				( attribute "LOCATION" "R3P48"
					( Origin gFrontEnd )
				)
				( attribute "MATERIAL" "CHIP"
					( Origin gFrontEnd )
				)
				( attribute "PACK_TYPE" "0402"
					( Origin gFrontEnd )
				)
				( attribute "PART_NUMBER" "G21796-058"
					( Origin gFrontEnd )
				)
				( attribute "PHYS_PAGE" "196"
					( Origin gFrontEnd )
				)
				( attribute "ROOM" "V_SUPER"
					( Origin gFrontEnd )
				)
				( attribute "ROT" "0"
					( Origin gFrontEnd )
				)
				( attribute "SEC" "1"
					( Origin gFrontEnd )
				)
				( attribute "SEC_TYPE" "0402"
					( Origin gFrontEnd )
				)
				( attribute "TOLERANCE" "1%"
					( Origin gFrontEnd )
				)
				( attribute "VALUE" "90.9K"
					( Origin gFrontEnd )
				)
				( attribute "VER" "2"
					( Origin gFrontEnd )
				)
				( attribute "WATTAGE" "1/16W"
					( Origin gFrontEnd )
				)
				( attribute "XY" "(-525,4750)"
					( Origin gFrontEnd )
				)
				( attribute "CHIPS_PART_NAME" "RES"
					( Origin gPackager )
				)
				( attribute "CDS_PART_NAME" "RES_0402-90.9K,1%,1/16W,CHIP,GA"
					( Origin gPackager )
				)
				( objectStatus "R3P48" )
			)
			( gate "@baseboard_fab2_lib.baseboard_fab2(sch_1):page196_i75"
				( attribute "CDS_LIB" "mstr_discrete"
					( Origin gPackager )
				)
				( attribute "CDS_LOCATION" "R3P51"
					( Origin gPackager )
				)
				( attribute "CDS_SEC" "1"
					( Origin gPackager )
				)
				( attribute "LOCATION" "R3P51"
					( Origin gFrontEnd )
				)
				( attribute "MATERIAL" "CHIP"
					( Origin gFrontEnd )
				)
				( attribute "PACK_TYPE" "0402"
					( Origin gFrontEnd )
				)
				( attribute "PART_NUMBER" "G21796-146"
					( Origin gFrontEnd )
				)
				( attribute "PHYS_PAGE" "196"
					( Origin gFrontEnd )
				)
				( attribute "ROOM" "V_SUPER"
					( Origin gFrontEnd )
				)
				( attribute "ROT" "0"
					( Origin gFrontEnd )
				)
				( attribute "SEC" "1"
					( Origin gFrontEnd )
				)
				( attribute "SEC_TYPE" "0402"
					( Origin gFrontEnd )
				)
				( attribute "TOLERANCE" "1%"
					( Origin gFrontEnd )
				)
				( attribute "VALUE" "6.34K"
					( Origin gFrontEnd )
				)
				( attribute "VER" "2"
					( Origin gFrontEnd )
				)
				( attribute "WATTAGE" "1/16W"
					( Origin gFrontEnd )
				)
				( attribute "XY" "(-525,4250)"
					( Origin gFrontEnd )
				)
				( attribute "CHIPS_PART_NAME" "RES"
					( Origin gPackager )
				)
				( attribute "CDS_PART_NAME" "RES_0402-6.34K,1%,1/16W,CHIP,GA"
					( Origin gPackager )
				)
				( objectStatus "R3P51" )
			)
			( gate "@baseboard_fab2_lib.baseboard_fab2(sch_1):page196_i80"
				( attribute "CDS_LIB" "mstr_analog"
					( Origin gPackager )
				)
				( attribute "CDS_LOCATION" "U1L3"
					( Origin gPackager )
				)
				( attribute "CDS_SEC" "1"
					( Origin gPackager )
				)
				( attribute "LOCATION" "U1L3"
					( Origin gFrontEnd )
				)
				( attribute "MATERIAL" "IC"
					( Origin gFrontEnd )
				)
				( attribute "PACK_TYPE" "SMLF"
					( Origin gFrontEnd )
				)
				( attribute "PART_NUMBER" "D23047-001"
					( Origin gFrontEnd )
				)
				( attribute "PHYS_PAGE" "196"
					( Origin gFrontEnd )
				)
				( attribute "ROOM" "V_SUPER"
					( Origin gFrontEnd )
				)
				( attribute "ROT" "0"
					( Origin gFrontEnd )
				)
				( attribute "SEC" "1"
					( Origin gPackager )
				)
				( attribute "VER" "1"
					( Origin gFrontEnd )
				)
				( attribute "XY" "(200,1350)"
					( Origin gFrontEnd )
				)
				( attribute "CHIPS_PART_NAME" "ADM809"
					( Origin gPackager )
				)
				( attribute "CDS_PART_NAME" "ADM809_SMLF-IC,D23047-001"
					( Origin gPackager )
				)
				( objectStatus "U1L3" )
			)
			( gate "@baseboard_fab2_lib.baseboard_fab2(sch_1):page196_i81"
				( attribute "CDS_LIB" "dev_discrete"
					( Origin gPackager )
				)
				( attribute "CDS_LOCATION" "C1L16"
					( Origin gPackager )
				)
				( attribute "LOCATION" "C1L16"
					( Origin gFrontEnd )
				)
				( attribute "MATERIAL" "X7R"
					( Origin gFrontEnd )
				)
				( attribute "PACK_TYPE" "0402V"
					( Origin gFrontEnd )
				)
				( attribute "PART_NUMBER" "A36096-030"
					( Origin gFrontEnd )
				)
				( attribute "PHYS_PAGE" "196"
					( Origin gFrontEnd )
				)
				( attribute "ROOM" "V_SUPER"
					( Origin gFrontEnd )
				)
				( attribute "ROT" "0"
					( Origin gFrontEnd )
				)
				( attribute "SEC" "1"
					( Origin gFrontEnd )
				)
				( attribute "TOLERANCE" "10%"
					( Origin gFrontEnd )
				)
				( attribute "VALUE" "0.1UF"
					( Origin gFrontEnd )
				)
				( attribute "VER" "1"
					( Origin gFrontEnd )
				)
				( attribute "VOLTAGE" "16V"
					( Units "uVoltage" "V" 1.000000)
					( Origin gFrontEnd )
				)
				( attribute "XY" "(-300,1250)"
					( Origin gFrontEnd )
				)
				( attribute "CHIPS_PART_NAME" "CAP_A"
					( Origin gPackager )
				)
				( attribute "CDS_PART_NAME" "CAP_A_0402V-0.1UF,16V,10%,X7R,A"
					( Origin gPackager )
				)
				( attribute "SEC_TYPE" "0402V"
					( Origin gFrontEnd )
				)
				( attribute "CDS_SEC" "1"
					( Origin gPackager )
				)
				( objectStatus "C1L16" )
			)
			( gate "@baseboard_fab2_lib.baseboard_fab2(sch_1):page196_i89"
				( attribute "CDS_LIB" "mstr_analog"
					( Origin gPackager )
				)
				( attribute "CDS_LOCATION" "U8E2"
					( Origin gPackager )
				)
				( attribute "CDS_SEC" "1"
					( Origin gPackager )
				)
				( attribute "LOCATION" "U8E2"
					( Origin gFrontEnd )
				)
				( attribute "MATERIAL" "IC"
					( Origin gFrontEnd )
				)
				( attribute "PACK_TYPE" "SMLF"
					( Origin gFrontEnd )
				)
				( attribute "PART_NUMBER" "D23047-001"
					( Origin gFrontEnd )
				)
				( attribute "PHYS_PAGE" "196"
					( Origin gFrontEnd )
				)
				( attribute "ROOM" "V_SUPER"
					( Origin gFrontEnd )
				)
				( attribute "ROT" "0"
					( Origin gFrontEnd )
				)
				( attribute "SEC" "1"
					( Origin gPackager )
				)
				( attribute "VER" "1"
					( Origin gFrontEnd )
				)
				( attribute "XY" "(400,3100)"
					( Origin gFrontEnd )
				)
				( attribute "CHIPS_PART_NAME" "ADM809"
					( Origin gPackager )
				)
				( attribute "CDS_PART_NAME" "ADM809_SMLF-IC,D23047-001"
					( Origin gPackager )
				)
				( objectStatus "U8E2" )
			)
			( gate "@baseboard_fab2_lib.baseboard_fab2(sch_1):page196_i90"
				( attribute "CDS_LIB" "mstr_discrete"
					( Origin gPackager )
				)
				( attribute "CDS_LOCATION" "R8E7"
					( Origin gPackager )
				)
				( attribute "CDS_SEC" "1"
					( Origin gPackager )
				)
				( attribute "LOCATION" "R8E7"
					( Origin gFrontEnd )
				)
				( attribute "MATERIAL" "CHIP"
					( Origin gFrontEnd )
				)
				( attribute "PACK_TYPE" "0402"
					( Origin gFrontEnd )
				)
				( attribute "PART_NUMBER" "G21796-250"
					( Origin gFrontEnd )
				)
				( attribute "PHYS_PAGE" "196"
					( Origin gFrontEnd )
				)
				( attribute "ROOM" "V_SUPER"
					( Origin gFrontEnd )
				)
				( attribute "ROT" "0"
					( Origin gFrontEnd )
				)
				( attribute "SEC" "1"
					( Origin gFrontEnd )
				)
				( attribute "SEC_TYPE" "0402"
					( Origin gFrontEnd )
				)
				( attribute "TOLERANCE" "1.0%"
					( Origin gFrontEnd )
				)
				( attribute "VALUE" "22.1"
					( Origin gFrontEnd )
				)
				( attribute "VER" "1"
					( Origin gFrontEnd )
				)
				( attribute "WATTAGE" "1/16W"
					( Origin gFrontEnd )
				)
				( attribute "XY" "(1325,3000)"
					( Origin gFrontEnd )
				)
				( attribute "CHIPS_PART_NAME" "RES"
					( Origin gPackager )
				)
				( attribute "CDS_PART_NAME" "RES_0402-22.1,1.0%,1/16W,CHIP,A"
					( Origin gPackager )
				)
				( objectStatus "R8E7" )
			)
			( gate "@baseboard_fab2_lib.baseboard_fab2(sch_1):page196_i94"
				( attribute "CDS_LIB" "dev_discrete"
					( Origin gPackager )
				)
				( attribute "CDS_LOCATION" "C8E3"
					( Origin gPackager )
				)
				( attribute "CDS_SEC" "1"
					( Origin gPackager )
				)
				( attribute "LOCATION" "C8E3"
					( Origin gFrontEnd )
				)
				( attribute "MATERIAL" "X7R"
					( Origin gFrontEnd )
				)
				( attribute "PACK_TYPE" "0402V"
					( Origin gFrontEnd )
				)
				( attribute "PART_NUMBER" "A36096-030"
					( Origin gFrontEnd )
				)
				( attribute "PHYS_PAGE" "196"
					( Origin gFrontEnd )
				)
				( attribute "ROOM" "V_SUPER"
					( Origin gFrontEnd )
				)
				( attribute "ROT" "0"
					( Origin gFrontEnd )
				)
				( attribute "SEC" "1"
					( Origin gFrontEnd )
				)
				( attribute "SEC_TYPE" "0402V"
					( Origin gFrontEnd )
				)
				( attribute "TOLERANCE" "10%"
					( Origin gFrontEnd )
				)
				( attribute "VALUE" "0.1UF"
					( Origin gFrontEnd )
				)
				( attribute "VER" "1"
					( Origin gFrontEnd )
				)
				( attribute "VOLTAGE" "16V"
					( Units "uVoltage" "V" 1.000000)
					( Origin gFrontEnd )
				)
				( attribute "XY" "(-300,2950)"
					( Origin gFrontEnd )
				)
				( attribute "CHIPS_PART_NAME" "CAP_A"
					( Origin gPackager )
				)
				( attribute "CDS_PART_NAME" "CAP_A_0402V-0.1UF,16V,10%,X7R,A"
					( Origin gPackager )
				)
				( objectStatus "C8E3" )
			)
			( gate "@baseboard_fab2_lib.baseboard_fab2(sch_1):page196_i102"
				( attribute "BOM_COST" "SB"
					( Origin gFrontEnd )
				)
				( attribute "CDS_LIB" "dev_discrete"
					( Origin gPackager )
				)
				( attribute "CDS_LOCATION" "C2U26"
					( Origin gPackager )
				)
				( attribute "CDS_SEC" "1"
					( Origin gPackager )
				)
				( attribute "LOCATION" "C2U26"
					( Origin gFrontEnd )
				)
				( attribute "MATERIAL" "X6S"
					( Origin gFrontEnd )
				)
				( attribute "NO_XNET_CONNECTION" "1"
					( Origin gFrontEnd )
				)
				( attribute "PACK_TYPE" "0402V"
					( Origin gFrontEnd )
				)
				( attribute "PART_NUMBER" "D97712-004"
					( Origin gFrontEnd )
				)
				( attribute "PHYS_PAGE" "196"
					( Origin gFrontEnd )
				)
				( attribute "ROOM" "SB_VRD"
					( Origin gFrontEnd )
				)
				( attribute "ROT" "0"
					( Origin gFrontEnd )
				)
				( attribute "SEC" "1"
					( Origin gFrontEnd )
				)
				( attribute "SEC_TYPE" "0402V"
					( Origin gFrontEnd )
				)
				( attribute "TOLERANCE" "10%"
					( Origin gFrontEnd )
				)
				( attribute "VALUE" "1.0UF"
					( Origin gFrontEnd )
				)
				( attribute "VER" "1"
					( Origin gFrontEnd )
				)
				( attribute "VOLTAGE" "6.3V"
					( Units "uVoltage" "V" 1.000000)
					( Origin gFrontEnd )
				)
				( attribute "XY" "(-2200,4500)"
					( Origin gFrontEnd )
				)
				( attribute "CHIPS_PART_NAME" "CAP_A"
					( Origin gPackager )
				)
				( attribute "CDS_PART_NAME" "CAP_A_0402V-1.0UF,6.3V,10%,X6SA"
					( Origin gPackager )
				)
				( objectStatus "C2U26" )
			)
			( gate "@baseboard_fab2_lib.baseboard_fab2(sch_1):page196_i103"
				( attribute "CDS_LIB" "mstr_discrete"
					( Origin gPackager )
				)
				( attribute "CDS_LOCATION" "CR7E1"
					( Origin gPackager )
				)
				( attribute "CDS_SEC" "1"
					( Origin gPackager )
				)
				( attribute "LOCATION" "CR7E1"
					( Origin gFrontEnd )
				)
				( attribute "MATERIAL" "IC"
					( Origin gFrontEnd )
				)
				( attribute "PACK_TYPE" "SMLF"
					( Origin gFrontEnd )
				)
				( attribute "PART_NUMBER" "C73510-001"
					( Origin gFrontEnd )
				)
				( attribute "PHYS_PAGE" "196"
					( Origin gFrontEnd )
				)
				( attribute "ROT" "0"
					( Origin gFrontEnd )
				)
				( attribute "SEC" "1"
					( Origin gFrontEnd )
				)
				( attribute "SEC_TYPE" "SMLF"
					( Origin gFrontEnd )
				)
				( attribute "VALUE" "BAT54WS"
					( Origin gFrontEnd )
				)
				( attribute "VER" "3"
					( Origin gFrontEnd )
				)
				( attribute "XY" "(825,3650)"
					( Origin gFrontEnd )
				)
				( attribute "CHIPS_PART_NAME" "DIODE"
					( Origin gPackager )
				)
				( attribute "CDS_PART_NAME" "DIODE_SMLF-BAT54WS,IC,C73510-0A"
					( Origin gPackager )
				)
				( objectStatus "CR7E1" )
			)
			( gate "@baseboard_fab2_lib.baseboard_fab2(sch_1):page196_i104"
				( attribute "CDS_LIB" "mstr_vreg"
					( Origin gPackager )
				)
				( attribute "CDS_LMAN_SYM_OUTLINE" "-250,200,250,-200"
					( Origin gPackager )
				)
				( attribute "CDS_LOCATION" "U8D8"
					( Origin gPackager )
				)
				( attribute "CDS_SEC" "1"
					( Origin gPackager )
				)
				( attribute "LOCATION" "U8D8"
					( Origin gFrontEnd )
				)
				( attribute "MATERIAL" "IC"
					( Origin gFrontEnd )
				)
				( attribute "PACK_TYPE" "SM"
					( Origin gFrontEnd )
				)
				( attribute "PART_NUMBER" "H69492-001"
					( Origin gFrontEnd )
				)
				( attribute "PHYS_PAGE" "196"
					( Origin gFrontEnd )
				)
				( attribute "ROOM" "V_SUPER"
					( Origin gFrontEnd )
				)
				( attribute "ROT" "0"
					( Origin gFrontEnd )
				)
				( attribute "SEC" "1"
					( Origin gPackager )
				)
				( attribute "VER" "1"
					( Origin gFrontEnd )
				)
				( attribute "XY" "(-500,2300)"
					( Origin gFrontEnd )
				)
				( attribute "CHIPS_PART_NAME" "TPS3700"
					( Origin gPackager )
				)
				( attribute "CDS_PART_NAME" "TPS3700_SM-IC,H69492-001"
					( Origin gPackager )
				)
				( objectStatus "U8D8" )
			)
			( gate "@baseboard_fab2_lib.baseboard_fab2(sch_1):page196_i105"
				( attribute "CDS_LIB" "dev_discrete"
					( Origin gPackager )
				)
				( attribute "CDS_LOCATION" "C8D4"
					( Origin gPackager )
				)
				( attribute "CDS_SEC" "1"
					( Origin gPackager )
				)
				( attribute "LOCATION" "C8D4"
					( Origin gFrontEnd )
				)
				( attribute "MATERIAL" "X7R"
					( Origin gFrontEnd )
				)
				( attribute "PACK_TYPE" "0402V"
					( Origin gFrontEnd )
				)
				( attribute "PART_NUMBER" "A36096-030"
					( Origin gFrontEnd )
				)
				( attribute "PHYS_PAGE" "196"
					( Origin gFrontEnd )
				)
				( attribute "ROOM" "V_SUPER"
					( Origin gFrontEnd )
				)
				( attribute "ROT" "0"
					( Origin gFrontEnd )
				)
				( attribute "SEC" "1"
					( Origin gPackager )
				)
				( attribute "TOLERANCE" "10%"
					( Origin gFrontEnd )
				)
				( attribute "VALUE" "0.1UF"
					( Origin gFrontEnd )
				)
				( attribute "VER" "1"
					( Origin gFrontEnd )
				)
				( attribute "VOLTAGE" "16V"
					( Units "uVoltage" "V" 1.000000)
					( Origin gFrontEnd )
				)
				( attribute "XY" "(-1000,1950)"
					( Origin gFrontEnd )
				)
				( attribute "CHIPS_PART_NAME" "CAP_A"
					( Origin gPackager )
				)
				( attribute "CDS_PART_NAME" "CAP_A_0402V-0.1UF,16V,10%,X7R,A"
					( Origin gPackager )
				)
				( objectStatus "C8D4" )
			)
			( gate "@baseboard_fab2_lib.baseboard_fab2(sch_1):page196_i106"
				( attribute "CDS_LIB" "mstr_discrete"
					( Origin gPackager )
				)
				( attribute "CDS_LOCATION" "R8D42"
					( Origin gPackager )
				)
				( attribute "CDS_SEC" "1"
					( Origin gPackager )
				)
				( attribute "LOCATION" "R8D42"
					( Origin gFrontEnd )
				)
				( attribute "MATERIAL" "CHIP"
					( Origin gFrontEnd )
				)
				( attribute "PACK_TYPE" "0402"
					( Origin gFrontEnd )
				)
				( attribute "PART_NUMBER" "G21796-017"
					( Origin gFrontEnd )
				)
				( attribute "PHYS_PAGE" "196"
					( Origin gFrontEnd )
				)
				( attribute "ROOM" "V_SUPER"
					( Origin gFrontEnd )
				)
				( attribute "ROT" "0"
					( Origin gFrontEnd )
				)
				( attribute "SEC" "1"
					( Origin gFrontEnd )
				)
				( attribute "SEC_TYPE" "0402"
					( Origin gFrontEnd )
				)
				( attribute "TOLERANCE" "1%"
					( Origin gFrontEnd )
				)
				( attribute "VALUE" "100.0"
					( Origin gFrontEnd )
				)
				( attribute "VER" "1"
					( Origin gFrontEnd )
				)
				( attribute "WATTAGE" "1/16W"
					( Origin gFrontEnd )
				)
				( attribute "XY" "(1350,2400)"
					( Origin gFrontEnd )
				)
				( attribute "CHIPS_PART_NAME" "RES"
					( Origin gPackager )
				)
				( attribute "CDS_PART_NAME" "RES_0402-100.0,1%,1/16W,CHIP,GA"
					( Origin gPackager )
				)
				( objectStatus "R8D42" )
			)
			( gate "@baseboard_fab2_lib.baseboard_fab2(sch_1):page196_i112"
				( attribute "CDS_LIB" "mstr_discrete"
					( Origin gPackager )
				)
				( attribute "CDS_LOCATION" "R8D38"
					( Origin gPackager )
				)
				( attribute "CDS_SEC" "1"
					( Origin gPackager )
				)
				( attribute "LOCATION" "R8D38"
					( Origin gFrontEnd )
				)
				( attribute "MATERIAL" "CHIP"
					( Origin gFrontEnd )
				)
				( attribute "PACK_TYPE" "0402"
					( Origin gFrontEnd )
				)
				( attribute "PART_NUMBER" "G21796-010"
					( Origin gFrontEnd )
				)
				( attribute "PHYS_PAGE" "196"
					( Origin gFrontEnd )
				)
				( attribute "ROOM" "V_SUPER"
					( Origin gFrontEnd )
				)
				( attribute "ROT" "0"
					( Origin gFrontEnd )
				)
				( attribute "SEC" "1"
					( Origin gFrontEnd )
				)
				( attribute "SEC_TYPE" "0402"
					( Origin gFrontEnd )
				)
				( attribute "TOLERANCE" "1%"
					( Origin gFrontEnd )
				)
				( attribute "VALUE" "100.0K"
					( Origin gFrontEnd )
				)
				( attribute "VER" "2"
					( Origin gFrontEnd )
				)
				( attribute "WATTAGE" "1/16W"
					( Origin gFrontEnd )
				)
				( attribute "XY" "(-1750,2850)"
					( Origin gFrontEnd )
				)
				( attribute "CHIPS_PART_NAME" "RES"
					( Origin gPackager )
				)
				( attribute "CDS_PART_NAME" "RES_0402-100.0K,1%,1/16W,CHIP,A"
					( Origin gPackager )
				)
				( attribute "CONFIG" "64.51135.6DL"
					( Origin gFrontEnd )
				)
				( attribute "NEW_VALUE" "511K"
					( Origin gFrontEnd )
				)
				( objectStatus "R8D38" )
			)
			( gate "@baseboard_fab2_lib.baseboard_fab2(sch_1):page200_i251"
				( attribute "CDS_LIB" "mstr_discrete"
					( Origin gPackager )
				)
				( attribute "CDS_LOCATION" "R9P9"
					( Origin gPackager )
				)
				( attribute "CDS_SEC" "1"
					( Origin gPackager )
				)
				( attribute "LOCATION" "R9P9"
					( Origin gFrontEnd )
				)
				( attribute "MATERIAL" "CHIP"
					( Origin gFrontEnd )
				)
				( attribute "PACK_TYPE" "0402"
					( Origin gFrontEnd )
				)
				( attribute "PART_NUMBER" "G21796-059"
					( Origin gFrontEnd )
				)
				( attribute "PHYS_PAGE" "200"
					( Origin gFrontEnd )
				)
				( attribute "ROOM" "V_SUPER"
					( Origin gFrontEnd )
				)
				( attribute "ROT" "0"
					( Origin gFrontEnd )
				)
				( attribute "SEC" "1"
					( Origin gFrontEnd )
				)
				( attribute "SEC_TYPE" "0402"
					( Origin gFrontEnd )
				)
				( attribute "TOLERANCE" "1%"
					( Origin gFrontEnd )
				)
				( attribute "VALUE" "3.74K"
					( Origin gFrontEnd )
				)
				( attribute "VER" "2"
					( Origin gFrontEnd )
				)
				( attribute "WATTAGE" "1/16W"
					( Origin gFrontEnd )
				)
				( attribute "XY" "(-1975,375)"
					( Origin gFrontEnd )
				)
				( attribute "CHIPS_PART_NAME" "RES"
					( Origin gPackager )
				)
				( attribute "CDS_PART_NAME" "RES_0402-3.74K,1%,1/16W,CHIP,GA"
					( Origin gPackager )
				)
				( objectStatus "R9P9" )
			)
			( gate "@baseboard_fab2_lib.baseboard_fab2(sch_1):page196_i114"
				( attribute "CDS_LIB" "mstr_discrete"
					( Origin gPackager )
				)
				( attribute "CDS_LOCATION" "R8D39"
					( Origin gPackager )
				)
				( attribute "CDS_SEC" "1"
					( Origin gPackager )
				)
				( attribute "LOCATION" "R8D39"
					( Origin gFrontEnd )
				)
				( attribute "MATERIAL" "CHIP"
					( Origin gFrontEnd )
				)
				( attribute "PACK_TYPE" "0402"
					( Origin gFrontEnd )
				)
				( attribute "PART_NUMBER" "G21796-048"
					( Origin gFrontEnd )
				)
				( attribute "PHYS_PAGE" "196"
					( Origin gFrontEnd )
				)
				( attribute "ROOM" "V_SUPER"
					( Origin gFrontEnd )
				)
				( attribute "ROT" "0"
					( Origin gFrontEnd )
				)
				( attribute "SEC" "1"
					( Origin gFrontEnd )
				)
				( attribute "SEC_TYPE" "0402"
					( Origin gFrontEnd )
				)
				( attribute "TOLERANCE" "1%"
					( Origin gFrontEnd )
				)
				( attribute "VALUE" "49.9K"
					( Origin gFrontEnd )
				)
				( attribute "VER" "2"
					( Origin gFrontEnd )
				)
				( attribute "WATTAGE" "1/16W"
					( Origin gFrontEnd )
				)
				( attribute "XY" "(-1750,1850)"
					( Origin gFrontEnd )
				)
				( attribute "CHIPS_PART_NAME" "RES"
					( Origin gPackager )
				)
				( attribute "CDS_PART_NAME" "RES_0402-49.9K,1%,1/16W,CHIP,GA"
					( Origin gPackager )
				)
				( objectStatus "R8D39" )
			)
			( gate "@baseboard_fab2_lib.baseboard_fab2(sch_1):page196_i115"
				( attribute "CDS_LIB" "mstr_discrete"
					( Origin gPackager )
				)
				( attribute "CDS_LOCATION" "R8D37"
					( Origin gPackager )
				)
				( attribute "CDS_SEC" "1"
					( Origin gPackager )
				)
				( attribute "LOCATION" "R8D37"
					( Origin gFrontEnd )
				)
				( attribute "MATERIAL" "CHIP"
					( Origin gFrontEnd )
				)
				( attribute "PACK_TYPE" "0402"
					( Origin gFrontEnd )
				)
				( attribute "PART_NUMBER" "G21796-072"
					( Origin gFrontEnd )
				)
				( attribute "PHYS_PAGE" "196"
					( Origin gFrontEnd )
				)
				( attribute "ROOM" "V_SUPER"
					( Origin gFrontEnd )
				)
				( attribute "ROT" "0"
					( Origin gFrontEnd )
				)
				( attribute "SEC" "1"
					( Origin gFrontEnd )
				)
				( attribute "SEC_TYPE" "0402"
					( Origin gFrontEnd )
				)
				( attribute "TOLERANCE" "1%"
					( Origin gFrontEnd )
				)
				( attribute "VALUE" "4.75K"
					( Origin gFrontEnd )
				)
				( attribute "VER" "2"
					( Origin gFrontEnd )
				)
				( attribute "WATTAGE" "1/16W"
					( Origin gFrontEnd )
				)
				( attribute "XY" "(-1750,1450)"
					( Origin gFrontEnd )
				)
				( attribute "CHIPS_PART_NAME" "RES"
					( Origin gPackager )
				)
				( attribute "CDS_PART_NAME" "RES_0402-4.75K,1%,1/16W,CHIP,GA"
					( Origin gPackager )
				)
				( objectStatus "R8D37" )
			)
			( gate "@baseboard_fab2_lib.baseboard_fab2(sch_1):page196_i120"
				( attribute "CDS_LIB" "mstr_discrete"
					( Origin gPackager )
				)
				( attribute "CDS_LOCATION" "R8D41"
					( Origin gPackager )
				)
				( attribute "CDS_SEC" "1"
					( Origin gPackager )
				)
				( attribute "LOCATION" "R8D41"
					( Origin gFrontEnd )
				)
				( attribute "MATERIAL" "CHIP"
					( Origin gFrontEnd )
				)
				( attribute "PACK_TYPE" "0402"
					( Origin gFrontEnd )
				)
				( attribute "PART_NUMBER" "G21796-016"
					( Origin gFrontEnd )
				)
				( attribute "PHYS_PAGE" "196"
					( Origin gFrontEnd )
				)
				( attribute "ROOM" "V_SUPER"
					( Origin gFrontEnd )
				)
				( attribute "ROT" "0"
					( Origin gFrontEnd )
				)
				( attribute "SEC" "1"
					( Origin gFrontEnd )
				)
				( attribute "SEC_TYPE" "0402"
					( Origin gFrontEnd )
				)
				( attribute "TOLERANCE" "1%"
					( Origin gFrontEnd )
				)
				( attribute "VALUE" "10.0K"
					( Origin gFrontEnd )
				)
				( attribute "VER" "2"
					( Origin gFrontEnd )
				)
				( attribute "WATTAGE" "1/16W"
					( Origin gFrontEnd )
				)
				( attribute "XY" "(50,2650)"
					( Origin gFrontEnd )
				)
				( attribute "CHIPS_PART_NAME" "RES"
					( Origin gPackager )
				)
				( attribute "CDS_PART_NAME" "RES_0402-10.0K,1%,1/16W,CHIP,GA"
					( Origin gPackager )
				)
				( objectStatus "R8D41" )
			)
			( gate "@baseboard_fab2_lib.baseboard_fab2(sch_1):page196_i121"
				( attribute "CDS_LIB" "mstr_discrete"
					( Origin gPackager )
				)
				( attribute "CDS_LOCATION" "R2P18"
					( Origin gPackager )
				)
				( attribute "CDS_SEC" "1"
					( Origin gPackager )
				)
				( attribute "LOCATION" "R2P18"
					( Origin gFrontEnd )
				)
				( attribute "MATERIAL" "CHIP"
					( Origin gFrontEnd )
				)
				( attribute "PACK_TYPE" "0402"
					( Origin gFrontEnd )
				)
				( attribute "PART_NUMBER" "G21796-016"
					( Origin gFrontEnd )
				)
				( attribute "PHYS_PAGE" "196"
					( Origin gFrontEnd )
				)
				( attribute "ROOM" "V_SUPER"
					( Origin gFrontEnd )
				)
				( attribute "ROT" "0"
					( Origin gFrontEnd )
				)
				( attribute "SEC" "1"
					( Origin gFrontEnd )
				)
				( attribute "SEC_TYPE" "0402"
					( Origin gFrontEnd )
				)
				( attribute "TOLERANCE" "1%"
					( Origin gFrontEnd )
				)
				( attribute "VALUE" "10.0K"
					( Origin gFrontEnd )
				)
				( attribute "VER" "2"
					( Origin gFrontEnd )
				)
				( attribute "WATTAGE" "1/16W"
					( Origin gFrontEnd )
				)
				( attribute "XY" "(250,2000)"
					( Origin gFrontEnd )
				)
				( attribute "CHIPS_PART_NAME" "RES"
					( Origin gPackager )
				)
				( attribute "CDS_PART_NAME" "RES_0402-10.0K,1%,1/16W,CHIP,GA"
					( Origin gPackager )
				)
				( objectStatus "R2P18" )
			)
			( gate "@baseboard_fab2_lib.baseboard_fab2(sch_1):page196_i122"
				( attribute "CDS_LIB" "mstr_discrete"
					( Origin gPackager )
				)
				( attribute "CDS_LOCATION" "R2P21"
					( Origin gPackager )
				)
				( attribute "CDS_SEC" "1"
					( Origin gPackager )
				)
				( attribute "LOCATION" "R2P21"
					( Origin gFrontEnd )
				)
				( attribute "MATERIAL" "CHIP"
					( Origin gFrontEnd )
				)
				( attribute "PACK_TYPE" "0402"
					( Origin gFrontEnd )
				)
				( attribute "PART_NUMBER" "G21796-016"
					( Origin gFrontEnd )
				)
				( attribute "PHYS_PAGE" "196"
					( Origin gFrontEnd )
				)
				( attribute "ROOM" "V_SUPER"
					( Origin gFrontEnd )
				)
				( attribute "ROT" "0"
					( Origin gFrontEnd )
				)
				( attribute "SEC" "1"
					( Origin gFrontEnd )
				)
				( attribute "SEC_TYPE" "0402"
					( Origin gFrontEnd )
				)
				( attribute "TOLERANCE" "1%"
					( Origin gFrontEnd )
				)
				( attribute "VALUE" "10.0K"
					( Origin gFrontEnd )
				)
				( attribute "VER" "2"
					( Origin gFrontEnd )
				)
				( attribute "WATTAGE" "1/16W"
					( Origin gFrontEnd )
				)
				( attribute "XY" "(750,2200)"
					( Origin gFrontEnd )
				)
				( attribute "CHIPS_PART_NAME" "RES"
					( Origin gPackager )
				)
				( attribute "CDS_PART_NAME" "RES_0402-10.0K,1%,1/16W,CHIP,GA"
					( Origin gPackager )
				)
				( objectStatus "R2P21" )
			)
			( gate "@baseboard_fab2_lib.baseboard_fab2(sch_1):page134_i14"
				( attribute "CDS_LIB" "mstr_discrete"
					( Origin gPackager )
				)
				( attribute "LOCATION" "Q7D1"
					( Origin gFrontEnd )
				)
				( attribute "MATERIAL" "FET"
					( Origin gFrontEnd )
				)
				( attribute "PACK_TYPE" "SOT23LF"
					( Origin gFrontEnd )
				)
				( attribute "PART_NUMBER" "C79254-001"
					( Origin gFrontEnd )
				)
				( attribute "PHYS_PAGE" "134"
					( Origin gFrontEnd )
				)
				( attribute "ROOM" "HOT_SWAP"
					( Origin gFrontEnd )
				)
				( attribute "ROT" "0"
					( Origin gFrontEnd )
				)
				( attribute "VALUE" "2N7002"
					( Origin gFrontEnd )
				)
				( attribute "VER" "8"
					( Origin gFrontEnd )
				)
				( attribute "XY" "(-2875,4400)"
					( Origin gFrontEnd )
				)
				( attribute "CHIPS_PART_NAME" "FET_N"
					( Origin gPackager )
				)
				( attribute "CDS_PART_NAME" "FET_N_SOT23LF-2N7002,FET,C7925A"
					( Origin gPackager )
				)
				( attribute "CDS_LOCATION" "Q7D1"
					( Origin gPackager )
				)
				( attribute "CDS_SEC" "1"
					( Origin gPackager )
				)
				( attribute "SEC" "1"
					( Origin gPackager )
				)
				( objectStatus "Q7D1" )
			)
			( gate "@baseboard_fab2_lib.baseboard_fab2(sch_1):page196_i128"
				( attribute "CDS_LIB" "mstr_discrete"
					( Origin gPackager )
				)
				( attribute "CDS_LOCATION" "CR8E1"
					( Origin gPackager )
				)
				( attribute "CDS_SEC" "1"
					( Origin gPackager )
				)
				( attribute "LOCATION" "CR8E1"
					( Origin gFrontEnd )
				)
				( attribute "MATERIAL" "IC"
					( Origin gFrontEnd )
				)
				( attribute "PACK_TYPE" "SMLF"
					( Origin gFrontEnd )
				)
				( attribute "PART_NUMBER" "C73510-001"
					( Origin gFrontEnd )
				)
				( attribute "PHYS_PAGE" "196"
					( Origin gFrontEnd )
				)
				( attribute "ROT" "0"
					( Origin gFrontEnd )
				)
				( attribute "SEC" "1"
					( Origin gFrontEnd )
				)
				( attribute "SEC_TYPE" "SMLF"
					( Origin gFrontEnd )
				)
				( attribute "VALUE" "BAT54WS"
					( Origin gFrontEnd )
				)
				( attribute "VER" "3"
					( Origin gFrontEnd )
				)
				( attribute "XY" "(1050,3400)"
					( Origin gFrontEnd )
				)
				( attribute "CHIPS_PART_NAME" "DIODE"
					( Origin gPackager )
				)
				( attribute "CDS_PART_NAME" "DIODE_SMLF-BAT54WS,IC,C73510-0A"
					( Origin gPackager )
				)
				( objectStatus "CR8E1" )
			)
			( gate "@baseboard_fab2_lib.baseboard_fab2(sch_1):page198_i1"
				( attribute "CDS_LIB" "mstr_vreg"
					( Origin gPackager )
				)
				( attribute "CDS_LMAN_SYM_OUTLINE" "-250,250,250,-250"
					( Origin gPackager )
				)
				( attribute "CDS_LOCATION" "EU2T1"
					( Origin gPackager )
				)
				( attribute "CDS_SEC" "1"
					( Origin gPackager )
				)
				( attribute "LOCATION" "EU2T1"
					( Origin gFrontEnd )
				)
				( attribute "MATERIAL" "IC"
					( Origin gFrontEnd )
				)
				( attribute "PACK_TYPE" "SM"
					( Origin gFrontEnd )
				)
				( attribute "PART_NUMBER" "G56246-001"
					( Origin gFrontEnd )
				)
				( attribute "PHYS_PAGE" "198"
					( Origin gFrontEnd )
				)
				( attribute "ROOM" "P3V3_PWR_SWITCH"
					( Origin gFrontEnd )
				)
				( attribute "ROT" "0"
					( Origin gFrontEnd )
				)
				( attribute "SEC" "1"
					( Origin gPackager )
				)
				( attribute "VER" "1"
					( Origin gFrontEnd )
				)
				( attribute "XY" "(-7000,3825)"
					( Origin gFrontEnd )
				)
				( attribute "CHIPS_PART_NAME" "SLG55021"
					( Origin gPackager )
				)
				( attribute "CDS_PART_NAME" "SLG55021_SM-IC,G56246-001"
					( Origin gPackager )
				)
				( objectStatus "EU2T1" )
			)
			( gate "@baseboard_fab2_lib.baseboard_fab2(sch_1):page198_i13"
				( attribute "CDS_LIB" "mstr_vreg"
					( Origin gPackager )
				)
				( attribute "CDS_LMAN_SYM_OUTLINE" "-250,250,250,-250"
					( Origin gPackager )
				)
				( attribute "CDS_LOCATION" "EU8B1"
					( Origin gPackager )
				)
				( attribute "CDS_SEC" "1"
					( Origin gPackager )
				)
				( attribute "LOCATION" "EU8B1"
					( Origin gFrontEnd )
				)
				( attribute "MATERIAL" "IC"
					( Origin gFrontEnd )
				)
				( attribute "PACK_TYPE" "SM"
					( Origin gFrontEnd )
				)
				( attribute "PART_NUMBER" "G56246-001"
					( Origin gFrontEnd )
				)
				( attribute "PHYS_PAGE" "198"
					( Origin gFrontEnd )
				)
				( attribute "ROOM" "P5V_PWR_SWITCH"
					( Origin gFrontEnd )
				)
				( attribute "ROT" "0"
					( Origin gFrontEnd )
				)
				( attribute "SEC" "1"
					( Origin gFrontEnd )
				)
				( attribute "SEC_TYPE" "SM"
					( Origin gFrontEnd )
				)
				( attribute "VER" "1"
					( Origin gFrontEnd )
				)
				( attribute "XY" "(-3300,3800)"
					( Origin gFrontEnd )
				)
				( attribute "CHIPS_PART_NAME" "SLG55021"
					( Origin gPackager )
				)
				( attribute "CDS_PART_NAME" "SLG55021_SM-IC,G56246-001"
					( Origin gPackager )
				)
				( objectStatus "EU8B1" )
			)
			( gate "@baseboard_fab2_lib.baseboard_fab2(sch_1):page198_i19"
				( attribute "CDS_LIB" "mstr_vreg"
					( Origin gPackager )
				)
				( attribute "CDS_LMAN_SYM_OUTLINE" "-250,250,250,-250"
					( Origin gPackager )
				)
				( attribute "CDS_LOCATION" "EU7E1"
					( Origin gPackager )
				)
				( attribute "CDS_SEC" "1"
					( Origin gPackager )
				)
				( attribute "LOCATION" "EU7E1"
					( Origin gFrontEnd )
				)
				( attribute "MATERIAL" "IC"
					( Origin gFrontEnd )
				)
				( attribute "PACK_TYPE" "SM"
					( Origin gFrontEnd )
				)
				( attribute "PART_NUMBER" "G56246-001"
					( Origin gFrontEnd )
				)
				( attribute "PHYS_PAGE" "198"
					( Origin gFrontEnd )
				)
				( attribute "ROOM" "P12V_PWR_SWITCH"
					( Origin gFrontEnd )
				)
				( attribute "ROT" "0"
					( Origin gFrontEnd )
				)
				( attribute "SEC" "1"
					( Origin gFrontEnd )
				)
				( attribute "SEC_TYPE" "SM"
					( Origin gFrontEnd )
				)
				( attribute "VER" "1"
					( Origin gFrontEnd )
				)
				( attribute "XY" "(-6725,1850)"
					( Origin gFrontEnd )
				)
				( attribute "CHIPS_PART_NAME" "SLG55021"
					( Origin gPackager )
				)
				( attribute "CDS_PART_NAME" "SLG55021_SM-IC,G56246-001"
					( Origin gPackager )
				)
				( objectStatus "EU7E1" )
			)
			( gate "@baseboard_fab2_lib.baseboard_fab2(sch_1):page198_i24"
				( attribute "CDS_LIB" "dev_discrete"
					( Origin gPackager )
				)
				( attribute "CDS_LOCATION" "C8F17"
					( Origin gPackager )
				)
				( attribute "CDS_SEC" "1"
					( Origin gPackager )
				)
				( attribute "LOCATION" "C8F17"
					( Origin gFrontEnd )
				)
				( attribute "MATERIAL" "X7R"
					( Origin gFrontEnd )
				)
				( attribute "PACK_TYPE" "0402V"
					( Origin gFrontEnd )
				)
				( attribute "PART_NUMBER" "A36096-030"
					( Origin gFrontEnd )
				)
				( attribute "PHYS_PAGE" "198"
					( Origin gFrontEnd )
				)
				( attribute "ROOM" "P3V3_PWR_SWITCH"
					( Origin gFrontEnd )
				)
				( attribute "ROT" "0"
					( Origin gFrontEnd )
				)
				( attribute "SEC" "1"
					( Origin gFrontEnd )
				)
				( attribute "SEC_TYPE" "0402V"
					( Origin gFrontEnd )
				)
				( attribute "TOLERANCE" "10%"
					( Origin gFrontEnd )
				)
				( attribute "VALUE" "0.1UF"
					( Origin gFrontEnd )
				)
				( attribute "VER" "1"
					( Origin gFrontEnd )
				)
				( attribute "VOLTAGE" "16V"
					( Units "uVoltage" "V" 1.000000)
					( Origin gFrontEnd )
				)
				( attribute "XY" "(-8000,4200)"
					( Origin gFrontEnd )
				)
				( attribute "CHIPS_PART_NAME" "CAP_A"
					( Origin gPackager )
				)
				( attribute "CDS_PART_NAME" "CAP_A_0402V-0.1UF,16V,10%,X7R,A"
					( Origin gPackager )
				)
				( objectStatus "C8F17" )
			)
			( gate "@baseboard_fab2_lib.baseboard_fab2(sch_1):page198_i26"
				( attribute "CDS_LIB" "dev_discrete"
					( Origin gPackager )
				)
				( attribute "CDS_LOCATION" "C8B8"
					( Origin gPackager )
				)
				( attribute "CDS_SEC" "1"
					( Origin gPackager )
				)
				( attribute "LOCATION" "C8B8"
					( Origin gFrontEnd )
				)
				( attribute "MATERIAL" "X7R"
					( Origin gFrontEnd )
				)
				( attribute "PACK_TYPE" "0402V"
					( Origin gFrontEnd )
				)
				( attribute "PART_NUMBER" "A36096-030"
					( Origin gFrontEnd )
				)
				( attribute "PHYS_PAGE" "198"
					( Origin gFrontEnd )
				)
				( attribute "ROOM" "P5V_PWR_SWITCH"
					( Origin gFrontEnd )
				)
				( attribute "ROT" "0"
					( Origin gFrontEnd )
				)
				( attribute "SEC" "1"
					( Origin gFrontEnd )
				)
				( attribute "SEC_TYPE" "0402V"
					( Origin gFrontEnd )
				)
				( attribute "TOLERANCE" "10%"
					( Origin gFrontEnd )
				)
				( attribute "VALUE" "0.1UF"
					( Origin gFrontEnd )
				)
				( attribute "VER" "1"
					( Origin gFrontEnd )
				)
				( attribute "VOLTAGE" "16V"
					( Units "uVoltage" "V" 1.000000)
					( Origin gFrontEnd )
				)
				( attribute "XY" "(-4300,4125)"
					( Origin gFrontEnd )
				)
				( attribute "CHIPS_PART_NAME" "CAP_A"
					( Origin gPackager )
				)
				( attribute "CDS_PART_NAME" "CAP_A_0402V-0.1UF,16V,10%,X7R,A"
					( Origin gPackager )
				)
				( objectStatus "C8B8" )
			)
			( gate "@baseboard_fab2_lib.baseboard_fab2(sch_1):page198_i28"
				( attribute "CDS_LIB" "dev_discrete"
					( Origin gPackager )
				)
				( attribute "CDS_LOCATION" "C8E19"
					( Origin gPackager )
				)
				( attribute "CDS_SEC" "1"
					( Origin gPackager )
				)
				( attribute "LOCATION" "C8E19"
					( Origin gFrontEnd )
				)
				( attribute "MATERIAL" "X7R"
					( Origin gFrontEnd )
				)
				( attribute "PACK_TYPE" "0402V"
					( Origin gFrontEnd )
				)
				( attribute "PART_NUMBER" "A36096-030"
					( Origin gFrontEnd )
				)
				( attribute "PHYS_PAGE" "198"
					( Origin gFrontEnd )
				)
				( attribute "ROOM" "P12V_PWR_SWITCH"
					( Origin gFrontEnd )
				)
				( attribute "ROT" "0"
					( Origin gFrontEnd )
				)
				( attribute "SEC" "1"
					( Origin gFrontEnd )
				)
				( attribute "SEC_TYPE" "0402V"
					( Origin gFrontEnd )
				)
				( attribute "TOLERANCE" "10%"
					( Origin gFrontEnd )
				)
				( attribute "VALUE" "0.1UF"
					( Origin gFrontEnd )
				)
				( attribute "VER" "1"
					( Origin gFrontEnd )
				)
				( attribute "VOLTAGE" "16V"
					( Units "uVoltage" "V" 1.000000)
					( Origin gFrontEnd )
				)
				( attribute "XY" "(-7725,2175)"
					( Origin gFrontEnd )
				)
				( attribute "CHIPS_PART_NAME" "CAP_A"
					( Origin gPackager )
				)
				( attribute "CDS_PART_NAME" "CAP_A_0402V-0.1UF,16V,10%,X7R,A"
					( Origin gPackager )
				)
				( objectStatus "C8E19" )
			)
			( gate "@baseboard_fab2_lib.baseboard_fab2(sch_1):page198_i37"
				( attribute "BOM_COST" "PWR_SWITCH"
					( Origin gFrontEnd )
				)
				( attribute "CDS_LIB" "dev_discrete"
					( Origin gPackager )
				)
				( attribute "CDS_LOCATION" "C8B5"
					( Origin gPackager )
				)
				( attribute "CDS_SEC" "1"
					( Origin gPackager )
				)
				( attribute "LOCATION" "C8B5"
					( Origin gFrontEnd )
				)
				( attribute "MATERIAL" "X7R"
					( Origin gFrontEnd )
				)
				( attribute "PACK_TYPE" "0402V"
					( Origin gFrontEnd )
				)
				( attribute "PART_NUMBER" "A36096-030"
					( Origin gFrontEnd )
				)
				( attribute "PHYS_PAGE" "198"
					( Origin gFrontEnd )
				)
				( attribute "ROOM" "P5V_PWR_SWITCH"
					( Origin gFrontEnd )
				)
				( attribute "ROT" "0"
					( Origin gFrontEnd )
				)
				( attribute "SEC" "1"
					( Origin gFrontEnd )
				)
				( attribute "SEC_TYPE" "0402V"
					( Origin gFrontEnd )
				)
				( attribute "TOLERANCE" "10%"
					( Origin gFrontEnd )
				)
				( attribute "VALUE" "0.1UF"
					( Origin gFrontEnd )
				)
				( attribute "VER" "1"
					( Origin gFrontEnd )
				)
				( attribute "VOLTAGE" "16V"
					( Units "uVoltage" "V" 1.000000)
					( Origin gFrontEnd )
				)
				( attribute "XY" "(-1050,4400)"
					( Origin gFrontEnd )
				)
				( attribute "CHIPS_PART_NAME" "CAP_A"
					( Origin gPackager )
				)
				( attribute "CDS_PART_NAME" "CAP_A_0402V-0.1UF,16V,10%,X7R,A"
					( Origin gPackager )
				)
				( objectStatus "C8B5" )
			)
			( gate "@baseboard_fab2_lib.baseboard_fab2(sch_1):page198_i38"
				( attribute "CDS_LIB" "mstr_discrete"
					( Origin gPackager )
				)
				( attribute "CDS_LOCATION" "C8B12"
					( Origin gPackager )
				)
				( attribute "CDS_SEC" "1"
					( Origin gPackager )
				)
				( attribute "LOCATION" "C8B12"
					( Origin gFrontEnd )
				)
				( attribute "MATERIAL" "X6S"
					( Origin gFrontEnd )
				)
				( attribute "PACK_TYPE" "0805"
					( Origin gFrontEnd )
				)
				( attribute "PART_NUMBER" "C95333-007"
					( Origin gFrontEnd )
				)
				( attribute "PHYS_PAGE" "198"
					( Origin gFrontEnd )
				)
				( attribute "ROOM" "P5V_PWR_SWITCH"
					( Origin gFrontEnd )
				)
				( attribute "ROT" "0"
					( Origin gFrontEnd )
				)
				( attribute "SEC" "1"
					( Origin gFrontEnd )
				)
				( attribute "SEC_TYPE" "0805"
					( Origin gFrontEnd )
				)
				( attribute "TOLERANCE" "10%"
					( Origin gFrontEnd )
				)
				( attribute "VALUE" "10UF"
					( Origin gFrontEnd )
				)
				( attribute "VER" "1"
					( Origin gFrontEnd )
				)
				( attribute "VOLTAGE" "16V"
					( Units "uVoltage" "V" 1.000000)
					( Origin gFrontEnd )
				)
				( attribute "XY" "(-1375,4400)"
					( Origin gFrontEnd )
				)
				( attribute "CHIPS_PART_NAME" "CAP"
					( Origin gPackager )
				)
				( attribute "CDS_PART_NAME" "CAP_0805-10UF,16V,10%,X6S,C953A"
					( Origin gPackager )
				)
				( objectStatus "C8B12" )
			)
			( gate "@baseboard_fab2_lib.baseboard_fab2(sch_1):page198_i40"
				( attribute "CDS_LIB" "mstr_discrete"
					( Origin gPackager )
				)
				( attribute "CDS_LOCATION" "C8B6"
					( Origin gPackager )
				)
				( attribute "CDS_SEC" "1"
					( Origin gPackager )
				)
				( attribute "LOCATION" "C8B6"
					( Origin gFrontEnd )
				)
				( attribute "MATERIAL" "X6S"
					( Origin gFrontEnd )
				)
				( attribute "PACK_TYPE" "0805"
					( Origin gFrontEnd )
				)
				( attribute "PART_NUMBER" "C95333-007"
					( Origin gFrontEnd )
				)
				( attribute "PHYS_PAGE" "198"
					( Origin gFrontEnd )
				)
				( attribute "ROOM" "P5V_PWR_SWITCH"
					( Origin gFrontEnd )
				)
				( attribute "ROT" "0"
					( Origin gFrontEnd )
				)
				( attribute "SEC" "1"
					( Origin gFrontEnd )
				)
				( attribute "SEC_TYPE" "0805"
					( Origin gFrontEnd )
				)
				( attribute "TOLERANCE" "10%"
					( Origin gFrontEnd )
				)
				( attribute "VALUE" "10UF"
					( Origin gFrontEnd )
				)
				( attribute "VER" "1"
					( Origin gFrontEnd )
				)
				( attribute "VOLTAGE" "16V"
					( Units "uVoltage" "V" 1.000000)
					( Origin gFrontEnd )
				)
				( attribute "XY" "(-1100,3250)"
					( Origin gFrontEnd )
				)
				( attribute "CHIPS_PART_NAME" "CAP"
					( Origin gPackager )
				)
				( attribute "CDS_PART_NAME" "CAP_0805-10UF,16V,10%,X6S,C953A"
					( Origin gPackager )
				)
				( objectStatus "C8B6" )
			)
			( gate "@baseboard_fab2_lib.baseboard_fab2(sch_1):page198_i41"
				( attribute "BOM_COST" "PWR_SWITCH"
					( Origin gFrontEnd )
				)
				( attribute "CDS_LIB" "dev_discrete"
					( Origin gPackager )
				)
				( attribute "CDS_LOCATION" "C8B7"
					( Origin gPackager )
				)
				( attribute "CDS_SEC" "1"
					( Origin gPackager )
				)
				( attribute "LOCATION" "C8B7"
					( Origin gFrontEnd )
				)
				( attribute "MATERIAL" "X7R"
					( Origin gFrontEnd )
				)
				( attribute "PACK_TYPE" "0402V"
					( Origin gFrontEnd )
				)
				( attribute "PART_NUMBER" "A36096-030"
					( Origin gFrontEnd )
				)
				( attribute "PHYS_PAGE" "198"
					( Origin gFrontEnd )
				)
				( attribute "ROOM" "P5V_PWR_SWITCH"
					( Origin gFrontEnd )
				)
				( attribute "ROT" "0"
					( Origin gFrontEnd )
				)
				( attribute "SEC" "1"
					( Origin gFrontEnd )
				)
				( attribute "SEC_TYPE" "0402V"
					( Origin gFrontEnd )
				)
				( attribute "TOLERANCE" "10%"
					( Origin gFrontEnd )
				)
				( attribute "VALUE" "0.1UF"
					( Origin gFrontEnd )
				)
				( attribute "VER" "1"
					( Origin gFrontEnd )
				)
				( attribute "VOLTAGE" "16V"
					( Units "uVoltage" "V" 1.000000)
					( Origin gFrontEnd )
				)
				( attribute "XY" "(-775,3250)"
					( Origin gFrontEnd )
				)
				( attribute "CHIPS_PART_NAME" "CAP_A"
					( Origin gPackager )
				)
				( attribute "CDS_PART_NAME" "CAP_A_0402V-0.1UF,16V,10%,X7R,A"
					( Origin gPackager )
				)
				( objectStatus "C8B7" )
			)
			( gate "@baseboard_fab2_lib.baseboard_fab2(sch_1):page198_i43"
				( attribute "BOM_COST" "PWR_SWITCH"
					( Origin gFrontEnd )
				)
				( attribute "CDS_LIB" "dev_discrete"
					( Origin gPackager )
				)
				( attribute "CDS_LOCATION" "C2T36"
					( Origin gPackager )
				)
				( attribute "CDS_SEC" "1"
					( Origin gPackager )
				)
				( attribute "LOCATION" "C2T36"
					( Origin gFrontEnd )
				)
				( attribute "MATERIAL" "X7R"
					( Origin gFrontEnd )
				)
				( attribute "PACK_TYPE" "0402V"
					( Origin gFrontEnd )
				)
				( attribute "PART_NUMBER" "A36096-030"
					( Origin gFrontEnd )
				)
				( attribute "PHYS_PAGE" "198"
					( Origin gFrontEnd )
				)
				( attribute "ROOM" "P3V3_PWR_SWITCH"
					( Origin gFrontEnd )
				)
				( attribute "ROT" "0"
					( Origin gFrontEnd )
				)
				( attribute "SEC" "1"
					( Origin gFrontEnd )
				)
				( attribute "SEC_TYPE" "0402V"
					( Origin gFrontEnd )
				)
				( attribute "TOLERANCE" "10%"
					( Origin gFrontEnd )
				)
				( attribute "VALUE" "0.1UF"
					( Origin gFrontEnd )
				)
				( attribute "VER" "1"
					( Origin gFrontEnd )
				)
				( attribute "VOLTAGE" "16V"
					( Units "uVoltage" "V" 1.000000)
					( Origin gFrontEnd )
				)
				( attribute "XY" "(-5050,4275)"
					( Origin gFrontEnd )
				)
				( attribute "CHIPS_PART_NAME" "CAP_A"
					( Origin gPackager )
				)
				( attribute "CDS_PART_NAME" "CAP_A_0402V-0.1UF,16V,10%,X7R,A"
					( Origin gPackager )
				)
				( objectStatus "C2T36" )
			)
			( gate "@baseboard_fab2_lib.baseboard_fab2(sch_1):page198_i44"
				( attribute "CDS_LIB" "mstr_discrete"
					( Origin gPackager )
				)
				( attribute "CDS_LOCATION" "C2U1"
					( Origin gPackager )
				)
				( attribute "CDS_SEC" "1"
					( Origin gPackager )
				)
				( attribute "LOCATION" "C2U1"
					( Origin gFrontEnd )
				)
				( attribute "MATERIAL" "X6S"
					( Origin gFrontEnd )
				)
				( attribute "PACK_TYPE" "0805"
					( Origin gFrontEnd )
				)
				( attribute "PART_NUMBER" "C95333-007"
					( Origin gFrontEnd )
				)
				( attribute "PHYS_PAGE" "198"
					( Origin gFrontEnd )
				)
				( attribute "ROOM" "P3V3_PWR_SWITCH"
					( Origin gFrontEnd )
				)
				( attribute "ROT" "0"
					( Origin gFrontEnd )
				)
				( attribute "SEC" "1"
					( Origin gFrontEnd )
				)
				( attribute "SEC_TYPE" "0805"
					( Origin gFrontEnd )
				)
				( attribute "TOLERANCE" "10%"
					( Origin gFrontEnd )
				)
				( attribute "VALUE" "10UF"
					( Origin gFrontEnd )
				)
				( attribute "VER" "1"
					( Origin gFrontEnd )
				)
				( attribute "VOLTAGE" "16V"
					( Units "uVoltage" "V" 1.000000)
					( Origin gFrontEnd )
				)
				( attribute "XY" "(-5375,4275)"
					( Origin gFrontEnd )
				)
				( attribute "CHIPS_PART_NAME" "CAP"
					( Origin gPackager )
				)
				( attribute "CDS_PART_NAME" "CAP_0805-10UF,16V,10%,X6S,C953A"
					( Origin gPackager )
				)
				( objectStatus "C2U1" )
			)
			( gate "@baseboard_fab2_lib.baseboard_fab2(sch_1):page198_i46"
				( attribute "BOM_COST" "PWR_SWITCH"
					( Origin gFrontEnd )
				)
				( attribute "CDS_LIB" "dev_discrete"
					( Origin gPackager )
				)
				( attribute "CDS_LOCATION" "C2U19"
					( Origin gPackager )
				)
				( attribute "CDS_SEC" "1"
					( Origin gPackager )
				)
				( attribute "LOCATION" "C2U19"
					( Origin gFrontEnd )
				)
				( attribute "MATERIAL" "X7R"
					( Origin gFrontEnd )
				)
				( attribute "PACK_TYPE" "0402V"
					( Origin gFrontEnd )
				)
				( attribute "PART_NUMBER" "A36096-030"
					( Origin gFrontEnd )
				)
				( attribute "PHYS_PAGE" "198"
					( Origin gFrontEnd )
				)
				( attribute "ROOM" "P3V3_PWR_SWITCH"
					( Origin gFrontEnd )
				)
				( attribute "ROT" "0"
					( Origin gFrontEnd )
				)
				( attribute "SEC" "1"
					( Origin gFrontEnd )
				)
				( attribute "SEC_TYPE" "0402V"
					( Origin gFrontEnd )
				)
				( attribute "TOLERANCE" "10%"
					( Origin gFrontEnd )
				)
				( attribute "VALUE" "0.1UF"
					( Origin gFrontEnd )
				)
				( attribute "VER" "1"
					( Origin gFrontEnd )
				)
				( attribute "VOLTAGE" "16V"
					( Units "uVoltage" "V" 1.000000)
					( Origin gFrontEnd )
				)
				( attribute "XY" "(-4675,3200)"
					( Origin gFrontEnd )
				)
				( attribute "CHIPS_PART_NAME" "CAP_A"
					( Origin gPackager )
				)
				( attribute "CDS_PART_NAME" "CAP_A_0402V-0.1UF,16V,10%,X7R,A"
					( Origin gPackager )
				)
				( objectStatus "C2U19" )
			)
			( gate "@baseboard_fab2_lib.baseboard_fab2(sch_1):page198_i47"
				( attribute "CDS_LIB" "mstr_discrete"
					( Origin gPackager )
				)
				( attribute "CDS_LOCATION" "C2U2"
					( Origin gPackager )
				)
				( attribute "CDS_SEC" "1"
					( Origin gPackager )
				)
				( attribute "LOCATION" "C2U2"
					( Origin gFrontEnd )
				)
				( attribute "MATERIAL" "X6S"
					( Origin gFrontEnd )
				)
				( attribute "PACK_TYPE" "0805"
					( Origin gFrontEnd )
				)
				( attribute "PART_NUMBER" "C95333-007"
					( Origin gFrontEnd )
				)
				( attribute "PHYS_PAGE" "198"
					( Origin gFrontEnd )
				)
				( attribute "ROOM" "P3V3_PWR_SWITCH"
					( Origin gFrontEnd )
				)
				( attribute "ROT" "0"
					( Origin gFrontEnd )
				)
				( attribute "SEC" "1"
					( Origin gFrontEnd )
				)
				( attribute "SEC_TYPE" "0805"
					( Origin gFrontEnd )
				)
				( attribute "TOLERANCE" "10%"
					( Origin gFrontEnd )
				)
				( attribute "VALUE" "10UF"
					( Origin gFrontEnd )
				)
				( attribute "VER" "1"
					( Origin gFrontEnd )
				)
				( attribute "VOLTAGE" "16V"
					( Units "uVoltage" "V" 1.000000)
					( Origin gFrontEnd )
				)
				( attribute "XY" "(-5000,3200)"
					( Origin gFrontEnd )
				)
				( attribute "CHIPS_PART_NAME" "CAP"
					( Origin gPackager )
				)
				( attribute "CDS_PART_NAME" "CAP_0805-10UF,16V,10%,X6S,C953A"
					( Origin gPackager )
				)
				( objectStatus "C2U2" )
			)
			( gate "@baseboard_fab2_lib.baseboard_fab2(sch_1):page198_i49"
				( attribute "BOM_COST" "PWR_SWITCH"
					( Origin gFrontEnd )
				)
				( attribute "CDS_LIB" "dev_discrete"
					( Origin gPackager )
				)
				( attribute "CDS_LOCATION" "C7E9"
					( Origin gPackager )
				)
				( attribute "CDS_SEC" "1"
					( Origin gPackager )
				)
				( attribute "LOCATION" "C7E9"
					( Origin gFrontEnd )
				)
				( attribute "MATERIAL" "X7R"
					( Origin gFrontEnd )
				)
				( attribute "PACK_TYPE" "0402V"
					( Origin gFrontEnd )
				)
				( attribute "PART_NUMBER" "A36096-030"
					( Origin gFrontEnd )
				)
				( attribute "PHYS_PAGE" "198"
					( Origin gFrontEnd )
				)
				( attribute "ROOM" "P12V_PWR_SWITCH"
					( Origin gFrontEnd )
				)
				( attribute "ROT" "0"
					( Origin gFrontEnd )
				)
				( attribute "SEC" "1"
					( Origin gFrontEnd )
				)
				( attribute "SEC_TYPE" "0402V"
					( Origin gFrontEnd )
				)
				( attribute "TOLERANCE" "10%"
					( Origin gFrontEnd )
				)
				( attribute "VALUE" "0.1UF"
					( Origin gFrontEnd )
				)
				( attribute "VER" "1"
					( Origin gFrontEnd )
				)
				( attribute "VOLTAGE" "16V"
					( Units "uVoltage" "V" 1.000000)
					( Origin gFrontEnd )
				)
				( attribute "XY" "(-4675,1200)"
					( Origin gFrontEnd )
				)
				( attribute "CHIPS_PART_NAME" "CAP_A"
					( Origin gPackager )
				)
				( attribute "CDS_PART_NAME" "CAP_A_0402V-0.1UF,16V,10%,X7R,A"
					( Origin gPackager )
				)
				( objectStatus "C7E9" )
			)
			( gate "@baseboard_fab2_lib.baseboard_fab2(sch_1):page198_i50"
				( attribute "CDS_LIB" "mstr_discrete"
					( Origin gPackager )
				)
				( attribute "CDS_LOCATION" "C7E8"
					( Origin gPackager )
				)
				( attribute "CDS_SEC" "1"
					( Origin gPackager )
				)
				( attribute "LOCATION" "C7E8"
					( Origin gFrontEnd )
				)
				( attribute "MATERIAL" "X6S"
					( Origin gFrontEnd )
				)
				( attribute "PACK_TYPE" "0805"
					( Origin gFrontEnd )
				)
				( attribute "PART_NUMBER" "C95333-007"
					( Origin gFrontEnd )
				)
				( attribute "PHYS_PAGE" "198"
					( Origin gFrontEnd )
				)
				( attribute "ROOM" "P12V_PWR_SWITCH"
					( Origin gFrontEnd )
				)
				( attribute "ROT" "0"
					( Origin gFrontEnd )
				)
				( attribute "SEC" "1"
					( Origin gFrontEnd )
				)
				( attribute "SEC_TYPE" "0805"
					( Origin gFrontEnd )
				)
				( attribute "TOLERANCE" "10%"
					( Origin gFrontEnd )
				)
				( attribute "VALUE" "10UF"
					( Origin gFrontEnd )
				)
				( attribute "VER" "1"
					( Origin gFrontEnd )
				)
				( attribute "VOLTAGE" "16V"
					( Units "uVoltage" "V" 1.000000)
					( Origin gFrontEnd )
				)
				( attribute "XY" "(-5125,1250)"
					( Origin gFrontEnd )
				)
				( attribute "CHIPS_PART_NAME" "CAP"
					( Origin gPackager )
				)
				( attribute "CDS_PART_NAME" "CAP_0805-10UF,16V,10%,X6S,C953A"
					( Origin gPackager )
				)
				( objectStatus "C7E8" )
			)
			( gate "@baseboard_fab2_lib.baseboard_fab2(sch_1):page198_i52"
				( attribute "BOM_COST" "PWR_SWITCH"
					( Origin gFrontEnd )
				)
				( attribute "CDS_LIB" "dev_discrete"
					( Origin gPackager )
				)
				( attribute "CDS_LOCATION" "C7E5"
					( Origin gPackager )
				)
				( attribute "CDS_SEC" "1"
					( Origin gPackager )
				)
				( attribute "LOCATION" "C7E5"
					( Origin gFrontEnd )
				)
				( attribute "MATERIAL" "X7R"
					( Origin gFrontEnd )
				)
				( attribute "PACK_TYPE" "0402V"
					( Origin gFrontEnd )
				)
				( attribute "PART_NUMBER" "A36096-030"
					( Origin gFrontEnd )
				)
				( attribute "PHYS_PAGE" "198"
					( Origin gFrontEnd )
				)
				( attribute "ROOM" "P12V_PWR_SWITCH"
					( Origin gFrontEnd )
				)
				( attribute "ROT" "0"
					( Origin gFrontEnd )
				)
				( attribute "SEC" "1"
					( Origin gFrontEnd )
				)
				( attribute "SEC_TYPE" "0402V"
					( Origin gFrontEnd )
				)
				( attribute "TOLERANCE" "10%"
					( Origin gFrontEnd )
				)
				( attribute "VALUE" "0.1UF"
					( Origin gFrontEnd )
				)
				( attribute "VER" "1"
					( Origin gFrontEnd )
				)
				( attribute "VOLTAGE" "16V"
					( Units "uVoltage" "V" 1.000000)
					( Origin gFrontEnd )
				)
				( attribute "XY" "(-4775,2250)"
					( Origin gFrontEnd )
				)
				( attribute "CHIPS_PART_NAME" "CAP_A"
					( Origin gPackager )
				)
				( attribute "CDS_PART_NAME" "CAP_A_0402V-0.1UF,16V,10%,X7R,A"
					( Origin gPackager )
				)
				( objectStatus "C7E5" )
			)
			( gate "@baseboard_fab2_lib.baseboard_fab2(sch_1):page198_i53"
				( attribute "CDS_LIB" "mstr_discrete"
					( Origin gPackager )
				)
				( attribute "CDS_LOCATION" "C7E6"
					( Origin gPackager )
				)
				( attribute "CDS_SEC" "1"
					( Origin gPackager )
				)
				( attribute "LOCATION" "C7E6"
					( Origin gFrontEnd )
				)
				( attribute "MATERIAL" "X6S"
					( Origin gFrontEnd )
				)
				( attribute "PACK_TYPE" "0805"
					( Origin gFrontEnd )
				)
				( attribute "PART_NUMBER" "C95333-007"
					( Origin gFrontEnd )
				)
				( attribute "PHYS_PAGE" "198"
					( Origin gFrontEnd )
				)
				( attribute "ROOM" "P12V_PWR_SWITCH"
					( Origin gFrontEnd )
				)
				( attribute "ROT" "0"
					( Origin gFrontEnd )
				)
				( attribute "SEC" "1"
					( Origin gFrontEnd )
				)
				( attribute "SEC_TYPE" "0805"
					( Origin gFrontEnd )
				)
				( attribute "TOLERANCE" "10%"
					( Origin gFrontEnd )
				)
				( attribute "VALUE" "10UF"
					( Origin gFrontEnd )
				)
				( attribute "VER" "1"
					( Origin gFrontEnd )
				)
				( attribute "VOLTAGE" "16V"
					( Units "uVoltage" "V" 1.000000)
					( Origin gFrontEnd )
				)
				( attribute "XY" "(-5100,2250)"
					( Origin gFrontEnd )
				)
				( attribute "CHIPS_PART_NAME" "CAP"
					( Origin gPackager )
				)
				( attribute "CDS_PART_NAME" "CAP_0805-10UF,16V,10%,X6S,C953A"
					( Origin gPackager )
				)
				( objectStatus "C7E6" )
			)
			( gate "@baseboard_fab2_lib.baseboard_fab2(sch_1):page198_i61"
				( attribute "CDS_LIB" "mstr_discrete"
					( Origin gPackager )
				)
				( attribute "CDS_LOCATION" "C1B18"
					( Origin gPackager )
				)
				( attribute "CDS_SEC" "1"
					( Origin gPackager )
				)
				( attribute "LOCATION" "C1B18"
					( Origin gFrontEnd )
				)
				( attribute "MATERIAL" "X6S"
					( Origin gFrontEnd )
				)
				( attribute "PACK_TYPE" "0805"
					( Origin gFrontEnd )
				)
				( attribute "PART_NUMBER" "C95333-007"
					( Origin gFrontEnd )
				)
				( attribute "PHYS_PAGE" "198"
					( Origin gFrontEnd )
				)
				( attribute "ROOM" "P12V_FAN_PWR_SWITCH"
					( Origin gFrontEnd )
				)
				( attribute "ROT" "0"
					( Origin gFrontEnd )
				)
				( attribute "SEC" "1"
					( Origin gFrontEnd )
				)
				( attribute "SEC_TYPE" "0805"
					( Origin gFrontEnd )
				)
				( attribute "TOLERANCE" "10%"
					( Origin gFrontEnd )
				)
				( attribute "VALUE" "10UF"
					( Origin gFrontEnd )
				)
				( attribute "VER" "1"
					( Origin gFrontEnd )
				)
				( attribute "VOLTAGE" "16V"
					( Units "uVoltage" "V" 1.000000)
					( Origin gFrontEnd )
				)
				( attribute "XY" "(-1175,1225)"
					( Origin gFrontEnd )
				)
				( attribute "CHIPS_PART_NAME" "CAP"
					( Origin gPackager )
				)
				( attribute "CDS_PART_NAME" "CAP_0805-10UF,16V,10%,X6S,C953A"
					( Origin gPackager )
				)
				( objectStatus "C1B18" )
			)
			( gate "@baseboard_fab2_lib.baseboard_fab2(sch_1):page198_i64"
				( attribute "BOM_COST" "PWR_SWITCH"
					( Origin gFrontEnd )
				)
				( attribute "CDS_LIB" "dev_discrete"
					( Origin gPackager )
				)
				( attribute "CDS_LOCATION" "C1B19"
					( Origin gPackager )
				)
				( attribute "CDS_SEC" "1"
					( Origin gPackager )
				)
				( attribute "LOCATION" "C1B19"
					( Origin gFrontEnd )
				)
				( attribute "MATERIAL" "X7R"
					( Origin gFrontEnd )
				)
				( attribute "PACK_TYPE" "0402V"
					( Origin gFrontEnd )
				)
				( attribute "PART_NUMBER" "A36096-030"
					( Origin gFrontEnd )
				)
				( attribute "PHYS_PAGE" "198"
					( Origin gFrontEnd )
				)
				( attribute "ROOM" "P12V_FAN_PWR_SWITCH"
					( Origin gFrontEnd )
				)
				( attribute "ROT" "0"
					( Origin gFrontEnd )
				)
				( attribute "SEC" "1"
					( Origin gFrontEnd )
				)
				( attribute "SEC_TYPE" "0402V"
					( Origin gFrontEnd )
				)
				( attribute "TOLERANCE" "10%"
					( Origin gFrontEnd )
				)
				( attribute "VALUE" "0.1UF"
					( Origin gFrontEnd )
				)
				( attribute "VER" "1"
					( Origin gFrontEnd )
				)
				( attribute "VOLTAGE" "16V"
					( Units "uVoltage" "V" 1.000000)
					( Origin gFrontEnd )
				)
				( attribute "XY" "(-725,1225)"
					( Origin gFrontEnd )
				)
				( attribute "CHIPS_PART_NAME" "CAP_A"
					( Origin gPackager )
				)
				( attribute "CDS_PART_NAME" "CAP_A_0402V-0.1UF,16V,10%,X7R,A"
					( Origin gPackager )
				)
				( objectStatus "C1B19" )
			)
			( gate "@baseboard_fab2_lib.baseboard_fab2(sch_1):page198_i67"
				( attribute "CDS_LIB" "dev_discrete"
					( Origin gPackager )
				)
				( attribute "CDS_LOCATION" "C9M6"
					( Origin gPackager )
				)
				( attribute "CDS_SEC" "1"
					( Origin gPackager )
				)
				( attribute "LOCATION" "C9M6"
					( Origin gFrontEnd )
				)
				( attribute "MATERIAL" "X7R"
					( Origin gFrontEnd )
				)
				( attribute "PACK_TYPE" "0402V"
					( Origin gFrontEnd )
				)
				( attribute "PART_NUMBER" "A36096-030"
					( Origin gFrontEnd )
				)
				( attribute "PHYS_PAGE" "198"
					( Origin gFrontEnd )
				)
				( attribute "ROOM" "P12V_FAN_PWR_SWITCH"
					( Origin gFrontEnd )
				)
				( attribute "ROT" "0"
					( Origin gFrontEnd )
				)
				( attribute "SEC" "1"
					( Origin gFrontEnd )
				)
				( attribute "SEC_TYPE" "0402V"
					( Origin gFrontEnd )
				)
				( attribute "TOLERANCE" "10%"
					( Origin gFrontEnd )
				)
				( attribute "VALUE" "0.1UF"
					( Origin gFrontEnd )
				)
				( attribute "VER" "1"
					( Origin gFrontEnd )
				)
				( attribute "VOLTAGE" "16V"
					( Units "uVoltage" "V" 1.000000)
					( Origin gFrontEnd )
				)
				( attribute "XY" "(-3775,2150)"
					( Origin gFrontEnd )
				)
				( attribute "CHIPS_PART_NAME" "CAP_A"
					( Origin gPackager )
				)
				( attribute "CDS_PART_NAME" "CAP_A_0402V-0.1UF,16V,10%,X7R,A"
					( Origin gPackager )
				)
				( objectStatus "C9M6" )
			)
			( gate "@baseboard_fab2_lib.baseboard_fab2(sch_1):page198_i69"
				( attribute "CDS_LIB" "mstr_vreg"
					( Origin gPackager )
				)
				( attribute "CDS_LMAN_SYM_OUTLINE" "-250,250,250,-250"
					( Origin gPackager )
				)
				( attribute "CDS_LOCATION" "EU9M1"
					( Origin gPackager )
				)
				( attribute "CDS_SEC" "1"
					( Origin gPackager )
				)
				( attribute "LOCATION" "EU9M1"
					( Origin gFrontEnd )
				)
				( attribute "MATERIAL" "IC"
					( Origin gFrontEnd )
				)
				( attribute "PACK_TYPE" "SM"
					( Origin gFrontEnd )
				)
				( attribute "PART_NUMBER" "G56246-001"
					( Origin gFrontEnd )
				)
				( attribute "PHYS_PAGE" "198"
					( Origin gFrontEnd )
				)
				( attribute "ROOM" "P12V_FAN_PWR_SWITCH"
					( Origin gFrontEnd )
				)
				( attribute "ROT" "0"
					( Origin gFrontEnd )
				)
				( attribute "SEC" "1"
					( Origin gFrontEnd )
				)
				( attribute "SEC_TYPE" "SM"
					( Origin gFrontEnd )
				)
				( attribute "VER" "1"
					( Origin gFrontEnd )
				)
				( attribute "XY" "(-2775,1825)"
					( Origin gFrontEnd )
				)
				( attribute "CHIPS_PART_NAME" "SLG55021"
					( Origin gPackager )
				)
				( attribute "CDS_PART_NAME" "SLG55021_SM-IC,G56246-001"
					( Origin gPackager )
				)
				( objectStatus "EU9M1" )
			)
			( gate "@baseboard_fab2_lib.baseboard_fab2(sch_1):page198_i74"
				( attribute "CDS_LIB" "mstr_discrete"
					( Origin gPackager )
				)
				( attribute "CDS_LOCATION" "C9M10"
					( Origin gPackager )
				)
				( attribute "CDS_SEC" "1"
					( Origin gPackager )
				)
				( attribute "LOCATION" "C9M10"
					( Origin gFrontEnd )
				)
				( attribute "MATERIAL" "X6S"
					( Origin gFrontEnd )
				)
				( attribute "PACK_TYPE" "0805"
					( Origin gFrontEnd )
				)
				( attribute "PART_NUMBER" "C95333-007"
					( Origin gFrontEnd )
				)
				( attribute "PHYS_PAGE" "198"
					( Origin gFrontEnd )
				)
				( attribute "ROOM" "P12V_FAN_PWR_SWITCH"
					( Origin gFrontEnd )
				)
				( attribute "ROT" "0"
					( Origin gFrontEnd )
				)
				( attribute "SEC" "1"
					( Origin gFrontEnd )
				)
				( attribute "SEC_TYPE" "0805"
					( Origin gFrontEnd )
				)
				( attribute "TOLERANCE" "10%"
					( Origin gFrontEnd )
				)
				( attribute "VALUE" "10UF"
					( Origin gFrontEnd )
				)
				( attribute "VER" "1"
					( Origin gFrontEnd )
				)
				( attribute "VOLTAGE" "16V"
					( Units "uVoltage" "V" 1.000000)
					( Origin gFrontEnd )
				)
				( attribute "XY" "(-1150,2225)"
					( Origin gFrontEnd )
				)
				( attribute "CHIPS_PART_NAME" "CAP"
					( Origin gPackager )
				)
				( attribute "CDS_PART_NAME" "CAP_0805-10UF,16V,10%,X6S,C953A"
					( Origin gPackager )
				)
				( objectStatus "C9M10" )
			)
			( gate "@baseboard_fab2_lib.baseboard_fab2(sch_1):page198_i76"
				( attribute "BOM_COST" "PWR_SWITCH"
					( Origin gFrontEnd )
				)
				( attribute "CDS_LIB" "dev_discrete"
					( Origin gPackager )
				)
				( attribute "CDS_LOCATION" "C9M9"
					( Origin gPackager )
				)
				( attribute "CDS_SEC" "1"
					( Origin gPackager )
				)
				( attribute "LOCATION" "C9M9"
					( Origin gFrontEnd )
				)
				( attribute "MATERIAL" "X7R"
					( Origin gFrontEnd )
				)
				( attribute "PACK_TYPE" "0402V"
					( Origin gFrontEnd )
				)
				( attribute "PART_NUMBER" "A36096-030"
					( Origin gFrontEnd )
				)
				( attribute "PHYS_PAGE" "198"
					( Origin gFrontEnd )
				)
				( attribute "ROOM" "P12V_FAN_PWR_SWITCH"
					( Origin gFrontEnd )
				)
				( attribute "ROT" "0"
					( Origin gFrontEnd )
				)
				( attribute "SEC" "1"
					( Origin gFrontEnd )
				)
				( attribute "SEC_TYPE" "0402V"
					( Origin gFrontEnd )
				)
				( attribute "TOLERANCE" "10%"
					( Origin gFrontEnd )
				)
				( attribute "VALUE" "0.1UF"
					( Origin gFrontEnd )
				)
				( attribute "VER" "1"
					( Origin gFrontEnd )
				)
				( attribute "VOLTAGE" "16V"
					( Units "uVoltage" "V" 1.000000)
					( Origin gFrontEnd )
				)
				( attribute "XY" "(-825,2225)"
					( Origin gFrontEnd )
				)
				( attribute "CHIPS_PART_NAME" "CAP_A"
					( Origin gPackager )
				)
				( attribute "CDS_PART_NAME" "CAP_A_0402V-0.1UF,16V,10%,X7R,A"
					( Origin gPackager )
				)
				( objectStatus "C9M9" )
			)
			( gate "@baseboard_fab2_lib.baseboard_fab2(sch_1):page198_i78"
				( attribute "BOM_COST" "IO_SLOT"
					( Origin gFrontEnd )
				)
				( attribute "CDS_LIB" "mstr_discrete"
					( Origin gPackager )
				)
				( attribute "CDS_LOCATION" "R8E12"
					( Origin gPackager )
				)
				( attribute "LOCATION" "R8E12"
					( Origin gFrontEnd )
				)
				( attribute "MATERIAL" "EMPTY"
					( Origin gFrontEnd )
				)
				( attribute "PACK_TYPE" "0402"
					( Origin gFrontEnd )
				)
				( attribute "PART_NUMBER" "G21796-072"
					( Origin gFrontEnd )
				)
				( attribute "PHYS_PAGE" "198"
					( Origin gFrontEnd )
				)
				( attribute "ROOM" "IO_SLOT"
					( Origin gFrontEnd )
				)
				( attribute "ROT" "0"
					( Origin gFrontEnd )
				)
				( attribute "SEC" "1"
					( Origin gFrontEnd )
				)
				( attribute "TOLERANCE" "1%"
					( Origin gFrontEnd )
				)
				( attribute "VALUE" "4.75K"
					( Origin gFrontEnd )
				)
				( attribute "VER" "2"
					( Origin gFrontEnd )
				)
				( attribute "WATTAGE" "1/16W"
					( Origin gFrontEnd )
				)
				( attribute "XY" "(-6925,3050)"
					( Origin gFrontEnd )
				)
				( attribute "CHIPS_PART_NAME" "RES"
					( Origin gPackager )
				)
				( attribute "CDS_PART_NAME" "RES_0402-4.75K,1%,1/16W,EMPTY,A"
					( Origin gPackager )
				)
				( attribute "SEC_TYPE" "0402"
					( Origin gFrontEnd )
				)
				( attribute "CDS_SEC" "1"
					( Origin gPackager )
				)
				( objectStatus "R8E12" )
			)
			( gate "@baseboard_fab2_lib.baseboard_fab2(sch_1):page198_i83"
				( attribute "CDS_LIB" "mstr_discrete"
					( Origin gPackager )
				)
				( attribute "CDS_LOCATION" "R8B4"
					( Origin gPackager )
				)
				( attribute "CDS_SEC" "1"
					( Origin gPackager )
				)
				( attribute "LOCATION" "R8B4"
					( Origin gFrontEnd )
				)
				( attribute "MATERIAL" "CHIP"
					( Origin gFrontEnd )
				)
				( attribute "PACK_TYPE" "0402"
					( Origin gFrontEnd )
				)
				( attribute "PART_NUMBER" "G21796-010"
					( Origin gFrontEnd )
				)
				( attribute "PHYS_PAGE" "198"
					( Origin gFrontEnd )
				)
				( attribute "ROOM" "HOT_SWAP"
					( Origin gFrontEnd )
				)
				( attribute "ROT" "0"
					( Origin gFrontEnd )
				)
				( attribute "SEC" "1"
					( Origin gFrontEnd )
				)
				( attribute "SEC_TYPE" "0402"
					( Origin gFrontEnd )
				)
				( attribute "TOLERANCE" "1%"
					( Origin gFrontEnd )
				)
				( attribute "VALUE" "100.0K"
					( Origin gFrontEnd )
				)
				( attribute "VER" "2"
					( Origin gFrontEnd )
				)
				( attribute "WATTAGE" "1/16W"
					( Origin gFrontEnd )
				)
				( attribute "XY" "(-6850,2625)"
					( Origin gFrontEnd )
				)
				( attribute "CHIPS_PART_NAME" "RES"
					( Origin gPackager )
				)
				( attribute "CDS_PART_NAME" "RES_0402-100.0K,1%,1/16W,CHIP,A"
					( Origin gPackager )
				)
				( objectStatus "R8B4" )
			)
			( gate "@baseboard_fab2_lib.baseboard_fab2(sch_1):page198_i85"
				( attribute "CDS_LIB" "mstr_discrete"
					( Origin gPackager )
				)
				( attribute "CDS_LOCATION" "Q8G1"
					( Origin gPackager )
				)
				( attribute "CDS_SEC" "1"
					( Origin gPackager )
				)
				( attribute "LOCATION" "Q8G1"
					( Origin gFrontEnd )
				)
				( attribute "MATERIAL" "NFET"
					( Origin gFrontEnd )
				)
				( attribute "PACK_TYPE" "LCC3"
					( Origin gFrontEnd )
				)
				( attribute "PART_NUMBER" "G26762-001"
					( Origin gFrontEnd )
				)
				( attribute "PHYS_PAGE" "198"
					( Origin gFrontEnd )
				)
				( attribute "ROT" "2"
					( Origin gFrontEnd )
				)
				( attribute "SEC" "1"
					( Origin gFrontEnd )
				)
				( attribute "SEC_TYPE" "LCC3"
					( Origin gFrontEnd )
				)
				( attribute "VALUE" "BSZ019N03LS"
					( Origin gFrontEnd )
				)
				( attribute "VER" "3"
					( Origin gFrontEnd )
				)
				( attribute "XY" "(-5650,3900)"
					( Origin gFrontEnd )
				)
				( attribute "CHIPS_PART_NAME" "MOSFET_N"
					( Origin gPackager )
				)
				( attribute "CDS_PART_NAME" "MOSFET_N_LCC3-BSZ019N03LS,NFETA"
					( Origin gPackager )
				)
				( objectStatus "Q8G1" )
			)
			( gate "@baseboard_fab2_lib.baseboard_fab2(sch_1):page198_i86"
				( attribute "CDS_LIB" "mstr_discrete"
					( Origin gPackager )
				)
				( attribute "CDS_LOCATION" "Q1B1"
					( Origin gPackager )
				)
				( attribute "CDS_SEC" "1"
					( Origin gPackager )
				)
				( attribute "LOCATION" "Q1B1"
					( Origin gFrontEnd )
				)
				( attribute "MATERIAL" "NFET"
					( Origin gFrontEnd )
				)
				( attribute "PACK_TYPE" "LCC3"
					( Origin gFrontEnd )
				)
				( attribute "PART_NUMBER" "G26762-001"
					( Origin gFrontEnd )
				)
				( attribute "PHYS_PAGE" "198"
					( Origin gFrontEnd )
				)
				( attribute "ROT" "2"
					( Origin gFrontEnd )
				)
				( attribute "SEC" "1"
					( Origin gFrontEnd )
				)
				( attribute "SEC_TYPE" "LCC3"
					( Origin gFrontEnd )
				)
				( attribute "VALUE" "BSZ019N03LS"
					( Origin gFrontEnd )
				)
				( attribute "VER" "3"
					( Origin gFrontEnd )
				)
				( attribute "XY" "(-1375,1850)"
					( Origin gFrontEnd )
				)
				( attribute "CHIPS_PART_NAME" "MOSFET_N"
					( Origin gPackager )
				)
				( attribute "CDS_PART_NAME" "MOSFET_N_LCC3-BSZ019N03LS,NFETA"
					( Origin gPackager )
				)
				( objectStatus "Q1B1" )
			)
			( gate "@baseboard_fab2_lib.baseboard_fab2(sch_1):page198_i87"
				( attribute "CDS_LIB" "mstr_discrete"
					( Origin gPackager )
				)
				( attribute "CDS_LOCATION" "Q8B1"
					( Origin gPackager )
				)
				( attribute "CDS_SEC" "1"
					( Origin gPackager )
				)
				( attribute "LOCATION" "Q8B1"
					( Origin gFrontEnd )
				)
				( attribute "MATERIAL" "NFET"
					( Origin gFrontEnd )
				)
				( attribute "PACK_TYPE" "LCC3"
					( Origin gFrontEnd )
				)
				( attribute "PART_NUMBER" "G26762-001"
					( Origin gFrontEnd )
				)
				( attribute "PHYS_PAGE" "198"
					( Origin gFrontEnd )
				)
				( attribute "ROT" "2"
					( Origin gFrontEnd )
				)
				( attribute "SEC" "1"
					( Origin gFrontEnd )
				)
				( attribute "SEC_TYPE" "LCC3"
					( Origin gFrontEnd )
				)
				( attribute "VALUE" "BSZ019N03LS"
					( Origin gFrontEnd )
				)
				( attribute "VER" "3"
					( Origin gFrontEnd )
				)
				( attribute "XY" "(-1600,3850)"
					( Origin gFrontEnd )
				)
				( attribute "CHIPS_PART_NAME" "MOSFET_N"
					( Origin gPackager )
				)
				( attribute "CDS_PART_NAME" "MOSFET_N_LCC3-BSZ019N03LS,NFETA"
					( Origin gPackager )
				)
				( objectStatus "Q8B1" )
			)
			( gate "@baseboard_fab2_lib.baseboard_fab2(sch_1):page198_i88"
				( attribute "CDS_LIB" "mstr_discrete"
					( Origin gPackager )
				)
				( attribute "CDS_LOCATION" "Q7E7"
					( Origin gPackager )
				)
				( attribute "CDS_SEC" "1"
					( Origin gPackager )
				)
				( attribute "LOCATION" "Q7E7"
					( Origin gFrontEnd )
				)
				( attribute "MATERIAL" "NFET"
					( Origin gFrontEnd )
				)
				( attribute "PACK_TYPE" "LCC3"
					( Origin gFrontEnd )
				)
				( attribute "PART_NUMBER" "G26762-001"
					( Origin gFrontEnd )
				)
				( attribute "PHYS_PAGE" "198"
					( Origin gFrontEnd )
				)
				( attribute "ROT" "2"
					( Origin gFrontEnd )
				)
				( attribute "SEC" "1"
					( Origin gFrontEnd )
				)
				( attribute "SEC_TYPE" "LCC3"
					( Origin gFrontEnd )
				)
				( attribute "VALUE" "BSZ019N03LS"
					( Origin gFrontEnd )
				)
				( attribute "VER" "3"
					( Origin gFrontEnd )
				)
				( attribute "XY" "(-5325,1850)"
					( Origin gFrontEnd )
				)
				( attribute "CHIPS_PART_NAME" "MOSFET_N"
					( Origin gPackager )
				)
				( attribute "CDS_PART_NAME" "MOSFET_N_LCC3-BSZ019N03LS,NFETA"
					( Origin gPackager )
				)
				( objectStatus "Q7E7" )
			)
			( gate "@baseboard_fab2_lib.baseboard_fab2(sch_1):page199_i2"
				( attribute "CDS_LIB" "mstr_discrete"
					( Origin gPackager )
				)
				( attribute "CDS_LOCATION" "R9P30"
					( Origin gPackager )
				)
				( attribute "CDS_SEC" "1"
					( Origin gPackager )
				)
				( attribute "LOCATION" "R9P30"
					( Origin gFrontEnd )
				)
				( attribute "MATERIAL" "CHIP"
					( Origin gFrontEnd )
				)
				( attribute "PACK_TYPE" "0603"
					( Origin gFrontEnd )
				)
				( attribute "PART_NUMBER" "G22026-041"
					( Origin gFrontEnd )
				)
				( attribute "PHYS_PAGE" "199"
					( Origin gFrontEnd )
				)
				( attribute "ROOM" "HOT_SWAP"
					( Origin gFrontEnd )
				)
				( attribute "ROT" "0"
					( Origin gFrontEnd )
				)
				( attribute "SEC" "1"
					( Origin gFrontEnd )
				)
				( attribute "SEC_TYPE" "0603"
					( Origin gFrontEnd )
				)
				( attribute "TOLERANCE" "1%"
					( Origin gFrontEnd )
				)
				( attribute "VALUE" "10.0"
					( Origin gFrontEnd )
				)
				( attribute "VER" "2"
					( Origin gFrontEnd )
				)
				( attribute "WATTAGE" "1/10W"
					( Origin gFrontEnd )
				)
				( attribute "XY" "(-5525,4025)"
					( Origin gFrontEnd )
				)
				( attribute "CHIPS_PART_NAME" "RES"
					( Origin gPackager )
				)
				( attribute "CDS_PART_NAME" "RES_0603-10.0,1%,1/10W,CHIP,G2A"
					( Origin gPackager )
				)
				( objectStatus "R9P30" )
			)
			( gate "@baseboard_fab2_lib.baseboard_fab2(sch_1):page199_i3"
				( attribute "CDS_LIB" "mstr_discrete"
					( Origin gPackager )
				)
				( attribute "CDS_LOCATION" "C1D25"
					( Origin gPackager )
				)
				( attribute "CDS_SEC" "1"
					( Origin gPackager )
				)
				( attribute "LOCATION" "C1D25"
					( Origin gFrontEnd )
				)
				( attribute "MATERIAL" "X6S"
					( Origin gFrontEnd )
				)
				( attribute "PACK_TYPE" "0402"
					( Origin gFrontEnd )
				)
				( attribute "PART_NUMBER" "D97712-011"
					( Origin gFrontEnd )
				)
				( attribute "PHYS_PAGE" "199"
					( Origin gFrontEnd )
				)
				( attribute "ROOM" "HOT_SWAP"
					( Origin gFrontEnd )
				)
				( attribute "ROT" "0"
					( Origin gFrontEnd )
				)
				( attribute "SEC" "1"
					( Origin gFrontEnd )
				)
				( attribute "SEC_TYPE" "0402"
					( Origin gFrontEnd )
				)
				( attribute "TOLERANCE" "10%"
					( Origin gFrontEnd )
				)
				( attribute "VALUE" "1.0UF"
					( Origin gFrontEnd )
				)
				( attribute "VER" "1"
					( Origin gFrontEnd )
				)
				( attribute "VOLTAGE" "16V"
					( Units "uVoltage" "V" 1.000000)
					( Origin gFrontEnd )
				)
				( attribute "XY" "(-5525,3600)"
					( Origin gFrontEnd )
				)
				( attribute "CHIPS_PART_NAME" "CAP"
					( Origin gPackager )
				)
				( attribute "CDS_PART_NAME" "CAP_0402-1.0UF,16V,10%,X6S,D97A"
					( Origin gPackager )
				)
				( objectStatus "C1D25" )
			)
			( gate "@baseboard_fab2_lib.baseboard_fab2(sch_1):page199_i7"
				( attribute "CDS_LIB" "dev_discrete"
					( Origin gPackager )
				)
				( attribute "CDS_LOCATION" "C1D27"
					( Origin gPackager )
				)
				( attribute "CDS_SEC" "1"
					( Origin gPackager )
				)
				( attribute "LOCATION" "C1D27"
					( Origin gFrontEnd )
				)
				( attribute "MATERIAL" "X7R"
					( Origin gFrontEnd )
				)
				( attribute "PACK_TYPE" "0402V"
					( Origin gFrontEnd )
				)
				( attribute "PART_NUMBER" "A36096-030"
					( Origin gFrontEnd )
				)
				( attribute "PHYS_PAGE" "199"
					( Origin gFrontEnd )
				)
				( attribute "ROOM" "HOT_SWAP"
					( Origin gFrontEnd )
				)
				( attribute "ROT" "2"
					( Origin gFrontEnd )
				)
				( attribute "SEC" "1"
					( Origin gFrontEnd )
				)
				( attribute "SEC_TYPE" "0402V"
					( Origin gFrontEnd )
				)
				( attribute "TOLERANCE" "10%"
					( Origin gFrontEnd )
				)
				( attribute "VALUE" "0.1UF"
					( Origin gFrontEnd )
				)
				( attribute "VER" "1"
					( Origin gFrontEnd )
				)
				( attribute "VOLTAGE" "16V"
					( Units "uVoltage" "V" 1.000000)
					( Origin gFrontEnd )
				)
				( attribute "XY" "(-6775,3575)"
					( Origin gFrontEnd )
				)
				( attribute "CHIPS_PART_NAME" "CAP_A"
					( Origin gPackager )
				)
				( attribute "CDS_PART_NAME" "CAP_A_0402V-0.1UF,16V,10%,X7R,A"
					( Origin gPackager )
				)
				( objectStatus "C1D27" )
			)
			( gate "@baseboard_fab2_lib.baseboard_fab2(sch_1):page199_i9"
				( attribute "CDS_LIB" "mstr_discrete"
					( Origin gPackager )
				)
				( attribute "CDS_LOCATION" "R1D43"
					( Origin gPackager )
				)
				( attribute "CDS_SEC" "1"
					( Origin gPackager )
				)
				( attribute "LOCATION" "R1D43"
					( Origin gFrontEnd )
				)
				( attribute "MATERIAL" "CHIP"
					( Origin gFrontEnd )
				)
				( attribute "PACK_TYPE" "0402"
					( Origin gFrontEnd )
				)
				( attribute "PART_NUMBER" "G21796-177"
					( Origin gFrontEnd )
				)
				( attribute "PHYS_PAGE" "199"
					( Origin gFrontEnd )
				)
				( attribute "ROOM" "HOT_SWAP"
					( Origin gFrontEnd )
				)
				( attribute "ROT" "0"
					( Origin gFrontEnd )
				)
				( attribute "SEC" "1"
					( Origin gFrontEnd )
				)
				( attribute "SEC_TYPE" "0402"
					( Origin gFrontEnd )
				)
				( attribute "TOLERANCE" "1%"
					( Origin gFrontEnd )
				)
				( attribute "VALUE" "7.5K"
					( Origin gFrontEnd )
				)
				( attribute "VER" "2"
					( Origin gFrontEnd )
				)
				( attribute "WATTAGE" "1/16W"
					( Origin gFrontEnd )
				)
				( attribute "XY" "(-7200,3625)"
					( Origin gFrontEnd )
				)
				( attribute "CHIPS_PART_NAME" "RES"
					( Origin gPackager )
				)
				( attribute "CDS_PART_NAME" "RES_0402-7.5K,1%,1/16W,CHIP,G2A"
					( Origin gPackager )
				)
				( attribute "CONFIG" "064.7501D.06DD"
					( Origin gFrontEnd )
				)
				( objectStatus "R1D43" )
			)
			( gate "@baseboard_fab2_lib.baseboard_fab2(sch_1):page199_i10"
				( attribute "CDS_LIB" "mstr_controller"
					( Origin gPackager )
				)
				( attribute "CDS_LOCATION" "EU1D2"
					( Origin gPackager )
				)
				( attribute "CDS_SEC" "1"
					( Origin gPackager )
				)
				( attribute "LOCATION" "EU1D2"
					( Origin gFrontEnd )
				)
				( attribute "MATERIAL" "IC"
					( Origin gFrontEnd )
				)
				( attribute "PACK_TYPE" "SM"
					( Origin gFrontEnd )
				)
				( attribute "PART_NUMBER" "G99251-001"
					( Origin gFrontEnd )
				)
				( attribute "PHYS_PAGE" "199"
					( Origin gFrontEnd )
				)
				( attribute "ROOM" "HOT_SWAP"
					( Origin gFrontEnd )
				)
				( attribute "ROT" "0"
					( Origin gFrontEnd )
				)
				( attribute "SEC" "1"
					( Origin gFrontEnd )
				)
				( attribute "SEC_TYPE" "SM"
					( Origin gFrontEnd )
				)
				( attribute "VER" "1"
					( Origin gFrontEnd )
				)
				( attribute "XY" "(-3250,2575)"
					( Origin gFrontEnd )
				)
				( attribute "CHIPS_PART_NAME" "ADM1278"
					( Origin gPackager )
				)
				( attribute "CDS_PART_NAME" "ADM1278_SM-IC,G99251-001"
					( Origin gPackager )
				)
				( objectStatus "EU1D2" )
			)
			( gate "@baseboard_fab2_lib.baseboard_fab2(sch_1):page199_i12"
				( attribute "CDS_LIB" "mstr_discrete"
					( Origin gPackager )
				)
				( attribute "CDS_LOCATION" "R9P29"
					( Origin gPackager )
				)
				( attribute "CDS_SEC" "1"
					( Origin gPackager )
				)
				( attribute "LOCATION" "R9P29"
					( Origin gFrontEnd )
				)
				( attribute "MATERIAL" "CHIP"
					( Origin gFrontEnd )
				)
				( attribute "PACK_TYPE" "0402"
					( Origin gFrontEnd )
				)
				( attribute "PART_NUMBER" "G21796-010"
					( Origin gFrontEnd )
				)
				( attribute "PHYS_PAGE" "199"
					( Origin gFrontEnd )
				)
				( attribute "ROOM" "HOT_SWAP"
					( Origin gFrontEnd )
				)
				( attribute "ROT" "0"
					( Origin gFrontEnd )
				)
				( attribute "SEC" "1"
					( Origin gFrontEnd )
				)
				( attribute "SEC_TYPE" "0402"
					( Origin gFrontEnd )
				)
				( attribute "TOLERANCE" "1%"
					( Origin gFrontEnd )
				)
				( attribute "VALUE" "100.0K"
					( Origin gFrontEnd )
				)
				( attribute "VER" "2"
					( Origin gFrontEnd )
				)
				( attribute "WATTAGE" "1/16W"
					( Origin gFrontEnd )
				)
				( attribute "XY" "(-6500,4050)"
					( Origin gFrontEnd )
				)
				( attribute "CHIPS_PART_NAME" "RES"
					( Origin gPackager )
				)
				( attribute "CDS_PART_NAME" "RES_0402-100.0K,1%,1/16W,CHIP,A"
					( Origin gPackager )
				)
				( objectStatus "R9P29" )
			)
			( gate "@baseboard_fab2_lib.baseboard_fab2(sch_1):page199_i13"
				( attribute "CDS_LIB" "mstr_discrete"
					( Origin gPackager )
				)
				( attribute "CDS_LOCATION" "R1D42"
					( Origin gPackager )
				)
				( attribute "CDS_SEC" "1"
					( Origin gPackager )
				)
				( attribute "LOCATION" "R1D42"
					( Origin gFrontEnd )
				)
				( attribute "MATERIAL" "CHIP"
					( Origin gFrontEnd )
				)
				( attribute "PACK_TYPE" "0402"
					( Origin gFrontEnd )
				)
				( attribute "PART_NUMBER" "G21796-220"
					( Origin gFrontEnd )
				)
				( attribute "PHYS_PAGE" "199"
					( Origin gFrontEnd )
				)
				( attribute "ROOM" "HOT_SWAP"
					( Origin gFrontEnd )
				)
				( attribute "ROT" "0"
					( Origin gFrontEnd )
				)
				( attribute "SEC" "1"
					( Origin gFrontEnd )
				)
				( attribute "SEC_TYPE" "0402"
					( Origin gFrontEnd )
				)
				( attribute "TOLERANCE" "1%"
					( Origin gFrontEnd )
				)
				( attribute "VALUE" "11K"
					( Origin gFrontEnd )
				)
				( attribute "VER" "2"
					( Origin gFrontEnd )
				)
				( attribute "WATTAGE" "1/16W"
					( Origin gFrontEnd )
				)
				( attribute "XY" "(-6500,3600)"
					( Origin gFrontEnd )
				)
				( attribute "CHIPS_PART_NAME" "RES"
					( Origin gPackager )
				)
				( attribute "CDS_PART_NAME" "RES_0402-11K,1%,1/16W,CHIP,G21A"
					( Origin gPackager )
				)
				( objectStatus "R1D42" )
			)
			( gate "@baseboard_fab2_lib.baseboard_fab2(sch_1):page199_i15"
				( attribute "CDS_LIB" "mstr_discrete"
					( Origin gPackager )
				)
				( attribute "CDS_LOCATION" "R1D37"
					( Origin gPackager )
				)
				( attribute "CDS_SEC" "1"
					( Origin gPackager )
				)
				( attribute "LOCATION" "R1D37"
					( Origin gFrontEnd )
				)
				( attribute "MATERIAL" "CHIP"
					( Origin gFrontEnd )
				)
				( attribute "NO_XNET_CONNECTION" "1"
					( Origin gFrontEnd )
				)
				( attribute "PACK_TYPE" "0402"
					( Origin gFrontEnd )
				)
				( attribute "PART_NUMBER" "G21796-010"
					( Origin gFrontEnd )
				)
				( attribute "PHYS_PAGE" "199"
					( Origin gFrontEnd )
				)
				( attribute "ROOM" "HOT_SWAP"
					( Origin gFrontEnd )
				)
				( attribute "ROT" "0"
					( Origin gFrontEnd )
				)
				( attribute "SEC" "1"
					( Origin gFrontEnd )
				)
				( attribute "SEC_TYPE" "0402"
					( Origin gFrontEnd )
				)
				( attribute "TOLERANCE" "1%"
					( Origin gFrontEnd )
				)
				( attribute "VALUE" "100.0K"
					( Origin gFrontEnd )
				)
				( attribute "VER" "2"
					( Origin gFrontEnd )
				)
				( attribute "WATTAGE" "1/16W"
					( Origin gFrontEnd )
				)
				( attribute "XY" "(-6600,1550)"
					( Origin gFrontEnd )
				)
				( attribute "CHIPS_PART_NAME" "RES"
					( Origin gPackager )
				)
				( attribute "CDS_PART_NAME" "RES_0402-100.0K,1%,1/16W,CHIP,A"
					( Origin gPackager )
				)
				( objectStatus "R1D37" )
			)
			( gate "@baseboard_fab2_lib.baseboard_fab2(sch_1):page199_i16"
				( attribute "CDS_LIB" "mstr_discrete"
					( Origin gPackager )
				)
				( attribute "CDS_LOCATION" "R1D39"
					( Origin gPackager )
				)
				( attribute "CDS_SEC" "1"
					( Origin gPackager )
				)
				( attribute "LOCATION" "R1D39"
					( Origin gFrontEnd )
				)
				( attribute "MATERIAL" "CHIP"
					( Origin gFrontEnd )
				)
				( attribute "NO_XNET_CONNECTION" "1"
					( Origin gFrontEnd )
				)
				( attribute "PACK_TYPE" "0402"
					( Origin gFrontEnd )
				)
				( attribute "PART_NUMBER" "G21796-010"
					( Origin gFrontEnd )
				)
				( attribute "PHYS_PAGE" "199"
					( Origin gFrontEnd )
				)
				( attribute "ROOM" "HOT_SWAP"
					( Origin gFrontEnd )
				)
				( attribute "ROT" "0"
					( Origin gFrontEnd )
				)
				( attribute "SEC" "1"
					( Origin gFrontEnd )
				)
				( attribute "SEC_TYPE" "0402"
					( Origin gFrontEnd )
				)
				( attribute "TOLERANCE" "1%"
					( Origin gFrontEnd )
				)
				( attribute "VALUE" "100.0K"
					( Origin gFrontEnd )
				)
				( attribute "VER" "2"
					( Origin gFrontEnd )
				)
				( attribute "WATTAGE" "1/16W"
					( Origin gFrontEnd )
				)
				( attribute "XY" "(-5300,1500)"
					( Origin gFrontEnd )
				)
				( attribute "CHIPS_PART_NAME" "RES"
					( Origin gPackager )
				)
				( attribute "CDS_PART_NAME" "RES_0402-100.0K,1%,1/16W,CHIP,A"
					( Origin gPackager )
				)
				( objectStatus "R1D39" )
			)
			( gate "@baseboard_fab2_lib.baseboard_fab2(sch_1):page199_i17"
				( attribute "CDS_LIB" "mstr_discrete"
					( Origin gPackager )
				)
				( attribute "CDS_LOCATION" "R1D32"
					( Origin gPackager )
				)
				( attribute "CDS_SEC" "1"
					( Origin gPackager )
				)
				( attribute "LOCATION" "R1D32"
					( Origin gFrontEnd )
				)
				( attribute "MATERIAL" "CHIP"
					( Origin gFrontEnd )
				)
				( attribute "NO_XNET_CONNECTION" "1"
					( Origin gFrontEnd )
				)
				( attribute "PACK_TYPE" "0402"
					( Origin gFrontEnd )
				)
				( attribute "PART_NUMBER" "G21796-010"
					( Origin gFrontEnd )
				)
				( attribute "PHYS_PAGE" "199"
					( Origin gFrontEnd )
				)
				( attribute "ROOM" "HOT_SWAP"
					( Origin gFrontEnd )
				)
				( attribute "ROT" "0"
					( Origin gFrontEnd )
				)
				( attribute "SEC" "1"
					( Origin gFrontEnd )
				)
				( attribute "SEC_TYPE" "0402"
					( Origin gFrontEnd )
				)
				( attribute "TOLERANCE" "1%"
					( Origin gFrontEnd )
				)
				( attribute "VALUE" "100.0K"
					( Origin gFrontEnd )
				)
				( attribute "VER" "2"
					( Origin gFrontEnd )
				)
				( attribute "WATTAGE" "1/16W"
					( Origin gFrontEnd )
				)
				( attribute "XY" "(-5600,1500)"
					( Origin gFrontEnd )
				)
				( attribute "CHIPS_PART_NAME" "RES"
					( Origin gPackager )
				)
				( attribute "CDS_PART_NAME" "RES_0402-100.0K,1%,1/16W,CHIP,A"
					( Origin gPackager )
				)
				( objectStatus "R1D32" )
			)
			( gate "@baseboard_fab2_lib.baseboard_fab2(sch_1):page199_i19"
				( attribute "CDS_LIB" "mstr_discrete"
					( Origin gPackager )
				)
				( attribute "CDS_LOCATION" "R1D41"
					( Origin gPackager )
				)
				( attribute "CDS_SEC" "1"
					( Origin gPackager )
				)
				( attribute "LOCATION" "R1D41"
					( Origin gFrontEnd )
				)
				( attribute "MATERIAL" "CHIP"
					( Origin gFrontEnd )
				)
				( attribute "PACK_TYPE" "0805"
					( Origin gFrontEnd )
				)
				( attribute "PART_NUMBER" "G22179-004"
					( Origin gFrontEnd )
				)
				( attribute "PHYS_PAGE" "199"
					( Origin gFrontEnd )
				)
				( attribute "ROOM" "HOT_SWAP"
					( Origin gFrontEnd )
				)
				( attribute "ROT" "0"
					( Origin gFrontEnd )
				)
				( attribute "SEC" "1"
					( Origin gFrontEnd )
				)
				( attribute "SEC_TYPE" "0805"
					( Origin gFrontEnd )
				)
				( attribute "TOLERANCE" "5%"
					( Origin gFrontEnd )
				)
				( attribute "VALUE" "0.0"
					( Origin gFrontEnd )
				)
				( attribute "VER" "1"
					( Origin gFrontEnd )
				)
				( attribute "WATTAGE" "1/8W"
					( Origin gFrontEnd )
				)
				( attribute "XY" "(-1650,300)"
					( Origin gFrontEnd )
				)
				( attribute "CHIPS_PART_NAME" "RES"
					( Origin gPackager )
				)
				( attribute "CDS_PART_NAME" "RES_0805-0.0,5%,1/8W,CHIP,G221A"
					( Origin gPackager )
				)
				( objectStatus "R1D41" )
			)
			( gate "@baseboard_fab2_lib.baseboard_fab2(sch_1):page199_i24"
				( attribute "CDS_LIB" "mstr_discrete"
					( Origin gPackager )
				)
				( attribute "CDS_LOCATION" "C9P14"
					( Origin gPackager )
				)
				( attribute "CDS_SEC" "1"
					( Origin gPackager )
				)
				( attribute "LOCATION" "C9P14"
					( Origin gFrontEnd )
				)
				( attribute "MATERIAL" "X7R"
					( Origin gFrontEnd )
				)
				( attribute "PACK_TYPE" "0603LF"
					( Origin gFrontEnd )
				)
				( attribute "PART_NUMBER" "603269-064"
					( Origin gFrontEnd )
				)
				( attribute "PHYS_PAGE" "199"
					( Origin gFrontEnd )
				)
				( attribute "ROOM" "HOT_SWAP"
					( Origin gFrontEnd )
				)
				( attribute "ROT" "0"
					( Origin gFrontEnd )
				)
				( attribute "SEC" "1"
					( Origin gFrontEnd )
				)
				( attribute "SEC_TYPE" "0603LF"
					( Origin gFrontEnd )
				)
				( attribute "TOLERANCE" "10%"
					( Origin gFrontEnd )
				)
				( attribute "VALUE" "0.033UF"
					( Origin gFrontEnd )
				)
				( attribute "VER" "1"
					( Origin gFrontEnd )
				)
				( attribute "VOLTAGE" "50V"
					( Units "uVoltage" "V" 1.000000)
					( Origin gFrontEnd )
				)
				( attribute "XY" "(-4850,1500)"
					( Origin gFrontEnd )
				)
				( attribute "CHIPS_PART_NAME" "CAP"
					( Origin gPackager )
				)
				( attribute "CDS_PART_NAME" "CAP_0603LF-0.033UF,50V,10%,X7RA"
					( Origin gPackager )
				)
				( objectStatus "C9P14" )
			)
			( gate "@baseboard_fab2_lib.baseboard_fab2(sch_1):page199_i26"
				( attribute "CDS_LIB" "mstr_discrete"
					( Origin gPackager )
				)
				( attribute "CDS_LOCATION" "R1D28"
					( Origin gPackager )
				)
				( attribute "CDS_SEC" "1"
					( Origin gPackager )
				)
				( attribute "LOCATION" "R1D28"
					( Origin gFrontEnd )
				)
				( attribute "MATERIAL" "EMPTY"
					( Origin gFrontEnd )
				)
				( attribute "PACK_TYPE" "0402"
					( Origin gFrontEnd )
				)
				( attribute "PART_NUMBER" "G21796-017"
					( Origin gFrontEnd )
				)
				( attribute "PHYS_PAGE" "199"
					( Origin gFrontEnd )
				)
				( attribute "ROOM" "HOT_SWAP"
					( Origin gFrontEnd )
				)
				( attribute "ROT" "0"
					( Origin gFrontEnd )
				)
				( attribute "SEC" "1"
					( Origin gFrontEnd )
				)
				( attribute "SEC_TYPE" "0402"
					( Origin gFrontEnd )
				)
				( attribute "TOLERANCE" "1%"
					( Origin gFrontEnd )
				)
				( attribute "VALUE" "100.0"
					( Origin gFrontEnd )
				)
				( attribute "VER" "2"
					( Origin gFrontEnd )
				)
				( attribute "WATTAGE" "1/16W"
					( Origin gFrontEnd )
				)
				( attribute "XY" "(-4625,1025)"
					( Origin gFrontEnd )
				)
				( attribute "CHIPS_PART_NAME" "RES"
					( Origin gPackager )
				)
				( attribute "CDS_PART_NAME" "RES_0402-100.0,1%,1/16W,EMPTY,A"
					( Origin gPackager )
				)
				( objectStatus "R1D28" )
			)
			( gate "@baseboard_fab2_lib.baseboard_fab2(sch_1):page199_i27"
				( attribute "CDS_LIB" "mstr_discrete"
					( Origin gPackager )
				)
				( attribute "CDS_LOCATION" "R1D24"
					( Origin gPackager )
				)
				( attribute "CDS_SEC" "1"
					( Origin gPackager )
				)
				( attribute "LOCATION" "R1D24"
					( Origin gFrontEnd )
				)
				( attribute "MATERIAL" "CHIP"
					( Origin gFrontEnd )
				)
				( attribute "PACK_TYPE" "0402"
					( Origin gFrontEnd )
				)
				( attribute "PART_NUMBER" "G21497-005"
					( Origin gFrontEnd )
				)
				( attribute "PHYS_PAGE" "199"
					( Origin gFrontEnd )
				)
				( attribute "ROOM" "HOT_SWAP"
					( Origin gFrontEnd )
				)
				( attribute "ROT" "0"
					( Origin gFrontEnd )
				)
				( attribute "SEC" "1"
					( Origin gFrontEnd )
				)
				( attribute "SEC_TYPE" "0402"
					( Origin gFrontEnd )
				)
				( attribute "TOLERANCE" "5%"
					( Origin gFrontEnd )
				)
				( attribute "VALUE" "0.0"
					( Origin gFrontEnd )
				)
				( attribute "VER" "1"
					( Origin gFrontEnd )
				)
				( attribute "WATTAGE" "1/16W"
					( Origin gFrontEnd )
				)
				( attribute "XY" "(-5600,2725)"
					( Origin gFrontEnd )
				)
				( attribute "CHIPS_PART_NAME" "RES"
					( Origin gPackager )
				)
				( attribute "CDS_PART_NAME" "RES_0402-0.0,5%,1/16W,CHIP,G21A"
					( Origin gPackager )
				)
				( objectStatus "R1D24" )
			)
			( gate "@baseboard_fab2_lib.baseboard_fab2(sch_1):page199_i28"
				( attribute "CDS_LIB" "mstr_discrete"
					( Origin gPackager )
				)
				( attribute "CDS_LOCATION" "R1D25"
					( Origin gPackager )
				)
				( attribute "CDS_SEC" "1"
					( Origin gPackager )
				)
				( attribute "LOCATION" "R1D25"
					( Origin gFrontEnd )
				)
				( attribute "MATERIAL" "CHIP"
					( Origin gFrontEnd )
				)
				( attribute "PACK_TYPE" "0402"
					( Origin gFrontEnd )
				)
				( attribute "PART_NUMBER" "G21497-005"
					( Origin gFrontEnd )
				)
				( attribute "PHYS_PAGE" "199"
					( Origin gFrontEnd )
				)
				( attribute "ROOM" "HOT_SWAP"
					( Origin gFrontEnd )
				)
				( attribute "ROT" "0"
					( Origin gFrontEnd )
				)
				( attribute "SEC" "1"
					( Origin gFrontEnd )
				)
				( attribute "SEC_TYPE" "0402"
					( Origin gFrontEnd )
				)
				( attribute "TOLERANCE" "5%"
					( Origin gFrontEnd )
				)
				( attribute "VALUE" "0.0"
					( Origin gFrontEnd )
				)
				( attribute "VER" "1"
					( Origin gFrontEnd )
				)
				( attribute "WATTAGE" "1/16W"
					( Origin gFrontEnd )
				)
				( attribute "XY" "(-5600,2675)"
					( Origin gFrontEnd )
				)
				( attribute "CHIPS_PART_NAME" "RES"
					( Origin gPackager )
				)
				( attribute "CDS_PART_NAME" "RES_0402-0.0,5%,1/16W,CHIP,G21A"
					( Origin gPackager )
				)
				( objectStatus "R1D25" )
			)
			( gate "@baseboard_fab2_lib.baseboard_fab2(sch_1):page199_i33"
				( attribute "CDS_LIB" "mstr_discrete"
					( Origin gPackager )
				)
				( attribute "CDS_LOCATION" "R9P17"
					( Origin gPackager )
				)
				( attribute "CDS_SEC" "1"
					( Origin gPackager )
				)
				( attribute "LOCATION" "R9P17"
					( Origin gFrontEnd )
				)
				( attribute "MATERIAL" "CHIP"
					( Origin gFrontEnd )
				)
				( attribute "PACK_TYPE" "0402"
					( Origin gFrontEnd )
				)
				( attribute "PART_NUMBER" "G21796-109"
					( Origin gFrontEnd )
				)
				( attribute "PHYS_PAGE" "199"
					( Origin gFrontEnd )
				)
				( attribute "ROOM" "HOT_SWAP"
					( Origin gFrontEnd )
				)
				( attribute "ROT" "0"
					( Origin gFrontEnd )
				)
				( attribute "SEC" "1"
					( Origin gFrontEnd )
				)
				( attribute "SEC_TYPE" "0402"
					( Origin gFrontEnd )
				)
				( attribute "TOLERANCE" "1%"
					( Origin gFrontEnd )
				)
				( attribute "VALUE" "150.0K"
					( Origin gFrontEnd )
				)
				( attribute "VER" "2"
					( Origin gFrontEnd )
				)
				( attribute "WATTAGE" "1/16W"
					( Origin gFrontEnd )
				)
				( attribute "XY" "(-8000,2375)"
					( Origin gFrontEnd )
				)
				( attribute "CHIPS_PART_NAME" "RES"
					( Origin gPackager )
				)
				( attribute "CDS_PART_NAME" "RES_0402-150.0K,1%,1/16W,CHIP,A"
					( Origin gPackager )
				)
				( objectStatus "R9P17" )
			)
			( gate "@baseboard_fab2_lib.baseboard_fab2(sch_1):page199_i36"
				( attribute "CDS_LIB" "mstr_discrete"
					( Origin gPackager )
				)
				( attribute "CDS_LOCATION" "R9P16"
					( Origin gPackager )
				)
				( attribute "CDS_SEC" "1"
					( Origin gPackager )
				)
				( attribute "LOCATION" "R9P16"
					( Origin gFrontEnd )
				)
				( attribute "MATERIAL" "CHIP"
					( Origin gFrontEnd )
				)
				( attribute "PACK_TYPE" "0402"
					( Origin gFrontEnd )
				)
				( attribute "PART_NUMBER" "G21497-005"
					( Origin gFrontEnd )
				)
				( attribute "PHYS_PAGE" "199"
					( Origin gFrontEnd )
				)
				( attribute "ROOM" "HOT_SWAP"
					( Origin gFrontEnd )
				)
				( attribute "ROT" "0"
					( Origin gFrontEnd )
				)
				( attribute "SEC" "1"
					( Origin gFrontEnd )
				)
				( attribute "SEC_TYPE" "0402"
					( Origin gFrontEnd )
				)
				( attribute "TOLERANCE" "5%"
					( Origin gFrontEnd )
				)
				( attribute "VALUE" "0.0"
					( Origin gFrontEnd )
				)
				( attribute "VER" "2"
					( Origin gFrontEnd )
				)
				( attribute "WATTAGE" "1/16W"
					( Origin gFrontEnd )
				)
				( attribute "XY" "(-7675,2375)"
					( Origin gFrontEnd )
				)
				( attribute "CHIPS_PART_NAME" "RES"
					( Origin gPackager )
				)
				( attribute "CDS_PART_NAME" "RES_0402-0.0,5%,1/16W,CHIP,G21A"
					( Origin gPackager )
				)
				( attribute "BOM_DS" "NOPOP"
					( Origin gFrontEnd )
				)
				( objectStatus "R9P16" )
			)
			( gate "@baseboard_fab2_lib.baseboard_fab2(sch_1):page199_i38"
				( attribute "CDS_LIB" "mstr_discrete"
					( Origin gPackager )
				)
				( attribute "CDS_LOCATION" "R1D27"
					( Origin gPackager )
				)
				( attribute "CDS_SEC" "1"
					( Origin gPackager )
				)
				( attribute "LOCATION" "R1D27"
					( Origin gFrontEnd )
				)
				( attribute "MATERIAL" "EMPTY"
					( Origin gFrontEnd )
				)
				( attribute "NO_XNET_CONNECTION" "1"
					( Origin gFrontEnd )
				)
				( attribute "PACK_TYPE" "0402"
					( Origin gFrontEnd )
				)
				( attribute "PART_NUMBER" "G21796-072"
					( Origin gFrontEnd )
				)
				( attribute "PHYS_PAGE" "199"
					( Origin gFrontEnd )
				)
				( attribute "ROOM" "HOT_SWAP"
					( Origin gFrontEnd )
				)
				( attribute "ROT" "0"
					( Origin gFrontEnd )
				)
				( attribute "SEC" "1"
					( Origin gFrontEnd )
				)
				( attribute "SEC_TYPE" "0402"
					( Origin gFrontEnd )
				)
				( attribute "TOLERANCE" "1%"
					( Origin gFrontEnd )
				)
				( attribute "VALUE" "4.75K"
					( Origin gFrontEnd )
				)
				( attribute "VER" "2"
					( Origin gFrontEnd )
				)
				( attribute "WATTAGE" "1/16W"
					( Origin gFrontEnd )
				)
				( attribute "XY" "(-7675,2950)"
					( Origin gFrontEnd )
				)
				( attribute "CHIPS_PART_NAME" "RES"
					( Origin gPackager )
				)
				( attribute "CDS_PART_NAME" "RES_0402-4.75K,1%,1/16W,EMPTY,A"
					( Origin gPackager )
				)
				( objectStatus "R1D27" )
			)
			( gate "@baseboard_fab2_lib.baseboard_fab2(sch_1):page199_i41"
				( attribute "BOM_COST" "MIO_USB"
					( Origin gFrontEnd )
				)
				( attribute "CDS_LIB" "mstr_discrete"
					( Origin gPackager )
				)
				( attribute "CDS_LOCATION" "R9P18"
					( Origin gPackager )
				)
				( attribute "CDS_SEC" "1"
					( Origin gPackager )
				)
				( attribute "LOCATION" "R9P18"
					( Origin gFrontEnd )
				)
				( attribute "MATERIAL" "CHIP"
					( Origin gFrontEnd )
				)
				( attribute "PACK_TYPE" "0402"
					( Origin gFrontEnd )
				)
				( attribute "PART_NUMBER" "G21796-107"
					( Origin gFrontEnd )
				)
				( attribute "PHYS_PAGE" "199"
					( Origin gFrontEnd )
				)
				( attribute "ROOM" "HOT_SWAP"
					( Origin gFrontEnd )
				)
				( attribute "ROT" "2"
					( Origin gFrontEnd )
				)
				( attribute "SEC" "1"
					( Origin gFrontEnd )
				)
				( attribute "SEC_TYPE" "0402"
					( Origin gFrontEnd )
				)
				( attribute "TOLERANCE" "1%"
					( Origin gFrontEnd )
				)
				( attribute "VALUE" "15.0K"
					( Origin gFrontEnd )
				)
				( attribute "VER" "2"
					( Origin gFrontEnd )
				)
				( attribute "WATTAGE" "1/16W"
					( Origin gFrontEnd )
				)
				( attribute "XY" "(-3125,1075)"
					( Origin gFrontEnd )
				)
				( attribute "CHIPS_PART_NAME" "RES"
					( Origin gPackager )
				)
				( attribute "CDS_PART_NAME" "RES_0402-15.0K,1%,1/16W,CHIP,GA"
					( Origin gPackager )
				)
				( objectStatus "R9P18" )
			)
			( gate "@baseboard_fab2_lib.baseboard_fab2(sch_1):page199_i43"
				( attribute "CDS_LIB" "mstr_discrete"
					( Origin gPackager )
				)
				( attribute "CDS_LOCATION" "R1D31"
					( Origin gPackager )
				)
				( attribute "CDS_SEC" "1"
					( Origin gPackager )
				)
				( attribute "LOCATION" "R1D31"
					( Origin gFrontEnd )
				)
				( attribute "MATERIAL" "CHIP"
					( Origin gFrontEnd )
				)
				( attribute "PACK_TYPE" "0402"
					( Origin gFrontEnd )
				)
				( attribute "PART_NUMBER" "G21796-161"
					( Origin gFrontEnd )
				)
				( attribute "PHYS_PAGE" "199"
					( Origin gFrontEnd )
				)
				( attribute "ROOM" "HOT_SWAP"
					( Origin gFrontEnd )
				)
				( attribute "ROT" "2"
					( Origin gFrontEnd )
				)
				( attribute "SEC" "1"
					( Origin gFrontEnd )
				)
				( attribute "SEC_TYPE" "0402"
					( Origin gFrontEnd )
				)
				( attribute "TOLERANCE" "1%"
					( Origin gFrontEnd )
				)
				( attribute "VALUE" "6.19K"
					( Origin gFrontEnd )
				)
				( attribute "VER" "2"
					( Origin gFrontEnd )
				)
				( attribute "WATTAGE" "1/16W"
					( Origin gFrontEnd )
				)
				( attribute "XY" "(-2825,750)"
					( Origin gFrontEnd )
				)
				( attribute "CHIPS_PART_NAME" "RES"
					( Origin gPackager )
				)
				( attribute "CDS_PART_NAME" "RES_0402-6.19K,1%,1/16W,CHIP,GA"
					( Origin gPackager )
				)
				( objectStatus "R1D31" )
			)
			( gate "@baseboard_fab2_lib.baseboard_fab2(sch_1):page199_i53"
				( attribute "CDS_LIB" "dev_discrete"
					( Origin gPackager )
				)
				( attribute "CDS_LOCATION" "C1D11"
					( Origin gPackager )
				)
				( attribute "CDS_SEC" "1"
					( Origin gPackager )
				)
				( attribute "LOCATION" "C1D11"
					( Origin gFrontEnd )
				)
				( attribute "MATERIAL" "X7R"
					( Origin gFrontEnd )
				)
				( attribute "PACK_TYPE" "0402V"
					( Origin gFrontEnd )
				)
				( attribute "PART_NUMBER" "A36096-030"
					( Origin gFrontEnd )
				)
				( attribute "PHYS_PAGE" "199"
					( Origin gFrontEnd )
				)
				( attribute "ROOM" "HOT_SWAP"
					( Origin gFrontEnd )
				)
				( attribute "ROT" "2"
					( Origin gFrontEnd )
				)
				( attribute "SEC" "1"
					( Origin gFrontEnd )
				)
				( attribute "SEC_TYPE" "0402V"
					( Origin gFrontEnd )
				)
				( attribute "TOLERANCE" "10%"
					( Origin gFrontEnd )
				)
				( attribute "VALUE" "0.1UF"
					( Origin gFrontEnd )
				)
				( attribute "VER" "1"
					( Origin gFrontEnd )
				)
				( attribute "VOLTAGE" "16V"
					( Units "uVoltage" "V" 1.000000)
					( Origin gFrontEnd )
				)
				( attribute "XY" "(-7025,2175)"
					( Origin gFrontEnd )
				)
				( attribute "CHIPS_PART_NAME" "CAP_A"
					( Origin gPackager )
				)
				( attribute "CDS_PART_NAME" "CAP_A_0402V-0.1UF,16V,10%,X7R,A"
					( Origin gPackager )
				)
				( objectStatus "C1D11" )
			)
			( gate "@baseboard_fab2_lib.baseboard_fab2(sch_1):page199_i54"
				( attribute "CDS_LIB" "mstr_discrete"
					( Origin gPackager )
				)
				( attribute "CDS_LOCATION" "R9P23"
					( Origin gPackager )
				)
				( attribute "CDS_SEC" "1"
					( Origin gPackager )
				)
				( attribute "LOCATION" "R9P23"
					( Origin gFrontEnd )
				)
				( attribute "MATERIAL" "CHIP"
					( Origin gFrontEnd )
				)
				( attribute "PACK_TYPE" "0402"
					( Origin gFrontEnd )
				)
				( attribute "PART_NUMBER" "G21796-010"
					( Origin gFrontEnd )
				)
				( attribute "PHYS_PAGE" "199"
					( Origin gFrontEnd )
				)
				( attribute "ROOM" "HOT_SWAP"
					( Origin gFrontEnd )
				)
				( attribute "ROT" "0"
					( Origin gFrontEnd )
				)
				( attribute "SEC" "1"
					( Origin gFrontEnd )
				)
				( attribute "SEC_TYPE" "0402"
					( Origin gFrontEnd )
				)
				( attribute "TOLERANCE" "1%"
					( Origin gFrontEnd )
				)
				( attribute "VALUE" "100.0K"
					( Origin gFrontEnd )
				)
				( attribute "VER" "2"
					( Origin gFrontEnd )
				)
				( attribute "WATTAGE" "1/16W"
					( Origin gFrontEnd )
				)
				( attribute "XY" "(-6725,2025)"
					( Origin gFrontEnd )
				)
				( attribute "CHIPS_PART_NAME" "RES"
					( Origin gPackager )
				)
				( attribute "CDS_PART_NAME" "RES_0402-100.0K,1%,1/16W,CHIP,A"
					( Origin gPackager )
				)
				( objectStatus "R9P23" )
			)
			( gate "@baseboard_fab2_lib.baseboard_fab2(sch_1):page199_i55"
				( attribute "BOM_COST" "MIO_USB"
					( Origin gFrontEnd )
				)
				( attribute "CDS_LIB" "mstr_discrete"
					( Origin gPackager )
				)
				( attribute "CDS_LOCATION" "R9P24"
					( Origin gPackager )
				)
				( attribute "CDS_SEC" "1"
					( Origin gPackager )
				)
				( attribute "LOCATION" "R9P24"
					( Origin gFrontEnd )
				)
				( attribute "MATERIAL" "CHIP"
					( Origin gFrontEnd )
				)
				( attribute "PACK_TYPE" "0402"
					( Origin gFrontEnd )
				)
				( attribute "PART_NUMBER" "G21796-089"
					( Origin gFrontEnd )
				)
				( attribute "PHYS_PAGE" "199"
					( Origin gFrontEnd )
				)
				( attribute "ROOM" "HOT_SWAP"
					( Origin gFrontEnd )
				)
				( attribute "ROT" "2"
					( Origin gFrontEnd )
				)
				( attribute "SEC" "1"
					( Origin gFrontEnd )
				)
				( attribute "SEC_TYPE" "0402"
					( Origin gFrontEnd )
				)
				( attribute "TOLERANCE" "1%"
					( Origin gFrontEnd )
				)
				( attribute "VALUE" "12.1K"
					( Origin gFrontEnd )
				)
				( attribute "VER" "2"
					( Origin gFrontEnd )
				)
				( attribute "WATTAGE" "1/16W"
					( Origin gFrontEnd )
				)
				( attribute "XY" "(-6725,1725)"
					( Origin gFrontEnd )
				)
				( attribute "CHIPS_PART_NAME" "RES"
					( Origin gPackager )
				)
				( attribute "CDS_PART_NAME" "RES_0402-12.1K,1%,1/16W,CHIP,GA"
					( Origin gPackager )
				)
				( objectStatus "R9P24" )
			)
			( gate "@baseboard_fab2_lib.baseboard_fab2(sch_1):page199_i58"
				( attribute "CDS_LIB" "mstr_discrete"
					( Origin gPackager )
				)
				( attribute "CDS_LOCATION" "Q1D3"
					( Origin gPackager )
				)
				( attribute "CDS_SEC" "1"
					( Origin gPackager )
				)
				( attribute "LOCATION" "Q1D3"
					( Origin gFrontEnd )
				)
				( attribute "MATERIAL" "IC"
					( Origin gFrontEnd )
				)
				( attribute "PACK_TYPE" "SM"
					( Origin gFrontEnd )
				)
				( attribute "PART_NUMBER" "C52245-001"
					( Origin gFrontEnd )
				)
				( attribute "PHYS_PAGE" "199"
					( Origin gFrontEnd )
				)
				( attribute "ROOM" "HOT_SWAP"
					( Origin gFrontEnd )
				)
				( attribute "ROT" "0"
					( Origin gFrontEnd )
				)
				( attribute "SEC" "1"
					( Origin gFrontEnd )
				)
				( attribute "SEC_TYPE" "SM"
					( Origin gFrontEnd )
				)
				( attribute "VALUE" "MMBT3904"
					( Origin gFrontEnd )
				)
				( attribute "VER" "1"
					( Origin gFrontEnd )
				)
				( attribute "XY" "(-525,1700)"
					( Origin gFrontEnd )
				)
				( attribute "CHIPS_PART_NAME" "NPN"
					( Origin gPackager )
				)
				( attribute "CDS_PART_NAME" "NPN_SM-MMBT3904,IC,C52245-001"
					( Origin gPackager )
				)
				( objectStatus "Q1D3" )
			)
			( gate "@baseboard_fab2_lib.baseboard_fab2(sch_1):page199_i65"
				( attribute "BOM_COST" "MIO_USB"
					( Origin gFrontEnd )
				)
				( attribute "CDS_LIB" "mstr_discrete"
					( Origin gPackager )
				)
				( attribute "CDS_LOCATION" "R1D36"
					( Origin gPackager )
				)
				( attribute "CDS_SEC" "1"
					( Origin gPackager )
				)
				( attribute "LOCATION" "R1D36"
					( Origin gFrontEnd )
				)
				( attribute "MATERIAL" "CHIP"
					( Origin gFrontEnd )
				)
				( attribute "PACK_TYPE" "0402"
					( Origin gFrontEnd )
				)
				( attribute "PART_NUMBER" "G21796-026"
					( Origin gFrontEnd )
				)
				( attribute "PHYS_PAGE" "199"
					( Origin gFrontEnd )
				)
				( attribute "ROOM" "HOT_SWAP"
					( Origin gFrontEnd )
				)
				( attribute "ROT" "0"
					( Origin gFrontEnd )
				)
				( attribute "SEC" "1"
					( Origin gFrontEnd )
				)
				( attribute "SEC_TYPE" "0402"
					( Origin gFrontEnd )
				)
				( attribute "TOLERANCE" "1%"
					( Origin gFrontEnd )
				)
				( attribute "VALUE" "1.00K"
					( Origin gFrontEnd )
				)
				( attribute "VER" "2"
					( Origin gFrontEnd )
				)
				( attribute "WATTAGE" "1/16W"
					( Origin gFrontEnd )
				)
				( attribute "XY" "(-400,3025)"
					( Origin gFrontEnd )
				)
				( attribute "CHIPS_PART_NAME" "RES"
					( Origin gPackager )
				)
				( attribute "CDS_PART_NAME" "RES_0402-1.00K,1%,1/16W,CHIP,GA"
					( Origin gPackager )
				)
				( objectStatus "R1D36" )
			)
			( gate "@baseboard_fab2_lib.baseboard_fab2(sch_1):page199_i67"
				( attribute "CDS_LIB" "dev_discrete"
					( Origin gPackager )
				)
				( attribute "CDS_LOCATION" "C9P12"
					( Origin gPackager )
				)
				( attribute "CDS_SEC" "1"
					( Origin gPackager )
				)
				( attribute "LOCATION" "C9P12"
					( Origin gFrontEnd )
				)
				( attribute "MATERIAL" "EMPTY"
					( Origin gFrontEnd )
				)
				( attribute "PACK_TYPE" "0402V"
					( Origin gFrontEnd )
				)
				( attribute "PART_NUMBER" "A36096-030"
					( Origin gFrontEnd )
				)
				( attribute "PHYS_PAGE" "199"
					( Origin gFrontEnd )
				)
				( attribute "ROOM" "HOT_SWAP"
					( Origin gFrontEnd )
				)
				( attribute "ROT" "0"
					( Origin gFrontEnd )
				)
				( attribute "SEC" "1"
					( Origin gFrontEnd )
				)
				( attribute "SEC_TYPE" "0402V"
					( Origin gFrontEnd )
				)
				( attribute "TOLERANCE" "10%"
					( Origin gFrontEnd )
				)
				( attribute "VALUE" "0.1UF"
					( Origin gFrontEnd )
				)
				( attribute "VER" "1"
					( Origin gFrontEnd )
				)
				( attribute "VOLTAGE" "16V"
					( Units "uVoltage" "V" 1.000000)
					( Origin gFrontEnd )
				)
				( attribute "XY" "(-400,2625)"
					( Origin gFrontEnd )
				)
				( attribute "CHIPS_PART_NAME" "CAP_A"
					( Origin gPackager )
				)
				( attribute "CDS_PART_NAME" "CAP_A_0402V-0.1UF,16V,10%,EMPTA"
					( Origin gPackager )
				)
				( objectStatus "C9P12" )
			)
			( gate "@baseboard_fab2_lib.baseboard_fab2(sch_1):page199_i82"
				( attribute "CDS_LIB" "mstr_discrete"
					( Origin gPackager )
				)
				( attribute "CDS_LOCATION" "Q1D1"
					( Origin gPackager )
				)
				( attribute "CDS_SEC" "2"
					( Origin gPackager )
				)
				( attribute "LOCATION" "Q1D1"
					( Origin gFrontEnd )
				)
				( attribute "MATERIAL" "FET"
					( Origin gFrontEnd )
				)
				( attribute "PACK_TYPE" "SMLF"
					( Origin gFrontEnd )
				)
				( attribute "PART_NUMBER" "D24280-001"
					( Origin gFrontEnd )
				)
				( attribute "PHYS_PAGE" "199"
					( Origin gFrontEnd )
				)
				( attribute "ROOM" "HOT_SWAP"
					( Origin gFrontEnd )
				)
				( attribute "ROT" "0"
					( Origin gFrontEnd )
				)
				( attribute "SEC" "2"
					( Origin gFrontEnd )
				)
				( attribute "SEC_TYPE" "SMLF"
					( Origin gFrontEnd )
				)
				( attribute "VALUE" "2N7002DW"
					( Origin gFrontEnd )
				)
				( attribute "VER" "5"
					( Origin gFrontEnd )
				)
				( attribute "XY" "(-6600,400)"
					( Origin gFrontEnd )
				)
				( attribute "CHIPS_PART_NAME" "FET_N_DUAL"
					( Origin gPackager )
				)
				( attribute "CDS_PART_NAME" "FET_N_DUAL_SMLF-2N7002DW,FET,DA"
					( Origin gPackager )
				)
				( objectStatus "Q1D1" )
			)
			( gate "@baseboard_fab2_lib.baseboard_fab2(sch_1):page199_i84"
				( attribute "CDS_LIB" "mstr_discrete"
					( Origin gPackager )
				)
				( attribute "CDS_LOCATION" "R1D13"
					( Origin gPackager )
				)
				( attribute "CDS_SEC" "1"
					( Origin gPackager )
				)
				( attribute "LOCATION" "R1D13"
					( Origin gFrontEnd )
				)
				( attribute "MATERIAL" "CHIP"
					( Origin gFrontEnd )
				)
				( attribute "NO_XNET_CONNECTION" "1"
					( Origin gFrontEnd )
				)
				( attribute "PACK_TYPE" "0402"
					( Origin gFrontEnd )
				)
				( attribute "PART_NUMBER" "G21796-058"
					( Origin gFrontEnd )
				)
				( attribute "PHYS_PAGE" "199"
					( Origin gFrontEnd )
				)
				( attribute "ROOM" "HOT_SWAP"
					( Origin gFrontEnd )
				)
				( attribute "ROT" "1"
					( Origin gFrontEnd )
				)
				( attribute "SEC" "1"
					( Origin gFrontEnd )
				)
				( attribute "SEC_TYPE" "0402"
					( Origin gFrontEnd )
				)
				( attribute "TOLERANCE" "1%"
					( Origin gFrontEnd )
				)
				( attribute "VALUE" "90.9K"
					( Origin gFrontEnd )
				)
				( attribute "VER" "1"
					( Origin gFrontEnd )
				)
				( attribute "WATTAGE" "1/16W"
					( Origin gFrontEnd )
				)
				( attribute "XY" "(-6600,975)"
					( Origin gFrontEnd )
				)
				( attribute "CHIPS_PART_NAME" "RES"
					( Origin gPackager )
				)
				( attribute "CDS_PART_NAME" "RES_0402-90.9K,1%,1/16W,CHIP,GA"
					( Origin gPackager )
				)
				( attribute "BOM_DS" "64.68125.6DL"
					( Origin gFrontEnd )
				)
				( objectStatus "R1D13" )
			)
			( gate "@baseboard_fab2_lib.baseboard_fab2(sch_1):page199_i85"
				( attribute "CDS_LIB" "mstr_discrete"
					( Origin gPackager )
				)
				( attribute "CDS_LOCATION" "R1D16"
					( Origin gPackager )
				)
				( attribute "CDS_SEC" "1"
					( Origin gPackager )
				)
				( attribute "LOCATION" "R1D16"
					( Origin gFrontEnd )
				)
				( attribute "MATERIAL" "CHIP"
					( Origin gFrontEnd )
				)
				( attribute "NO_XNET_CONNECTION" "1"
					( Origin gFrontEnd )
				)
				( attribute "PACK_TYPE" "0402"
					( Origin gFrontEnd )
				)
				( attribute "PART_NUMBER" "G21796-007"
					( Origin gFrontEnd )
				)
				( attribute "PHYS_PAGE" "199"
					( Origin gFrontEnd )
				)
				( attribute "ROOM" "HOT_SWAP"
					( Origin gFrontEnd )
				)
				( attribute "ROT" "0"
					( Origin gFrontEnd )
				)
				( attribute "SEC" "1"
					( Origin gFrontEnd )
				)
				( attribute "SEC_TYPE" "0402"
					( Origin gFrontEnd )
				)
				( attribute "TOLERANCE" "1%"
					( Origin gFrontEnd )
				)
				( attribute "VALUE" "69.8K"
					( Origin gFrontEnd )
				)
				( attribute "VER" "2"
					( Origin gFrontEnd )
				)
				( attribute "WATTAGE" "1/16W"
					( Origin gFrontEnd )
				)
				( attribute "XY" "(-5875,875)"
					( Origin gFrontEnd )
				)
				( attribute "CHIPS_PART_NAME" "RES"
					( Origin gPackager )
				)
				( attribute "CDS_PART_NAME" "RES_0402-69.8K,1%,1/16W,CHIP,GA"
					( Origin gPackager )
				)
				( attribute "BOM_DS" "64.57625.6DL"
					( Origin gFrontEnd )
				)
				( objectStatus "R1D16" )
			)
			( gate "@baseboard_fab2_lib.baseboard_fab2(sch_1):page199_i86"
				( attribute "CDS_LIB" "mstr_discrete"
					( Origin gPackager )
				)
				( attribute "CDS_LOCATION" "Q1D1"
					( Origin gPackager )
				)
				( attribute "CDS_SEC" "1"
					( Origin gPackager )
				)
				( attribute "LOCATION" "Q1D1"
					( Origin gFrontEnd )
				)
				( attribute "MATERIAL" "FET"
					( Origin gFrontEnd )
				)
				( attribute "PACK_TYPE" "SMLF"
					( Origin gFrontEnd )
				)
				( attribute "PART_NUMBER" "D24280-001"
					( Origin gFrontEnd )
				)
				( attribute "PHYS_PAGE" "199"
					( Origin gFrontEnd )
				)
				( attribute "ROOM" "HOT_SWAP"
					( Origin gFrontEnd )
				)
				( attribute "ROT" "0"
					( Origin gFrontEnd )
				)
				( attribute "SEC" "1"
					( Origin gFrontEnd )
				)
				( attribute "SEC_TYPE" "SMLF"
					( Origin gFrontEnd )
				)
				( attribute "VALUE" "2N7002DW"
					( Origin gFrontEnd )
				)
				( attribute "VER" "5"
					( Origin gFrontEnd )
				)
				( attribute "XY" "(-5875,275)"
					( Origin gFrontEnd )
				)
				( attribute "CHIPS_PART_NAME" "FET_N_DUAL"
					( Origin gPackager )
				)
				( attribute "CDS_PART_NAME" "FET_N_DUAL_SMLF-2N7002DW,FET,DA"
					( Origin gPackager )
				)
				( objectStatus "Q1D1" )
			)
			( gate "@baseboard_fab2_lib.baseboard_fab2(sch_1):page199_i88"
				( attribute "CDS_LIB" "mstr_discrete"
					( Origin gPackager )
				)
				( attribute "CDS_LOCATION" "R1D11"
					( Origin gPackager )
				)
				( attribute "LOCATION" "R1D11"
					( Origin gFrontEnd )
				)
				( attribute "MATERIAL" "CHIP"
					( Origin gFrontEnd )
				)
				( attribute "PACK_TYPE" "0402"
					( Origin gFrontEnd )
				)
				( attribute "PART_NUMBER" "G21796-010"
					( Origin gFrontEnd )
				)
				( attribute "PHYS_PAGE" "199"
					( Origin gFrontEnd )
				)
				( attribute "ROOM" "HOT_SWAP"
					( Origin gFrontEnd )
				)
				( attribute "ROT" "0"
					( Origin gFrontEnd )
				)
				( attribute "SEC" "1"
					( Origin gFrontEnd )
				)
				( attribute "SEC_TYPE" "0402"
					( Origin gFrontEnd )
				)
				( attribute "TOLERANCE" "1%"
					( Origin gFrontEnd )
				)
				( attribute "VALUE" "100.0K"
					( Origin gFrontEnd )
				)
				( attribute "VER" "2"
					( Origin gFrontEnd )
				)
				( attribute "WATTAGE" "1/16W"
					( Origin gFrontEnd )
				)
				( attribute "XY" "(-6300,-50)"
					( Origin gFrontEnd )
				)
				( attribute "CHIPS_PART_NAME" "RES"
					( Origin gPackager )
				)
				( attribute "CDS_PART_NAME" "RES_0402-100.0K,1%,1/16W,CHIP,A"
					( Origin gPackager )
				)
				( attribute "CDS_SEC" "1"
					( Origin gPackager )
				)
				( objectStatus "R1D11" )
			)
			( gate "@baseboard_fab2_lib.baseboard_fab2(sch_1):page199_i92"
				( attribute "CDS_LIB" "mstr_discrete"
					( Origin gPackager )
				)
				( attribute "CDS_LOCATION" "R1D15"
					( Origin gPackager )
				)
				( attribute "CDS_SEC" "1"
					( Origin gPackager )
				)
				( attribute "LOCATION" "R1D15"
					( Origin gFrontEnd )
				)
				( attribute "MATERIAL" "CHIP"
					( Origin gFrontEnd )
				)
				( attribute "PACK_TYPE" "0402"
					( Origin gFrontEnd )
				)
				( attribute "PART_NUMBER" "G21796-010"
					( Origin gFrontEnd )
				)
				( attribute "PHYS_PAGE" "199"
					( Origin gFrontEnd )
				)
				( attribute "ROOM" "HOT_SWAP"
					( Origin gFrontEnd )
				)
				( attribute "ROT" "0"
					( Origin gFrontEnd )
				)
				( attribute "SEC" "1"
					( Origin gFrontEnd )
				)
				( attribute "SEC_TYPE" "0402"
					( Origin gFrontEnd )
				)
				( attribute "TOLERANCE" "1%"
					( Origin gFrontEnd )
				)
				( attribute "VALUE" "100.0K"
					( Origin gFrontEnd )
				)
				( attribute "VER" "2"
					( Origin gFrontEnd )
				)
				( attribute "WATTAGE" "1/16W"
					( Origin gFrontEnd )
				)
				( attribute "XY" "(-7300,750)"
					( Origin gFrontEnd )
				)
				( attribute "CHIPS_PART_NAME" "RES"
					( Origin gPackager )
				)
				( attribute "CDS_PART_NAME" "RES_0402-100.0K,1%,1/16W,CHIP,A"
					( Origin gPackager )
				)
				( objectStatus "R1D15" )
			)
			( gate "@baseboard_fab2_lib.baseboard_fab2(sch_1):page199_i99"
				( attribute "CDS_LIB" "mstr_discrete"
					( Origin gPackager )
				)
				( attribute "CDS_LOCATION" "VR1D1"
					( Origin gPackager )
				)
				( attribute "CDS_SEC" "1"
					( Origin gPackager )
				)
				( attribute "LOCATION" "VR1D1"
					( Origin gFrontEnd )
				)
				( attribute "MATERIAL" "IC"
					( Origin gFrontEnd )
				)
				( attribute "PACK_TYPE" "SM"
					( Origin gFrontEnd )
				)
				( attribute "PART_NUMBER" "H69095-001"
					( Origin gFrontEnd )
				)
				( attribute "PHYS_PAGE" "199"
					( Origin gFrontEnd )
				)
				( attribute "ROT" "0"
					( Origin gFrontEnd )
				)
				( attribute "SEC" "1"
					( Origin gFrontEnd )
				)
				( attribute "SEC_TYPE" "SM"
					( Origin gFrontEnd )
				)
				( attribute "VALUE" "13V"
					( Origin gFrontEnd )
				)
				( attribute "VER" "4"
					( Origin gFrontEnd )
				)
				( attribute "XY" "(-5100,3875)"
					( Origin gFrontEnd )
				)
				( attribute "CHIPS_PART_NAME" "ZENER"
					( Origin gPackager )
				)
				( attribute "CDS_PART_NAME" "ZENER_SM-13V,IC,H69095-001"
					( Origin gPackager )
				)
				( attribute "NEW_VALUE" "14V"
					( Origin gFrontEnd )
				)
				( attribute "NEW_PN" "083.01514.00AD"
					( Origin gFrontEnd )
				)
				( objectStatus "VR1D1" )
			)
			( gate "@baseboard_fab2_lib.baseboard_fab2(sch_1):page199_i100"
				( attribute "CDS_LIB" "mstr_discrete"
					( Origin gPackager )
				)
				( attribute "CDS_LOCATION" "R1D40"
					( Origin gPackager )
				)
				( attribute "CDS_SEC" "1"
					( Origin gPackager )
				)
				( attribute "LOCATION" "R1D40"
					( Origin gFrontEnd )
				)
				( attribute "MATERIAL" "CHIP"
					( Origin gFrontEnd )
				)
				( attribute "PACK_TYPE" "0402"
					( Origin gFrontEnd )
				)
				( attribute "PART_NUMBER" "G21796-133"
					( Origin gFrontEnd )
				)
				( attribute "PHYS_PAGE" "199"
					( Origin gFrontEnd )
				)
				( attribute "ROOM" "HOT_SWAP"
					( Origin gFrontEnd )
				)
				( attribute "ROT" "0"
					( Origin gFrontEnd )
				)
				( attribute "SEC" "1"
					( Origin gFrontEnd )
				)
				( attribute "SEC_TYPE" "0402"
					( Origin gFrontEnd )
				)
				( attribute "TOLERANCE" "1%"
					( Origin gFrontEnd )
				)
				( attribute "VALUE" "40.2K"
					( Origin gFrontEnd )
				)
				( attribute "VER" "2"
					( Origin gFrontEnd )
				)
				( attribute "WATTAGE" "1/16W"
					( Origin gFrontEnd )
				)
				( attribute "XY" "(-5300,800)"
					( Origin gFrontEnd )
				)
				( attribute "CHIPS_PART_NAME" "RES"
					( Origin gPackager )
				)
				( attribute "CDS_PART_NAME" "RES_0402-40.2K,1%,1/16W,CHIP,GA"
					( Origin gPackager )
				)
				( objectStatus "R1D40" )
			)
			( gate "@baseboard_fab2_lib.baseboard_fab2(sch_1):page199_i102"
				( attribute "CDS_LIB" "mstr_discrete"
					( Origin gPackager )
				)
				( attribute "CDS_LOCATION" "R1D34"
					( Origin gPackager )
				)
				( attribute "CDS_SEC" "1"
					( Origin gPackager )
				)
				( attribute "LOCATION" "R1D34"
					( Origin gFrontEnd )
				)
				( attribute "MATERIAL" "CHIP"
					( Origin gFrontEnd )
				)
				( attribute "PACK_TYPE" "0402"
					( Origin gFrontEnd )
				)
				( attribute "PART_NUMBER" "G21796-317"
					( Origin gFrontEnd )
				)
				( attribute "PHYS_PAGE" "199"
					( Origin gFrontEnd )
				)
				( attribute "ROOM" "HOT_SWAP"
					( Origin gFrontEnd )
				)
				( attribute "ROT" "0"
					( Origin gFrontEnd )
				)
				( attribute "SEC" "1"
					( Origin gFrontEnd )
				)
				( attribute "SEC_TYPE" "0402"
					( Origin gFrontEnd )
				)
				( attribute "TOLERANCE" "1.0%"
					( Origin gFrontEnd )
				)
				( attribute "VALUE" "16K"
					( Origin gFrontEnd )
				)
				( attribute "VER" "2"
					( Origin gFrontEnd )
				)
				( attribute "WATTAGE" "1/16W"
					( Origin gFrontEnd )
				)
				( attribute "XY" "(-5600,750)"
					( Origin gFrontEnd )
				)
				( attribute "CHIPS_PART_NAME" "RES"
					( Origin gPackager )
				)
				( attribute "CDS_PART_NAME" "RES_0402-16K,1.0%,1/16W,CHIP,GA"
					( Origin gPackager )
				)
				( objectStatus "R1D34" )
			)
			( gate "@baseboard_fab2_lib.baseboard_fab2(sch_1):page199_i105"
				( attribute "CDS_LIB" "dev_discrete"
					( Origin gPackager )
				)
				( attribute "CDS_LOCATION" "C9P15"
					( Origin gPackager )
				)
				( attribute "LOCATION" "C9P15"
					( Origin gFrontEnd )
				)
				( attribute "MATERIAL" "X7R"
					( Origin gFrontEnd )
				)
				( attribute "PACK_TYPE" "0402V"
					( Origin gFrontEnd )
				)
				( attribute "PART_NUMBER" "A36096-030"
					( Origin gFrontEnd )
				)
				( attribute "PHYS_PAGE" "199"
					( Origin gFrontEnd )
				)
				( attribute "ROOM" "HOT_SWAP"
					( Origin gFrontEnd )
				)
				( attribute "ROT" "2"
					( Origin gFrontEnd )
				)
				( attribute "SEC" "1"
					( Origin gFrontEnd )
				)
				( attribute "TOLERANCE" "10%"
					( Origin gFrontEnd )
				)
				( attribute "VALUE" "0.1UF"
					( Origin gFrontEnd )
				)
				( attribute "VER" "1"
					( Origin gFrontEnd )
				)
				( attribute "VOLTAGE" "16V"
					( Units "uVoltage" "V" 1.000000)
					( Origin gFrontEnd )
				)
				( attribute "XY" "(-6150,850)"
					( Origin gFrontEnd )
				)
				( attribute "CHIPS_PART_NAME" "CAP_A"
					( Origin gPackager )
				)
				( attribute "CDS_PART_NAME" "CAP_A_0402V-0.1UF,16V,10%,X7R,A"
					( Origin gPackager )
				)
				( attribute "SEC_TYPE" "0402V"
					( Origin gFrontEnd )
				)
				( attribute "CDS_SEC" "1"
					( Origin gPackager )
				)
				( objectStatus "C9P15" )
			)
			( gate "@baseboard_fab2_lib.baseboard_fab2(sch_1):page199_i107"
				( attribute "CDS_LIB" "dev_discrete"
					( Origin gPackager )
				)
				( attribute "CDS_LOCATION" "C1D26"
					( Origin gPackager )
				)
				( attribute "CDS_SEC" "1"
					( Origin gPackager )
				)
				( attribute "LOCATION" "C1D26"
					( Origin gFrontEnd )
				)
				( attribute "MATERIAL" "X7R"
					( Origin gFrontEnd )
				)
				( attribute "PACK_TYPE" "0402V"
					( Origin gFrontEnd )
				)
				( attribute "PART_NUMBER" "A36096-030"
					( Origin gFrontEnd )
				)
				( attribute "PHYS_PAGE" "199"
					( Origin gFrontEnd )
				)
				( attribute "ROOM" "HOT_SWAP"
					( Origin gFrontEnd )
				)
				( attribute "ROT" "2"
					( Origin gFrontEnd )
				)
				( attribute "SEC" "1"
					( Origin gFrontEnd )
				)
				( attribute "SEC_TYPE" "0402V"
					( Origin gFrontEnd )
				)
				( attribute "TOLERANCE" "10%"
					( Origin gFrontEnd )
				)
				( attribute "VALUE" "0.1UF"
					( Origin gFrontEnd )
				)
				( attribute "VER" "1"
					( Origin gFrontEnd )
				)
				( attribute "VOLTAGE" "16V"
					( Units "uVoltage" "V" 1.000000)
					( Origin gFrontEnd )
				)
				( attribute "XY" "(-6075,3575)"
					( Origin gFrontEnd )
				)
				( attribute "CHIPS_PART_NAME" "CAP_A"
					( Origin gPackager )
				)
				( attribute "CDS_PART_NAME" "CAP_A_0402V-0.1UF,16V,10%,X7R,A"
					( Origin gPackager )
				)
				( objectStatus "C1D26" )
			)
			( gate "@baseboard_fab2_lib.baseboard_fab2(sch_1):page199_i108"
				( attribute "CDS_LIB" "mstr_discrete"
					( Origin gPackager )
				)
				( attribute "CDS_LOCATION" "R1D33"
					( Origin gPackager )
				)
				( attribute "CDS_SEC" "1"
					( Origin gPackager )
				)
				( attribute "LOCATION" "R1D33"
					( Origin gFrontEnd )
				)
				( attribute "MATERIAL" "CHIP"
					( Origin gFrontEnd )
				)
				( attribute "PACK_TYPE" "0402"
					( Origin gFrontEnd )
				)
				( attribute "PART_NUMBER" "G21796-074"
					( Origin gFrontEnd )
				)
				( attribute "PHYS_PAGE" "199"
					( Origin gFrontEnd )
				)
				( attribute "ROT" "0"
					( Origin gFrontEnd )
				)
				( attribute "SEC" "1"
					( Origin gFrontEnd )
				)
				( attribute "SEC_TYPE" "0402"
					( Origin gFrontEnd )
				)
				( attribute "TOLERANCE" "1%"
					( Origin gFrontEnd )
				)
				( attribute "VALUE" "33.2"
					( Origin gFrontEnd )
				)
				( attribute "VER" "1"
					( Origin gFrontEnd )
				)
				( attribute "WATTAGE" "1/16W"
					( Origin gFrontEnd )
				)
				( attribute "XY" "(-2050,925)"
					( Origin gFrontEnd )
				)
				( attribute "CHIPS_PART_NAME" "RES"
					( Origin gPackager )
				)
				( attribute "CDS_PART_NAME" "RES_0402-33.2,1%,1/16W,CHIP,G2A"
					( Origin gPackager )
				)
				( objectStatus "R1D33" )
			)
			( gate "@baseboard_fab2_lib.baseboard_fab2(sch_1):page199_i109"
				( attribute "CDS_LIB" "mstr_discrete"
					( Origin gPackager )
				)
				( attribute "CDS_LOCATION" "R1D26"
					( Origin gPackager )
				)
				( attribute "CDS_SEC" "1"
					( Origin gPackager )
				)
				( attribute "LOCATION" "R1D26"
					( Origin gFrontEnd )
				)
				( attribute "MATERIAL" "CHIP"
					( Origin gFrontEnd )
				)
				( attribute "PACK_TYPE" "0402"
					( Origin gFrontEnd )
				)
				( attribute "PART_NUMBER" "G21796-074"
					( Origin gFrontEnd )
				)
				( attribute "PHYS_PAGE" "199"
					( Origin gFrontEnd )
				)
				( attribute "ROT" "0"
					( Origin gFrontEnd )
				)
				( attribute "SEC" "1"
					( Origin gFrontEnd )
				)
				( attribute "SEC_TYPE" "0402"
					( Origin gFrontEnd )
				)
				( attribute "TOLERANCE" "1%"
					( Origin gFrontEnd )
				)
				( attribute "VALUE" "33.2"
					( Origin gFrontEnd )
				)
				( attribute "VER" "1"
					( Origin gFrontEnd )
				)
				( attribute "WATTAGE" "1/16W"
					( Origin gFrontEnd )
				)
				( attribute "XY" "(-1700,3950)"
					( Origin gFrontEnd )
				)
				( attribute "CHIPS_PART_NAME" "RES"
					( Origin gPackager )
				)
				( attribute "CDS_PART_NAME" "RES_0402-33.2,1%,1/16W,CHIP,G2A"
					( Origin gPackager )
				)
				( objectStatus "R1D26" )
			)
			( gate "@baseboard_fab2_lib.baseboard_fab2(sch_1):page199_i110"
				( attribute "CDS_LIB" "mstr_discrete"
					( Origin gPackager )
				)
				( attribute "CDS_LOCATION" "R1D30"
					( Origin gPackager )
				)
				( attribute "CDS_SEC" "1"
					( Origin gPackager )
				)
				( attribute "LOCATION" "R1D30"
					( Origin gFrontEnd )
				)
				( attribute "MATERIAL" "CHIP"
					( Origin gFrontEnd )
				)
				( attribute "PACK_TYPE" "0402"
					( Origin gFrontEnd )
				)
				( attribute "PART_NUMBER" "G21796-074"
					( Origin gFrontEnd )
				)
				( attribute "PHYS_PAGE" "199"
					( Origin gFrontEnd )
				)
				( attribute "ROT" "0"
					( Origin gFrontEnd )
				)
				( attribute "SEC" "1"
					( Origin gFrontEnd )
				)
				( attribute "SEC_TYPE" "0402"
					( Origin gFrontEnd )
				)
				( attribute "TOLERANCE" "1%"
					( Origin gFrontEnd )
				)
				( attribute "VALUE" "33.2"
					( Origin gFrontEnd )
				)
				( attribute "VER" "1"
					( Origin gFrontEnd )
				)
				( attribute "WATTAGE" "1/16W"
					( Origin gFrontEnd )
				)
				( attribute "XY" "(-2050,1375)"
					( Origin gFrontEnd )
				)
				( attribute "CHIPS_PART_NAME" "RES"
					( Origin gPackager )
				)
				( attribute "CDS_PART_NAME" "RES_0402-33.2,1%,1/16W,CHIP,G2A"
					( Origin gPackager )
				)
				( objectStatus "R1D30" )
			)
			( gate "@baseboard_fab2_lib.baseboard_fab2(sch_1):page199_i119"
				( attribute "CDS_LIB" "mstr_discrete"
					( Origin gPackager )
				)
				( attribute "CDS_LOCATION" "C1D19"
					( Origin gPackager )
				)
				( attribute "CDS_SEC" "1"
					( Origin gPackager )
				)
				( attribute "LOCATION" "C1D19"
					( Origin gFrontEnd )
				)
				( attribute "MATERIAL" "X6S"
					( Origin gFrontEnd )
				)
				( attribute "PACK_TYPE" "0402"
					( Origin gFrontEnd )
				)
				( attribute "PART_NUMBER" "D97712-011"
					( Origin gFrontEnd )
				)
				( attribute "PHYS_PAGE" "199"
					( Origin gFrontEnd )
				)
				( attribute "ROOM" "HOT_SWAP"
					( Origin gFrontEnd )
				)
				( attribute "ROT" "0"
					( Origin gFrontEnd )
				)
				( attribute "SEC" "1"
					( Origin gFrontEnd )
				)
				( attribute "SEC_TYPE" "0402"
					( Origin gFrontEnd )
				)
				( attribute "TOLERANCE" "10%"
					( Origin gFrontEnd )
				)
				( attribute "VALUE" "1.0UF"
					( Origin gFrontEnd )
				)
				( attribute "VER" "1"
					( Origin gFrontEnd )
				)
				( attribute "VOLTAGE" "16V"
					( Units "uVoltage" "V" 1.000000)
					( Origin gFrontEnd )
				)
				( attribute "XY" "(-5650,2000)"
					( Origin gFrontEnd )
				)
				( attribute "CHIPS_PART_NAME" "CAP"
					( Origin gPackager )
				)
				( attribute "CDS_PART_NAME" "CAP_0402-1.0UF,16V,10%,X6S,D97A"
					( Origin gPackager )
				)
				( objectStatus "C1D19" )
			)
			( gate "@baseboard_fab2_lib.baseboard_fab2(sch_1):page199_i121"
				( attribute "CDS_LIB" "dev_discrete"
					( Origin gPackager )
				)
				( attribute "CDS_LOCATION" "C1D21"
					( Origin gPackager )
				)
				( attribute "CDS_SEC" "1"
					( Origin gPackager )
				)
				( attribute "LOCATION" "C1D21"
					( Origin gFrontEnd )
				)
				( attribute "MATERIAL" "X7R"
					( Origin gFrontEnd )
				)
				( attribute "PACK_TYPE" "0402V"
					( Origin gFrontEnd )
				)
				( attribute "PART_NUMBER" "A36096-030"
					( Origin gFrontEnd )
				)
				( attribute "PHYS_PAGE" "199"
					( Origin gFrontEnd )
				)
				( attribute "ROOM" "HOT_SWAP"
					( Origin gFrontEnd )
				)
				( attribute "ROT" "2"
					( Origin gFrontEnd )
				)
				( attribute "SEC" "1"
					( Origin gFrontEnd )
				)
				( attribute "SEC_TYPE" "0402V"
					( Origin gFrontEnd )
				)
				( attribute "TOLERANCE" "10%"
					( Origin gFrontEnd )
				)
				( attribute "VALUE" "0.1UF"
					( Origin gFrontEnd )
				)
				( attribute "VER" "1"
					( Origin gFrontEnd )
				)
				( attribute "VOLTAGE" "16V"
					( Units "uVoltage" "V" 1.000000)
					( Origin gFrontEnd )
				)
				( attribute "XY" "(-5000,425)"
					( Origin gFrontEnd )
				)
				( attribute "CHIPS_PART_NAME" "CAP_A"
					( Origin gPackager )
				)
				( attribute "CDS_PART_NAME" "CAP_A_0402V-0.1UF,16V,10%,X7R,A"
					( Origin gPackager )
				)
				( objectStatus "C1D21" )
			)
			( gate "@baseboard_fab2_lib.baseboard_fab2(sch_1):page200_i36"
				( attribute "CDS_LIB" "dev_discrete"
					( Origin gPackager )
				)
				( attribute "CDS_LOCATION" "C9P17"
					( Origin gPackager )
				)
				( attribute "CDS_SEC" "1"
					( Origin gPackager )
				)
				( attribute "LOCATION" "C9P17"
					( Origin gFrontEnd )
				)
				( attribute "MATERIAL" "EMPTY"
					( Origin gFrontEnd )
				)
				( attribute "PACK_TYPE" "0402V"
					( Origin gFrontEnd )
				)
				( attribute "PART_NUMBER" "A36096-030"
					( Origin gFrontEnd )
				)
				( attribute "PHYS_PAGE" "200"
					( Origin gFrontEnd )
				)
				( attribute "ROOM" "HOT_SWAP"
					( Origin gFrontEnd )
				)
				( attribute "ROT" "0"
					( Origin gFrontEnd )
				)
				( attribute "SEC" "1"
					( Origin gFrontEnd )
				)
				( attribute "SEC_TYPE" "0402V"
					( Origin gFrontEnd )
				)
				( attribute "TOLERANCE" "10%"
					( Origin gFrontEnd )
				)
				( attribute "VALUE" "0.1UF"
					( Origin gFrontEnd )
				)
				( attribute "VER" "1"
					( Origin gFrontEnd )
				)
				( attribute "VOLTAGE" "16V"
					( Units "uVoltage" "V" 1.000000)
					( Origin gFrontEnd )
				)
				( attribute "XY" "(-1025,3425)"
					( Origin gFrontEnd )
				)
				( attribute "CHIPS_PART_NAME" "CAP_A"
					( Origin gPackager )
				)
				( attribute "CDS_PART_NAME" "CAP_A_0402V-0.1UF,16V,10%,EMPTA"
					( Origin gPackager )
				)
				( objectStatus "C9P17" )
			)
			( gate "@baseboard_fab2_lib.baseboard_fab2(sch_1):page200_i40"
				( attribute "CDS_LIB" "dev_discrete"
					( Origin gPackager )
				)
				( attribute "CDS_LOCATION" "C9P16"
					( Origin gPackager )
				)
				( attribute "CDS_SEC" "1"
					( Origin gPackager )
				)
				( attribute "LOCATION" "C9P16"
					( Origin gFrontEnd )
				)
				( attribute "MATERIAL" "EMPTY"
					( Origin gFrontEnd )
				)
				( attribute "PACK_TYPE" "0402V"
					( Origin gFrontEnd )
				)
				( attribute "PART_NUMBER" "A36096-030"
					( Origin gFrontEnd )
				)
				( attribute "PHYS_PAGE" "200"
					( Origin gFrontEnd )
				)
				( attribute "ROOM" "HOT_SWAP"
					( Origin gFrontEnd )
				)
				( attribute "ROT" "0"
					( Origin gFrontEnd )
				)
				( attribute "SEC" "1"
					( Origin gPackager )
				)
				( attribute "TOLERANCE" "10%"
					( Origin gFrontEnd )
				)
				( attribute "VALUE" "0.1UF"
					( Origin gFrontEnd )
				)
				( attribute "VER" "1"
					( Origin gFrontEnd )
				)
				( attribute "VOLTAGE" "16V"
					( Units "uVoltage" "V" 1.000000)
					( Origin gFrontEnd )
				)
				( attribute "XY" "(-675,3000)"
					( Origin gFrontEnd )
				)
				( attribute "CHIPS_PART_NAME" "CAP_A"
					( Origin gPackager )
				)
				( attribute "CDS_PART_NAME" "CAP_A_0402V-0.1UF,16V,10%,EMPTA"
					( Origin gPackager )
				)
				( objectStatus "C9P16" )
			)
			( gate "@baseboard_fab2_lib.baseboard_fab2(sch_1):page200_i42"
				( attribute "CDS_LIB" "dev_discrete"
					( Origin gPackager )
				)
				( attribute "CDS_LOCATION" "C1D22"
					( Origin gPackager )
				)
				( attribute "CDS_SEC" "1"
					( Origin gPackager )
				)
				( attribute "LOCATION" "C1D22"
					( Origin gFrontEnd )
				)
				( attribute "MATERIAL" "EMPTY"
					( Origin gFrontEnd )
				)
				( attribute "PACK_TYPE" "0402V"
					( Origin gFrontEnd )
				)
				( attribute "PART_NUMBER" "A36096-030"
					( Origin gFrontEnd )
				)
				( attribute "PHYS_PAGE" "200"
					( Origin gFrontEnd )
				)
				( attribute "ROOM" "HOT_SWAP"
					( Origin gFrontEnd )
				)
				( attribute "ROT" "0"
					( Origin gFrontEnd )
				)
				( attribute "SEC" "1"
					( Origin gPackager )
				)
				( attribute "TOLERANCE" "10%"
					( Origin gFrontEnd )
				)
				( attribute "VALUE" "0.1UF"
					( Origin gFrontEnd )
				)
				( attribute "VER" "1"
					( Origin gFrontEnd )
				)
				( attribute "VOLTAGE" "16V"
					( Units "uVoltage" "V" 1.000000)
					( Origin gFrontEnd )
				)
				( attribute "XY" "(-175,3425)"
					( Origin gFrontEnd )
				)
				( attribute "CHIPS_PART_NAME" "CAP_A"
					( Origin gPackager )
				)
				( attribute "CDS_PART_NAME" "CAP_A_0402V-0.1UF,16V,10%,EMPTA"
					( Origin gPackager )
				)
				( objectStatus "C1D22" )
			)
			( gate "@baseboard_fab2_lib.baseboard_fab2(sch_1):page200_i43"
				( attribute "CDS_LIB" "mstr_discrete"
					( Origin gPackager )
				)
				( attribute "CDS_LOCATION" "R1D45"
					( Origin gPackager )
				)
				( attribute "CDS_SEC" "1"
					( Origin gPackager )
				)
				( attribute "LOCATION" "R1D45"
					( Origin gFrontEnd )
				)
				( attribute "MATERIAL" "CHIP"
					( Origin gFrontEnd )
				)
				( attribute "PACK_TYPE" "0402"
					( Origin gFrontEnd )
				)
				( attribute "PART_NUMBER" "G21497-005"
					( Origin gFrontEnd )
				)
				( attribute "PHYS_PAGE" "200"
					( Origin gFrontEnd )
				)
				( attribute "ROOM" "HOT_SWAP"
					( Origin gFrontEnd )
				)
				( attribute "ROT" "0"
					( Origin gFrontEnd )
				)
				( attribute "SEC" "1"
					( Origin gPackager )
				)
				( attribute "TOLERANCE" "5%"
					( Origin gFrontEnd )
				)
				( attribute "VALUE" "0.0"
					( Origin gFrontEnd )
				)
				( attribute "VER" "1"
					( Origin gFrontEnd )
				)
				( attribute "WATTAGE" "1/16W"
					( Origin gFrontEnd )
				)
				( attribute "XY" "(250,3625)"
					( Origin gFrontEnd )
				)
				( attribute "CHIPS_PART_NAME" "RES"
					( Origin gPackager )
				)
				( attribute "CDS_PART_NAME" "RES_0402-0.0,5%,1/16W,CHIP,G21A"
					( Origin gPackager )
				)
				( objectStatus "R1D45" )
			)
			( gate "@baseboard_fab2_lib.baseboard_fab2(sch_1):page200_i44"
				( attribute "CDS_LIB" "mstr_discrete"
					( Origin gPackager )
				)
				( attribute "CDS_LOCATION" "R1D44"
					( Origin gPackager )
				)
				( attribute "CDS_SEC" "1"
					( Origin gPackager )
				)
				( attribute "LOCATION" "R1D44"
					( Origin gFrontEnd )
				)
				( attribute "MATERIAL" "CHIP"
					( Origin gFrontEnd )
				)
				( attribute "PACK_TYPE" "0402"
					( Origin gFrontEnd )
				)
				( attribute "PART_NUMBER" "G21497-005"
					( Origin gFrontEnd )
				)
				( attribute "PHYS_PAGE" "200"
					( Origin gFrontEnd )
				)
				( attribute "ROOM" "HOT_SWAP"
					( Origin gFrontEnd )
				)
				( attribute "ROT" "0"
					( Origin gFrontEnd )
				)
				( attribute "SEC" "1"
					( Origin gPackager )
				)
				( attribute "TOLERANCE" "5%"
					( Origin gFrontEnd )
				)
				( attribute "VALUE" "0.0"
					( Origin gFrontEnd )
				)
				( attribute "VER" "1"
					( Origin gFrontEnd )
				)
				( attribute "WATTAGE" "1/16W"
					( Origin gFrontEnd )
				)
				( attribute "XY" "(225,3150)"
					( Origin gFrontEnd )
				)
				( attribute "CHIPS_PART_NAME" "RES"
					( Origin gPackager )
				)
				( attribute "CDS_PART_NAME" "RES_0402-0.0,5%,1/16W,CHIP,G21A"
					( Origin gPackager )
				)
				( objectStatus "R1D44" )
			)
			( gate "@baseboard_fab2_lib.baseboard_fab2(sch_1):page200_i47"
				( attribute "CDS_LIB" "mstr_discrete"
					( Origin gPackager )
				)
				( attribute "CDS_LOCATION" "R9P27"
					( Origin gPackager )
				)
				( attribute "CDS_SEC" "1"
					( Origin gPackager )
				)
				( attribute "LOCATION" "R9P27"
					( Origin gFrontEnd )
				)
				( attribute "MATERIAL" "CHIP"
					( Origin gFrontEnd )
				)
				( attribute "PACK_TYPE" "0402"
					( Origin gFrontEnd )
				)
				( attribute "PART_NUMBER" "G21796-066"
					( Origin gFrontEnd )
				)
				( attribute "PHYS_PAGE" "200"
					( Origin gFrontEnd )
				)
				( attribute "ROOM" "HOT_SWAP"
					( Origin gFrontEnd )
				)
				( attribute "ROT" "0"
					( Origin gFrontEnd )
				)
				( attribute "SEC" "1"
					( Origin gPackager )
				)
				( attribute "TOLERANCE" "1%"
					( Origin gFrontEnd )
				)
				( attribute "VALUE" "10.0"
					( Origin gFrontEnd )
				)
				( attribute "VER" "2"
					( Origin gFrontEnd )
				)
				( attribute "WATTAGE" "1/16W"
					( Origin gFrontEnd )
				)
				( attribute "XY" "(875,2800)"
					( Origin gFrontEnd )
				)
				( attribute "CHIPS_PART_NAME" "RES"
					( Origin gPackager )
				)
				( attribute "CDS_PART_NAME" "RES_0402-10.0,1%,1/16W,CHIP,G2A"
					( Origin gPackager )
				)
				( objectStatus "R9P27" )
			)
			( gate "@baseboard_fab2_lib.baseboard_fab2(sch_1):page200_i48"
				( attribute "CDS_LIB" "mstr_discrete"
					( Origin gPackager )
				)
				( attribute "CDS_LOCATION" "R1D46"
					( Origin gPackager )
				)
				( attribute "CDS_SEC" "1"
					( Origin gPackager )
				)
				( attribute "LOCATION" "R1D46"
					( Origin gFrontEnd )
				)
				( attribute "MATERIAL" "CHIP"
					( Origin gFrontEnd )
				)
				( attribute "PACK_TYPE" "0402"
					( Origin gFrontEnd )
				)
				( attribute "PART_NUMBER" "G21796-066"
					( Origin gFrontEnd )
				)
				( attribute "PHYS_PAGE" "200"
					( Origin gFrontEnd )
				)
				( attribute "ROOM" "HOT_SWAP"
					( Origin gFrontEnd )
				)
				( attribute "ROT" "2"
					( Origin gFrontEnd )
				)
				( attribute "SEC" "1"
					( Origin gPackager )
				)
				( attribute "TOLERANCE" "1%"
					( Origin gFrontEnd )
				)
				( attribute "VALUE" "10.0"
					( Origin gFrontEnd )
				)
				( attribute "VER" "2"
					( Origin gFrontEnd )
				)
				( attribute "WATTAGE" "1/16W"
					( Origin gFrontEnd )
				)
				( attribute "XY" "(750,2800)"
					( Origin gFrontEnd )
				)
				( attribute "CHIPS_PART_NAME" "RES"
					( Origin gPackager )
				)
				( attribute "CDS_PART_NAME" "RES_0402-10.0,1%,1/16W,CHIP,G2A"
					( Origin gPackager )
				)
				( objectStatus "R1D46" )
			)
			( gate "@baseboard_fab2_lib.baseboard_fab2(sch_1):page200_i49"
				( attribute "CDS_LIB" "mstr_discrete"
					( Origin gPackager )
				)
				( attribute "CDS_LMAN_SYM_OUTLINE" "-50,100,50,-100"
					( Origin gPackager )
				)
				( attribute "CDS_LOCATION" "R9R1"
					( Origin gPackager )
				)
				( attribute "CDS_SEC" "1"
					( Origin gPackager )
				)
				( attribute "LOCATION" "R9R1"
					( Origin gFrontEnd )
				)
				( attribute "MATERIAL" "CHIP"
					( Origin gFrontEnd )
				)
				( attribute "PACK_TYPE" "6PAD"
					( Origin gFrontEnd )
				)
				( attribute "PART_NUMBER" "E74391-005"
					( Origin gFrontEnd )
				)
				( attribute "PHYS_PAGE" "200"
					( Origin gFrontEnd )
				)
				( attribute "ROOM" "HOT_SWAP"
					( Origin gFrontEnd )
				)
				( attribute "ROT" "0"
					( Origin gFrontEnd )
				)
				( attribute "SEC" "1"
					( Origin gFrontEnd )
				)
				( attribute "SEC_TYPE" "6PAD"
					( Origin gFrontEnd )
				)
				( attribute "TOLERANCE" "1%"
					( Origin gFrontEnd )
				)
				( attribute "VALUE" "0.001"
					( Origin gFrontEnd )
				)
				( attribute "VER" "2"
					( Origin gFrontEnd )
				)
				( attribute "WATTAGE" "3W"
					( Origin gFrontEnd )
				)
				( attribute "XY" "(1125,3200)"
					( Origin gFrontEnd )
				)
				( attribute "CHIPS_PART_NAME" "RES_PWR"
					( Origin gPackager )
				)
				( attribute "CDS_PART_NAME" "RES_PWR_6PAD-0.001,1%,3W,CHIP,A"
					( Origin gPackager )
				)
				( attribute "BOM_DS" "064.0U505.0C71"
					( Origin gFrontEnd )
				)
				( objectStatus "R9R1" )
			)
			( gate "@baseboard_fab2_lib.baseboard_fab2(sch_1):page200_i50"
				( attribute "CDS_LIB" "mstr_discrete"
					( Origin gPackager )
				)
				( attribute "CDS_LMAN_SYM_OUTLINE" "-50,100,50,-100"
					( Origin gPackager )
				)
				( attribute "CDS_LOCATION" "R1D49"
					( Origin gPackager )
				)
				( attribute "CDS_SEC" "1"
					( Origin gPackager )
				)
				( attribute "LOCATION" "R1D49"
					( Origin gFrontEnd )
				)
				( attribute "MATERIAL" "CHIP"
					( Origin gFrontEnd )
				)
				( attribute "PACK_TYPE" "6PAD"
					( Origin gFrontEnd )
				)
				( attribute "PART_NUMBER" "E74391-005"
					( Origin gFrontEnd )
				)
				( attribute "PHYS_PAGE" "200"
					( Origin gFrontEnd )
				)
				( attribute "ROOM" "HOT_SWAP"
					( Origin gFrontEnd )
				)
				( attribute "ROT" "0"
					( Origin gFrontEnd )
				)
				( attribute "SEC" "1"
					( Origin gFrontEnd )
				)
				( attribute "SEC_TYPE" "6PAD"
					( Origin gFrontEnd )
				)
				( attribute "TOLERANCE" "1%"
					( Origin gFrontEnd )
				)
				( attribute "VALUE" "0.001"
					( Origin gFrontEnd )
				)
				( attribute "VER" "2"
					( Origin gFrontEnd )
				)
				( attribute "WATTAGE" "3W"
					( Origin gFrontEnd )
				)
				( attribute "XY" "(1125,3600)"
					( Origin gFrontEnd )
				)
				( attribute "CHIPS_PART_NAME" "RES_PWR"
					( Origin gPackager )
				)
				( attribute "CDS_PART_NAME" "RES_PWR_6PAD-0.001,1%,3W,CHIP,A"
					( Origin gPackager )
				)
				( attribute "BOM_DS" "064.0U505.0C71"
					( Origin gFrontEnd )
				)
				( objectStatus "R1D49" )
			)
			( gate "@baseboard_fab2_lib.baseboard_fab2(sch_1):page200_i51"
				( attribute "CDS_LIB" "mstr_discrete"
					( Origin gPackager )
				)
				( attribute "CDS_LOCATION" "R9P26"
					( Origin gPackager )
				)
				( attribute "CDS_SEC" "1"
					( Origin gPackager )
				)
				( attribute "LOCATION" "R9P26"
					( Origin gFrontEnd )
				)
				( attribute "MATERIAL" "CHIP"
					( Origin gFrontEnd )
				)
				( attribute "PACK_TYPE" "0402"
					( Origin gFrontEnd )
				)
				( attribute "PART_NUMBER" "G21796-066"
					( Origin gFrontEnd )
				)
				( attribute "PHYS_PAGE" "200"
					( Origin gFrontEnd )
				)
				( attribute "ROOM" "HOT_SWAP"
					( Origin gFrontEnd )
				)
				( attribute "ROT" "2"
					( Origin gFrontEnd )
				)
				( attribute "SEC" "1"
					( Origin gPackager )
				)
				( attribute "TOLERANCE" "1%"
					( Origin gFrontEnd )
				)
				( attribute "VALUE" "10.0"
					( Origin gFrontEnd )
				)
				( attribute "VER" "2"
					( Origin gFrontEnd )
				)
				( attribute "WATTAGE" "1/16W"
					( Origin gFrontEnd )
				)
				( attribute "XY" "(1350,2800)"
					( Origin gFrontEnd )
				)
				( attribute "CHIPS_PART_NAME" "RES"
					( Origin gPackager )
				)
				( attribute "CDS_PART_NAME" "RES_0402-10.0,1%,1/16W,CHIP,G2A"
					( Origin gPackager )
				)
				( objectStatus "R9P26" )
			)
			( gate "@baseboard_fab2_lib.baseboard_fab2(sch_1):page200_i52"
				( attribute "CDS_LIB" "mstr_discrete"
					( Origin gPackager )
				)
				( attribute "CDS_LOCATION" "R1D47"
					( Origin gPackager )
				)
				( attribute "CDS_SEC" "1"
					( Origin gPackager )
				)
				( attribute "LOCATION" "R1D47"
					( Origin gFrontEnd )
				)
				( attribute "MATERIAL" "CHIP"
					( Origin gFrontEnd )
				)
				( attribute "PACK_TYPE" "0402"
					( Origin gFrontEnd )
				)
				( attribute "PART_NUMBER" "G21796-066"
					( Origin gFrontEnd )
				)
				( attribute "PHYS_PAGE" "200"
					( Origin gFrontEnd )
				)
				( attribute "ROOM" "HOT_SWAP"
					( Origin gFrontEnd )
				)
				( attribute "ROT" "0"
					( Origin gFrontEnd )
				)
				( attribute "SEC" "1"
					( Origin gPackager )
				)
				( attribute "TOLERANCE" "1%"
					( Origin gFrontEnd )
				)
				( attribute "VALUE" "10.0"
					( Origin gFrontEnd )
				)
				( attribute "VER" "2"
					( Origin gFrontEnd )
				)
				( attribute "WATTAGE" "1/16W"
					( Origin gFrontEnd )
				)
				( attribute "XY" "(1475,2800)"
					( Origin gFrontEnd )
				)
				( attribute "CHIPS_PART_NAME" "RES"
					( Origin gPackager )
				)
				( attribute "CDS_PART_NAME" "RES_0402-10.0,1%,1/16W,CHIP,G2A"
					( Origin gPackager )
				)
				( objectStatus "R1D47" )
			)
			( gate "@baseboard_fab2_lib.baseboard_fab2(sch_1):page200_i54"
				( attribute "CDS_LIB" "mstr_discrete"
					( Origin gPackager )
				)
				( attribute "CDS_LOCATION" "EU1E3"
					( Origin gPackager )
				)
				( attribute "CDS_SEC" "1"
					( Origin gPackager )
				)
				( attribute "LOCATION" "EU1E3"
					( Origin gFrontEnd )
				)
				( attribute "MATERIAL" "IC"
					( Origin gFrontEnd )
				)
				( attribute "PACK_TYPE" "SOT5"
					( Origin gFrontEnd )
				)
				( attribute "PART_NUMBER" "G68777-001"
					( Origin gFrontEnd )
				)
				( attribute "PHYS_PAGE" "200"
					( Origin gFrontEnd )
				)
				( attribute "ROOM" "HOT_SWAP"
					( Origin gFrontEnd )
				)
				( attribute "ROT" "1"
					( Origin gFrontEnd )
				)
				( attribute "SEC" "1"
					( Origin gFrontEnd )
				)
				( attribute "SEC_TYPE" "SOT5"
					( Origin gFrontEnd )
				)
				( attribute "VER" "1"
					( Origin gFrontEnd )
				)
				( attribute "XY" "(2275,3375)"
					( Origin gFrontEnd )
				)
				( attribute "CHIPS_PART_NAME" "MOSFETN_1D3S"
					( Origin gPackager )
				)
				( attribute "CDS_PART_NAME" "MOSFETN_1D3S_SOT5-IC,G68777-001"
					( Origin gPackager )
				)
				( objectStatus "EU1E3" )
			)
			( gate "@baseboard_fab2_lib.baseboard_fab2(sch_1):page200_i56"
				( attribute "CDS_LIB" "mstr_discrete"
					( Origin gPackager )
				)
				( attribute "CDS_LOCATION" "R1E1"
					( Origin gPackager )
				)
				( attribute "CDS_SEC" "1"
					( Origin gPackager )
				)
				( attribute "LOCATION" "R1E1"
					( Origin gFrontEnd )
				)
				( attribute "MATERIAL" "CHIP"
					( Origin gFrontEnd )
				)
				( attribute "PACK_TYPE" "0402"
					( Origin gFrontEnd )
				)
				( attribute "PART_NUMBER" "G21796-066"
					( Origin gFrontEnd )
				)
				( attribute "PHYS_PAGE" "200"
					( Origin gFrontEnd )
				)
				( attribute "ROOM" "HOT_SWAP"
					( Origin gFrontEnd )
				)
				( attribute "ROT" "0"
					( Origin gFrontEnd )
				)
				( attribute "SEC" "1"
					( Origin gFrontEnd )
				)
				( attribute "SEC_TYPE" "0402"
					( Origin gFrontEnd )
				)
				( attribute "TOLERANCE" "1%"
					( Origin gFrontEnd )
				)
				( attribute "VALUE" "10.0"
					( Origin gFrontEnd )
				)
				( attribute "VER" "1"
					( Origin gFrontEnd )
				)
				( attribute "WATTAGE" "1/16W"
					( Origin gFrontEnd )
				)
				( attribute "XY" "(2000,3075)"
					( Origin gFrontEnd )
				)
				( attribute "CHIPS_PART_NAME" "RES"
					( Origin gPackager )
				)
				( attribute "CDS_PART_NAME" "RES_0402-10.0,1%,1/16W,CHIP,G2A"
					( Origin gPackager )
				)
				( objectStatus "R1E1" )
			)
			( gate "@baseboard_fab2_lib.baseboard_fab2(sch_1):page200_i57"
				( attribute "CDS_LIB" "mstr_discrete"
					( Origin gPackager )
				)
				( attribute "CDS_LOCATION" "EU9R1"
					( Origin gPackager )
				)
				( attribute "CDS_SEC" "1"
					( Origin gPackager )
				)
				( attribute "LOCATION" "EU9R1"
					( Origin gFrontEnd )
				)
				( attribute "MATERIAL" "IC"
					( Origin gFrontEnd )
				)
				( attribute "PACK_TYPE" "SOT5"
					( Origin gFrontEnd )
				)
				( attribute "PART_NUMBER" "G68777-001"
					( Origin gFrontEnd )
				)
				( attribute "PHYS_PAGE" "200"
					( Origin gFrontEnd )
				)
				( attribute "ROOM" "HOT_SWAP"
					( Origin gFrontEnd )
				)
				( attribute "ROT" "1"
					( Origin gFrontEnd )
				)
				( attribute "SEC" "1"
					( Origin gFrontEnd )
				)
				( attribute "SEC_TYPE" "SOT5"
					( Origin gFrontEnd )
				)
				( attribute "VER" "1"
					( Origin gFrontEnd )
				)
				( attribute "XY" "(2300,2825)"
					( Origin gFrontEnd )
				)
				( attribute "CHIPS_PART_NAME" "MOSFETN_1D3S"
					( Origin gPackager )
				)
				( attribute "CDS_PART_NAME" "MOSFETN_1D3S_SOT5-IC,G68777-001"
					( Origin gPackager )
				)
				( objectStatus "EU9R1" )
			)
			( gate "@baseboard_fab2_lib.baseboard_fab2(sch_1):page200_i58"
				( attribute "CDS_LIB" "mstr_discrete"
					( Origin gPackager )
				)
				( attribute "CDS_LOCATION" "R9R4"
					( Origin gPackager )
				)
				( attribute "CDS_SEC" "1"
					( Origin gPackager )
				)
				( attribute "LOCATION" "R9R4"
					( Origin gFrontEnd )
				)
				( attribute "MATERIAL" "CHIP"
					( Origin gFrontEnd )
				)
				( attribute "PACK_TYPE" "0402"
					( Origin gFrontEnd )
				)
				( attribute "PART_NUMBER" "G21796-066"
					( Origin gFrontEnd )
				)
				( attribute "PHYS_PAGE" "200"
					( Origin gFrontEnd )
				)
				( attribute "ROOM" "HOT_SWAP"
					( Origin gFrontEnd )
				)
				( attribute "ROT" "0"
					( Origin gFrontEnd )
				)
				( attribute "SEC" "1"
					( Origin gPackager )
				)
				( attribute "TOLERANCE" "1%"
					( Origin gFrontEnd )
				)
				( attribute "VALUE" "10.0"
					( Origin gFrontEnd )
				)
				( attribute "VER" "1"
					( Origin gFrontEnd )
				)
				( attribute "WATTAGE" "1/16W"
					( Origin gFrontEnd )
				)
				( attribute "XY" "(2000,2525)"
					( Origin gFrontEnd )
				)
				( attribute "CHIPS_PART_NAME" "RES"
					( Origin gPackager )
				)
				( attribute "CDS_PART_NAME" "RES_0402-10.0,1%,1/16W,CHIP,G2A"
					( Origin gPackager )
				)
				( objectStatus "R9R4" )
			)
			( gate "@baseboard_fab2_lib.baseboard_fab2(sch_1):page200_i59"
				( attribute "CDS_LIB" "mstr_discrete"
					( Origin gPackager )
				)
				( attribute "CDS_LOCATION" "EU1E1"
					( Origin gPackager )
				)
				( attribute "CDS_SEC" "1"
					( Origin gPackager )
				)
				( attribute "LOCATION" "EU1E1"
					( Origin gFrontEnd )
				)
				( attribute "MATERIAL" "IC"
					( Origin gFrontEnd )
				)
				( attribute "PACK_TYPE" "SOT5"
					( Origin gFrontEnd )
				)
				( attribute "PART_NUMBER" "G68777-001"
					( Origin gFrontEnd )
				)
				( attribute "PHYS_PAGE" "200"
					( Origin gFrontEnd )
				)
				( attribute "ROOM" "HOT_SWAP"
					( Origin gFrontEnd )
				)
				( attribute "ROT" "1"
					( Origin gFrontEnd )
				)
				( attribute "SEC" "1"
					( Origin gFrontEnd )
				)
				( attribute "SEC_TYPE" "SOT5"
					( Origin gFrontEnd )
				)
				( attribute "VER" "1"
					( Origin gFrontEnd )
				)
				( attribute "XY" "(2275,2100)"
					( Origin gFrontEnd )
				)
				( attribute "CHIPS_PART_NAME" "MOSFETN_1D3S"
					( Origin gPackager )
				)
				( attribute "CDS_PART_NAME" "MOSFETN_1D3S_SOT5-IC,G68777-001"
					( Origin gPackager )
				)
				( objectStatus "EU1E1" )
			)
			( gate "@baseboard_fab2_lib.baseboard_fab2(sch_1):page200_i60"
				( attribute "CDS_LIB" "mstr_discrete"
					( Origin gPackager )
				)
				( attribute "CDS_LOCATION" "R1D48"
					( Origin gPackager )
				)
				( attribute "CDS_SEC" "1"
					( Origin gPackager )
				)
				( attribute "LOCATION" "R1D48"
					( Origin gFrontEnd )
				)
				( attribute "MATERIAL" "CHIP"
					( Origin gFrontEnd )
				)
				( attribute "PACK_TYPE" "0402"
					( Origin gFrontEnd )
				)
				( attribute "PART_NUMBER" "G21796-066"
					( Origin gFrontEnd )
				)
				( attribute "PHYS_PAGE" "200"
					( Origin gFrontEnd )
				)
				( attribute "ROOM" "HOT_SWAP"
					( Origin gFrontEnd )
				)
				( attribute "ROT" "0"
					( Origin gFrontEnd )
				)
				( attribute "SEC" "1"
					( Origin gFrontEnd )
				)
				( attribute "SEC_TYPE" "0402"
					( Origin gFrontEnd )
				)
				( attribute "TOLERANCE" "1%"
					( Origin gFrontEnd )
				)
				( attribute "VALUE" "10.0"
					( Origin gFrontEnd )
				)
				( attribute "VER" "1"
					( Origin gFrontEnd )
				)
				( attribute "WATTAGE" "1/16W"
					( Origin gFrontEnd )
				)
				( attribute "XY" "(1950,1775)"
					( Origin gFrontEnd )
				)
				( attribute "CHIPS_PART_NAME" "RES"
					( Origin gPackager )
				)
				( attribute "CDS_PART_NAME" "RES_0402-10.0,1%,1/16W,CHIP,G2A"
					( Origin gPackager )
				)
				( objectStatus "R1D48" )
			)
			( gate "@baseboard_fab2_lib.baseboard_fab2(sch_1):page200_i70"
				( attribute "CDS_LIB" "mstr_discrete"
					( Origin gPackager )
				)
				( attribute "CDS_LOCATION" "R9P19"
					( Origin gPackager )
				)
				( attribute "CDS_SEC" "1"
					( Origin gPackager )
				)
				( attribute "LOCATION" "R9P19"
					( Origin gFrontEnd )
				)
				( attribute "MATERIAL" "EMPTY"
					( Origin gFrontEnd )
				)
				( attribute "PACK_TYPE" "0402"
					( Origin gFrontEnd )
				)
				( attribute "PART_NUMBER" "G21796-016"
					( Origin gFrontEnd )
				)
				( attribute "PHYS_PAGE" "200"
					( Origin gFrontEnd )
				)
				( attribute "ROOM" "HOT_SWAP"
					( Origin gFrontEnd )
				)
				( attribute "ROT" "0"
					( Origin gFrontEnd )
				)
				( attribute "SEC" "1"
					( Origin gFrontEnd )
				)
				( attribute "SEC_TYPE" "0402"
					( Origin gFrontEnd )
				)
				( attribute "TOLERANCE" "1%"
					( Origin gFrontEnd )
				)
				( attribute "VALUE" "10.0K"
					( Origin gFrontEnd )
				)
				( attribute "VER" "2"
					( Origin gFrontEnd )
				)
				( attribute "WATTAGE" "1/16W"
					( Origin gFrontEnd )
				)
				( attribute "XY" "(-4400,-400)"
					( Origin gFrontEnd )
				)
				( attribute "CHIPS_PART_NAME" "RES"
					( Origin gPackager )
				)
				( attribute "CDS_PART_NAME" "RES_0402-10.0K,1%,1/16W,EMPTY,A"
					( Origin gPackager )
				)
				( objectStatus "R9P19" )
			)
			( gate "@baseboard_fab2_lib.baseboard_fab2(sch_1):page200_i71"
				( attribute "CDS_LIB" "mstr_discrete"
					( Origin gPackager )
				)
				( attribute "CDS_LOCATION" "R9P21"
					( Origin gPackager )
				)
				( attribute "CDS_SEC" "1"
					( Origin gPackager )
				)
				( attribute "LOCATION" "R9P21"
					( Origin gFrontEnd )
				)
				( attribute "MATERIAL" "CHIP"
					( Origin gFrontEnd )
				)
				( attribute "PACK_TYPE" "0402"
					( Origin gFrontEnd )
				)
				( attribute "PART_NUMBER" "G21497-005"
					( Origin gFrontEnd )
				)
				( attribute "PHYS_PAGE" "200"
					( Origin gFrontEnd )
				)
				( attribute "ROOM" "HOT_SWAP"
					( Origin gFrontEnd )
				)
				( attribute "ROT" "0"
					( Origin gFrontEnd )
				)
				( attribute "SEC" "1"
					( Origin gFrontEnd )
				)
				( attribute "SEC_TYPE" "0402"
					( Origin gFrontEnd )
				)
				( attribute "TOLERANCE" "5%"
					( Origin gFrontEnd )
				)
				( attribute "VALUE" "0.0"
					( Origin gFrontEnd )
				)
				( attribute "VER" "2"
					( Origin gFrontEnd )
				)
				( attribute "WATTAGE" "1/16W"
					( Origin gFrontEnd )
				)
				( attribute "XY" "(-4400,250)"
					( Origin gFrontEnd )
				)
				( attribute "CHIPS_PART_NAME" "RES"
					( Origin gPackager )
				)
				( attribute "CDS_PART_NAME" "RES_0402-0.0,5%,1/16W,CHIP,G21A"
					( Origin gPackager )
				)
				( objectStatus "R9P21" )
			)
			( gate "@baseboard_fab2_lib.baseboard_fab2(sch_1):page200_i86"
				( attribute "CDS_LIB" "mstr_discrete"
					( Origin gPackager )
				)
				( attribute "CDS_LOCATION" "R9P20"
					( Origin gPackager )
				)
				( attribute "CDS_SEC" "1"
					( Origin gPackager )
				)
				( attribute "LOCATION" "R9P20"
					( Origin gFrontEnd )
				)
				( attribute "MATERIAL" "CHIP"
					( Origin gFrontEnd )
				)
				( attribute "PACK_TYPE" "0402"
					( Origin gFrontEnd )
				)
				( attribute "PART_NUMBER" "G21796-344"
					( Origin gFrontEnd )
				)
				( attribute "PHYS_PAGE" "200"
					( Origin gFrontEnd )
				)
				( attribute "ROOM" "HOT_SWAP"
					( Origin gFrontEnd )
				)
				( attribute "ROT" "0"
					( Origin gFrontEnd )
				)
				( attribute "SEC" "1"
					( Origin gFrontEnd )
				)
				( attribute "SEC_TYPE" "0402"
					( Origin gFrontEnd )
				)
				( attribute "TOLERANCE" "1%"
					( Origin gFrontEnd )
				)
				( attribute "VALUE" "2.7K"
					( Origin gFrontEnd )
				)
				( attribute "VER" "2"
					( Origin gFrontEnd )
				)
				( attribute "WATTAGE" "1/16W"
					( Origin gFrontEnd )
				)
				( attribute "XY" "(-3300,450)"
					( Origin gFrontEnd )
				)
				( attribute "CHIPS_PART_NAME" "RES"
					( Origin gPackager )
				)
				( attribute "CDS_PART_NAME" "RES_0402-2.7K,1%,1/16W,CHIP,G2A"
					( Origin gPackager )
				)
				( objectStatus "R9P20" )
			)
			( gate "@baseboard_fab2_lib.baseboard_fab2(sch_1):page200_i103"
				( attribute "CDS_LIB" "mstr_ttl"
					( Origin gPackager )
				)
				( attribute "CDS_LOCATION" "U1D1"
					( Origin gPackager )
				)
				( attribute "CDS_SEC" "1"
					( Origin gPackager )
				)
				( attribute "LOCATION" "U1D1"
					( Origin gFrontEnd )
				)
				( attribute "MATERIAL" "IC"
					( Origin gFrontEnd )
				)
				( attribute "PACK_TYPE" "SOT"
					( Origin gFrontEnd )
				)
				( attribute "PART_NUMBER" "A79322-001"
					( Origin gFrontEnd )
				)
				( attribute "PHYS_PAGE" "200"
					( Origin gFrontEnd )
				)
				( attribute "ROOM" "HOT_SWAP"
					( Origin gFrontEnd )
				)
				( attribute "ROT" "0"
					( Origin gFrontEnd )
				)
				( attribute "SEC" "1"
					( Origin gFrontEnd )
				)
				( attribute "SEC_TYPE" "SOT"
					( Origin gFrontEnd )
				)
				( attribute "VALUE" "74HC1G126"
					( Origin gFrontEnd )
				)
				( attribute "VER" "1"
					( Origin gFrontEnd )
				)
				( attribute "XY" "(-2900,2225)"
					( Origin gFrontEnd )
				)
				( attribute "CHIPS_PART_NAME" "TTL1G126_A"
					( Origin gPackager )
				)
				( attribute "CDS_PART_NAME" "TTL1G126_A_SOT-74HC1G126,IC,A7B"
					( Origin gPackager )
				)
				( objectStatus "U1D1" )
			)
			( gate "@baseboard_fab2_lib.baseboard_fab2(sch_1):page200_i108"
				( attribute "CDS_LIB" "mstr_discrete"
					( Origin gPackager )
				)
				( attribute "CDS_LOCATION" "R9P11"
					( Origin gPackager )
				)
				( attribute "CDS_SEC" "1"
					( Origin gPackager )
				)
				( attribute "LOCATION" "R9P11"
					( Origin gFrontEnd )
				)
				( attribute "MATERIAL" "CHIP"
					( Origin gFrontEnd )
				)
				( attribute "PACK_TYPE" "0402"
					( Origin gFrontEnd )
				)
				( attribute "PART_NUMBER" "G21796-016"
					( Origin gFrontEnd )
				)
				( attribute "PHYS_PAGE" "200"
					( Origin gFrontEnd )
				)
				( attribute "ROOM" "HOT_SWAP"
					( Origin gFrontEnd )
				)
				( attribute "ROT" "0"
					( Origin gFrontEnd )
				)
				( attribute "SEC" "1"
					( Origin gFrontEnd )
				)
				( attribute "SEC_TYPE" "0402"
					( Origin gFrontEnd )
				)
				( attribute "TOLERANCE" "1%"
					( Origin gFrontEnd )
				)
				( attribute "VALUE" "10.0K"
					( Origin gFrontEnd )
				)
				( attribute "VER" "2"
					( Origin gFrontEnd )
				)
				( attribute "WATTAGE" "1/16W"
					( Origin gFrontEnd )
				)
				( attribute "XY" "(-1650,-150)"
					( Origin gFrontEnd )
				)
				( attribute "CHIPS_PART_NAME" "RES"
					( Origin gPackager )
				)
				( attribute "CDS_PART_NAME" "RES_0402-10.0K,1%,1/16W,CHIP,GA"
					( Origin gPackager )
				)
				( attribute "CONFIG" "64.1002D.6DL"
					( Origin gFrontEnd )
				)
				( objectStatus "R9P11" )
			)
			( gate "@baseboard_fab2_lib.baseboard_fab2(sch_1):page200_i149"
				( attribute "CDS_LIB" "mstr_discrete"
					( Origin gPackager )
				)
				( attribute "CDS_LOCATION" "R9P6"
					( Origin gPackager )
				)
				( attribute "CDS_SEC" "1"
					( Origin gPackager )
				)
				( attribute "LOCATION" "R9P6"
					( Origin gFrontEnd )
				)
				( attribute "MATERIAL" "CHIP"
					( Origin gFrontEnd )
				)
				( attribute "PACK_TYPE" "0402"
					( Origin gFrontEnd )
				)
				( attribute "PART_NUMBER" "G21796-016"
					( Origin gFrontEnd )
				)
				( attribute "PHYS_PAGE" "200"
					( Origin gFrontEnd )
				)
				( attribute "ROOM" "HOT_SWAP"
					( Origin gFrontEnd )
				)
				( attribute "ROT" "0"
					( Origin gFrontEnd )
				)
				( attribute "SEC" "1"
					( Origin gFrontEnd )
				)
				( attribute "SEC_TYPE" "0402"
					( Origin gFrontEnd )
				)
				( attribute "TOLERANCE" "1%"
					( Origin gFrontEnd )
				)
				( attribute "VALUE" "10.0K"
					( Origin gFrontEnd )
				)
				( attribute "VER" "2"
					( Origin gFrontEnd )
				)
				( attribute "WATTAGE" "1/16W"
					( Origin gFrontEnd )
				)
				( attribute "XY" "(600,1100)"
					( Origin gFrontEnd )
				)
				( attribute "CHIPS_PART_NAME" "RES"
					( Origin gPackager )
				)
				( attribute "CDS_PART_NAME" "RES_0402-10.0K,1%,1/16W,CHIP,GA"
					( Origin gPackager )
				)
				( objectStatus "R9P6" )
			)
			( gate "@baseboard_fab2_lib.baseboard_fab2(sch_1):page200_i154"
				( attribute "CDS_LIB" "mstr_discrete"
					( Origin gPackager )
				)
				( attribute "CDS_LOCATION" "R1D51"
					( Origin gPackager )
				)
				( attribute "CDS_SEC" "1"
					( Origin gPackager )
				)
				( attribute "LOCATION" "R1D51"
					( Origin gFrontEnd )
				)
				( attribute "MATERIAL" "CHIP"
					( Origin gFrontEnd )
				)
				( attribute "PACK_TYPE" "0402"
					( Origin gFrontEnd )
				)
				( attribute "PART_NUMBER" "G21796-066"
					( Origin gFrontEnd )
				)
				( attribute "PHYS_PAGE" "200"
					( Origin gFrontEnd )
				)
				( attribute "ROOM" "HOT_SWAP"
					( Origin gFrontEnd )
				)
				( attribute "ROT" "0"
					( Origin gFrontEnd )
				)
				( attribute "SEC" "1"
					( Origin gFrontEnd )
				)
				( attribute "SEC_TYPE" "0402"
					( Origin gFrontEnd )
				)
				( attribute "TOLERANCE" "1%"
					( Origin gFrontEnd )
				)
				( attribute "VALUE" "10.0"
					( Origin gFrontEnd )
				)
				( attribute "VER" "1"
					( Origin gFrontEnd )
				)
				( attribute "WATTAGE" "1/16W"
					( Origin gFrontEnd )
				)
				( attribute "XY" "(1350,1875)"
					( Origin gFrontEnd )
				)
				( attribute "CHIPS_PART_NAME" "RES"
					( Origin gPackager )
				)
				( attribute "CDS_PART_NAME" "RES_0402-10.0,1%,1/16W,CHIP,G2A"
					( Origin gPackager )
				)
				( objectStatus "R1D51" )
			)
			( gate "@baseboard_fab2_lib.baseboard_fab2(sch_1):page200_i155"
				( attribute "CDS_LIB" "mstr_discrete"
					( Origin gPackager )
				)
				( attribute "CDS_LOCATION" "C1E2"
					( Origin gPackager )
				)
				( attribute "CDS_SEC" "1"
					( Origin gPackager )
				)
				( attribute "LOCATION" "C1E2"
					( Origin gFrontEnd )
				)
				( attribute "MATERIAL" "X7R"
					( Origin gFrontEnd )
				)
				( attribute "PACK_TYPE" "1206"
					( Origin gFrontEnd )
				)
				( attribute "PART_NUMBER" "108427-047"
					( Origin gFrontEnd )
				)
				( attribute "PHYS_PAGE" "200"
					( Origin gFrontEnd )
				)
				( attribute "ROT" "0"
					( Origin gFrontEnd )
				)
				( attribute "SEC" "1"
					( Origin gFrontEnd )
				)
				( attribute "SEC_TYPE" "1206"
					( Origin gFrontEnd )
				)
				( attribute "TOLERANCE" "20%"
					( Origin gFrontEnd )
				)
				( attribute "VALUE" "0.068UF"
					( Origin gFrontEnd )
				)
				( attribute "VER" "1"
					( Origin gFrontEnd )
				)
				( attribute "VOLTAGE" "50V"
					( Units "uVoltage" "V" 1.000000)
					( Origin gFrontEnd )
				)
				( attribute "XY" "(900,1675)"
					( Origin gFrontEnd )
				)
				( attribute "CHIPS_PART_NAME" "CAP"
					( Origin gPackager )
				)
				( attribute "CDS_PART_NAME" "CAP_1206-0.068UF,50V,20%,X7R,1A"
					( Origin gPackager )
				)
				( objectStatus "C1E2" )
			)
			( gate "@baseboard_fab2_lib.baseboard_fab2(sch_1):page200_i158"
				( attribute "CDS_LIB" "mstr_discrete"
					( Origin gPackager )
				)
				( attribute "CDS_LOCATION" "R1D22"
					( Origin gPackager )
				)
				( attribute "CDS_SEC" "1"
					( Origin gPackager )
				)
				( attribute "LOCATION" "R1D22"
					( Origin gFrontEnd )
				)
				( attribute "MATERIAL" "CHIP"
					( Origin gFrontEnd )
				)
				( attribute "PACK_TYPE" "0402"
					( Origin gFrontEnd )
				)
				( attribute "PART_NUMBER" "G21796-016"
					( Origin gFrontEnd )
				)
				( attribute "PHYS_PAGE" "200"
					( Origin gFrontEnd )
				)
				( attribute "ROOM" "HOT_SWAP"
					( Origin gFrontEnd )
				)
				( attribute "ROT" "0"
					( Origin gFrontEnd )
				)
				( attribute "SEC" "1"
					( Origin gFrontEnd )
				)
				( attribute "SEC_TYPE" "0402"
					( Origin gFrontEnd )
				)
				( attribute "TOLERANCE" "1%"
					( Origin gFrontEnd )
				)
				( attribute "VALUE" "10.0K"
					( Origin gFrontEnd )
				)
				( attribute "VER" "2"
					( Origin gFrontEnd )
				)
				( attribute "WATTAGE" "1/16W"
					( Origin gFrontEnd )
				)
				( attribute "XY" "(-1650,2350)"
					( Origin gFrontEnd )
				)
				( attribute "CHIPS_PART_NAME" "RES"
					( Origin gPackager )
				)
				( attribute "CDS_PART_NAME" "RES_0402-10.0K,1%,1/16W,CHIP,GA"
					( Origin gPackager )
				)
				( objectStatus "R1D22" )
			)
			( gate "@baseboard_fab2_lib.baseboard_fab2(sch_1):page200_i163"
				( attribute "CDS_LIB" "mstr_vreg"
					( Origin gPackager )
				)
				( attribute "CDS_LMAN_SYM_OUTLINE" "-250,200,250,-200"
					( Origin gPackager )
				)
				( attribute "CDS_LOCATION" "U9P1"
					( Origin gPackager )
				)
				( attribute "CDS_SEC" "1"
					( Origin gPackager )
				)
				( attribute "LOCATION" "U9P1"
					( Origin gFrontEnd )
				)
				( attribute "MATERIAL" "IC"
					( Origin gFrontEnd )
				)
				( attribute "PACK_TYPE" "SM"
					( Origin gFrontEnd )
				)
				( attribute "PART_NUMBER" "H69492-001"
					( Origin gFrontEnd )
				)
				( attribute "PHYS_PAGE" "200"
					( Origin gFrontEnd )
				)
				( attribute "ROT" "0"
					( Origin gFrontEnd )
				)
				( attribute "SEC" "1"
					( Origin gFrontEnd )
				)
				( attribute "SEC_TYPE" "SM"
					( Origin gFrontEnd )
				)
				( attribute "VER" "1"
					( Origin gFrontEnd )
				)
				( attribute "XY" "(-350,350)"
					( Origin gFrontEnd )
				)
				( attribute "CHIPS_PART_NAME" "TPS3700"
					( Origin gPackager )
				)
				( attribute "CDS_PART_NAME" "TPS3700_SM-IC,H69492-001"
					( Origin gPackager )
				)
				( objectStatus "U9P1" )
			)
			( gate "@baseboard_fab2_lib.baseboard_fab2(sch_1):page200_i170"
				( attribute "CDS_LIB" "mstr_vreg"
					( Origin gPackager )
				)
				( attribute "CDS_LMAN_SYM_OUTLINE" "-250,200,250,-200"
					( Origin gPackager )
				)
				( attribute "CDS_LOCATION" "U1D2"
					( Origin gPackager )
				)
				( attribute "CDS_SEC" "1"
					( Origin gPackager )
				)
				( attribute "LOCATION" "U1D2"
					( Origin gFrontEnd )
				)
				( attribute "MATERIAL" "IC"
					( Origin gFrontEnd )
				)
				( attribute "PACK_TYPE" "SM"
					( Origin gFrontEnd )
				)
				( attribute "PART_NUMBER" "H69492-001"
					( Origin gFrontEnd )
				)
				( attribute "PHYS_PAGE" "200"
					( Origin gFrontEnd )
				)
				( attribute "ROT" "0"
					( Origin gFrontEnd )
				)
				( attribute "SEC" "1"
					( Origin gFrontEnd )
				)
				( attribute "SEC_TYPE" "SM"
					( Origin gFrontEnd )
				)
				( attribute "VER" "1"
					( Origin gFrontEnd )
				)
				( attribute "XY" "(-3100,3125)"
					( Origin gFrontEnd )
				)
				( attribute "CHIPS_PART_NAME" "TPS3700"
					( Origin gPackager )
				)
				( attribute "CDS_PART_NAME" "TPS3700_SM-IC,H69492-001"
					( Origin gPackager )
				)
				( objectStatus "U1D2" )
			)
			( gate "@baseboard_fab2_lib.baseboard_fab2(sch_1):page200_i174"
				( attribute "CDS_LIB" "mstr_discrete"
					( Origin gPackager )
				)
				( attribute "CDS_LOCATION" "R1D12"
					( Origin gPackager )
				)
				( attribute "CDS_SEC" "1"
					( Origin gPackager )
				)
				( attribute "LOCATION" "R1D12"
					( Origin gFrontEnd )
				)
				( attribute "MATERIAL" "CHIP"
					( Origin gFrontEnd )
				)
				( attribute "PACK_TYPE" "0402"
					( Origin gFrontEnd )
				)
				( attribute "PART_NUMBER" "G21796-016"
					( Origin gFrontEnd )
				)
				( attribute "PHYS_PAGE" "200"
					( Origin gFrontEnd )
				)
				( attribute "ROOM" "HOT_SWAP"
					( Origin gFrontEnd )
				)
				( attribute "ROT" "0"
					( Origin gFrontEnd )
				)
				( attribute "SEC" "1"
					( Origin gFrontEnd )
				)
				( attribute "SEC_TYPE" "0402"
					( Origin gFrontEnd )
				)
				( attribute "TOLERANCE" "1%"
					( Origin gFrontEnd )
				)
				( attribute "VALUE" "10.0K"
					( Origin gFrontEnd )
				)
				( attribute "VER" "2"
					( Origin gFrontEnd )
				)
				( attribute "WATTAGE" "1/16W"
					( Origin gFrontEnd )
				)
				( attribute "XY" "(-4575,2875)"
					( Origin gFrontEnd )
				)
				( attribute "CHIPS_PART_NAME" "RES"
					( Origin gPackager )
				)
				( attribute "CDS_PART_NAME" "RES_0402-10.0K,1%,1/16W,CHIP,GA"
					( Origin gPackager )
				)
				( attribute "CONFIG" "64.1002D.6DL"
					( Origin gFrontEnd )
				)
				( objectStatus "R1D12" )
			)
			( gate "@baseboard_fab2_lib.baseboard_fab2(sch_1):page200_i175"
				( attribute "CDS_LIB" "mstr_discrete"
					( Origin gPackager )
				)
				( attribute "CDS_LOCATION" "R1D19"
					( Origin gPackager )
				)
				( attribute "CDS_SEC" "1"
					( Origin gPackager )
				)
				( attribute "LOCATION" "R1D19"
					( Origin gFrontEnd )
				)
				( attribute "MATERIAL" "CHIP"
					( Origin gFrontEnd )
				)
				( attribute "PACK_TYPE" "0402"
					( Origin gFrontEnd )
				)
				( attribute "PART_NUMBER" "G21796-016"
					( Origin gFrontEnd )
				)
				( attribute "PHYS_PAGE" "200"
					( Origin gFrontEnd )
				)
				( attribute "ROOM" "HOT_SWAP"
					( Origin gFrontEnd )
				)
				( attribute "ROT" "0"
					( Origin gFrontEnd )
				)
				( attribute "SEC" "1"
					( Origin gFrontEnd )
				)
				( attribute "SEC_TYPE" "0402"
					( Origin gFrontEnd )
				)
				( attribute "TOLERANCE" "1%"
					( Origin gFrontEnd )
				)
				( attribute "VALUE" "10.0K"
					( Origin gFrontEnd )
				)
				( attribute "VER" "2"
					( Origin gFrontEnd )
				)
				( attribute "WATTAGE" "1/16W"
					( Origin gFrontEnd )
				)
				( attribute "XY" "(-4150,2450)"
					( Origin gFrontEnd )
				)
				( attribute "CHIPS_PART_NAME" "RES"
					( Origin gPackager )
				)
				( attribute "CDS_PART_NAME" "RES_0402-10.0K,1%,1/16W,CHIP,GA"
					( Origin gPackager )
				)
				( attribute "CONFIG" "64.1002D.6DL"
					( Origin gFrontEnd )
				)
				( objectStatus "R1D19" )
			)
			( gate "@baseboard_fab2_lib.baseboard_fab2(sch_1):page200_i185"
				( attribute "CDS_LIB" "dev_discrete"
					( Origin gPackager )
				)
				( attribute "CDS_LOCATION" "C9P6"
					( Origin gPackager )
				)
				( attribute "CDS_SEC" "1"
					( Origin gPackager )
				)
				( attribute "LOCATION" "C9P6"
					( Origin gFrontEnd )
				)
				( attribute "MATERIAL" "X7R"
					( Origin gFrontEnd )
				)
				( attribute "PACK_TYPE" "0402V"
					( Origin gFrontEnd )
				)
				( attribute "PART_NUMBER" "A36096-030"
					( Origin gFrontEnd )
				)
				( attribute "PHYS_PAGE" "200"
					( Origin gFrontEnd )
				)
				( attribute "ROOM" "HOT_SWAP"
					( Origin gFrontEnd )
				)
				( attribute "ROT" "2"
					( Origin gFrontEnd )
				)
				( attribute "SEC" "1"
					( Origin gFrontEnd )
				)
				( attribute "SEC_TYPE" "0402V"
					( Origin gFrontEnd )
				)
				( attribute "TOLERANCE" "10%"
					( Origin gFrontEnd )
				)
				( attribute "VALUE" "0.1UF"
					( Origin gFrontEnd )
				)
				( attribute "VER" "1"
					( Origin gFrontEnd )
				)
				( attribute "VOLTAGE" "16V"
					( Units "uVoltage" "V" 1.000000)
					( Origin gFrontEnd )
				)
				( attribute "XY" "(-825,775)"
					( Origin gFrontEnd )
				)
				( attribute "CHIPS_PART_NAME" "CAP_A"
					( Origin gPackager )
				)
				( attribute "CDS_PART_NAME" "CAP_A_0402V-0.1UF,16V,10%,X7R,A"
					( Origin gPackager )
				)
				( objectStatus "C9P6" )
			)
			( gate "@baseboard_fab2_lib.baseboard_fab2(sch_1):page200_i187"
				( attribute "CDS_LIB" "dev_discrete"
					( Origin gPackager )
				)
				( attribute "CDS_LOCATION" "C1D9"
					( Origin gPackager )
				)
				( attribute "CDS_SEC" "1"
					( Origin gPackager )
				)
				( attribute "LOCATION" "C1D9"
					( Origin gFrontEnd )
				)
				( attribute "MATERIAL" "X7R"
					( Origin gFrontEnd )
				)
				( attribute "PACK_TYPE" "0402V"
					( Origin gFrontEnd )
				)
				( attribute "PART_NUMBER" "A36096-030"
					( Origin gFrontEnd )
				)
				( attribute "PHYS_PAGE" "200"
					( Origin gFrontEnd )
				)
				( attribute "ROOM" "HOT_SWAP"
					( Origin gFrontEnd )
				)
				( attribute "ROT" "2"
					( Origin gFrontEnd )
				)
				( attribute "SEC" "1"
					( Origin gFrontEnd )
				)
				( attribute "SEC_TYPE" "0402V"
					( Origin gFrontEnd )
				)
				( attribute "TOLERANCE" "10%"
					( Origin gFrontEnd )
				)
				( attribute "VALUE" "0.1UF"
					( Origin gFrontEnd )
				)
				( attribute "VER" "1"
					( Origin gFrontEnd )
				)
				( attribute "VOLTAGE" "16V"
					( Units "uVoltage" "V" 1.000000)
					( Origin gFrontEnd )
				)
				( attribute "XY" "(-3800,3425)"
					( Origin gFrontEnd )
				)
				( attribute "CHIPS_PART_NAME" "CAP_A"
					( Origin gPackager )
				)
				( attribute "CDS_PART_NAME" "CAP_A_0402V-0.1UF,16V,10%,X7R,A"
					( Origin gPackager )
				)
				( objectStatus "C1D9" )
			)
			( gate "@baseboard_fab2_lib.baseboard_fab2(sch_1):page199_i87"
				( attribute "CDS_LIB" "mstr_discrete"
					( Origin gPackager )
				)
				( attribute "CDS_LOCATION" "R1D18"
					( Origin gPackager )
				)
				( attribute "LOCATION" "R1D18"
					( Origin gFrontEnd )
				)
				( attribute "MATERIAL" "CHIP"
					( Origin gFrontEnd )
				)
				( attribute "PACK_TYPE" "0402"
					( Origin gFrontEnd )
				)
				( attribute "PART_NUMBER" "G21796-010"
					( Origin gFrontEnd )
				)
				( attribute "PHYS_PAGE" "199"
					( Origin gFrontEnd )
				)
				( attribute "ROOM" "HOT_SWAP"
					( Origin gFrontEnd )
				)
				( attribute "ROT" "0"
					( Origin gFrontEnd )
				)
				( attribute "SEC" "1"
					( Origin gFrontEnd )
				)
				( attribute "SEC_TYPE" "0402"
					( Origin gFrontEnd )
				)
				( attribute "TOLERANCE" "1%"
					( Origin gFrontEnd )
				)
				( attribute "VALUE" "100.0K"
					( Origin gFrontEnd )
				)
				( attribute "VER" "2"
					( Origin gFrontEnd )
				)
				( attribute "WATTAGE" "1/16W"
					( Origin gFrontEnd )
				)
				( attribute "XY" "(-6950,-50)"
					( Origin gFrontEnd )
				)
				( attribute "CHIPS_PART_NAME" "RES"
					( Origin gPackager )
				)
				( attribute "CDS_PART_NAME" "RES_0402-100.0K,1%,1/16W,CHIP,A"
					( Origin gPackager )
				)
				( attribute "CDS_SEC" "1"
					( Origin gPackager )
				)
				( objectStatus "R1D18" )
			)
			( gate "@baseboard_fab2_lib.baseboard_fab2(sch_1):page200_i191"
				( attribute "CDS_LIB" "mstr_discrete"
					( Origin gPackager )
				)
				( attribute "CDS_LOCATION" "R1D23"
					( Origin gPackager )
				)
				( attribute "CDS_SEC" "1"
					( Origin gPackager )
				)
				( attribute "LOCATION" "R1D23"
					( Origin gFrontEnd )
				)
				( attribute "MATERIAL" "CHIP"
					( Origin gFrontEnd )
				)
				( attribute "PACK_TYPE" "0402"
					( Origin gFrontEnd )
				)
				( attribute "PART_NUMBER" "G21796-016"
					( Origin gFrontEnd )
				)
				( attribute "PHYS_PAGE" "200"
					( Origin gFrontEnd )
				)
				( attribute "ROOM" "HOT_SWAP"
					( Origin gFrontEnd )
				)
				( attribute "ROT" "0"
					( Origin gFrontEnd )
				)
				( attribute "SEC" "1"
					( Origin gFrontEnd )
				)
				( attribute "SEC_TYPE" "0402"
					( Origin gFrontEnd )
				)
				( attribute "TOLERANCE" "1%"
					( Origin gFrontEnd )
				)
				( attribute "VALUE" "10.0K"
					( Origin gFrontEnd )
				)
				( attribute "VER" "2"
					( Origin gFrontEnd )
				)
				( attribute "WATTAGE" "1/16W"
					( Origin gFrontEnd )
				)
				( attribute "XY" "(-2950,3550)"
					( Origin gFrontEnd )
				)
				( attribute "CHIPS_PART_NAME" "RES"
					( Origin gPackager )
				)
				( attribute "CDS_PART_NAME" "RES_0402-10.0K,1%,1/16W,CHIP,GA"
					( Origin gPackager )
				)
				( objectStatus "R1D23" )
			)
			( gate "@baseboard_fab2_lib.baseboard_fab2(sch_1):page200_i192"
				( attribute "CDS_LIB" "mstr_discrete"
					( Origin gPackager )
				)
				( attribute "CDS_LOCATION" "R9P10"
					( Origin gPackager )
				)
				( attribute "CDS_SEC" "1"
					( Origin gPackager )
				)
				( attribute "LOCATION" "R9P10"
					( Origin gFrontEnd )
				)
				( attribute "MATERIAL" "CHIP"
					( Origin gFrontEnd )
				)
				( attribute "PACK_TYPE" "0402"
					( Origin gFrontEnd )
				)
				( attribute "PART_NUMBER" "G21796-016"
					( Origin gFrontEnd )
				)
				( attribute "PHYS_PAGE" "200"
					( Origin gFrontEnd )
				)
				( attribute "ROOM" "HOT_SWAP"
					( Origin gFrontEnd )
				)
				( attribute "ROT" "0"
					( Origin gFrontEnd )
				)
				( attribute "SEC" "1"
					( Origin gFrontEnd )
				)
				( attribute "SEC_TYPE" "0402"
					( Origin gFrontEnd )
				)
				( attribute "TOLERANCE" "1%"
					( Origin gFrontEnd )
				)
				( attribute "VALUE" "10.0K"
					( Origin gFrontEnd )
				)
				( attribute "VER" "2"
					( Origin gFrontEnd )
				)
				( attribute "WATTAGE" "1/16W"
					( Origin gFrontEnd )
				)
				( attribute "XY" "(275,1075)"
					( Origin gFrontEnd )
				)
				( attribute "CHIPS_PART_NAME" "RES"
					( Origin gPackager )
				)
				( attribute "CDS_PART_NAME" "RES_0402-10.0K,1%,1/16W,CHIP,GA"
					( Origin gPackager )
				)
				( objectStatus "R9P10" )
			)
			( gate "@baseboard_fab2_lib.baseboard_fab2(sch_1):page200_i196"
				( attribute "CDS_LIB" "mstr_discrete"
					( Origin gPackager )
				)
				( attribute "CDS_LOCATION" "Q9P1"
					( Origin gPackager )
				)
				( attribute "CDS_SEC" "1"
					( Origin gPackager )
				)
				( attribute "LOCATION" "Q9P1"
					( Origin gFrontEnd )
				)
				( attribute "MATERIAL" "FET"
					( Origin gFrontEnd )
				)
				( attribute "PACK_TYPE" "SMLF"
					( Origin gFrontEnd )
				)
				( attribute "PART_NUMBER" "D24280-001"
					( Origin gFrontEnd )
				)
				( attribute "PHYS_PAGE" "200"
					( Origin gFrontEnd )
				)
				( attribute "ROOM" "HOT_SWAP"
					( Origin gFrontEnd )
				)
				( attribute "ROT" "0"
					( Origin gFrontEnd )
				)
				( attribute "SEC" "1"
					( Origin gFrontEnd )
				)
				( attribute "SEC_TYPE" "SMLF"
					( Origin gFrontEnd )
				)
				( attribute "VALUE" "2N7002DW"
					( Origin gFrontEnd )
				)
				( attribute "VER" "5"
					( Origin gFrontEnd )
				)
				( attribute "XY" "(-2000,3325)"
					( Origin gFrontEnd )
				)
				( attribute "CHIPS_PART_NAME" "FET_N_DUAL"
					( Origin gPackager )
				)
				( attribute "CDS_PART_NAME" "FET_N_DUAL_SMLF-2N7002DW,FET,DA"
					( Origin gPackager )
				)
				( objectStatus "Q9P1" )
			)
			( gate "@baseboard_fab2_lib.baseboard_fab2(sch_1):page200_i199"
				( attribute "CDS_LIB" "mstr_discrete"
					( Origin gPackager )
				)
				( attribute "CDS_LOCATION" "Q9P1"
					( Origin gPackager )
				)
				( attribute "CDS_SEC" "2"
					( Origin gPackager )
				)
				( attribute "LOCATION" "Q9P1"
					( Origin gFrontEnd )
				)
				( attribute "MATERIAL" "FET"
					( Origin gFrontEnd )
				)
				( attribute "PACK_TYPE" "SMLF"
					( Origin gFrontEnd )
				)
				( attribute "PART_NUMBER" "D24280-001"
					( Origin gFrontEnd )
				)
				( attribute "PHYS_PAGE" "200"
					( Origin gFrontEnd )
				)
				( attribute "ROOM" "HOT_SWAP"
					( Origin gFrontEnd )
				)
				( attribute "ROT" "0"
					( Origin gFrontEnd )
				)
				( attribute "SEC" "2"
					( Origin gFrontEnd )
				)
				( attribute "SEC_TYPE" "SMLF"
					( Origin gFrontEnd )
				)
				( attribute "VALUE" "2N7002DW"
					( Origin gFrontEnd )
				)
				( attribute "VER" "5"
					( Origin gFrontEnd )
				)
				( attribute "XY" "(550,-100)"
					( Origin gFrontEnd )
				)
				( attribute "CHIPS_PART_NAME" "FET_N_DUAL"
					( Origin gPackager )
				)
				( attribute "CDS_PART_NAME" "FET_N_DUAL_SMLF-2N7002DW,FET,DA"
					( Origin gPackager )
				)
				( objectStatus "Q9P1" )
			)
			( gate "@baseboard_fab2_lib.baseboard_fab2(sch_1):page200_i200"
				( attribute "CDS_LIB" "mstr_vreg"
					( Origin gPackager )
				)
				( attribute "CDS_LMAN_SYM_OUTLINE" "-250,200,250,-200"
					( Origin gPackager )
				)
				( attribute "CDS_LOCATION" "U9P2"
					( Origin gPackager )
				)
				( attribute "CDS_SEC" "1"
					( Origin gPackager )
				)
				( attribute "LOCATION" "U9P2"
					( Origin gFrontEnd )
				)
				( attribute "MATERIAL" "IC"
					( Origin gFrontEnd )
				)
				( attribute "PACK_TYPE" "SM"
					( Origin gFrontEnd )
				)
				( attribute "PART_NUMBER" "H69492-001"
					( Origin gFrontEnd )
				)
				( attribute "PHYS_PAGE" "200"
					( Origin gFrontEnd )
				)
				( attribute "ROT" "0"
					( Origin gFrontEnd )
				)
				( attribute "SEC" "1"
					( Origin gPackager )
				)
				( attribute "VER" "1"
					( Origin gFrontEnd )
				)
				( attribute "XY" "(-3425,-150)"
					( Origin gFrontEnd )
				)
				( attribute "CHIPS_PART_NAME" "TPS3700"
					( Origin gPackager )
				)
				( attribute "CDS_PART_NAME" "TPS3700_SM-IC,H69492-001"
					( Origin gPackager )
				)
				( objectStatus "U9P2" )
			)
			( gate "@baseboard_fab2_lib.baseboard_fab2(sch_1):page200_i201"
				( attribute "CDS_LIB" "dev_discrete"
					( Origin gPackager )
				)
				( attribute "CDS_LOCATION" "C9P11"
					( Origin gPackager )
				)
				( attribute "CDS_SEC" "1"
					( Origin gPackager )
				)
				( attribute "LOCATION" "C9P11"
					( Origin gFrontEnd )
				)
				( attribute "MATERIAL" "X7R"
					( Origin gFrontEnd )
				)
				( attribute "PACK_TYPE" "0402V"
					( Origin gFrontEnd )
				)
				( attribute "PART_NUMBER" "A36096-030"
					( Origin gFrontEnd )
				)
				( attribute "PHYS_PAGE" "200"
					( Origin gFrontEnd )
				)
				( attribute "ROOM" "HOT_SWAP"
					( Origin gFrontEnd )
				)
				( attribute "ROT" "2"
					( Origin gFrontEnd )
				)
				( attribute "SEC" "1"
					( Origin gFrontEnd )
				)
				( attribute "SEC_TYPE" "0402V"
					( Origin gFrontEnd )
				)
				( attribute "TOLERANCE" "10%"
					( Origin gFrontEnd )
				)
				( attribute "VALUE" "0.1UF"
					( Origin gFrontEnd )
				)
				( attribute "VER" "1"
					( Origin gFrontEnd )
				)
				( attribute "VOLTAGE" "16V"
					( Units "uVoltage" "V" 1.000000)
					( Origin gFrontEnd )
				)
				( attribute "XY" "(-3450,500)"
					( Origin gFrontEnd )
				)
				( attribute "CHIPS_PART_NAME" "CAP_A"
					( Origin gPackager )
				)
				( attribute "CDS_PART_NAME" "CAP_A_0402V-0.1UF,16V,10%,X7R,A"
					( Origin gPackager )
				)
				( objectStatus "C9P11" )
			)
			( gate "@baseboard_fab2_lib.baseboard_fab2(sch_1):page200_i203"
				( attribute "CDS_LIB" "mstr_discrete"
					( Origin gPackager )
				)
				( attribute "CDS_LOCATION" "Q1D2"
					( Origin gPackager )
				)
				( attribute "CDS_SEC" "1"
					( Origin gPackager )
				)
				( attribute "LOCATION" "Q1D2"
					( Origin gFrontEnd )
				)
				( attribute "MATERIAL" "FET"
					( Origin gFrontEnd )
				)
				( attribute "PACK_TYPE" "SOT23LF"
					( Origin gFrontEnd )
				)
				( attribute "PART_NUMBER" "C79254-001"
					( Origin gFrontEnd )
				)
				( attribute "PHYS_PAGE" "200"
					( Origin gFrontEnd )
				)
				( attribute "ROOM" "HOT_SWAP"
					( Origin gFrontEnd )
				)
				( attribute "ROT" "0"
					( Origin gFrontEnd )
				)
				( attribute "SEC" "1"
					( Origin gFrontEnd )
				)
				( attribute "SEC_TYPE" "SOT23LF"
					( Origin gFrontEnd )
				)
				( attribute "VALUE" "2N7002"
					( Origin gFrontEnd )
				)
				( attribute "VER" "8"
					( Origin gFrontEnd )
				)
				( attribute "XY" "(-3500,1300)"
					( Origin gFrontEnd )
				)
				( attribute "CHIPS_PART_NAME" "FET_N"
					( Origin gPackager )
				)
				( attribute "CDS_PART_NAME" "FET_N_SOT23LF-2N7002,FET,C7925A"
					( Origin gPackager )
				)
				( objectStatus "Q1D2" )
			)
			( gate "@baseboard_fab2_lib.baseboard_fab2(sch_1):page200_i204"
				( attribute "CDS_LIB" "mstr_discrete"
					( Origin gPackager )
				)
				( attribute "CDS_LOCATION" "R1D21"
					( Origin gPackager )
				)
				( attribute "CDS_SEC" "1"
					( Origin gPackager )
				)
				( attribute "LOCATION" "R1D21"
					( Origin gFrontEnd )
				)
				( attribute "MATERIAL" "CHIP"
					( Origin gFrontEnd )
				)
				( attribute "PACK_TYPE" "0402"
					( Origin gFrontEnd )
				)
				( attribute "PART_NUMBER" "G21796-072"
					( Origin gFrontEnd )
				)
				( attribute "PHYS_PAGE" "200"
					( Origin gFrontEnd )
				)
				( attribute "ROOM" "HOT_SWAP"
					( Origin gFrontEnd )
				)
				( attribute "ROT" "0"
					( Origin gFrontEnd )
				)
				( attribute "SEC" "1"
					( Origin gFrontEnd )
				)
				( attribute "SEC_TYPE" "0402"
					( Origin gFrontEnd )
				)
				( attribute "TOLERANCE" "1%"
					( Origin gFrontEnd )
				)
				( attribute "VALUE" "4.75K"
					( Origin gFrontEnd )
				)
				( attribute "VER" "2"
					( Origin gFrontEnd )
				)
				( attribute "WATTAGE" "1/16W"
					( Origin gFrontEnd )
				)
				( attribute "XY" "(-3500,1750)"
					( Origin gFrontEnd )
				)
				( attribute "CHIPS_PART_NAME" "RES"
					( Origin gPackager )
				)
				( attribute "CDS_PART_NAME" "RES_0402-4.75K,1%,1/16W,CHIP,GA"
					( Origin gPackager )
				)
				( objectStatus "R1D21" )
			)
			( gate "@baseboard_fab2_lib.baseboard_fab2(sch_1):page200_i210"
				( attribute "CDS_LIB" "mstr_discrete"
					( Origin gPackager )
				)
				( attribute "CDS_LOCATION" "R9P4"
					( Origin gPackager )
				)
				( attribute "CDS_SEC" "1"
					( Origin gPackager )
				)
				( attribute "LOCATION" "R9P4"
					( Origin gFrontEnd )
				)
				( attribute "MATERIAL" "CHIP"
					( Origin gFrontEnd )
				)
				( attribute "PACK_TYPE" "0402"
					( Origin gFrontEnd )
				)
				( attribute "PART_NUMBER" "G21796-344"
					( Origin gFrontEnd )
				)
				( attribute "PHYS_PAGE" "200"
					( Origin gFrontEnd )
				)
				( attribute "ROOM" "HOT_SWAP"
					( Origin gFrontEnd )
				)
				( attribute "ROT" "0"
					( Origin gFrontEnd )
				)
				( attribute "SEC" "1"
					( Origin gFrontEnd )
				)
				( attribute "SEC_TYPE" "0402"
					( Origin gFrontEnd )
				)
				( attribute "TOLERANCE" "1%"
					( Origin gFrontEnd )
				)
				( attribute "VALUE" "2.7K"
					( Origin gFrontEnd )
				)
				( attribute "VER" "2"
					( Origin gFrontEnd )
				)
				( attribute "WATTAGE" "1/16W"
					( Origin gFrontEnd )
				)
				( attribute "XY" "(1750,225)"
					( Origin gFrontEnd )
				)
				( attribute "CHIPS_PART_NAME" "RES"
					( Origin gPackager )
				)
				( attribute "CDS_PART_NAME" "RES_0402-2.7K,1%,1/16W,CHIP,G2A"
					( Origin gPackager )
				)
				( objectStatus "R9P4" )
			)
			( gate "@baseboard_fab2_lib.baseboard_fab2(sch_1):page200_i213"
				( attribute "CDS_LIB" "mstr_discrete"
					( Origin gPackager )
				)
				( attribute "CDS_LOCATION" "CR9P2"
					( Origin gPackager )
				)
				( attribute "CDS_SEC" "1"
					( Origin gPackager )
				)
				( attribute "LOCATION" "CR9P2"
					( Origin gFrontEnd )
				)
				( attribute "MATERIAL" "IC"
					( Origin gFrontEnd )
				)
				( attribute "PACK_TYPE" "SMLF"
					( Origin gFrontEnd )
				)
				( attribute "PART_NUMBER" "C73510-001"
					( Origin gFrontEnd )
				)
				( attribute "PHYS_PAGE" "200"
					( Origin gFrontEnd )
				)
				( attribute "ROT" "2"
					( Origin gFrontEnd )
				)
				( attribute "SEC" "1"
					( Origin gFrontEnd )
				)
				( attribute "SEC_TYPE" "SMLF"
					( Origin gFrontEnd )
				)
				( attribute "VALUE" "BAT54WS"
					( Origin gFrontEnd )
				)
				( attribute "VER" "1"
					( Origin gFrontEnd )
				)
				( attribute "XY" "(1000,675)"
					( Origin gFrontEnd )
				)
				( attribute "CHIPS_PART_NAME" "DIODE"
					( Origin gPackager )
				)
				( attribute "CDS_PART_NAME" "DIODE_SMLF-BAT54WS,IC,C73510-0A"
					( Origin gPackager )
				)
				( objectStatus "CR9P2" )
			)
			( gate "@baseboard_fab2_lib.baseboard_fab2(sch_1):page200_i214"
				( attribute "CDS_LIB" "mstr_discrete"
					( Origin gPackager )
				)
				( attribute "CDS_LOCATION" "CR9P1"
					( Origin gPackager )
				)
				( attribute "CDS_SEC" "1"
					( Origin gPackager )
				)
				( attribute "LOCATION" "CR9P1"
					( Origin gFrontEnd )
				)
				( attribute "MATERIAL" "IC"
					( Origin gFrontEnd )
				)
				( attribute "PACK_TYPE" "SMLF"
					( Origin gFrontEnd )
				)
				( attribute "PART_NUMBER" "C73510-001"
					( Origin gFrontEnd )
				)
				( attribute "PHYS_PAGE" "200"
					( Origin gFrontEnd )
				)
				( attribute "ROT" "2"
					( Origin gFrontEnd )
				)
				( attribute "SEC" "1"
					( Origin gFrontEnd )
				)
				( attribute "SEC_TYPE" "SMLF"
					( Origin gFrontEnd )
				)
				( attribute "VALUE" "BAT54WS"
					( Origin gFrontEnd )
				)
				( attribute "VER" "1"
					( Origin gFrontEnd )
				)
				( attribute "XY" "(1050,175)"
					( Origin gFrontEnd )
				)
				( attribute "CHIPS_PART_NAME" "DIODE"
					( Origin gPackager )
				)
				( attribute "CDS_PART_NAME" "DIODE_SMLF-BAT54WS,IC,C73510-0A"
					( Origin gPackager )
				)
				( attribute "POP" "NOPOP"
					( Origin gFrontEnd )
				)
				( objectStatus "CR9P1" )
			)
			( gate "@baseboard_fab2_lib.baseboard_fab2(sch_1):page200_i215"
				( attribute "CDS_LIB" "mstr_discrete"
					( Origin gPackager )
				)
				( attribute "CDS_LOCATION" "R9P5"
					( Origin gPackager )
				)
				( attribute "CDS_SEC" "1"
					( Origin gPackager )
				)
				( attribute "LOCATION" "R9P5"
					( Origin gFrontEnd )
				)
				( attribute "MATERIAL" "CHIP"
					( Origin gFrontEnd )
				)
				( attribute "PACK_TYPE" "0402"
					( Origin gFrontEnd )
				)
				( attribute "PART_NUMBER" "G21796-016"
					( Origin gFrontEnd )
				)
				( attribute "PHYS_PAGE" "200"
					( Origin gFrontEnd )
				)
				( attribute "ROOM" "HOT_SWAP"
					( Origin gFrontEnd )
				)
				( attribute "ROT" "0"
					( Origin gFrontEnd )
				)
				( attribute "SEC" "1"
					( Origin gFrontEnd )
				)
				( attribute "SEC_TYPE" "0402"
					( Origin gFrontEnd )
				)
				( attribute "TOLERANCE" "1%"
					( Origin gFrontEnd )
				)
				( attribute "VALUE" "10.0K"
					( Origin gFrontEnd )
				)
				( attribute "VER" "2"
					( Origin gFrontEnd )
				)
				( attribute "WATTAGE" "1/16W"
					( Origin gFrontEnd )
				)
				( attribute "XY" "(1500,1125)"
					( Origin gFrontEnd )
				)
				( attribute "CHIPS_PART_NAME" "RES"
					( Origin gPackager )
				)
				( attribute "CDS_PART_NAME" "RES_0402-10.0K,1%,1/16W,CHIP,GA"
					( Origin gPackager )
				)
				( objectStatus "R9P5" )
			)
			( gate "@baseboard_fab2_lib.baseboard_fab2(sch_1):page200_i218"
				( attribute "CDS_LIB" "mstr_discrete"
					( Origin gPackager )
				)
				( attribute "CDS_LOCATION" "R9P12"
					( Origin gPackager )
				)
				( attribute "CDS_SEC" "1"
					( Origin gPackager )
				)
				( attribute "LOCATION" "R9P12"
					( Origin gFrontEnd )
				)
				( attribute "MATERIAL" "CHIP"
					( Origin gFrontEnd )
				)
				( attribute "PACK_TYPE" "0402"
					( Origin gFrontEnd )
				)
				( attribute "PART_NUMBER" "G21796-013"
					( Origin gFrontEnd )
				)
				( attribute "PHYS_PAGE" "200"
					( Origin gFrontEnd )
				)
				( attribute "ROOM" "HOT_SWAP"
					( Origin gFrontEnd )
				)
				( attribute "ROT" "0"
					( Origin gFrontEnd )
				)
				( attribute "SEC" "1"
					( Origin gFrontEnd )
				)
				( attribute "SEC_TYPE" "0402"
					( Origin gFrontEnd )
				)
				( attribute "TOLERANCE" "1%"
					( Origin gFrontEnd )
				)
				( attribute "VALUE" "4.99K"
					( Origin gFrontEnd )
				)
				( attribute "VER" "2"
					( Origin gFrontEnd )
				)
				( attribute "WATTAGE" "1/16W"
					( Origin gFrontEnd )
				)
				( attribute "XY" "(-3950,-475)"
					( Origin gFrontEnd )
				)
				( attribute "CHIPS_PART_NAME" "RES"
					( Origin gPackager )
				)
				( attribute "CDS_PART_NAME" "RES_0402-4.99K,1%,1/16W,CHIP,GA"
					( Origin gPackager )
				)
				( objectStatus "R9P12" )
			)
			( gate "@baseboard_fab2_lib.baseboard_fab2(sch_1):page200_i220"
				( attribute "CDS_LIB" "mstr_discrete"
					( Origin gPackager )
				)
				( attribute "CDS_LOCATION" "CR1F5"
					( Origin gPackager )
				)
				( attribute "CDS_SEC" "1"
					( Origin gPackager )
				)
				( attribute "LOCATION" "CR1F5"
					( Origin gFrontEnd )
				)
				( attribute "MATERIAL" "EMPTY"
					( Origin gFrontEnd )
				)
				( attribute "PACK_TYPE" "SM"
					( Origin gFrontEnd )
				)
				( attribute "PART_NUMBER" "C81983-002"
					( Origin gFrontEnd )
				)
				( attribute "PHYS_PAGE" "200"
					( Origin gFrontEnd )
				)
				( attribute "ROT" "1"
					( Origin gFrontEnd )
				)
				( attribute "SEC" "1"
					( Origin gFrontEnd )
				)
				( attribute "SEC_TYPE" "SM"
					( Origin gFrontEnd )
				)
				( attribute "VALUE" "MBRS340T3G"
					( Origin gFrontEnd )
				)
				( attribute "VER" "1"
					( Origin gFrontEnd )
				)
				( attribute "XY" "(2750,3275)"
					( Origin gFrontEnd )
				)
				( attribute "CHIPS_PART_NAME" "DIODE"
					( Origin gPackager )
				)
				( attribute "CDS_PART_NAME" "DIODE_SM-MBRS340T3G,EMPTY,C819A"
					( Origin gPackager )
				)
				( objectStatus "CR1F5" )
			)
			( gate "@baseboard_fab2_lib.baseboard_fab2(sch_1):page200_i222"
				( attribute "CDS_LIB" "mstr_discrete"
					( Origin gPackager )
				)
				( attribute "CDS_LOCATION" "R9P33"
					( Origin gPackager )
				)
				( attribute "CDS_SEC" "1"
					( Origin gPackager )
				)
				( attribute "LOCATION" "R9P33"
					( Origin gFrontEnd )
				)
				( attribute "MATERIAL" "CHIP"
					( Origin gFrontEnd )
				)
				( attribute "PACK_TYPE" "0402"
					( Origin gFrontEnd )
				)
				( attribute "PART_NUMBER" "G21796-010"
					( Origin gFrontEnd )
				)
				( attribute "PHYS_PAGE" "200"
					( Origin gFrontEnd )
				)
				( attribute "ROOM" "HOT_SWAP"
					( Origin gFrontEnd )
				)
				( attribute "ROT" "2"
					( Origin gFrontEnd )
				)
				( attribute "SEC" "1"
					( Origin gPackager )
				)
				( attribute "TOLERANCE" "1%"
					( Origin gFrontEnd )
				)
				( attribute "VALUE" "100.0K"
					( Origin gFrontEnd )
				)
				( attribute "VER" "2"
					( Origin gFrontEnd )
				)
				( attribute "WATTAGE" "1/16W"
					( Origin gFrontEnd )
				)
				( attribute "XY" "(-3950,200)"
					( Origin gFrontEnd )
				)
				( attribute "CHIPS_PART_NAME" "RES"
					( Origin gPackager )
				)
				( attribute "CDS_PART_NAME" "RES_0402-100.0K,1%,1/16W,CHIP,A"
					( Origin gPackager )
				)
				( objectStatus "R9P33" )
			)
			( gate "@baseboard_fab2_lib.baseboard_fab2(sch_1):page206_i155"
				( attribute "CDS_LIB" "mstr_discrete"
					( Origin gPackager )
				)
				( attribute "CDS_LOCATION" "R1D7"
					( Origin gPackager )
				)
				( attribute "CDS_SEC" "1"
					( Origin gPackager )
				)
				( attribute "LOCATION" "R1D7"
					( Origin gFrontEnd )
				)
				( attribute "MATERIAL" "CHIP"
					( Origin gFrontEnd )
				)
				( attribute "PACK_TYPE" "0402"
					( Origin gFrontEnd )
				)
				( attribute "PART_NUMBER" "G21796-026"
					( Origin gFrontEnd )
				)
				( attribute "PHYS_PAGE" "206"
					( Origin gFrontEnd )
				)
				( attribute "ROOM" "PVCCIN_CPU1_VR"
					( Origin gFrontEnd )
				)
				( attribute "ROT" "0"
					( Origin gFrontEnd )
				)
				( attribute "SEC" "1"
					( Origin gFrontEnd )
				)
				( attribute "SEC_TYPE" "0402"
					( Origin gFrontEnd )
				)
				( attribute "TOLERANCE" "1%"
					( Origin gFrontEnd )
				)
				( attribute "VALUE" "1.00K"
					( Origin gFrontEnd )
				)
				( attribute "VER" "2"
					( Origin gFrontEnd )
				)
				( attribute "WATTAGE" "1/16W"
					( Origin gFrontEnd )
				)
				( attribute "XY" "(-2050,4150)"
					( Origin gFrontEnd )
				)
				( attribute "CHIPS_PART_NAME" "RES"
					( Origin gPackager )
				)
				( attribute "CDS_PART_NAME" "RES_0402-1.00K,1%,1/16W,CHIP,GA"
					( Origin gPackager )
				)
				( objectStatus "R1D7" )
			)
			( gate "@baseboard_fab2_lib.baseboard_fab2(sch_1):page218_i70"
				( attribute "CDS_LIB" "mstr_discrete"
					( Origin gPackager )
				)
				( attribute "CDS_LOCATION" "R3L13"
					( Origin gPackager )
				)
				( attribute "CDS_SEC" "1"
					( Origin gPackager )
				)
				( attribute "LOCATION" "R3L13"
					( Origin gFrontEnd )
				)
				( attribute "MATERIAL" "EMPTY"
					( Origin gFrontEnd )
				)
				( attribute "PACK_TYPE" "0402"
					( Origin gFrontEnd )
				)
				( attribute "PART_NUMBER" "G21796-047"
					( Origin gFrontEnd )
				)
				( attribute "PHYS_PAGE" "218"
					( Origin gFrontEnd )
				)
				( attribute "ROOM" "VDDQ_ABC_PWR_VR"
					( Origin gFrontEnd )
				)
				( attribute "ROT" "0"
					( Origin gFrontEnd )
				)
				( attribute "SEC" "1"
					( Origin gFrontEnd )
				)
				( attribute "SEC_TYPE" "0402"
					( Origin gFrontEnd )
				)
				( attribute "TOLERANCE" "1%"
					( Origin gFrontEnd )
				)
				( attribute "VALUE" "49.9"
					( Origin gFrontEnd )
				)
				( attribute "VER" "2"
					( Origin gFrontEnd )
				)
				( attribute "WATTAGE" "1/16W"
					( Origin gFrontEnd )
				)
				( attribute "XY" "(-1900,3250)"
					( Origin gFrontEnd )
				)
				( attribute "CHIPS_PART_NAME" "RES"
					( Origin gPackager )
				)
				( attribute "CDS_PART_NAME" "RES_0402-49.9,1%,1/16W,EMPTY,GA"
					( Origin gPackager )
				)
				( objectStatus "R3L13" )
			)
			( gate "@baseboard_fab2_lib.baseboard_fab2(sch_1):page201_i22"
				( attribute "CDS_LIB" "mstr_discrete"
					( Origin gPackager )
				)
				( attribute "CDS_LOCATION" "R4D31"
					( Origin gPackager )
				)
				( attribute "CDS_SEC" "1"
					( Origin gPackager )
				)
				( attribute "LOCATION" "R4D31"
					( Origin gFrontEnd )
				)
				( attribute "MATERIAL" "EMPTY"
					( Origin gFrontEnd )
				)
				( attribute "PACK_TYPE" "0402"
					( Origin gFrontEnd )
				)
				( attribute "PART_NUMBER" "G21796-311"
					( Origin gFrontEnd )
				)
				( attribute "PHYS_PAGE" "201"
					( Origin gFrontEnd )
				)
				( attribute "ROOM" "PVCCIN_CPU0_VR"
					( Origin gFrontEnd )
				)
				( attribute "ROT" "0"
					( Origin gFrontEnd )
				)
				( attribute "SEC" "1"
					( Origin gFrontEnd )
				)
				( attribute "SEC_TYPE" "0402"
					( Origin gFrontEnd )
				)
				( attribute "TOLERANCE" "1.0%"
					( Origin gFrontEnd )
				)
				( attribute "VALUE" "2.26K"
					( Origin gFrontEnd )
				)
				( attribute "VER" "2"
					( Origin gFrontEnd )
				)
				( attribute "WATTAGE" "1/16W"
					( Origin gFrontEnd )
				)
				( attribute "XY" "(-2075,3750)"
					( Origin gFrontEnd )
				)
				( attribute "CHIPS_PART_NAME" "RES"
					( Origin gPackager )
				)
				( attribute "CDS_PART_NAME" "RES_0402-2.26K,1.0%,1/16W,EMPTA"
					( Origin gPackager )
				)
				( objectStatus "R4D31" )
			)
			( gate "@baseboard_fab2_lib.baseboard_fab2(sch_1):page201_i25"
				( attribute "CDS_LIB" "mstr_discrete"
					( Origin gPackager )
				)
				( attribute "CDS_LOCATION" "R4D58"
					( Origin gPackager )
				)
				( attribute "CDS_SEC" "1"
					( Origin gPackager )
				)
				( attribute "LOCATION" "R4D58"
					( Origin gFrontEnd )
				)
				( attribute "MATERIAL" "CHIP"
					( Origin gFrontEnd )
				)
				( attribute "PACK_TYPE" "0402"
					( Origin gFrontEnd )
				)
				( attribute "PART_NUMBER" "G21796-026"
					( Origin gFrontEnd )
				)
				( attribute "PHYS_PAGE" "201"
					( Origin gFrontEnd )
				)
				( attribute "ROOM" "PVCCIN_CPU0_VR"
					( Origin gFrontEnd )
				)
				( attribute "ROT" "0"
					( Origin gFrontEnd )
				)
				( attribute "SEC" "1"
					( Origin gFrontEnd )
				)
				( attribute "SEC_TYPE" "0402"
					( Origin gFrontEnd )
				)
				( attribute "TOLERANCE" "1%"
					( Origin gFrontEnd )
				)
				( attribute "VALUE" "1.00K"
					( Origin gFrontEnd )
				)
				( attribute "VER" "2"
					( Origin gFrontEnd )
				)
				( attribute "WATTAGE" "1/16W"
					( Origin gFrontEnd )
				)
				( attribute "XY" "(-2500,3925)"
					( Origin gFrontEnd )
				)
				( attribute "CHIPS_PART_NAME" "RES"
					( Origin gPackager )
				)
				( attribute "CDS_PART_NAME" "RES_0402-1.00K,1%,1/16W,CHIP,GA"
					( Origin gPackager )
				)
				( objectStatus "R4D58" )
			)
			( gate "@baseboard_fab2_lib.baseboard_fab2(sch_1):page201_i26"
				( attribute "CDS_LIB" "mstr_discrete"
					( Origin gPackager )
				)
				( attribute "CDS_LOCATION" "R4D67"
					( Origin gPackager )
				)
				( attribute "CDS_SEC" "1"
					( Origin gPackager )
				)
				( attribute "LOCATION" "R4D67"
					( Origin gFrontEnd )
				)
				( attribute "MATERIAL" "CHIP"
					( Origin gFrontEnd )
				)
				( attribute "PACK_TYPE" "0402"
					( Origin gFrontEnd )
				)
				( attribute "PART_NUMBER" "G21497-005"
					( Origin gFrontEnd )
				)
				( attribute "PHYS_PAGE" "201"
					( Origin gFrontEnd )
				)
				( attribute "ROOM" "PVCCIN_CPU0_VR"
					( Origin gFrontEnd )
				)
				( attribute "ROT" "0"
					( Origin gFrontEnd )
				)
				( attribute "SEC" "1"
					( Origin gFrontEnd )
				)
				( attribute "SEC_TYPE" "0402"
					( Origin gFrontEnd )
				)
				( attribute "TOLERANCE" "5%"
					( Origin gFrontEnd )
				)
				( attribute "VALUE" "0.0"
					( Origin gFrontEnd )
				)
				( attribute "VER" "1"
					( Origin gFrontEnd )
				)
				( attribute "WATTAGE" "1/16W"
					( Origin gFrontEnd )
				)
				( attribute "XY" "(-2025,2875)"
					( Origin gFrontEnd )
				)
				( attribute "CHIPS_PART_NAME" "RES"
					( Origin gPackager )
				)
				( attribute "CDS_PART_NAME" "RES_0402-0.0,5%,1/16W,CHIP,G21A"
					( Origin gPackager )
				)
				( objectStatus "R4D67" )
			)
			( gate "@baseboard_fab2_lib.baseboard_fab2(sch_1):page201_i27"
				( attribute "CDS_LIB" "mstr_discrete"
					( Origin gPackager )
				)
				( attribute "CDS_LOCATION" "R4E5"
					( Origin gPackager )
				)
				( attribute "CDS_SEC" "1"
					( Origin gPackager )
				)
				( attribute "LOCATION" "R4E5"
					( Origin gFrontEnd )
				)
				( attribute "MATERIAL" "CHIP"
					( Origin gFrontEnd )
				)
				( attribute "PACK_TYPE" "0402"
					( Origin gFrontEnd )
				)
				( attribute "PART_NUMBER" "G21796-026"
					( Origin gFrontEnd )
				)
				( attribute "PHYS_PAGE" "201"
					( Origin gFrontEnd )
				)
				( attribute "ROOM" "PVCCIN_CPU0_VR"
					( Origin gFrontEnd )
				)
				( attribute "ROT" "2"
					( Origin gFrontEnd )
				)
				( attribute "SEC" "1"
					( Origin gFrontEnd )
				)
				( attribute "SEC_TYPE" "0402"
					( Origin gFrontEnd )
				)
				( attribute "TOLERANCE" "1%"
					( Origin gFrontEnd )
				)
				( attribute "VALUE" "1.00K"
					( Origin gFrontEnd )
				)
				( attribute "VER" "2"
					( Origin gFrontEnd )
				)
				( attribute "WATTAGE" "1/16W"
					( Origin gFrontEnd )
				)
				( attribute "XY" "(-2775,3925)"
					( Origin gFrontEnd )
				)
				( attribute "CHIPS_PART_NAME" "RES"
					( Origin gPackager )
				)
				( attribute "CDS_PART_NAME" "RES_0402-1.00K,1%,1/16W,CHIP,GA"
					( Origin gPackager )
				)
				( objectStatus "R4E5" )
			)
			( gate "@baseboard_fab2_lib.baseboard_fab2(sch_1):page201_i30"
				( attribute "CDS_LIB" "dev_discrete"
					( Origin gPackager )
				)
				( attribute "CDS_LOCATION" "C4D25"
					( Origin gPackager )
				)
				( attribute "CDS_SEC" "1"
					( Origin gPackager )
				)
				( attribute "LOCATION" "C4D25"
					( Origin gFrontEnd )
				)
				( attribute "MATERIAL" "X6S"
					( Origin gFrontEnd )
				)
				( attribute "PACK_TYPE" "0402V"
					( Origin gFrontEnd )
				)
				( attribute "PART_NUMBER" "D97712-004"
					( Origin gFrontEnd )
				)
				( attribute "PHYS_PAGE" "201"
					( Origin gFrontEnd )
				)
				( attribute "ROOM" "PVCCIN_CPU0_VR"
					( Origin gFrontEnd )
				)
				( attribute "ROT" "0"
					( Origin gFrontEnd )
				)
				( attribute "SEC" "1"
					( Origin gFrontEnd )
				)
				( attribute "SEC_TYPE" "0402V"
					( Origin gFrontEnd )
				)
				( attribute "TOLERANCE" "10%"
					( Origin gFrontEnd )
				)
				( attribute "VALUE" "1.0UF"
					( Origin gFrontEnd )
				)
				( attribute "VER" "1"
					( Origin gFrontEnd )
				)
				( attribute "VOLTAGE" "6.3V"
					( Units "uVoltage" "V" 1.000000)
					( Origin gFrontEnd )
				)
				( attribute "XY" "(-1475,1000)"
					( Origin gFrontEnd )
				)
				( attribute "CHIPS_PART_NAME" "CAP_A"
					( Origin gPackager )
				)
				( attribute "CDS_PART_NAME" "CAP_A_0402V-1.0UF,6.3V,10%,X6SA"
					( Origin gPackager )
				)
				( objectStatus "C4D25" )
			)
			( gate "@baseboard_fab2_lib.baseboard_fab2(sch_1):page201_i32"
				( attribute "CDS_LIB" "dev_discrete"
					( Origin gPackager )
				)
				( attribute "CDS_LOCATION" "C4D26"
					( Origin gPackager )
				)
				( attribute "CDS_SEC" "1"
					( Origin gPackager )
				)
				( attribute "LOCATION" "C4D26"
					( Origin gFrontEnd )
				)
				( attribute "MATERIAL" "X7R"
					( Origin gFrontEnd )
				)
				( attribute "PACK_TYPE" "0402V"
					( Origin gFrontEnd )
				)
				( attribute "PART_NUMBER" "A36096-030"
					( Origin gFrontEnd )
				)
				( attribute "PHYS_PAGE" "201"
					( Origin gFrontEnd )
				)
				( attribute "ROOM" "PVCCIN_CPU0_VR"
					( Origin gFrontEnd )
				)
				( attribute "ROT" "0"
					( Origin gFrontEnd )
				)
				( attribute "SEC" "1"
					( Origin gFrontEnd )
				)
				( attribute "SEC_TYPE" "0402V"
					( Origin gFrontEnd )
				)
				( attribute "TOLERANCE" "10%"
					( Origin gFrontEnd )
				)
				( attribute "VALUE" "0.1UF"
					( Origin gFrontEnd )
				)
				( attribute "VER" "1"
					( Origin gFrontEnd )
				)
				( attribute "VOLTAGE" "16V"
					( Units "uVoltage" "V" 1.000000)
					( Origin gFrontEnd )
				)
				( attribute "XY" "(-1875,1000)"
					( Origin gFrontEnd )
				)
				( attribute "CHIPS_PART_NAME" "CAP_A"
					( Origin gPackager )
				)
				( attribute "CDS_PART_NAME" "CAP_A_0402V-0.1UF,16V,10%,X7R,A"
					( Origin gPackager )
				)
				( objectStatus "C4D26" )
			)
			( gate "@baseboard_fab2_lib.baseboard_fab2(sch_1):page201_i37"
				( attribute "CDS_LIB" "dev_discrete"
					( Origin gPackager )
				)
				( attribute "CDS_LOCATION" "C4D15"
					( Origin gPackager )
				)
				( attribute "CDS_SEC" "1"
					( Origin gPackager )
				)
				( attribute "LOCATION" "C4D15"
					( Origin gFrontEnd )
				)
				( attribute "MATERIAL" "X6S"
					( Origin gFrontEnd )
				)
				( attribute "PACK_TYPE" "0402V"
					( Origin gFrontEnd )
				)
				( attribute "PART_NUMBER" "D97712-004"
					( Origin gFrontEnd )
				)
				( attribute "PHYS_PAGE" "201"
					( Origin gFrontEnd )
				)
				( attribute "ROOM" "PVCCIN_CPU0_VR"
					( Origin gFrontEnd )
				)
				( attribute "ROT" "0"
					( Origin gFrontEnd )
				)
				( attribute "SEC" "1"
					( Origin gFrontEnd )
				)
				( attribute "SEC_TYPE" "0402V"
					( Origin gFrontEnd )
				)
				( attribute "TOLERANCE" "10%"
					( Origin gFrontEnd )
				)
				( attribute "VALUE" "1.0UF"
					( Origin gFrontEnd )
				)
				( attribute "VER" "1"
					( Origin gFrontEnd )
				)
				( attribute "VOLTAGE" "6.3V"
					( Units "uVoltage" "V" 1.000000)
					( Origin gFrontEnd )
				)
				( attribute "XY" "(-3550,3925)"
					( Origin gFrontEnd )
				)
				( attribute "CHIPS_PART_NAME" "CAP_A"
					( Origin gPackager )
				)
				( attribute "CDS_PART_NAME" "CAP_A_0402V-1.0UF,6.3V,10%,X6SA"
					( Origin gPackager )
				)
				( objectStatus "C4D15" )
			)
			( gate "@baseboard_fab2_lib.baseboard_fab2(sch_1):page201_i39"
				( attribute "CDS_LIB" "dev_discrete"
					( Origin gPackager )
				)
				( attribute "CDS_LOCATION" "C4D19"
					( Origin gPackager )
				)
				( attribute "CDS_SEC" "1"
					( Origin gPackager )
				)
				( attribute "LOCATION" "C4D19"
					( Origin gFrontEnd )
				)
				( attribute "MATERIAL" "X7R"
					( Origin gFrontEnd )
				)
				( attribute "PACK_TYPE" "0402V"
					( Origin gFrontEnd )
				)
				( attribute "PART_NUMBER" "A36096-030"
					( Origin gFrontEnd )
				)
				( attribute "PHYS_PAGE" "201"
					( Origin gFrontEnd )
				)
				( attribute "ROOM" "PVCCIN_CPU0_VR"
					( Origin gFrontEnd )
				)
				( attribute "ROT" "0"
					( Origin gFrontEnd )
				)
				( attribute "SEC" "1"
					( Origin gFrontEnd )
				)
				( attribute "SEC_TYPE" "0402V"
					( Origin gFrontEnd )
				)
				( attribute "TOLERANCE" "10%"
					( Origin gFrontEnd )
				)
				( attribute "VALUE" "0.1UF"
					( Origin gFrontEnd )
				)
				( attribute "VER" "1"
					( Origin gFrontEnd )
				)
				( attribute "VOLTAGE" "16V"
					( Units "uVoltage" "V" 1.000000)
					( Origin gFrontEnd )
				)
				( attribute "XY" "(-3950,3925)"
					( Origin gFrontEnd )
				)
				( attribute "CHIPS_PART_NAME" "CAP_A"
					( Origin gPackager )
				)
				( attribute "CDS_PART_NAME" "CAP_A_0402V-0.1UF,16V,10%,X7R,A"
					( Origin gPackager )
				)
				( objectStatus "C4D19" )
			)
			( gate "@baseboard_fab2_lib.baseboard_fab2(sch_1):page201_i40"
				( attribute "CDS_LIB" "mstr_discrete"
					( Origin gPackager )
				)
				( attribute "CDS_LOCATION" "R4D26"
					( Origin gPackager )
				)
				( attribute "CDS_SEC" "1"
					( Origin gPackager )
				)
				( attribute "LOCATION" "R4D26"
					( Origin gFrontEnd )
				)
				( attribute "MATERIAL" "CHIP"
					( Origin gFrontEnd )
				)
				( attribute "PACK_TYPE" "0402"
					( Origin gFrontEnd )
				)
				( attribute "PART_NUMBER" "G21497-005"
					( Origin gFrontEnd )
				)
				( attribute "PHYS_PAGE" "201"
					( Origin gFrontEnd )
				)
				( attribute "ROOM" "PVCCIN_CPU0_VR"
					( Origin gFrontEnd )
				)
				( attribute "ROT" "0"
					( Origin gFrontEnd )
				)
				( attribute "SEC" "1"
					( Origin gFrontEnd )
				)
				( attribute "SEC_TYPE" "0402"
					( Origin gFrontEnd )
				)
				( attribute "TOLERANCE" "5%"
					( Origin gFrontEnd )
				)
				( attribute "VALUE" "0.0"
					( Origin gFrontEnd )
				)
				( attribute "VER" "2"
					( Origin gFrontEnd )
				)
				( attribute "WATTAGE" "1/16W"
					( Origin gFrontEnd )
				)
				( attribute "XY" "(-4250,4275)"
					( Origin gFrontEnd )
				)
				( attribute "CHIPS_PART_NAME" "RES"
					( Origin gPackager )
				)
				( attribute "CDS_PART_NAME" "RES_0402-0.0,5%,1/16W,CHIP,G21A"
					( Origin gPackager )
				)
				( objectStatus "R4D26" )
			)
			( gate "@baseboard_fab2_lib.baseboard_fab2(sch_1):page211_i99"
				( attribute "CDS_LIB" "mstr_discrete"
					( Origin gPackager )
				)
				( attribute "CDS_LOCATION" "R3P17"
					( Origin gPackager )
				)
				( attribute "CDS_SEC" "1"
					( Origin gPackager )
				)
				( attribute "LOCATION" "R3P17"
					( Origin gFrontEnd )
				)
				( attribute "MATERIAL" "CHIP"
					( Origin gFrontEnd )
				)
				( attribute "PACK_TYPE" "0402"
					( Origin gFrontEnd )
				)
				( attribute "PART_NUMBER" "G21796-047"
					( Origin gFrontEnd )
				)
				( attribute "PHYS_PAGE" "211"
					( Origin gFrontEnd )
				)
				( attribute "ROOM" "PVCCIN_CPU0_VR"
					( Origin gFrontEnd )
				)
				( attribute "ROT" "0"
					( Origin gFrontEnd )
				)
				( attribute "SEC" "1"
					( Origin gFrontEnd )
				)
				( attribute "SEC_TYPE" "0402"
					( Origin gFrontEnd )
				)
				( attribute "TOLERANCE" "1%"
					( Origin gFrontEnd )
				)
				( attribute "VALUE" "49.9"
					( Origin gFrontEnd )
				)
				( attribute "VER" "2"
					( Origin gFrontEnd )
				)
				( attribute "WATTAGE" "1/16W"
					( Origin gFrontEnd )
				)
				( attribute "XY" "(-2125,4525)"
					( Origin gFrontEnd )
				)
				( attribute "CHIPS_PART_NAME" "RES"
					( Origin gPackager )
				)
				( attribute "CDS_PART_NAME" "RES_0402-49.9,1%,1/16W,CHIP,G2A"
					( Origin gPackager )
				)
				( objectStatus "R3P17" )
			)
			( gate "@baseboard_fab2_lib.baseboard_fab2(sch_1):page201_i54"
				( attribute "CDS_LIB" "mstr_discrete"
					( Origin gPackager )
				)
				( attribute "CDS_LOCATION" "R4D27"
					( Origin gPackager )
				)
				( attribute "CDS_SEC" "1"
					( Origin gPackager )
				)
				( attribute "LOCATION" "R4D27"
					( Origin gFrontEnd )
				)
				( attribute "MATERIAL" "CHIP"
					( Origin gFrontEnd )
				)
				( attribute "PACK_TYPE" "0402"
					( Origin gFrontEnd )
				)
				( attribute "PART_NUMBER" "G21796-160"
					( Origin gFrontEnd )
				)
				( attribute "PHYS_PAGE" "201"
					( Origin gFrontEnd )
				)
				( attribute "ROOM" "PVCCIN_CPU0_VR"
					( Origin gFrontEnd )
				)
				( attribute "ROT" "0"
					( Origin gFrontEnd )
				)
				( attribute "SEC" "1"
					( Origin gFrontEnd )
				)
				( attribute "SEC_TYPE" "0402"
					( Origin gFrontEnd )
				)
				( attribute "TOLERANCE" "1%"
					( Origin gFrontEnd )
				)
				( attribute "VALUE" "100.0K"
					( Origin gFrontEnd )
				)
				( attribute "VER" "2"
					( Origin gFrontEnd )
				)
				( attribute "WATTAGE" "1/16W"
					( Origin gFrontEnd )
				)
				( attribute "XY" "(-6050,4625)"
					( Origin gFrontEnd )
				)
				( attribute "CHIPS_PART_NAME" "RES"
					( Origin gPackager )
				)
				( attribute "CDS_PART_NAME" "RES_0402-100.0K,1%,1/16W,CHIP,B"
					( Origin gPackager )
				)
				( objectStatus "R4D27" )
			)
			( gate "@baseboard_fab2_lib.baseboard_fab2(sch_1):page201_i55"
				( attribute "CDS_LIB" "mstr_discrete"
					( Origin gPackager )
				)
				( attribute "CDS_LOCATION" "R4D32"
					( Origin gPackager )
				)
				( attribute "CDS_SEC" "1"
					( Origin gPackager )
				)
				( attribute "LOCATION" "R4D32"
					( Origin gFrontEnd )
				)
				( attribute "MATERIAL" "CHIP"
					( Origin gFrontEnd )
				)
				( attribute "PACK_TYPE" "0402"
					( Origin gFrontEnd )
				)
				( attribute "PART_NUMBER" "G21796-003"
					( Origin gFrontEnd )
				)
				( attribute "PHYS_PAGE" "201"
					( Origin gFrontEnd )
				)
				( attribute "ROOM" "PVCCIN_CPU0_VR"
					( Origin gFrontEnd )
				)
				( attribute "ROT" "0"
					( Origin gFrontEnd )
				)
				( attribute "SEC" "1"
					( Origin gFrontEnd )
				)
				( attribute "SEC_TYPE" "0402"
					( Origin gFrontEnd )
				)
				( attribute "TOLERANCE" "1%"
					( Origin gFrontEnd )
				)
				( attribute "VALUE" "1.5K"
					( Origin gFrontEnd )
				)
				( attribute "VER" "2"
					( Origin gFrontEnd )
				)
				( attribute "WATTAGE" "1/16W"
					( Origin gFrontEnd )
				)
				( attribute "XY" "(-6050,4200)"
					( Origin gFrontEnd )
				)
				( attribute "CHIPS_PART_NAME" "RES"
					( Origin gPackager )
				)
				( attribute "CDS_PART_NAME" "RES_0402-1.5K,1%,1/16W,CHIP,G2A"
					( Origin gPackager )
				)
				( objectStatus "R4D32" )
			)
			( gate "@baseboard_fab2_lib.baseboard_fab2(sch_1):page201_i56"
				( attribute "CDS_LIB" "mstr_discrete"
					( Origin gPackager )
				)
				( attribute "CDS_LOCATION" "R4E6"
					( Origin gPackager )
				)
				( attribute "CDS_SEC" "1"
					( Origin gPackager )
				)
				( attribute "LOCATION" "R4E6"
					( Origin gFrontEnd )
				)
				( attribute "MATERIAL" "CHIP"
					( Origin gFrontEnd )
				)
				( attribute "PACK_TYPE" "0402"
					( Origin gFrontEnd )
				)
				( attribute "PART_NUMBER" "G21796-009"
					( Origin gFrontEnd )
				)
				( attribute "PHYS_PAGE" "201"
					( Origin gFrontEnd )
				)
				( attribute "ROOM" "PVCCIN_CPU0_VR"
					( Origin gFrontEnd )
				)
				( attribute "ROT" "0"
					( Origin gFrontEnd )
				)
				( attribute "SEC" "1"
					( Origin gFrontEnd )
				)
				( attribute "SEC_TYPE" "0402"
					( Origin gFrontEnd )
				)
				( attribute "TOLERANCE" "1%"
					( Origin gFrontEnd )
				)
				( attribute "VALUE" "150.0"
					( Origin gFrontEnd )
				)
				( attribute "VER" "1"
					( Origin gFrontEnd )
				)
				( attribute "WATTAGE" "1/16W"
					( Origin gFrontEnd )
				)
				( attribute "XY" "(-5400,3950)"
					( Origin gFrontEnd )
				)
				( attribute "CHIPS_PART_NAME" "RES"
					( Origin gPackager )
				)
				( attribute "CDS_PART_NAME" "RES_0402-150.0,1%,1/16W,CHIP,GA"
					( Origin gPackager )
				)
				( objectStatus "R4E6" )
			)
			( gate "@baseboard_fab2_lib.baseboard_fab2(sch_1):page206_i156"
				( attribute "BOM_COST" "SM_THERM"
					( Origin gFrontEnd )
				)
				( attribute "CDS_LIB" "dev_discrete"
					( Origin gPackager )
				)
				( attribute "CDS_LOCATION" "C1C8"
					( Origin gPackager )
				)
				( attribute "CDS_SEC" "1"
					( Origin gPackager )
				)
				( attribute "LOCATION" "C1C8"
					( Origin gFrontEnd )
				)
				( attribute "MATERIAL" "X7R"
					( Origin gFrontEnd )
				)
				( attribute "PACK_TYPE" "0402V"
					( Origin gFrontEnd )
				)
				( attribute "PART_NUMBER" "A36096-030"
					( Origin gFrontEnd )
				)
				( attribute "PHYS_PAGE" "206"
					( Origin gFrontEnd )
				)
				( attribute "ROOM" "CPU_FANS"
					( Origin gFrontEnd )
				)
				( attribute "ROT" "0"
					( Origin gFrontEnd )
				)
				( attribute "SEC" "1"
					( Origin gFrontEnd )
				)
				( attribute "SEC_TYPE" "0402V"
					( Origin gFrontEnd )
				)
				( attribute "TOLERANCE" "10%"
					( Origin gFrontEnd )
				)
				( attribute "VALUE" "0.1UF"
					( Origin gFrontEnd )
				)
				( attribute "VER" "1"
					( Origin gFrontEnd )
				)
				( attribute "VOLTAGE" "16V"
					( Units "uVoltage" "V" 1.000000)
					( Origin gFrontEnd )
				)
				( attribute "XY" "(-6750,4200)"
					( Origin gFrontEnd )
				)
				( attribute "CHIPS_PART_NAME" "CAP_A"
					( Origin gPackager )
				)
				( attribute "CDS_PART_NAME" "CAP_A_0402V-0.1UF,16V,10%,X7R,A"
					( Origin gPackager )
				)
				( objectStatus "C1C8" )
			)
			( gate "@baseboard_fab2_lib.baseboard_fab2(sch_1):page201_i64"
				( attribute "CDS_LIB" "mstr_discrete"
					( Origin gPackager )
				)
				( attribute "CDS_LOCATION" "C4D29"
					( Origin gPackager )
				)
				( attribute "CDS_SEC" "1"
					( Origin gPackager )
				)
				( attribute "LOCATION" "C4D29"
					( Origin gFrontEnd )
				)
				( attribute "MATERIAL" "X7R"
					( Origin gFrontEnd )
				)
				( attribute "NO_XNET_CONNECTION" "1"
					( Origin gFrontEnd )
				)
				( attribute "PACK_TYPE" "0402LF"
					( Origin gFrontEnd )
				)
				( attribute "PART_NUMBER" "A36096-050"
					( Origin gFrontEnd )
				)
				( attribute "PHYS_PAGE" "201"
					( Origin gFrontEnd )
				)
				( attribute "ROOM" "PVCCIN_CPU0_VR"
					( Origin gFrontEnd )
				)
				( attribute "ROT" "0"
					( Origin gFrontEnd )
				)
				( attribute "SEC" "1"
					( Origin gFrontEnd )
				)
				( attribute "SEC_TYPE" "0402LF"
					( Origin gFrontEnd )
				)
				( attribute "TOLERANCE" "10%"
					( Origin gFrontEnd )
				)
				( attribute "VALUE" "220PF"
					( Origin gFrontEnd )
				)
				( attribute "VER" "1"
					( Origin gFrontEnd )
				)
				( attribute "VOLTAGE" "50V"
					( Units "uVoltage" "V" 1.000000)
					( Origin gFrontEnd )
				)
				( attribute "XY" "(-5550,2075)"
					( Origin gFrontEnd )
				)
				( attribute "CHIPS_PART_NAME" "CAP"
					( Origin gPackager )
				)
				( attribute "CDS_PART_NAME" "CAP_0402LF-220PF,50V,10%,X7R,AA"
					( Origin gPackager )
				)
				( objectStatus "C4D29" )
			)
			( gate "@baseboard_fab2_lib.baseboard_fab2(sch_1):page201_i66"
				( attribute "CDS_LIB" "mstr_discrete"
					( Origin gPackager )
				)
				( attribute "CDS_LOCATION" "C4D17"
					( Origin gPackager )
				)
				( attribute "CDS_SEC" "1"
					( Origin gPackager )
				)
				( attribute "LOCATION" "C4D17"
					( Origin gFrontEnd )
				)
				( attribute "MATERIAL" "X7R"
					( Origin gFrontEnd )
				)
				( attribute "PACK_TYPE" "0402LF"
					( Origin gFrontEnd )
				)
				( attribute "PART_NUMBER" "A36096-050"
					( Origin gFrontEnd )
				)
				( attribute "PHYS_PAGE" "201"
					( Origin gFrontEnd )
				)
				( attribute "ROOM" "PVCCIN_CPU0_VR"
					( Origin gFrontEnd )
				)
				( attribute "ROT" "0"
					( Origin gFrontEnd )
				)
				( attribute "SEC" "1"
					( Origin gFrontEnd )
				)
				( attribute "SEC_TYPE" "0402LF"
					( Origin gFrontEnd )
				)
				( attribute "TOLERANCE" "10%"
					( Origin gFrontEnd )
				)
				( attribute "VALUE" "220PF"
					( Origin gFrontEnd )
				)
				( attribute "VER" "1"
					( Origin gFrontEnd )
				)
				( attribute "VOLTAGE" "50V"
					( Units "uVoltage" "V" 1.000000)
					( Origin gFrontEnd )
				)
				( attribute "XY" "(-5425,1275)"
					( Origin gFrontEnd )
				)
				( attribute "CHIPS_PART_NAME" "CAP"
					( Origin gPackager )
				)
				( attribute "CDS_PART_NAME" "CAP_0402LF-220PF,50V,10%,X7R,AA"
					( Origin gPackager )
				)
				( objectStatus "C4D17" )
			)
			( gate "@baseboard_fab2_lib.baseboard_fab2(sch_1):page201_i68"
				( attribute "CDS_LIB" "mstr_discrete"
					( Origin gPackager )
				)
				( attribute "CDS_LOCATION" "C4D18"
					( Origin gPackager )
				)
				( attribute "CDS_SEC" "1"
					( Origin gPackager )
				)
				( attribute "LOCATION" "C4D18"
					( Origin gFrontEnd )
				)
				( attribute "MATERIAL" "X7R"
					( Origin gFrontEnd )
				)
				( attribute "PACK_TYPE" "0402LF"
					( Origin gFrontEnd )
				)
				( attribute "PART_NUMBER" "A36096-050"
					( Origin gFrontEnd )
				)
				( attribute "PHYS_PAGE" "201"
					( Origin gFrontEnd )
				)
				( attribute "ROOM" "PVCCIN_CPU0_VR"
					( Origin gFrontEnd )
				)
				( attribute "ROT" "2"
					( Origin gFrontEnd )
				)
				( attribute "SEC" "1"
					( Origin gFrontEnd )
				)
				( attribute "SEC_TYPE" "0402LF"
					( Origin gFrontEnd )
				)
				( attribute "TOLERANCE" "10%"
					( Origin gFrontEnd )
				)
				( attribute "VALUE" "220PF"
					( Origin gFrontEnd )
				)
				( attribute "VER" "1"
					( Origin gFrontEnd )
				)
				( attribute "VOLTAGE" "50V"
					( Units "uVoltage" "V" 1.000000)
					( Origin gFrontEnd )
				)
				( attribute "XY" "(-5125,1000)"
					( Origin gFrontEnd )
				)
				( attribute "CHIPS_PART_NAME" "CAP"
					( Origin gPackager )
				)
				( attribute "CDS_PART_NAME" "CAP_0402LF-220PF,50V,10%,X7R,AA"
					( Origin gPackager )
				)
				( objectStatus "C4D18" )
			)
			( gate "@baseboard_fab2_lib.baseboard_fab2(sch_1):page201_i70"
				( attribute "CDS_LIB" "mstr_discrete"
					( Origin gPackager )
				)
				( attribute "CDS_LOCATION" "C4D45"
					( Origin gPackager )
				)
				( attribute "CDS_SEC" "1"
					( Origin gPackager )
				)
				( attribute "LOCATION" "C4D45"
					( Origin gFrontEnd )
				)
				( attribute "MATERIAL" "X7R"
					( Origin gFrontEnd )
				)
				( attribute "NO_XNET_CONNECTION" "1"
					( Origin gFrontEnd )
				)
				( attribute "PACK_TYPE" "0402LF"
					( Origin gFrontEnd )
				)
				( attribute "PART_NUMBER" "A36096-050"
					( Origin gFrontEnd )
				)
				( attribute "PHYS_PAGE" "201"
					( Origin gFrontEnd )
				)
				( attribute "ROOM" "PVCCIN_CPU0_VR"
					( Origin gFrontEnd )
				)
				( attribute "ROT" "0"
					( Origin gFrontEnd )
				)
				( attribute "SEC" "1"
					( Origin gFrontEnd )
				)
				( attribute "SEC_TYPE" "0402LF"
					( Origin gFrontEnd )
				)
				( attribute "TOLERANCE" "10%"
					( Origin gFrontEnd )
				)
				( attribute "VALUE" "220PF"
					( Origin gFrontEnd )
				)
				( attribute "VER" "1"
					( Origin gFrontEnd )
				)
				( attribute "VOLTAGE" "50V"
					( Units "uVoltage" "V" 1.000000)
					( Origin gFrontEnd )
				)
				( attribute "XY" "(-6450,2375)"
					( Origin gFrontEnd )
				)
				( attribute "CHIPS_PART_NAME" "CAP"
					( Origin gPackager )
				)
				( attribute "CDS_PART_NAME" "CAP_0402LF-220PF,50V,10%,X7R,AA"
					( Origin gPackager )
				)
				( objectStatus "C4D45" )
			)
			( gate "@baseboard_fab2_lib.baseboard_fab2(sch_1):page201_i98"
				( attribute "CDS_LIB" "mstr_discrete"
					( Origin gPackager )
				)
				( attribute "CDS_LOCATION" "R4D66"
					( Origin gPackager )
				)
				( attribute "CDS_SEC" "1"
					( Origin gPackager )
				)
				( attribute "LOCATION" "R4D66"
					( Origin gFrontEnd )
				)
				( attribute "MATERIAL" "CHIP"
					( Origin gFrontEnd )
				)
				( attribute "PACK_TYPE" "0402"
					( Origin gFrontEnd )
				)
				( attribute "PART_NUMBER" "G21497-005"
					( Origin gFrontEnd )
				)
				( attribute "PHYS_PAGE" "201"
					( Origin gFrontEnd )
				)
				( attribute "ROOM" "PVCCIN_CPU0_VR"
					( Origin gFrontEnd )
				)
				( attribute "ROT" "0"
					( Origin gFrontEnd )
				)
				( attribute "SEC" "1"
					( Origin gFrontEnd )
				)
				( attribute "SEC_TYPE" "0402"
					( Origin gFrontEnd )
				)
				( attribute "TOLERANCE" "5%"
					( Origin gFrontEnd )
				)
				( attribute "VALUE" "0.0"
					( Origin gFrontEnd )
				)
				( attribute "VER" "1"
					( Origin gFrontEnd )
				)
				( attribute "WATTAGE" "1/16W"
					( Origin gFrontEnd )
				)
				( attribute "XY" "(-2400,2725)"
					( Origin gFrontEnd )
				)
				( attribute "CHIPS_PART_NAME" "RES"
					( Origin gPackager )
				)
				( attribute "CDS_PART_NAME" "RES_0402-0.0,5%,1/16W,CHIP,G21A"
					( Origin gPackager )
				)
				( objectStatus "R4D66" )
			)
			( gate "@baseboard_fab2_lib.baseboard_fab2(sch_1):page201_i102"
				( attribute "CDS_LIB" "mstr_discrete"
					( Origin gPackager )
				)
				( attribute "CDS_LOCATION" "R6P32"
					( Origin gPackager )
				)
				( attribute "LOCATION" "R6P32"
					( Origin gFrontEnd )
				)
				( attribute "MATERIAL" "EMPTY"
					( Origin gFrontEnd )
				)
				( attribute "PACK_TYPE" "0402"
					( Origin gFrontEnd )
				)
				( attribute "PART_NUMBER" "G21796-001"
					( Origin gFrontEnd )
				)
				( attribute "PHYS_PAGE" "201"
					( Origin gFrontEnd )
				)
				( attribute "ROOM" "PVCCIN_CPU0_VR"
					( Origin gFrontEnd )
				)
				( attribute "ROT" "0"
					( Origin gFrontEnd )
				)
				( attribute "SEC" "1"
					( Origin gFrontEnd )
				)
				( attribute "TOLERANCE" "1%"
					( Origin gFrontEnd )
				)
				( attribute "VALUE" "2.0K"
					( Origin gFrontEnd )
				)
				( attribute "VER" "2"
					( Origin gFrontEnd )
				)
				( attribute "WATTAGE" "1/16W"
					( Origin gFrontEnd )
				)
				( attribute "XY" "(-1100,2000)"
					( Origin gFrontEnd )
				)
				( attribute "CHIPS_PART_NAME" "RES"
					( Origin gPackager )
				)
				( attribute "CDS_PART_NAME" "RES_0402-2.0K,1%,1/16W,EMPTY,GA"
					( Origin gPackager )
				)
				( attribute "SEC_TYPE" "0402"
					( Origin gFrontEnd )
				)
				( attribute "CDS_SEC" "1"
					( Origin gPackager )
				)
				( objectStatus "R6P32" )
			)
			( gate "@baseboard_fab2_lib.baseboard_fab2(sch_1):page201_i103"
				( attribute "CDS_LIB" "mstr_discrete"
					( Origin gPackager )
				)
				( attribute "CDS_LOCATION" "R6P37"
					( Origin gPackager )
				)
				( attribute "LOCATION" "R6P37"
					( Origin gFrontEnd )
				)
				( attribute "MATERIAL" "EMPTY"
					( Origin gFrontEnd )
				)
				( attribute "PACK_TYPE" "0402"
					( Origin gFrontEnd )
				)
				( attribute "PART_NUMBER" "G21796-001"
					( Origin gFrontEnd )
				)
				( attribute "PHYS_PAGE" "201"
					( Origin gFrontEnd )
				)
				( attribute "ROOM" "PVCCIN_CPU0_VR"
					( Origin gFrontEnd )
				)
				( attribute "ROT" "0"
					( Origin gFrontEnd )
				)
				( attribute "SEC" "1"
					( Origin gFrontEnd )
				)
				( attribute "TOLERANCE" "1%"
					( Origin gFrontEnd )
				)
				( attribute "VALUE" "2.0K"
					( Origin gFrontEnd )
				)
				( attribute "VER" "2"
					( Origin gFrontEnd )
				)
				( attribute "WATTAGE" "1/16W"
					( Origin gFrontEnd )
				)
				( attribute "XY" "(-825,2000)"
					( Origin gFrontEnd )
				)
				( attribute "CHIPS_PART_NAME" "RES"
					( Origin gPackager )
				)
				( attribute "CDS_PART_NAME" "RES_0402-2.0K,1%,1/16W,EMPTY,GA"
					( Origin gPackager )
				)
				( attribute "SEC_TYPE" "0402"
					( Origin gFrontEnd )
				)
				( attribute "CDS_SEC" "1"
					( Origin gPackager )
				)
				( objectStatus "R6P37" )
			)
			( gate "@baseboard_fab2_lib.baseboard_fab2(sch_1):page201_i109"
				( attribute "CDS_LIB" "mstr_discrete"
					( Origin gPackager )
				)
				( attribute "CDS_LOCATION" "R4E8"
					( Origin gPackager )
				)
				( attribute "CDS_SEC" "1"
					( Origin gPackager )
				)
				( attribute "LOCATION" "R4E8"
					( Origin gFrontEnd )
				)
				( attribute "MATERIAL" "CHIP"
					( Origin gFrontEnd )
				)
				( attribute "NO_XNET_CONNECTION" "1"
					( Origin gFrontEnd )
				)
				( attribute "PACK_TYPE" "0402"
					( Origin gFrontEnd )
				)
				( attribute "PART_NUMBER" "G21796-066"
					( Origin gFrontEnd )
				)
				( attribute "PHYS_PAGE" "201"
					( Origin gFrontEnd )
				)
				( attribute "ROOM" "PVCCIN_CPU0_VR"
					( Origin gFrontEnd )
				)
				( attribute "ROT" "0"
					( Origin gFrontEnd )
				)
				( attribute "SEC" "1"
					( Origin gFrontEnd )
				)
				( attribute "SEC_TYPE" "0402"
					( Origin gFrontEnd )
				)
				( attribute "TOLERANCE" "1%"
					( Origin gFrontEnd )
				)
				( attribute "VALUE" "10.0"
					( Origin gFrontEnd )
				)
				( attribute "VER" "1"
					( Origin gFrontEnd )
				)
				( attribute "WATTAGE" "1/16W"
					( Origin gFrontEnd )
				)
				( attribute "XY" "(-6675,2525)"
					( Origin gFrontEnd )
				)
				( attribute "CHIPS_PART_NAME" "RES"
					( Origin gPackager )
				)
				( attribute "CDS_PART_NAME" "RES_0402-10.0,1%,1/16W,CHIP,G2A"
					( Origin gPackager )
				)
				( objectStatus "R4E8" )
			)
			( gate "@baseboard_fab2_lib.baseboard_fab2(sch_1):page201_i110"
				( attribute "CDS_LIB" "mstr_discrete"
					( Origin gPackager )
				)
				( attribute "CDS_LOCATION" "R4D39"
					( Origin gPackager )
				)
				( attribute "CDS_SEC" "1"
					( Origin gPackager )
				)
				( attribute "LOCATION" "R4D39"
					( Origin gFrontEnd )
				)
				( attribute "MATERIAL" "CHIP"
					( Origin gFrontEnd )
				)
				( attribute "NO_XNET_CONNECTION" "1"
					( Origin gFrontEnd )
				)
				( attribute "PACK_TYPE" "0402"
					( Origin gFrontEnd )
				)
				( attribute "PART_NUMBER" "G21796-066"
					( Origin gFrontEnd )
				)
				( attribute "PHYS_PAGE" "201"
					( Origin gFrontEnd )
				)
				( attribute "ROOM" "PVCCIN_CPU0_VR"
					( Origin gFrontEnd )
				)
				( attribute "ROT" "0"
					( Origin gFrontEnd )
				)
				( attribute "SEC" "1"
					( Origin gFrontEnd )
				)
				( attribute "SEC_TYPE" "0402"
					( Origin gFrontEnd )
				)
				( attribute "TOLERANCE" "1%"
					( Origin gFrontEnd )
				)
				( attribute "VALUE" "10.0"
					( Origin gFrontEnd )
				)
				( attribute "VER" "1"
					( Origin gFrontEnd )
				)
				( attribute "WATTAGE" "1/16W"
					( Origin gFrontEnd )
				)
				( attribute "XY" "(-6250,2075)"
					( Origin gFrontEnd )
				)
				( attribute "CHIPS_PART_NAME" "RES"
					( Origin gPackager )
				)
				( attribute "CDS_PART_NAME" "RES_0402-10.0,1%,1/16W,CHIP,G2A"
					( Origin gPackager )
				)
				( objectStatus "R4D39" )
			)
			( gate "@baseboard_fab2_lib.baseboard_fab2(sch_1):page201_i111"
				( attribute "CDS_LIB" "mstr_discrete"
					( Origin gPackager )
				)
				( attribute "CDS_LOCATION" "R4E3"
					( Origin gPackager )
				)
				( attribute "CDS_SEC" "1"
					( Origin gPackager )
				)
				( attribute "LOCATION" "R4E3"
					( Origin gFrontEnd )
				)
				( attribute "MATERIAL" "CHIP"
					( Origin gFrontEnd )
				)
				( attribute "PACK_TYPE" "0402"
					( Origin gFrontEnd )
				)
				( attribute "PART_NUMBER" "G21796-026"
					( Origin gFrontEnd )
				)
				( attribute "PHYS_PAGE" "201"
					( Origin gFrontEnd )
				)
				( attribute "ROOM" "PVCCIN_CPU0_VR"
					( Origin gFrontEnd )
				)
				( attribute "ROT" "2"
					( Origin gFrontEnd )
				)
				( attribute "SEC" "1"
					( Origin gFrontEnd )
				)
				( attribute "SEC_TYPE" "0402"
					( Origin gFrontEnd )
				)
				( attribute "TOLERANCE" "1%"
					( Origin gFrontEnd )
				)
				( attribute "VALUE" "1.00K"
					( Origin gFrontEnd )
				)
				( attribute "VER" "2"
					( Origin gFrontEnd )
				)
				( attribute "WATTAGE" "1/16W"
					( Origin gFrontEnd )
				)
				( attribute "XY" "(-3050,4125)"
					( Origin gFrontEnd )
				)
				( attribute "CHIPS_PART_NAME" "RES"
					( Origin gPackager )
				)
				( attribute "CDS_PART_NAME" "RES_0402-1.00K,1%,1/16W,CHIP,GA"
					( Origin gPackager )
				)
				( objectStatus "R4E3" )
			)
			( gate "@baseboard_fab2_lib.baseboard_fab2(sch_1):page201_i116"
				( attribute "CDS_LIB" "mstr_discrete"
					( Origin gPackager )
				)
				( attribute "CDS_LOCATION" "R4E20"
					( Origin gPackager )
				)
				( attribute "CDS_SEC" "1"
					( Origin gPackager )
				)
				( attribute "LOCATION" "R4E20"
					( Origin gFrontEnd )
				)
				( attribute "MATERIAL" "EMPTY"
					( Origin gFrontEnd )
				)
				( attribute "PACK_TYPE" "0402"
					( Origin gFrontEnd )
				)
				( attribute "PART_NUMBER" "G21796-311"
					( Origin gFrontEnd )
				)
				( attribute "PHYS_PAGE" "201"
					( Origin gFrontEnd )
				)
				( attribute "ROOM" "PVCCIN_CPU0_VR"
					( Origin gFrontEnd )
				)
				( attribute "ROT" "0"
					( Origin gFrontEnd )
				)
				( attribute "SEC" "1"
					( Origin gFrontEnd )
				)
				( attribute "SEC_TYPE" "0402"
					( Origin gFrontEnd )
				)
				( attribute "TOLERANCE" "1.0%"
					( Origin gFrontEnd )
				)
				( attribute "VALUE" "2.26K"
					( Origin gFrontEnd )
				)
				( attribute "VER" "2"
					( Origin gFrontEnd )
				)
				( attribute "WATTAGE" "1/16W"
					( Origin gFrontEnd )
				)
				( attribute "XY" "(-1575,4200)"
					( Origin gFrontEnd )
				)
				( attribute "CHIPS_PART_NAME" "RES"
					( Origin gPackager )
				)
				( attribute "CDS_PART_NAME" "RES_0402-2.26K,1.0%,1/16W,EMPTA"
					( Origin gPackager )
				)
				( objectStatus "R4E20" )
			)
			( gate "@baseboard_fab2_lib.baseboard_fab2(sch_1):page201_i120"
				( attribute "CDS_LIB" "mstr_discrete"
					( Origin gPackager )
				)
				( attribute "CDS_LOCATION" "R6P27"
					( Origin gPackager )
				)
				( attribute "CDS_SEC" "1"
					( Origin gPackager )
				)
				( attribute "LOCATION" "R6P27"
					( Origin gFrontEnd )
				)
				( attribute "MATERIAL" "CHIP"
					( Origin gFrontEnd )
				)
				( attribute "PACK_TYPE" "0402"
					( Origin gFrontEnd )
				)
				( attribute "PART_NUMBER" "G21796-082"
					( Origin gFrontEnd )
				)
				( attribute "PHYS_PAGE" "201"
					( Origin gFrontEnd )
				)
				( attribute "ROOM" "PVCCIN_CPU0_VR"
					( Origin gFrontEnd )
				)
				( attribute "ROT" "0"
					( Origin gFrontEnd )
				)
				( attribute "SEC" "1"
					( Origin gFrontEnd )
				)
				( attribute "SEC_TYPE" "0402"
					( Origin gFrontEnd )
				)
				( attribute "TOLERANCE" "1%"
					( Origin gFrontEnd )
				)
				( attribute "VALUE" "4.02K"
					( Origin gFrontEnd )
				)
				( attribute "VER" "2"
					( Origin gFrontEnd )
				)
				( attribute "WATTAGE" "1/16W"
					( Origin gFrontEnd )
				)
				( attribute "XY" "(-4400,900)"
					( Origin gFrontEnd )
				)
				( attribute "CHIPS_PART_NAME" "RES"
					( Origin gPackager )
				)
				( attribute "CDS_PART_NAME" "RES_0402-4.02K,1%,1/16W,CHIP,GA"
					( Origin gPackager )
				)
				( objectStatus "R6P27" )
			)
			( gate "@baseboard_fab2_lib.baseboard_fab2(sch_1):page201_i121"
				( attribute "CDS_LIB" "mstr_discrete"
					( Origin gPackager )
				)
				( attribute "CDS_LOCATION" "R6P28"
					( Origin gPackager )
				)
				( attribute "CDS_SEC" "1"
					( Origin gPackager )
				)
				( attribute "LOCATION" "R6P28"
					( Origin gFrontEnd )
				)
				( attribute "MATERIAL" "CHIP"
					( Origin gFrontEnd )
				)
				( attribute "PACK_TYPE" "0402"
					( Origin gFrontEnd )
				)
				( attribute "PART_NUMBER" "G21796-082"
					( Origin gFrontEnd )
				)
				( attribute "PHYS_PAGE" "201"
					( Origin gFrontEnd )
				)
				( attribute "ROOM" "PVCCIN_CPU0_VR"
					( Origin gFrontEnd )
				)
				( attribute "ROT" "0"
					( Origin gFrontEnd )
				)
				( attribute "SEC" "1"
					( Origin gFrontEnd )
				)
				( attribute "SEC_TYPE" "0402"
					( Origin gFrontEnd )
				)
				( attribute "TOLERANCE" "1%"
					( Origin gFrontEnd )
				)
				( attribute "VALUE" "4.02K"
					( Origin gFrontEnd )
				)
				( attribute "VER" "2"
					( Origin gFrontEnd )
				)
				( attribute "WATTAGE" "1/16W"
					( Origin gFrontEnd )
				)
				( attribute "XY" "(-4725,900)"
					( Origin gFrontEnd )
				)
				( attribute "CHIPS_PART_NAME" "RES"
					( Origin gPackager )
				)
				( attribute "CDS_PART_NAME" "RES_0402-4.02K,1%,1/16W,CHIP,GA"
					( Origin gPackager )
				)
				( objectStatus "R6P28" )
			)
			( gate "@baseboard_fab2_lib.baseboard_fab2(sch_1):page201_i124"
				( attribute "CDS_LIB" "mstr_discrete"
					( Origin gPackager )
				)
				( attribute "CDS_LOCATION" "R4D63"
					( Origin gPackager )
				)
				( attribute "LOCATION" "R4D63"
					( Origin gFrontEnd )
				)
				( attribute "MATERIAL" "CHIP"
					( Origin gFrontEnd )
				)
				( attribute "PACK_TYPE" "0402"
					( Origin gFrontEnd )
				)
				( attribute "PART_NUMBER" "G21796-250"
					( Origin gFrontEnd )
				)
				( attribute "PHYS_PAGE" "201"
					( Origin gFrontEnd )
				)
				( attribute "ROOM" "PVCCIN_CPU0_VR"
					( Origin gFrontEnd )
				)
				( attribute "ROT" "0"
					( Origin gFrontEnd )
				)
				( attribute "SEC" "1"
					( Origin gFrontEnd )
				)
				( attribute "TOLERANCE" "1.0%"
					( Origin gFrontEnd )
				)
				( attribute "VALUE" "22.1"
					( Origin gFrontEnd )
				)
				( attribute "VER" "1"
					( Origin gFrontEnd )
				)
				( attribute "WATTAGE" "1/16W"
					( Origin gFrontEnd )
				)
				( attribute "XY" "(-1125,3325)"
					( Origin gFrontEnd )
				)
				( attribute "CHIPS_PART_NAME" "RES"
					( Origin gPackager )
				)
				( attribute "CDS_PART_NAME" "RES_0402-22.1,1.0%,1/16W,CHIP,A"
					( Origin gPackager )
				)
				( attribute "SEC_TYPE" "0402"
					( Origin gFrontEnd )
				)
				( attribute "CDS_SEC" "1"
					( Origin gPackager )
				)
				( objectStatus "R4D63" )
			)
			( gate "@baseboard_fab2_lib.baseboard_fab2(sch_1):page201_i125"
				( attribute "CDS_LIB" "mstr_discrete"
					( Origin gPackager )
				)
				( attribute "CDS_LOCATION" "C4D42"
					( Origin gPackager )
				)
				( attribute "CDS_SEC" "1"
					( Origin gPackager )
				)
				( attribute "LOCATION" "C4D42"
					( Origin gFrontEnd )
				)
				( attribute "MATERIAL" "X7R"
					( Origin gFrontEnd )
				)
				( attribute "PACK_TYPE" "0402LF"
					( Origin gFrontEnd )
				)
				( attribute "PART_NUMBER" "A36096-046"
					( Origin gFrontEnd )
				)
				( attribute "PHYS_PAGE" "201"
					( Origin gFrontEnd )
				)
				( attribute "ROOM" "PVCCIN_CPU0_VR"
					( Origin gFrontEnd )
				)
				( attribute "ROT" "0"
					( Origin gFrontEnd )
				)
				( attribute "SEC" "1"
					( Origin gFrontEnd )
				)
				( attribute "SEC_TYPE" "0402LF"
					( Origin gFrontEnd )
				)
				( attribute "TOLERANCE" "10%"
					( Origin gFrontEnd )
				)
				( attribute "VALUE" "1000PF"
					( Origin gFrontEnd )
				)
				( attribute "VER" "1"
					( Origin gFrontEnd )
				)
				( attribute "VOLTAGE" "50V"
					( Units "uVoltage" "V" 1.000000)
					( Origin gFrontEnd )
				)
				( attribute "XY" "(-1450,2075)"
					( Origin gFrontEnd )
				)
				( attribute "CHIPS_PART_NAME" "CAP"
					( Origin gPackager )
				)
				( attribute "CDS_PART_NAME" "CAP_0402LF-1000PF,50V,10%,X7R,A"
					( Origin gPackager )
				)
				( objectStatus "C4D42" )
			)
			( gate "@baseboard_fab2_lib.baseboard_fab2(sch_1):page201_i127"
				( attribute "CDS_LIB" "mstr_discrete"
					( Origin gPackager )
				)
				( attribute "CDS_LOCATION" "R4D65"
					( Origin gPackager )
				)
				( attribute "CDS_SEC" "1"
					( Origin gPackager )
				)
				( attribute "LOCATION" "R4D65"
					( Origin gFrontEnd )
				)
				( attribute "MATERIAL" "CHIP"
					( Origin gFrontEnd )
				)
				( attribute "PACK_TYPE" "0402"
					( Origin gFrontEnd )
				)
				( attribute "PART_NUMBER" "G21796-074"
					( Origin gFrontEnd )
				)
				( attribute "PHYS_PAGE" "201"
					( Origin gFrontEnd )
				)
				( attribute "ROT" "0"
					( Origin gFrontEnd )
				)
				( attribute "SEC" "1"
					( Origin gFrontEnd )
				)
				( attribute "SEC_TYPE" "0402"
					( Origin gFrontEnd )
				)
				( attribute "TOLERANCE" "1%"
					( Origin gFrontEnd )
				)
				( attribute "VALUE" "33.2"
					( Origin gFrontEnd )
				)
				( attribute "VER" "1"
					( Origin gFrontEnd )
				)
				( attribute "WATTAGE" "1/16W"
					( Origin gFrontEnd )
				)
				( attribute "XY" "(-1800,2675)"
					( Origin gFrontEnd )
				)
				( attribute "CHIPS_PART_NAME" "RES"
					( Origin gPackager )
				)
				( attribute "CDS_PART_NAME" "RES_0402-33.2,1%,1/16W,CHIP,G2A"
					( Origin gPackager )
				)
				( objectStatus "R4D65" )
			)
			( gate "@baseboard_fab2_lib.baseboard_fab2(sch_1):page201_i128"
				( attribute "CDS_LIB" "mstr_discrete"
					( Origin gPackager )
				)
				( attribute "CDS_LOCATION" "R6P45"
					( Origin gPackager )
				)
				( attribute "CDS_SEC" "1"
					( Origin gPackager )
				)
				( attribute "LOCATION" "R6P45"
					( Origin gFrontEnd )
				)
				( attribute "MATERIAL" "CHIP"
					( Origin gFrontEnd )
				)
				( attribute "PACK_TYPE" "0402"
					( Origin gFrontEnd )
				)
				( attribute "PART_NUMBER" "G21796-074"
					( Origin gFrontEnd )
				)
				( attribute "PHYS_PAGE" "201"
					( Origin gFrontEnd )
				)
				( attribute "ROT" "0"
					( Origin gFrontEnd )
				)
				( attribute "SEC" "1"
					( Origin gFrontEnd )
				)
				( attribute "SEC_TYPE" "0402"
					( Origin gFrontEnd )
				)
				( attribute "TOLERANCE" "1%"
					( Origin gFrontEnd )
				)
				( attribute "VALUE" "33.2"
					( Origin gFrontEnd )
				)
				( attribute "VER" "1"
					( Origin gFrontEnd )
				)
				( attribute "WATTAGE" "1/16W"
					( Origin gFrontEnd )
				)
				( attribute "XY" "(-2400,2975)"
					( Origin gFrontEnd )
				)
				( attribute "CHIPS_PART_NAME" "RES"
					( Origin gPackager )
				)
				( attribute "CDS_PART_NAME" "RES_0402-33.2,1%,1/16W,CHIP,G2A"
					( Origin gPackager )
				)
				( objectStatus "R6P45" )
			)
			( gate "@baseboard_fab2_lib.baseboard_fab2(sch_1):page201_i131"
				( attribute "CDS_LIB" "mstr_discrete"
					( Origin gPackager )
				)
				( attribute "CDS_LOCATION" "R6P18"
					( Origin gPackager )
				)
				( attribute "CDS_SEC" "1"
					( Origin gPackager )
				)
				( attribute "LOCATION" "R6P18"
					( Origin gFrontEnd )
				)
				( attribute "MATERIAL" "CHIP"
					( Origin gFrontEnd )
				)
				( attribute "PACK_TYPE" "0402"
					( Origin gFrontEnd )
				)
				( attribute "PART_NUMBER" "G21497-005"
					( Origin gFrontEnd )
				)
				( attribute "PHYS_PAGE" "201"
					( Origin gFrontEnd )
				)
				( attribute "ROOM" "PVCCIN_CPU0_VR"
					( Origin gFrontEnd )
				)
				( attribute "ROT" "0"
					( Origin gFrontEnd )
				)
				( attribute "SEC" "1"
					( Origin gFrontEnd )
				)
				( attribute "SEC_TYPE" "0402"
					( Origin gFrontEnd )
				)
				( attribute "TOLERANCE" "5%"
					( Origin gFrontEnd )
				)
				( attribute "VALUE" "0.0"
					( Origin gFrontEnd )
				)
				( attribute "VER" "1"
					( Origin gFrontEnd )
				)
				( attribute "WATTAGE" "1/16W"
					( Origin gFrontEnd )
				)
				( attribute "XY" "(-5100,2225)"
					( Origin gFrontEnd )
				)
				( attribute "CHIPS_PART_NAME" "RES"
					( Origin gPackager )
				)
				( attribute "CDS_PART_NAME" "RES_0402-0.0,5%,1/16W,CHIP,G21A"
					( Origin gPackager )
				)
				( objectStatus "R6P18" )
			)
			( gate "@baseboard_fab2_lib.baseboard_fab2(sch_1):page201_i132"
				( attribute "BOM_COST" "SM_CONTROLLER"
					( Origin gFrontEnd )
				)
				( attribute "CDS_LIB" "mstr_discrete"
					( Origin gPackager )
				)
				( attribute "CDS_LOCATION" "R6P16"
					( Origin gPackager )
				)
				( attribute "LOCATION" "R6P16"
					( Origin gFrontEnd )
				)
				( attribute "MATERIAL" "CHIP"
					( Origin gFrontEnd )
				)
				( attribute "PACK_TYPE" "0402"
					( Origin gFrontEnd )
				)
				( attribute "PART_NUMBER" "G21796-026"
					( Origin gFrontEnd )
				)
				( attribute "PHYS_PAGE" "201"
					( Origin gFrontEnd )
				)
				( attribute "ROOM" "BMC"
					( Origin gFrontEnd )
				)
				( attribute "ROT" "0"
					( Origin gFrontEnd )
				)
				( attribute "SEC" "1"
					( Origin gFrontEnd )
				)
				( attribute "TOLERANCE" "1%"
					( Origin gFrontEnd )
				)
				( attribute "VALUE" "1.00K"
					( Origin gFrontEnd )
				)
				( attribute "VER" "2"
					( Origin gFrontEnd )
				)
				( attribute "WATTAGE" "1/16W"
					( Origin gFrontEnd )
				)
				( attribute "XY" "(-4775,4350)"
					( Origin gFrontEnd )
				)
				( attribute "CHIPS_PART_NAME" "RES"
					( Origin gPackager )
				)
				( attribute "CDS_PART_NAME" "RES_0402-1.00K,1%,1/16W,CHIP,GA"
					( Origin gPackager )
				)
				( attribute "SEC_TYPE" "0402"
					( Origin gFrontEnd )
				)
				( attribute "CDS_SEC" "1"
					( Origin gPackager )
				)
				( objectStatus "R6P16" )
			)
			( gate "@baseboard_fab2_lib.baseboard_fab2(sch_1):page201_i155"
				( attribute "CDS_LIB" "mstr_controller"
					( Origin gPackager )
				)
				( attribute "CDS_LMAN_SYM_OUTLINE" "-400,900,400,-900"
					( Origin gPackager )
				)
				( attribute "CDS_LOCATION" "EU4D4"
					( Origin gPackager )
				)
				( attribute "CDS_SEC" "1"
					( Origin gPackager )
				)
				( attribute "LOCATION" "EU4D4"
					( Origin gFrontEnd )
				)
				( attribute "MATERIAL" "IC"
					( Origin gFrontEnd )
				)
				( attribute "PACK_TYPE" "QFN"
					( Origin gFrontEnd )
				)
				( attribute "PART_NUMBER" "H79206-001"
					( Origin gFrontEnd )
				)
				( attribute "PHYS_PAGE" "201"
					( Origin gFrontEnd )
				)
				( attribute "ROT" "0"
					( Origin gFrontEnd )
				)
				( attribute "SEC" "1"
					( Origin gPackager )
				)
				( attribute "VER" "1"
					( Origin gFrontEnd )
				)
				( attribute "XY" "(-3800,2575)"
					( Origin gFrontEnd )
				)
				( attribute "CHIPS_PART_NAME" "PXE1610B"
					( Origin gPackager )
				)
				( attribute "CDS_PART_NAME" "PXE1610B_QFN-IC,H79206-001"
					( Origin gPackager )
				)
				( objectStatus "EU4D4" )
			)
			( gate "@baseboard_fab2_lib.baseboard_fab2(sch_1):page202_i110"
				( attribute "CDS_LIB" "w_hdl"
					( Origin gPackager )
				)
				( attribute "CDS_LMAN_SYM_OUTLINE" "-75,100,75,-100"
					( Origin gPackager )
				)
				( attribute "LOCATION" "L4D3"
					( Origin gFrontEnd )
				)
				( attribute "PACK_TYPE" "DISCRET-GB2"
					( Origin gFrontEnd )
				)
				( attribute "PART_NUMBER" "068.1202N.M001"
					( Origin gFrontEnd )
				)
				( attribute "PHYS_PAGE" "202"
					( Origin gFrontEnd )
				)
				( attribute "ROT" "1"
					( Origin gFrontEnd )
				)
				( attribute "SEC" "1"
					( Origin gFrontEnd )
				)
				( attribute "SEC_TYPE" "DISCRET-GB2"
					( Origin gFrontEnd )
				)
				( attribute "VALUE" "IND-120NH-30-GP"
					( Origin gFrontEnd )
				)
				( attribute "VER" "1"
					( Origin gFrontEnd )
				)
				( attribute "XY" "(-1300,975)"
					( Origin gFrontEnd )
				)
				( attribute "CHIPS_PART_NAME" "IND-120NH-30-GP"
					( Origin gPackager )
				)
				( attribute "CDS_PART_NAME" "IND-120NH-30-GP_DISCRET-GB2-INA"
					( Origin gPackager )
				)
				( attribute "CDS_LOCATION" "L4D3"
					( Origin gPackager )
				)
				( attribute "CDS_SEC" "1"
					( Origin gPackager )
				)
				( attribute "ATTRIBUTE" "120NH"
					( Origin gFrontEnd )
				)
				( attribute "PACK_SIZE" "DCR=0.17MOHM"
					( Origin gFrontEnd )
				)
				( attribute "RATED" "ISAT=94A@25C"
					( Origin gFrontEnd )
				)
				( attribute "TYPE" "IRMS=66A@DELTA_T<40C"
					( Origin gFrontEnd )
				)
				( objectStatus "L4D3" )
			)
			( gate "@baseboard_fab2_lib.baseboard_fab2(sch_1):page202_i9"
				( attribute "BOM_COST" "PROC_VRD_VCCIN_CPU0"
					( Origin gFrontEnd )
				)
				( attribute "CDS_LIB" "dev_discrete"
					( Origin gPackager )
				)
				( attribute "CDS_LOCATION" "C6R7"
					( Origin gPackager )
				)
				( attribute "CDS_SEC" "1"
					( Origin gPackager )
				)
				( attribute "LOCATION" "C6R7"
					( Origin gFrontEnd )
				)
				( attribute "MATERIAL" "X6S"
					( Origin gFrontEnd )
				)
				( attribute "PACK_TYPE" "0603V"
					( Origin gFrontEnd )
				)
				( attribute "PART_NUMBER" "E15431-004"
					( Origin gFrontEnd )
				)
				( attribute "PHYS_PAGE" "202"
					( Origin gFrontEnd )
				)
				( attribute "ROOM" "PVCCIN_CPU0_PWR_VR"
					( Origin gFrontEnd )
				)
				( attribute "ROT" "0"
					( Origin gFrontEnd )
				)
				( attribute "SEC" "1"
					( Origin gFrontEnd )
				)
				( attribute "SEC_TYPE" "0603V"
					( Origin gFrontEnd )
				)
				( attribute "TOLERANCE" "20%"
					( Origin gFrontEnd )
				)
				( attribute "VALUE" "22.0UF"
					( Origin gFrontEnd )
				)
				( attribute "VER" "1"
					( Origin gFrontEnd )
				)
				( attribute "VOLTAGE" "4V"
					( Units "uVoltage" "V" 1.000000)
					( Origin gFrontEnd )
				)
				( attribute "XY" "(-1250,3300)"
					( Origin gFrontEnd )
				)
				( attribute "CHIPS_PART_NAME" "CAP_A"
					( Origin gPackager )
				)
				( attribute "CDS_PART_NAME" "CAP_A_0603V-22.0UF,4V,20%,X6S,A"
					( Origin gPackager )
				)
				( attribute "GROUP" "PWR_MLCC_CAP"
					( Origin gFrontEnd )
				)
				( objectStatus "C6R7" )
			)
			( gate "@baseboard_fab2_lib.baseboard_fab2(sch_1):page202_i18"
				( attribute "CDS_LIB" "mstr_discrete"
					( Origin gPackager )
				)
				( attribute "CDS_LOCATION" "C4E5"
					( Origin gPackager )
				)
				( attribute "CDS_SEC" "1"
					( Origin gPackager )
				)
				( attribute "LOCATION" "C4E5"
					( Origin gFrontEnd )
				)
				( attribute "MATERIAL" "X7R"
					( Origin gFrontEnd )
				)
				( attribute "PACK_TYPE" "0402"
					( Origin gFrontEnd )
				)
				( attribute "PART_NUMBER" "A36096-155"
					( Origin gFrontEnd )
				)
				( attribute "PHYS_PAGE" "202"
					( Origin gFrontEnd )
				)
				( attribute "ROOM" "PVCCIN_CPU0_PWR_VR"
					( Origin gFrontEnd )
				)
				( attribute "ROT" "0"
					( Origin gFrontEnd )
				)
				( attribute "SEC" "1"
					( Origin gFrontEnd )
				)
				( attribute "SEC_TYPE" "0402"
					( Origin gFrontEnd )
				)
				( attribute "TOLERANCE" "10%"
					( Origin gFrontEnd )
				)
				( attribute "VALUE" "0.22UF"
					( Origin gFrontEnd )
				)
				( attribute "VER" "1"
					( Origin gFrontEnd )
				)
				( attribute "VOLTAGE" "16V"
					( Units "uVoltage" "V" 1.000000)
					( Origin gFrontEnd )
				)
				( attribute "XY" "(-4900,4125)"
					( Origin gFrontEnd )
				)
				( attribute "CHIPS_PART_NAME" "CAP"
					( Origin gPackager )
				)
				( attribute "CDS_PART_NAME" "CAP_0402-0.22UF,16V,10%,X7R,A3A"
					( Origin gPackager )
				)
				( objectStatus "C4E5" )
			)
			( gate "@baseboard_fab2_lib.baseboard_fab2(sch_1):page219_i152"
				( attribute "CDS_LIB" "w_hdl"
					( Origin gPackager )
				)
				( attribute "CDS_LMAN_SYM_OUTLINE" "-50,25,50,-25"
					( Origin gPackager )
				)
				( attribute "LOCATION" "C7A26"
					( Origin gFrontEnd )
				)
				( attribute "PACK_TYPE" "SMD-BCG6"
					( Origin gFrontEnd )
				)
				( attribute "PART_NUMBER" "78.10523.8FL"
					( Origin gFrontEnd )
				)
				( attribute "PHYS_PAGE" "219"
					( Origin gFrontEnd )
				)
				( attribute "ROT" "0"
					( Origin gFrontEnd )
				)
				( attribute "SEC" "1"
					( Origin gFrontEnd )
				)
				( attribute "SEC_TYPE" "SMD-BCG6"
					( Origin gFrontEnd )
				)
				( attribute "VALUE" "SC1U10V2KX-4-GP"
					( Origin gFrontEnd )
				)
				( attribute "VER" "1"
					( Origin gFrontEnd )
				)
				( attribute "XY" "(-525,100)"
					( Origin gFrontEnd )
				)
				( attribute "CHIPS_PART_NAME" "SC1U10V2KX-4-GP"
					( Origin gPackager )
				)
				( attribute "CDS_PART_NAME" "SC1U10V2KX-4-GP_SMD-BCG6-SC1U1A"
					( Origin gPackager )
				)
				( attribute "CDS_LOCATION" "C7A26"
					( Origin gPackager )
				)
				( attribute "CDS_SEC" "1"
					( Origin gPackager )
				)
				( attribute "ATTRIBUTE" "1UF"
					( Origin gFrontEnd )
				)
				( attribute "PACK_SIZE" "0402"
					( Origin gFrontEnd )
				)
				( attribute "RATED" "10V"
					( Origin gFrontEnd )
				)
				( attribute "TOLERANCE" "10%"
					( Origin gFrontEnd )
				)
				( attribute "BOM_SS" "NOPOP"
					( Origin gFrontEnd )
				)
				( objectStatus "C7A26" )
			)
			( gate "@baseboard_fab2_lib.baseboard_fab2(sch_1):page202_i22"
				( attribute "CDS_LIB" "mstr_discrete"
					( Origin gPackager )
				)
				( attribute "CDS_LOCATION" "C4E17"
					( Origin gPackager )
				)
				( attribute "CDS_SEC" "1"
					( Origin gPackager )
				)
				( attribute "LOCATION" "C4E17"
					( Origin gFrontEnd )
				)
				( attribute "MATERIAL" "X7R"
					( Origin gFrontEnd )
				)
				( attribute "NO_XNET_CONNECTION" "1"
					( Origin gFrontEnd )
				)
				( attribute "PACK_TYPE" "0402"
					( Origin gFrontEnd )
				)
				( attribute "PART_NUMBER" "A36096-104"
					( Origin gFrontEnd )
				)
				( attribute "PHYS_PAGE" "202"
					( Origin gFrontEnd )
				)
				( attribute "ROOM" "PVCCIN_CPU0_PWR_VR"
					( Origin gFrontEnd )
				)
				( attribute "ROT" "2"
					( Origin gFrontEnd )
				)
				( attribute "SEC" "1"
					( Origin gFrontEnd )
				)
				( attribute "SEC_TYPE" "0402"
					( Origin gFrontEnd )
				)
				( attribute "SPOF" "TRUE"
					( Origin gFrontEnd )
				)
				( attribute "TOLERANCE" "10%"
					( Origin gFrontEnd )
				)
				( attribute "VALUE" "0.220UF"
					( Origin gFrontEnd )
				)
				( attribute "VER" "1"
					( Origin gFrontEnd )
				)
				( attribute "VOLTAGE" "16V"
					( Units "uVoltage" "V" 1.000000)
					( Origin gFrontEnd )
				)
				( attribute "XY" "(-5850,3450)"
					( Origin gFrontEnd )
				)
				( attribute "CHIPS_PART_NAME" "CAP"
					( Origin gPackager )
				)
				( attribute "CDS_PART_NAME" "CAP_0402-0.220UF,16V,10%,X7R,AA"
					( Origin gPackager )
				)
				( objectStatus "C4E17" )
			)
			( gate "@baseboard_fab2_lib.baseboard_fab2(sch_1):page202_i24"
				( attribute "CDS_LIB" "mstr_discrete"
					( Origin gPackager )
				)
				( attribute "CDS_LOCATION" "C4E27"
					( Origin gPackager )
				)
				( attribute "CDS_SEC" "1"
					( Origin gPackager )
				)
				( attribute "LOCATION" "C4E27"
					( Origin gFrontEnd )
				)
				( attribute "MATERIAL" "X7R"
					( Origin gFrontEnd )
				)
				( attribute "PACK_TYPE" "0402"
					( Origin gFrontEnd )
				)
				( attribute "PART_NUMBER" "A36096-155"
					( Origin gFrontEnd )
				)
				( attribute "PHYS_PAGE" "202"
					( Origin gFrontEnd )
				)
				( attribute "ROOM" "PVCCIN_CPU0_PWR_VR"
					( Origin gFrontEnd )
				)
				( attribute "ROT" "0"
					( Origin gFrontEnd )
				)
				( attribute "SEC" "1"
					( Origin gFrontEnd )
				)
				( attribute "SEC_TYPE" "0402"
					( Origin gFrontEnd )
				)
				( attribute "TOLERANCE" "10%"
					( Origin gFrontEnd )
				)
				( attribute "VALUE" "0.22UF"
					( Origin gFrontEnd )
				)
				( attribute "VER" "1"
					( Origin gFrontEnd )
				)
				( attribute "VOLTAGE" "16V"
					( Units "uVoltage" "V" 1.000000)
					( Origin gFrontEnd )
				)
				( attribute "XY" "(-4950,1425)"
					( Origin gFrontEnd )
				)
				( attribute "CHIPS_PART_NAME" "CAP"
					( Origin gPackager )
				)
				( attribute "CDS_PART_NAME" "CAP_0402-0.22UF,16V,10%,X7R,A3A"
					( Origin gPackager )
				)
				( objectStatus "C4E27" )
			)
			( gate "@baseboard_fab2_lib.baseboard_fab2(sch_1):page214_i175"
				( attribute "CDS_LIB" "w_hdl"
					( Origin gPackager )
				)
				( attribute "CDS_LMAN_SYM_OUTLINE" "-50,25,50,-25"
					( Origin gPackager )
				)
				( attribute "LOCATION" "C4E28"
					( Origin gFrontEnd )
				)
				( attribute "PACK_TYPE" "SMD-BCG6"
					( Origin gFrontEnd )
				)
				( attribute "PART_NUMBER" "78.10523.8FL"
					( Origin gFrontEnd )
				)
				( attribute "PHYS_PAGE" "214"
					( Origin gFrontEnd )
				)
				( attribute "ROT" "0"
					( Origin gFrontEnd )
				)
				( attribute "SEC" "1"
					( Origin gFrontEnd )
				)
				( attribute "SEC_TYPE" "SMD-BCG6"
					( Origin gFrontEnd )
				)
				( attribute "VALUE" "SC1U10V2KX-4-GP"
					( Origin gFrontEnd )
				)
				( attribute "VER" "1"
					( Origin gFrontEnd )
				)
				( attribute "XY" "(-1350,4175)"
					( Origin gFrontEnd )
				)
				( attribute "CHIPS_PART_NAME" "SC1U10V2KX-4-GP"
					( Origin gPackager )
				)
				( attribute "CDS_PART_NAME" "SC1U10V2KX-4-GP_SMD-BCG6-SC1U1A"
					( Origin gPackager )
				)
				( attribute "CDS_LOCATION" "C4E28"
					( Origin gPackager )
				)
				( attribute "CDS_SEC" "1"
					( Origin gPackager )
				)
				( attribute "ATTRIBUTE" "1UF"
					( Origin gFrontEnd )
				)
				( attribute "PACK_SIZE" "0402"
					( Origin gFrontEnd )
				)
				( attribute "RATED" "10V"
					( Origin gFrontEnd )
				)
				( attribute "TOLERANCE" "10%"
					( Origin gFrontEnd )
				)
				( objectStatus "C4E28" )
			)
			( gate "@baseboard_fab2_lib.baseboard_fab2(sch_1):page202_i27"
				( attribute "BOM_COST" "PROC_VRD_VCCIN_CPU0"
					( Origin gFrontEnd )
				)
				( attribute "CDS_LIB" "dev_discrete"
					( Origin gPackager )
				)
				( attribute "CDS_LOCATION" "C4E11"
					( Origin gPackager )
				)
				( attribute "CDS_SEC" "1"
					( Origin gPackager )
				)
				( attribute "LOCATION" "C4E11"
					( Origin gFrontEnd )
				)
				( attribute "MATERIAL" "X6S"
					( Origin gFrontEnd )
				)
				( attribute "PACK_TYPE" "0603V"
					( Origin gFrontEnd )
				)
				( attribute "PART_NUMBER" "E15431-004"
					( Origin gFrontEnd )
				)
				( attribute "PHYS_PAGE" "202"
					( Origin gFrontEnd )
				)
				( attribute "ROOM" "PVCCIN_CPU0_PWR_VR"
					( Origin gFrontEnd )
				)
				( attribute "ROT" "0"
					( Origin gFrontEnd )
				)
				( attribute "SEC" "1"
					( Origin gFrontEnd )
				)
				( attribute "SEC_TYPE" "0603V"
					( Origin gFrontEnd )
				)
				( attribute "TOLERANCE" "20%"
					( Origin gFrontEnd )
				)
				( attribute "VALUE" "22.0UF"
					( Origin gFrontEnd )
				)
				( attribute "VER" "1"
					( Origin gFrontEnd )
				)
				( attribute "VOLTAGE" "4V"
					( Units "uVoltage" "V" 1.000000)
					( Origin gFrontEnd )
				)
				( attribute "XY" "(-850,750)"
					( Origin gFrontEnd )
				)
				( attribute "CHIPS_PART_NAME" "CAP_A"
					( Origin gPackager )
				)
				( attribute "CDS_PART_NAME" "CAP_A_0603V-22.0UF,4V,20%,X6S,A"
					( Origin gPackager )
				)
				( attribute "GROUP" "PWR_MLCC_CAP"
					( Origin gFrontEnd )
				)
				( objectStatus "C4E11" )
			)
			( gate "@baseboard_fab2_lib.baseboard_fab2(sch_1):page203_i130"
				( attribute "CDS_LIB" "w_hdl"
					( Origin gPackager )
				)
				( attribute "CDS_LMAN_SYM_OUTLINE" "-75,100,75,-100"
					( Origin gPackager )
				)
				( attribute "LOCATION" "L4D2"
					( Origin gFrontEnd )
				)
				( attribute "PACK_TYPE" "DISCRET-GB2"
					( Origin gFrontEnd )
				)
				( attribute "PART_NUMBER" "068.1202N.M001"
					( Origin gFrontEnd )
				)
				( attribute "PHYS_PAGE" "203"
					( Origin gFrontEnd )
				)
				( attribute "ROT" "1"
					( Origin gFrontEnd )
				)
				( attribute "SEC" "1"
					( Origin gFrontEnd )
				)
				( attribute "SEC_TYPE" "DISCRET-GB2"
					( Origin gFrontEnd )
				)
				( attribute "VALUE" "IND-120NH-30-GP"
					( Origin gFrontEnd )
				)
				( attribute "VER" "1"
					( Origin gFrontEnd )
				)
				( attribute "XY" "(-1175,3675)"
					( Origin gFrontEnd )
				)
				( attribute "CHIPS_PART_NAME" "IND-120NH-30-GP"
					( Origin gPackager )
				)
				( attribute "CDS_PART_NAME" "IND-120NH-30-GP_DISCRET-GB2-INA"
					( Origin gPackager )
				)
				( attribute "CDS_LOCATION" "L4D2"
					( Origin gPackager )
				)
				( attribute "CDS_SEC" "1"
					( Origin gPackager )
				)
				( attribute "ATTRIBUTE" "120NH"
					( Origin gFrontEnd )
				)
				( attribute "PACK_SIZE" "DCR=0.17MOHM"
					( Origin gFrontEnd )
				)
				( attribute "RATED" "ISAT=94A@25C"
					( Origin gFrontEnd )
				)
				( attribute "TYPE" "IRMS=66A@DELTA_T<40C"
					( Origin gFrontEnd )
				)
				( objectStatus "L4D2" )
			)
			( gate "@baseboard_fab2_lib.baseboard_fab2(sch_1):page202_i32"
				( attribute "CDS_LIB" "mstr_discrete"
					( Origin gPackager )
				)
				( attribute "CDS_LOCATION" "C4D50"
					( Origin gPackager )
				)
				( attribute "CDS_SEC" "1"
					( Origin gPackager )
				)
				( attribute "LOCATION" "C4D50"
					( Origin gFrontEnd )
				)
				( attribute "MATERIAL" "X7R"
					( Origin gFrontEnd )
				)
				( attribute "NO_XNET_CONNECTION" "1"
					( Origin gFrontEnd )
				)
				( attribute "PACK_TYPE" "0402"
					( Origin gFrontEnd )
				)
				( attribute "PART_NUMBER" "A36096-104"
					( Origin gFrontEnd )
				)
				( attribute "PHYS_PAGE" "202"
					( Origin gFrontEnd )
				)
				( attribute "ROOM" "PVCCIN_CPU0_PWR_VR"
					( Origin gFrontEnd )
				)
				( attribute "ROT" "2"
					( Origin gFrontEnd )
				)
				( attribute "SEC" "1"
					( Origin gFrontEnd )
				)
				( attribute "SEC_TYPE" "0402"
					( Origin gFrontEnd )
				)
				( attribute "SPOF" "TRUE"
					( Origin gFrontEnd )
				)
				( attribute "TOLERANCE" "10%"
					( Origin gFrontEnd )
				)
				( attribute "VALUE" "0.220UF"
					( Origin gFrontEnd )
				)
				( attribute "VER" "1"
					( Origin gFrontEnd )
				)
				( attribute "VOLTAGE" "16V"
					( Units "uVoltage" "V" 1.000000)
					( Origin gFrontEnd )
				)
				( attribute "XY" "(-5950,825)"
					( Origin gFrontEnd )
				)
				( attribute "CHIPS_PART_NAME" "CAP"
					( Origin gPackager )
				)
				( attribute "CDS_PART_NAME" "CAP_0402-0.220UF,16V,10%,X7R,AA"
					( Origin gPackager )
				)
				( objectStatus "C4D50" )
			)
			( gate "@baseboard_fab2_lib.baseboard_fab2(sch_1):page207_i106"
				( attribute "BOM_COST" "PROC_SIDEBAND"
					( Origin gFrontEnd )
				)
				( attribute "CDS_LIB" "mstr_discrete"
					( Origin gPackager )
				)
				( attribute "CDS_LOCATION" "R9R2"
					( Origin gPackager )
				)
				( attribute "CDS_SEC" "1"
					( Origin gPackager )
				)
				( attribute "LOCATION" "R9R2"
					( Origin gFrontEnd )
				)
				( attribute "MATERIAL" "CHIP"
					( Origin gFrontEnd )
				)
				( attribute "PACK_TYPE" "0402"
					( Origin gFrontEnd )
				)
				( attribute "PART_NUMBER" "G21497-005"
					( Origin gFrontEnd )
				)
				( attribute "PHYS_PAGE" "207"
					( Origin gFrontEnd )
				)
				( attribute "ROOM" "CPU0"
					( Origin gFrontEnd )
				)
				( attribute "ROT" "0"
					( Origin gFrontEnd )
				)
				( attribute "SEC" "1"
					( Origin gFrontEnd )
				)
				( attribute "SEC_TYPE" "0402"
					( Origin gFrontEnd )
				)
				( attribute "TOLERANCE" "5%"
					( Origin gFrontEnd )
				)
				( attribute "VALUE" "0.0"
					( Origin gFrontEnd )
				)
				( attribute "VER" "1"
					( Origin gFrontEnd )
				)
				( attribute "WATTAGE" "1/16W"
					( Origin gFrontEnd )
				)
				( attribute "XY" "(-5400,4650)"
					( Origin gFrontEnd )
				)
				( attribute "CHIPS_PART_NAME" "RES"
					( Origin gPackager )
				)
				( attribute "CDS_PART_NAME" "RES_0402-0.0,5%,1/16W,CHIP,G21A"
					( Origin gPackager )
				)
				( objectStatus "R9R2" )
			)
			( gate "@baseboard_fab2_lib.baseboard_fab2(sch_1):page202_i34"
				( attribute "CDS_LIB" "mstr_discrete"
					( Origin gPackager )
				)
				( attribute "CDS_LOCATION" "C4E10"
					( Origin gPackager )
				)
				( attribute "CDS_SEC" "1"
					( Origin gPackager )
				)
				( attribute "LOCATION" "C4E10"
					( Origin gFrontEnd )
				)
				( attribute "MATERIAL" "X6S"
					( Origin gFrontEnd )
				)
				( attribute "PACK_TYPE" "0402"
					( Origin gFrontEnd )
				)
				( attribute "PART_NUMBER" "D97712-011"
					( Origin gFrontEnd )
				)
				( attribute "PHYS_PAGE" "202"
					( Origin gFrontEnd )
				)
				( attribute "ROOM" "PVCCIN_CPU0_PWR_VR"
					( Origin gFrontEnd )
				)
				( attribute "ROT" "0"
					( Origin gFrontEnd )
				)
				( attribute "SEC" "1"
					( Origin gFrontEnd )
				)
				( attribute "SEC_TYPE" "0402"
					( Origin gFrontEnd )
				)
				( attribute "TOLERANCE" "10%"
					( Origin gFrontEnd )
				)
				( attribute "VALUE" "1.0UF"
					( Origin gFrontEnd )
				)
				( attribute "VER" "1"
					( Origin gFrontEnd )
				)
				( attribute "VOLTAGE" "16V"
					( Units "uVoltage" "V" 1.000000)
					( Origin gFrontEnd )
				)
				( attribute "XY" "(-5700,4025)"
					( Origin gFrontEnd )
				)
				( attribute "CHIPS_PART_NAME" "CAP"
					( Origin gPackager )
				)
				( attribute "CDS_PART_NAME" "CAP_0402-1.0UF,16V,10%,X6S,D97A"
					( Origin gPackager )
				)
				( objectStatus "C4E10" )
			)
			( gate "@baseboard_fab2_lib.baseboard_fab2(sch_1):page202_i35"
				( attribute "CDS_LIB" "dev_discrete"
					( Origin gPackager )
				)
				( attribute "CDS_LOCATION" "C4E20"
					( Origin gPackager )
				)
				( attribute "CDS_SEC" "1"
					( Origin gPackager )
				)
				( attribute "LOCATION" "C4E20"
					( Origin gFrontEnd )
				)
				( attribute "MATERIAL" "X7R"
					( Origin gFrontEnd )
				)
				( attribute "PACK_TYPE" "0402V"
					( Origin gFrontEnd )
				)
				( attribute "PART_NUMBER" "A36096-030"
					( Origin gFrontEnd )
				)
				( attribute "PHYS_PAGE" "202"
					( Origin gFrontEnd )
				)
				( attribute "ROOM" "PVCCIN_CPU0_PWR_VR"
					( Origin gFrontEnd )
				)
				( attribute "ROT" "0"
					( Origin gFrontEnd )
				)
				( attribute "SEC" "1"
					( Origin gFrontEnd )
				)
				( attribute "SEC_TYPE" "0402V"
					( Origin gFrontEnd )
				)
				( attribute "TOLERANCE" "10%"
					( Origin gFrontEnd )
				)
				( attribute "VALUE" "0.1UF"
					( Origin gFrontEnd )
				)
				( attribute "VER" "1"
					( Origin gFrontEnd )
				)
				( attribute "VOLTAGE" "16V"
					( Units "uVoltage" "V" 1.000000)
					( Origin gFrontEnd )
				)
				( attribute "XY" "(-5975,4050)"
					( Origin gFrontEnd )
				)
				( attribute "CHIPS_PART_NAME" "CAP_A"
					( Origin gPackager )
				)
				( attribute "CDS_PART_NAME" "CAP_A_0402V-0.1UF,16V,10%,X7R,A"
					( Origin gPackager )
				)
				( objectStatus "C4E20" )
			)
			( gate "@baseboard_fab2_lib.baseboard_fab2(sch_1):page202_i36"
				( attribute "CDS_LIB" "mstr_discrete"
					( Origin gPackager )
				)
				( attribute "CDS_LOCATION" "C4E19"
					( Origin gPackager )
				)
				( attribute "CDS_SEC" "1"
					( Origin gPackager )
				)
				( attribute "LOCATION" "C4E19"
					( Origin gFrontEnd )
				)
				( attribute "MATERIAL" "X6S"
					( Origin gFrontEnd )
				)
				( attribute "PACK_TYPE" "0402"
					( Origin gFrontEnd )
				)
				( attribute "PART_NUMBER" "D97712-011"
					( Origin gFrontEnd )
				)
				( attribute "PHYS_PAGE" "202"
					( Origin gFrontEnd )
				)
				( attribute "ROOM" "PVCCIN_CPU0_PWR_VR"
					( Origin gFrontEnd )
				)
				( attribute "ROT" "0"
					( Origin gFrontEnd )
				)
				( attribute "SEC" "1"
					( Origin gFrontEnd )
				)
				( attribute "SEC_TYPE" "0402"
					( Origin gFrontEnd )
				)
				( attribute "TOLERANCE" "10%"
					( Origin gFrontEnd )
				)
				( attribute "VALUE" "1.0UF"
					( Origin gFrontEnd )
				)
				( attribute "VER" "1"
					( Origin gFrontEnd )
				)
				( attribute "VOLTAGE" "16V"
					( Units "uVoltage" "V" 1.000000)
					( Origin gFrontEnd )
				)
				( attribute "XY" "(-6250,4075)"
					( Origin gFrontEnd )
				)
				( attribute "CHIPS_PART_NAME" "CAP"
					( Origin gPackager )
				)
				( attribute "CDS_PART_NAME" "CAP_0402-1.0UF,16V,10%,X6S,D97A"
					( Origin gPackager )
				)
				( objectStatus "C4E19" )
			)
			( gate "@baseboard_fab2_lib.baseboard_fab2(sch_1):page202_i37"
				( attribute "CDS_LIB" "mstr_discrete"
					( Origin gPackager )
				)
				( attribute "CDS_LOCATION" "C6R11"
					( Origin gPackager )
				)
				( attribute "CDS_SEC" "1"
					( Origin gPackager )
				)
				( attribute "LOCATION" "C6R11"
					( Origin gFrontEnd )
				)
				( attribute "MATERIAL" "X6S"
					( Origin gFrontEnd )
				)
				( attribute "PACK_TYPE" "0805"
					( Origin gFrontEnd )
				)
				( attribute "PART_NUMBER" "C95333-007"
					( Origin gFrontEnd )
				)
				( attribute "PHYS_PAGE" "202"
					( Origin gFrontEnd )
				)
				( attribute "ROOM" "PVCCIN_CPU0_PWR_VR"
					( Origin gFrontEnd )
				)
				( attribute "ROT" "0"
					( Origin gFrontEnd )
				)
				( attribute "SEC" "1"
					( Origin gFrontEnd )
				)
				( attribute "SEC_TYPE" "0805"
					( Origin gFrontEnd )
				)
				( attribute "TOLERANCE" "10%"
					( Origin gFrontEnd )
				)
				( attribute "VALUE" "10UF"
					( Origin gFrontEnd )
				)
				( attribute "VER" "1"
					( Origin gFrontEnd )
				)
				( attribute "VOLTAGE" "16V"
					( Units "uVoltage" "V" 1.000000)
					( Origin gFrontEnd )
				)
				( attribute "XY" "(-6550,4075)"
					( Origin gFrontEnd )
				)
				( attribute "CHIPS_PART_NAME" "CAP"
					( Origin gPackager )
				)
				( attribute "CDS_PART_NAME" "CAP_0805-10UF,16V,10%,X6S,C953A"
					( Origin gPackager )
				)
				( objectStatus "C6R11" )
			)
			( gate "@baseboard_fab2_lib.baseboard_fab2(sch_1):page202_i38"
				( attribute "CDS_LIB" "mstr_discrete"
					( Origin gPackager )
				)
				( attribute "CDS_LOCATION" "C6P13"
					( Origin gPackager )
				)
				( attribute "CDS_SEC" "1"
					( Origin gPackager )
				)
				( attribute "LOCATION" "C6P13"
					( Origin gFrontEnd )
				)
				( attribute "MATERIAL" "X6S"
					( Origin gFrontEnd )
				)
				( attribute "PACK_TYPE" "0805"
					( Origin gFrontEnd )
				)
				( attribute "PART_NUMBER" "C95333-007"
					( Origin gFrontEnd )
				)
				( attribute "PHYS_PAGE" "202"
					( Origin gFrontEnd )
				)
				( attribute "ROOM" "PVCCIN_CPU0_PWR_VR"
					( Origin gFrontEnd )
				)
				( attribute "ROT" "0"
					( Origin gFrontEnd )
				)
				( attribute "SEC" "1"
					( Origin gFrontEnd )
				)
				( attribute "SEC_TYPE" "0805"
					( Origin gFrontEnd )
				)
				( attribute "TOLERANCE" "10%"
					( Origin gFrontEnd )
				)
				( attribute "VALUE" "10UF"
					( Origin gFrontEnd )
				)
				( attribute "VER" "1"
					( Origin gFrontEnd )
				)
				( attribute "VOLTAGE" "16V"
					( Units "uVoltage" "V" 1.000000)
					( Origin gFrontEnd )
				)
				( attribute "XY" "(-6825,4075)"
					( Origin gFrontEnd )
				)
				( attribute "CHIPS_PART_NAME" "CAP"
					( Origin gPackager )
				)
				( attribute "CDS_PART_NAME" "CAP_0805-10UF,16V,10%,X6S,C953A"
					( Origin gPackager )
				)
				( objectStatus "C6P13" )
			)
			( gate "@baseboard_fab2_lib.baseboard_fab2(sch_1):page205_i81"
				( attribute "BOM_COST" "PROC_SIDEBAND"
					( Origin gFrontEnd )
				)
				( attribute "CDS_LIB" "mstr_discrete"
					( Origin gPackager )
				)
				( attribute "CDS_LOCATION" "R6N3"
					( Origin gPackager )
				)
				( attribute "CDS_SEC" "1"
					( Origin gPackager )
				)
				( attribute "LOCATION" "R6N3"
					( Origin gFrontEnd )
				)
				( attribute "MATERIAL" "CHIP"
					( Origin gFrontEnd )
				)
				( attribute "PACK_TYPE" "0402"
					( Origin gFrontEnd )
				)
				( attribute "PART_NUMBER" "G21497-005"
					( Origin gFrontEnd )
				)
				( attribute "PHYS_PAGE" "205"
					( Origin gFrontEnd )
				)
				( attribute "ROOM" "CPU0"
					( Origin gFrontEnd )
				)
				( attribute "ROT" "0"
					( Origin gFrontEnd )
				)
				( attribute "SEC" "1"
					( Origin gFrontEnd )
				)
				( attribute "SEC_TYPE" "0402"
					( Origin gFrontEnd )
				)
				( attribute "TOLERANCE" "5%"
					( Origin gFrontEnd )
				)
				( attribute "VALUE" "0.0"
					( Origin gFrontEnd )
				)
				( attribute "VER" "1"
					( Origin gFrontEnd )
				)
				( attribute "WATTAGE" "1/16W"
					( Origin gFrontEnd )
				)
				( attribute "XY" "(-5850,4725)"
					( Origin gFrontEnd )
				)
				( attribute "CHIPS_PART_NAME" "RES"
					( Origin gPackager )
				)
				( attribute "CDS_PART_NAME" "RES_0402-0.0,5%,1/16W,CHIP,G21A"
					( Origin gPackager )
				)
				( objectStatus "R6N3" )
			)
			( gate "@baseboard_fab2_lib.baseboard_fab2(sch_1):page202_i42"
				( attribute "CDS_LIB" "mstr_discrete"
					( Origin gPackager )
				)
				( attribute "CDS_LOCATION" "C6R13"
					( Origin gPackager )
				)
				( attribute "CDS_SEC" "1"
					( Origin gPackager )
				)
				( attribute "LOCATION" "C6R13"
					( Origin gFrontEnd )
				)
				( attribute "MATERIAL" "X6S"
					( Origin gFrontEnd )
				)
				( attribute "PACK_TYPE" "0805"
					( Origin gFrontEnd )
				)
				( attribute "PART_NUMBER" "C95333-007"
					( Origin gFrontEnd )
				)
				( attribute "PHYS_PAGE" "202"
					( Origin gFrontEnd )
				)
				( attribute "ROOM" "PVCCIN_CPU0_PWR_VR"
					( Origin gFrontEnd )
				)
				( attribute "ROT" "0"
					( Origin gFrontEnd )
				)
				( attribute "SEC" "1"
					( Origin gFrontEnd )
				)
				( attribute "SEC_TYPE" "0805"
					( Origin gFrontEnd )
				)
				( attribute "TOLERANCE" "10%"
					( Origin gFrontEnd )
				)
				( attribute "VALUE" "10UF"
					( Origin gFrontEnd )
				)
				( attribute "VER" "1"
					( Origin gFrontEnd )
				)
				( attribute "VOLTAGE" "16V"
					( Units "uVoltage" "V" 1.000000)
					( Origin gFrontEnd )
				)
				( attribute "XY" "(-7100,4075)"
					( Origin gFrontEnd )
				)
				( attribute "CHIPS_PART_NAME" "CAP"
					( Origin gPackager )
				)
				( attribute "CDS_PART_NAME" "CAP_0805-10UF,16V,10%,X6S,C953A"
					( Origin gPackager )
				)
				( objectStatus "C6R13" )
			)
			( gate "@baseboard_fab2_lib.baseboard_fab2(sch_1):page202_i45"
				( attribute "CDS_LIB" "mstr_discrete"
					( Origin gPackager )
				)
				( attribute "CDS_LOCATION" "C4E26"
					( Origin gPackager )
				)
				( attribute "CDS_SEC" "1"
					( Origin gPackager )
				)
				( attribute "LOCATION" "C4E26"
					( Origin gFrontEnd )
				)
				( attribute "MATERIAL" "X6S"
					( Origin gFrontEnd )
				)
				( attribute "PACK_TYPE" "0402"
					( Origin gFrontEnd )
				)
				( attribute "PART_NUMBER" "D97712-011"
					( Origin gFrontEnd )
				)
				( attribute "PHYS_PAGE" "202"
					( Origin gFrontEnd )
				)
				( attribute "ROOM" "PVCCIN_CPU0_PWR_VR"
					( Origin gFrontEnd )
				)
				( attribute "ROT" "0"
					( Origin gFrontEnd )
				)
				( attribute "SEC" "1"
					( Origin gFrontEnd )
				)
				( attribute "SEC_TYPE" "0402"
					( Origin gFrontEnd )
				)
				( attribute "TOLERANCE" "10%"
					( Origin gFrontEnd )
				)
				( attribute "VALUE" "1.0UF"
					( Origin gFrontEnd )
				)
				( attribute "VER" "1"
					( Origin gFrontEnd )
				)
				( attribute "VOLTAGE" "16V"
					( Units "uVoltage" "V" 1.000000)
					( Origin gFrontEnd )
				)
				( attribute "XY" "(-5775,1475)"
					( Origin gFrontEnd )
				)
				( attribute "CHIPS_PART_NAME" "CAP"
					( Origin gPackager )
				)
				( attribute "CDS_PART_NAME" "CAP_0402-1.0UF,16V,10%,X6S,D97A"
					( Origin gPackager )
				)
				( objectStatus "C4E26" )
			)
			( gate "@baseboard_fab2_lib.baseboard_fab2(sch_1):page202_i46"
				( attribute "CDS_LIB" "dev_discrete"
					( Origin gPackager )
				)
				( attribute "CDS_LOCATION" "C4D49"
					( Origin gPackager )
				)
				( attribute "CDS_SEC" "1"
					( Origin gPackager )
				)
				( attribute "LOCATION" "C4D49"
					( Origin gFrontEnd )
				)
				( attribute "MATERIAL" "X7R"
					( Origin gFrontEnd )
				)
				( attribute "PACK_TYPE" "0402V"
					( Origin gFrontEnd )
				)
				( attribute "PART_NUMBER" "A36096-030"
					( Origin gFrontEnd )
				)
				( attribute "PHYS_PAGE" "202"
					( Origin gFrontEnd )
				)
				( attribute "ROOM" "PVCCIN_CPU0_PWR_VR"
					( Origin gFrontEnd )
				)
				( attribute "ROT" "0"
					( Origin gFrontEnd )
				)
				( attribute "SEC" "1"
					( Origin gFrontEnd )
				)
				( attribute "SEC_TYPE" "0402V"
					( Origin gFrontEnd )
				)
				( attribute "TOLERANCE" "10%"
					( Origin gFrontEnd )
				)
				( attribute "VALUE" "0.1UF"
					( Origin gFrontEnd )
				)
				( attribute "VER" "1"
					( Origin gFrontEnd )
				)
				( attribute "VOLTAGE" "16V"
					( Units "uVoltage" "V" 1.000000)
					( Origin gFrontEnd )
				)
				( attribute "XY" "(-6050,1475)"
					( Origin gFrontEnd )
				)
				( attribute "CHIPS_PART_NAME" "CAP_A"
					( Origin gPackager )
				)
				( attribute "CDS_PART_NAME" "CAP_A_0402V-0.1UF,16V,10%,X7R,A"
					( Origin gPackager )
				)
				( objectStatus "C4D49" )
			)
			( gate "@baseboard_fab2_lib.baseboard_fab2(sch_1):page202_i47"
				( attribute "CDS_LIB" "mstr_discrete"
					( Origin gPackager )
				)
				( attribute "CDS_LOCATION" "C4D48"
					( Origin gPackager )
				)
				( attribute "CDS_SEC" "1"
					( Origin gPackager )
				)
				( attribute "LOCATION" "C4D48"
					( Origin gFrontEnd )
				)
				( attribute "MATERIAL" "X6S"
					( Origin gFrontEnd )
				)
				( attribute "PACK_TYPE" "0402"
					( Origin gFrontEnd )
				)
				( attribute "PART_NUMBER" "D97712-011"
					( Origin gFrontEnd )
				)
				( attribute "PHYS_PAGE" "202"
					( Origin gFrontEnd )
				)
				( attribute "ROOM" "PVCCIN_CPU0_PWR_VR"
					( Origin gFrontEnd )
				)
				( attribute "ROT" "0"
					( Origin gFrontEnd )
				)
				( attribute "SEC" "1"
					( Origin gFrontEnd )
				)
				( attribute "SEC_TYPE" "0402"
					( Origin gFrontEnd )
				)
				( attribute "TOLERANCE" "10%"
					( Origin gFrontEnd )
				)
				( attribute "VALUE" "1.0UF"
					( Origin gFrontEnd )
				)
				( attribute "VER" "1"
					( Origin gFrontEnd )
				)
				( attribute "VOLTAGE" "16V"
					( Units "uVoltage" "V" 1.000000)
					( Origin gFrontEnd )
				)
				( attribute "XY" "(-6350,1475)"
					( Origin gFrontEnd )
				)
				( attribute "CHIPS_PART_NAME" "CAP"
					( Origin gPackager )
				)
				( attribute "CDS_PART_NAME" "CAP_0402-1.0UF,16V,10%,X6S,D97A"
					( Origin gPackager )
				)
				( objectStatus "C4D48" )
			)
			( gate "@baseboard_fab2_lib.baseboard_fab2(sch_1):page202_i48"
				( attribute "CDS_LIB" "mstr_discrete"
					( Origin gPackager )
				)
				( attribute "CDS_LOCATION" "C6R4"
					( Origin gPackager )
				)
				( attribute "CDS_SEC" "1"
					( Origin gPackager )
				)
				( attribute "LOCATION" "C6R4"
					( Origin gFrontEnd )
				)
				( attribute "MATERIAL" "X6S"
					( Origin gFrontEnd )
				)
				( attribute "PACK_TYPE" "0805"
					( Origin gFrontEnd )
				)
				( attribute "PART_NUMBER" "C95333-007"
					( Origin gFrontEnd )
				)
				( attribute "PHYS_PAGE" "202"
					( Origin gFrontEnd )
				)
				( attribute "ROOM" "PVCCIN_CPU0_PWR_VR"
					( Origin gFrontEnd )
				)
				( attribute "ROT" "0"
					( Origin gFrontEnd )
				)
				( attribute "SEC" "1"
					( Origin gFrontEnd )
				)
				( attribute "SEC_TYPE" "0805"
					( Origin gFrontEnd )
				)
				( attribute "TOLERANCE" "10%"
					( Origin gFrontEnd )
				)
				( attribute "VALUE" "10UF"
					( Origin gFrontEnd )
				)
				( attribute "VER" "1"
					( Origin gFrontEnd )
				)
				( attribute "VOLTAGE" "16V"
					( Units "uVoltage" "V" 1.000000)
					( Origin gFrontEnd )
				)
				( attribute "XY" "(-6625,1475)"
					( Origin gFrontEnd )
				)
				( attribute "CHIPS_PART_NAME" "CAP"
					( Origin gPackager )
				)
				( attribute "CDS_PART_NAME" "CAP_0805-10UF,16V,10%,X6S,C953A"
					( Origin gPackager )
				)
				( objectStatus "C6R4" )
			)
			( gate "@baseboard_fab2_lib.baseboard_fab2(sch_1):page202_i49"
				( attribute "CDS_LIB" "mstr_discrete"
					( Origin gPackager )
				)
				( attribute "CDS_LOCATION" "C6P22"
					( Origin gPackager )
				)
				( attribute "CDS_SEC" "1"
					( Origin gPackager )
				)
				( attribute "LOCATION" "C6P22"
					( Origin gFrontEnd )
				)
				( attribute "MATERIAL" "X6S"
					( Origin gFrontEnd )
				)
				( attribute "PACK_TYPE" "0805"
					( Origin gFrontEnd )
				)
				( attribute "PART_NUMBER" "C95333-007"
					( Origin gFrontEnd )
				)
				( attribute "PHYS_PAGE" "202"
					( Origin gFrontEnd )
				)
				( attribute "ROOM" "PVCCIN_CPU0_PWR_VR"
					( Origin gFrontEnd )
				)
				( attribute "ROT" "0"
					( Origin gFrontEnd )
				)
				( attribute "SEC" "1"
					( Origin gFrontEnd )
				)
				( attribute "SEC_TYPE" "0805"
					( Origin gFrontEnd )
				)
				( attribute "TOLERANCE" "10%"
					( Origin gFrontEnd )
				)
				( attribute "VALUE" "10UF"
					( Origin gFrontEnd )
				)
				( attribute "VER" "1"
					( Origin gFrontEnd )
				)
				( attribute "VOLTAGE" "16V"
					( Units "uVoltage" "V" 1.000000)
					( Origin gFrontEnd )
				)
				( attribute "XY" "(-6900,1475)"
					( Origin gFrontEnd )
				)
				( attribute "CHIPS_PART_NAME" "CAP"
					( Origin gPackager )
				)
				( attribute "CDS_PART_NAME" "CAP_0805-10UF,16V,10%,X6S,C953A"
					( Origin gPackager )
				)
				( objectStatus "C6P22" )
			)
			( gate "@baseboard_fab2_lib.baseboard_fab2(sch_1):page202_i51"
				( attribute "CDS_LIB" "mstr_discrete"
					( Origin gPackager )
				)
				( attribute "CDS_LOCATION" "C6N8"
					( Origin gPackager )
				)
				( attribute "CDS_SEC" "1"
					( Origin gPackager )
				)
				( attribute "LOCATION" "C6N8"
					( Origin gFrontEnd )
				)
				( attribute "MATERIAL" "X6S"
					( Origin gFrontEnd )
				)
				( attribute "PACK_TYPE" "0805"
					( Origin gFrontEnd )
				)
				( attribute "PART_NUMBER" "C95333-007"
					( Origin gFrontEnd )
				)
				( attribute "PHYS_PAGE" "202"
					( Origin gFrontEnd )
				)
				( attribute "ROOM" "PVCCIN_CPU0_PWR_VR"
					( Origin gFrontEnd )
				)
				( attribute "ROT" "0"
					( Origin gFrontEnd )
				)
				( attribute "SEC" "1"
					( Origin gFrontEnd )
				)
				( attribute "SEC_TYPE" "0805"
					( Origin gFrontEnd )
				)
				( attribute "TOLERANCE" "10%"
					( Origin gFrontEnd )
				)
				( attribute "VALUE" "10UF"
					( Origin gFrontEnd )
				)
				( attribute "VER" "1"
					( Origin gFrontEnd )
				)
				( attribute "VOLTAGE" "16V"
					( Units "uVoltage" "V" 1.000000)
					( Origin gFrontEnd )
				)
				( attribute "XY" "(-7175,1475)"
					( Origin gFrontEnd )
				)
				( attribute "CHIPS_PART_NAME" "CAP"
					( Origin gPackager )
				)
				( attribute "CDS_PART_NAME" "CAP_0805-10UF,16V,10%,X6S,C953A"
					( Origin gPackager )
				)
				( objectStatus "C6N8" )
			)
			( gate "@baseboard_fab2_lib.baseboard_fab2(sch_1):page202_i61"
				( attribute "CDS_LIB" "dev_discrete"
					( Origin gPackager )
				)
				( attribute "CDS_LOCATION" "C4E3"
					( Origin gPackager )
				)
				( attribute "CDS_SEC" "1"
					( Origin gPackager )
				)
				( attribute "LOCATION" "C4E3"
					( Origin gFrontEnd )
				)
				( attribute "MATERIAL" "X6S"
					( Origin gFrontEnd )
				)
				( attribute "PACK_TYPE" "0603V"
					( Origin gFrontEnd )
				)
				( attribute "PART_NUMBER" "E15431-004"
					( Origin gFrontEnd )
				)
				( attribute "PHYS_PAGE" "202"
					( Origin gFrontEnd )
				)
				( attribute "ROT" "0"
					( Origin gFrontEnd )
				)
				( attribute "SEC" "1"
					( Origin gFrontEnd )
				)
				( attribute "SEC_TYPE" "0603V"
					( Origin gFrontEnd )
				)
				( attribute "TOLERANCE" "20%"
					( Origin gFrontEnd )
				)
				( attribute "VALUE" "22.0UF"
					( Origin gFrontEnd )
				)
				( attribute "VER" "1"
					( Origin gFrontEnd )
				)
				( attribute "VOLTAGE" "4V"
					( Units "uVoltage" "V" 1.000000)
					( Origin gFrontEnd )
				)
				( attribute "XY" "(-650,3300)"
					( Origin gFrontEnd )
				)
				( attribute "CHIPS_PART_NAME" "CAP_A"
					( Origin gPackager )
				)
				( attribute "CDS_PART_NAME" "CAP_A_0603V-22.0UF,4V,20%,X6S,A"
					( Origin gPackager )
				)
				( attribute "GROUP" "PWR_MLCC_CAP"
					( Origin gFrontEnd )
				)
				( objectStatus "C4E3" )
			)
			( gate "@baseboard_fab2_lib.baseboard_fab2(sch_1):page202_i62"
				( attribute "CDS_LIB" "dev_discrete"
					( Origin gPackager )
				)
				( attribute "CDS_LOCATION" "C6P16"
					( Origin gPackager )
				)
				( attribute "CDS_SEC" "1"
					( Origin gPackager )
				)
				( attribute "LOCATION" "C6P16"
					( Origin gFrontEnd )
				)
				( attribute "MATERIAL" "X6S"
					( Origin gFrontEnd )
				)
				( attribute "PACK_TYPE" "0603V"
					( Origin gFrontEnd )
				)
				( attribute "PART_NUMBER" "E15431-004"
					( Origin gFrontEnd )
				)
				( attribute "PHYS_PAGE" "202"
					( Origin gFrontEnd )
				)
				( attribute "ROT" "0"
					( Origin gFrontEnd )
				)
				( attribute "SEC" "1"
					( Origin gFrontEnd )
				)
				( attribute "SEC_TYPE" "0603V"
					( Origin gFrontEnd )
				)
				( attribute "TOLERANCE" "20%"
					( Origin gFrontEnd )
				)
				( attribute "VALUE" "22.0UF"
					( Origin gFrontEnd )
				)
				( attribute "VER" "1"
					( Origin gFrontEnd )
				)
				( attribute "VOLTAGE" "4V"
					( Units "uVoltage" "V" 1.000000)
					( Origin gFrontEnd )
				)
				( attribute "XY" "(-500,750)"
					( Origin gFrontEnd )
				)
				( attribute "CHIPS_PART_NAME" "CAP_A"
					( Origin gPackager )
				)
				( attribute "CDS_PART_NAME" "CAP_A_0603V-22.0UF,4V,20%,X6S,A"
					( Origin gPackager )
				)
				( attribute "GROUP" "PWR_MLCC_CAP"
					( Origin gFrontEnd )
				)
				( objectStatus "C6P16" )
			)
			( gate "@baseboard_fab2_lib.baseboard_fab2(sch_1):page202_i63"
				( attribute "CDS_LIB" "mstr_discrete"
					( Origin gPackager )
				)
				( attribute "CDS_LOCATION" "EU4E1"
					( Origin gPackager )
				)
				( attribute "CDS_SEC" "1"
					( Origin gPackager )
				)
				( attribute "LOCATION" "EU4E1"
					( Origin gFrontEnd )
				)
				( attribute "MATERIAL" "IC"
					( Origin gFrontEnd )
				)
				( attribute "PACK_TYPE" "SM"
					( Origin gFrontEnd )
				)
				( attribute "PART_NUMBER" "H73688-001"
					( Origin gFrontEnd )
				)
				( attribute "PHYS_PAGE" "202"
					( Origin gFrontEnd )
				)
				( attribute "ROT" "0"
					( Origin gFrontEnd )
				)
				( attribute "SEC" "1"
					( Origin gPackager )
				)
				( attribute "VALUE" "IR35411"
					( Origin gFrontEnd )
				)
				( attribute "VER" "1"
					( Origin gFrontEnd )
				)
				( attribute "XY" "(-3425,3800)"
					( Origin gFrontEnd )
				)
				( attribute "CHIPS_PART_NAME" "IR354XX"
					( Origin gPackager )
				)
				( attribute "CDS_PART_NAME" "IR354XX_SM-IR35411,IC,H73688-0A"
					( Origin gPackager )
				)
				( objectStatus "EU4E1" )
			)
			( gate "@baseboard_fab2_lib.baseboard_fab2(sch_1):page202_i64"
				( attribute "CDS_LIB" "mstr_discrete"
					( Origin gPackager )
				)
				( attribute "CDS_LOCATION" "EU4D6"
					( Origin gPackager )
				)
				( attribute "CDS_SEC" "1"
					( Origin gPackager )
				)
				( attribute "LOCATION" "EU4D6"
					( Origin gFrontEnd )
				)
				( attribute "MATERIAL" "IC"
					( Origin gFrontEnd )
				)
				( attribute "PACK_TYPE" "SM"
					( Origin gFrontEnd )
				)
				( attribute "PART_NUMBER" "H73688-001"
					( Origin gFrontEnd )
				)
				( attribute "PHYS_PAGE" "202"
					( Origin gFrontEnd )
				)
				( attribute "ROT" "0"
					( Origin gFrontEnd )
				)
				( attribute "SEC" "1"
					( Origin gPackager )
				)
				( attribute "VALUE" "IR35411"
					( Origin gFrontEnd )
				)
				( attribute "VER" "1"
					( Origin gFrontEnd )
				)
				( attribute "XY" "(-3475,1175)"
					( Origin gFrontEnd )
				)
				( attribute "CHIPS_PART_NAME" "IR354XX"
					( Origin gPackager )
				)
				( attribute "CDS_PART_NAME" "IR354XX_SM-IR35411,IC,H73688-0A"
					( Origin gPackager )
				)
				( objectStatus "EU4D6" )
			)
			( gate "@baseboard_fab2_lib.baseboard_fab2(sch_1):page202_i65"
				( attribute "CDS_LIB" "mstr_discrete"
					( Origin gPackager )
				)
				( attribute "CDS_LOCATION" "R4E22"
					( Origin gPackager )
				)
				( attribute "LOCATION" "R4E22"
					( Origin gFrontEnd )
				)
				( attribute "MATERIAL" "EMPTY"
					( Origin gFrontEnd )
				)
				( attribute "PACK_TYPE" "0402"
					( Origin gFrontEnd )
				)
				( attribute "PART_NUMBER" "G21796-187"
					( Origin gFrontEnd )
				)
				( attribute "PHYS_PAGE" "202"
					( Origin gFrontEnd )
				)
				( attribute "ROT" "0"
					( Origin gFrontEnd )
				)
				( attribute "SEC" "1"
					( Origin gFrontEnd )
				)
				( attribute "TOLERANCE" "1%"
					( Origin gFrontEnd )
				)
				( attribute "VALUE" "68.1K"
					( Origin gFrontEnd )
				)
				( attribute "VER" "2"
					( Origin gFrontEnd )
				)
				( attribute "WATTAGE" "1/16W"
					( Origin gFrontEnd )
				)
				( attribute "XY" "(-750,3900)"
					( Origin gFrontEnd )
				)
				( attribute "CHIPS_PART_NAME" "RES"
					( Origin gPackager )
				)
				( attribute "CDS_PART_NAME" "RES_0402-68.1K,1%,1/16W,EMPTY,A"
					( Origin gPackager )
				)
				( attribute "SEC_TYPE" "0402"
					( Origin gFrontEnd )
				)
				( attribute "CDS_SEC" "1"
					( Origin gPackager )
				)
				( objectStatus "R4E22" )
			)
			( gate "@baseboard_fab2_lib.baseboard_fab2(sch_1):page202_i67"
				( attribute "CDS_LIB" "mstr_discrete"
					( Origin gPackager )
				)
				( attribute "CDS_LOCATION" "R4E19"
					( Origin gPackager )
				)
				( attribute "CDS_SEC" "1"
					( Origin gPackager )
				)
				( attribute "LOCATION" "R4E19"
					( Origin gFrontEnd )
				)
				( attribute "MATERIAL" "EMPTY"
					( Origin gFrontEnd )
				)
				( attribute "PACK_TYPE" "0402"
					( Origin gFrontEnd )
				)
				( attribute "PART_NUMBER" "G21796-187"
					( Origin gFrontEnd )
				)
				( attribute "PHYS_PAGE" "202"
					( Origin gFrontEnd )
				)
				( attribute "ROT" "0"
					( Origin gFrontEnd )
				)
				( attribute "SEC" "1"
					( Origin gPackager )
				)
				( attribute "TOLERANCE" "1%"
					( Origin gFrontEnd )
				)
				( attribute "VALUE" "68.1K"
					( Origin gFrontEnd )
				)
				( attribute "VER" "2"
					( Origin gFrontEnd )
				)
				( attribute "WATTAGE" "1/16W"
					( Origin gFrontEnd )
				)
				( attribute "XY" "(-825,1350)"
					( Origin gFrontEnd )
				)
				( attribute "CHIPS_PART_NAME" "RES"
					( Origin gPackager )
				)
				( attribute "CDS_PART_NAME" "RES_0402-68.1K,1%,1/16W,EMPTY,A"
					( Origin gPackager )
				)
				( objectStatus "R4E19" )
			)
			( gate "@baseboard_fab2_lib.baseboard_fab2(sch_1):page203_i1"
				( attribute "CDS_LIB" "mstr_discrete"
					( Origin gPackager )
				)
				( attribute "CDS_LOCATION" "C6P24"
					( Origin gPackager )
				)
				( attribute "CDS_SEC" "1"
					( Origin gPackager )
				)
				( attribute "LOCATION" "C6P24"
					( Origin gFrontEnd )
				)
				( attribute "MATERIAL" "X6S"
					( Origin gFrontEnd )
				)
				( attribute "PACK_TYPE" "0805"
					( Origin gFrontEnd )
				)
				( attribute "PART_NUMBER" "C95333-007"
					( Origin gFrontEnd )
				)
				( attribute "PHYS_PAGE" "203"
					( Origin gFrontEnd )
				)
				( attribute "ROOM" "PVCCIN_CPU0_PWR_VR"
					( Origin gFrontEnd )
				)
				( attribute "ROT" "0"
					( Origin gFrontEnd )
				)
				( attribute "SEC" "1"
					( Origin gFrontEnd )
				)
				( attribute "SEC_TYPE" "0805"
					( Origin gFrontEnd )
				)
				( attribute "TOLERANCE" "10%"
					( Origin gFrontEnd )
				)
				( attribute "VALUE" "10UF"
					( Origin gFrontEnd )
				)
				( attribute "VER" "1"
					( Origin gFrontEnd )
				)
				( attribute "VOLTAGE" "16V"
					( Units "uVoltage" "V" 1.000000)
					( Origin gFrontEnd )
				)
				( attribute "XY" "(-6350,4175)"
					( Origin gFrontEnd )
				)
				( attribute "CHIPS_PART_NAME" "CAP"
					( Origin gPackager )
				)
				( attribute "CDS_PART_NAME" "CAP_0805-10UF,16V,10%,X6S,C953A"
					( Origin gPackager )
				)
				( objectStatus "C6P24" )
			)
			( gate "@baseboard_fab2_lib.baseboard_fab2(sch_1):page203_i2"
				( attribute "CDS_LIB" "mstr_discrete"
					( Origin gPackager )
				)
				( attribute "CDS_LOCATION" "C6R6"
					( Origin gPackager )
				)
				( attribute "CDS_SEC" "1"
					( Origin gPackager )
				)
				( attribute "LOCATION" "C6R6"
					( Origin gFrontEnd )
				)
				( attribute "MATERIAL" "X6S"
					( Origin gFrontEnd )
				)
				( attribute "PACK_TYPE" "0805"
					( Origin gFrontEnd )
				)
				( attribute "PART_NUMBER" "C95333-007"
					( Origin gFrontEnd )
				)
				( attribute "PHYS_PAGE" "203"
					( Origin gFrontEnd )
				)
				( attribute "ROOM" "PVCCIN_CPU0_PWR_VR"
					( Origin gFrontEnd )
				)
				( attribute "ROT" "0"
					( Origin gFrontEnd )
				)
				( attribute "SEC" "1"
					( Origin gFrontEnd )
				)
				( attribute "SEC_TYPE" "0805"
					( Origin gFrontEnd )
				)
				( attribute "TOLERANCE" "10%"
					( Origin gFrontEnd )
				)
				( attribute "VALUE" "10UF"
					( Origin gFrontEnd )
				)
				( attribute "VER" "1"
					( Origin gFrontEnd )
				)
				( attribute "VOLTAGE" "16V"
					( Units "uVoltage" "V" 1.000000)
					( Origin gFrontEnd )
				)
				( attribute "XY" "(-6700,4175)"
					( Origin gFrontEnd )
				)
				( attribute "CHIPS_PART_NAME" "CAP"
					( Origin gPackager )
				)
				( attribute "CDS_PART_NAME" "CAP_0805-10UF,16V,10%,X6S,C953A"
					( Origin gPackager )
				)
				( objectStatus "C6R6" )
			)
			( gate "@baseboard_fab2_lib.baseboard_fab2(sch_1):page203_i3"
				( attribute "CDS_LIB" "mstr_discrete"
					( Origin gPackager )
				)
				( attribute "CDS_LOCATION" "C4D9"
					( Origin gPackager )
				)
				( attribute "CDS_SEC" "1"
					( Origin gPackager )
				)
				( attribute "LOCATION" "C4D9"
					( Origin gFrontEnd )
				)
				( attribute "MATERIAL" "X7R"
					( Origin gFrontEnd )
				)
				( attribute "NO_XNET_CONNECTION" "1"
					( Origin gFrontEnd )
				)
				( attribute "PACK_TYPE" "0402"
					( Origin gFrontEnd )
				)
				( attribute "PART_NUMBER" "A36096-104"
					( Origin gFrontEnd )
				)
				( attribute "PHYS_PAGE" "203"
					( Origin gFrontEnd )
				)
				( attribute "ROOM" "PVCCIN_CPU0_PWR_VR"
					( Origin gFrontEnd )
				)
				( attribute "ROT" "2"
					( Origin gFrontEnd )
				)
				( attribute "SEC" "1"
					( Origin gFrontEnd )
				)
				( attribute "SEC_TYPE" "0402"
					( Origin gFrontEnd )
				)
				( attribute "SPOF" "TRUE"
					( Origin gFrontEnd )
				)
				( attribute "TOLERANCE" "10%"
					( Origin gFrontEnd )
				)
				( attribute "VALUE" "0.220UF"
					( Origin gFrontEnd )
				)
				( attribute "VER" "1"
					( Origin gFrontEnd )
				)
				( attribute "VOLTAGE" "16V"
					( Units "uVoltage" "V" 1.000000)
					( Origin gFrontEnd )
				)
				( attribute "XY" "(-5875,825)"
					( Origin gFrontEnd )
				)
				( attribute "CHIPS_PART_NAME" "CAP"
					( Origin gPackager )
				)
				( attribute "CDS_PART_NAME" "CAP_0402-0.220UF,16V,10%,X7R,AA"
					( Origin gPackager )
				)
				( objectStatus "C4D9" )
			)
			( gate "@baseboard_fab2_lib.baseboard_fab2(sch_1):page207_i108"
				( attribute "CDS_LIB" "w_hdl"
					( Origin gPackager )
				)
				( attribute "CDS_LMAN_SYM_OUTLINE" "-75,100,75,-100"
					( Origin gPackager )
				)
				( attribute "LOCATION" "L1D3"
					( Origin gFrontEnd )
				)
				( attribute "PACK_TYPE" "DISCRET-GB2"
					( Origin gFrontEnd )
				)
				( attribute "PART_NUMBER" "068.1202N.M001"
					( Origin gFrontEnd )
				)
				( attribute "PHYS_PAGE" "207"
					( Origin gFrontEnd )
				)
				( attribute "ROT" "1"
					( Origin gFrontEnd )
				)
				( attribute "SEC" "1"
					( Origin gFrontEnd )
				)
				( attribute "SEC_TYPE" "DISCRET-GB2"
					( Origin gFrontEnd )
				)
				( attribute "VALUE" "IND-120NH-30-GP"
					( Origin gFrontEnd )
				)
				( attribute "VER" "1"
					( Origin gFrontEnd )
				)
				( attribute "XY" "(-1425,975)"
					( Origin gFrontEnd )
				)
				( attribute "CHIPS_PART_NAME" "IND-120NH-30-GP"
					( Origin gPackager )
				)
				( attribute "CDS_PART_NAME" "IND-120NH-30-GP_DISCRET-GB2-INA"
					( Origin gPackager )
				)
				( attribute "CDS_LOCATION" "L1D3"
					( Origin gPackager )
				)
				( attribute "CDS_SEC" "1"
					( Origin gPackager )
				)
				( attribute "ATTRIBUTE" "120NH"
					( Origin gFrontEnd )
				)
				( attribute "PACK_SIZE" "DCR=0.17MOHM"
					( Origin gFrontEnd )
				)
				( attribute "RATED" "ISAT=94A@25C"
					( Origin gFrontEnd )
				)
				( attribute "TYPE" "IRMS=66A@DELTA_T<40C"
					( Origin gFrontEnd )
				)
				( objectStatus "L1D3" )
			)
			( gate "@baseboard_fab2_lib.baseboard_fab2(sch_1):page203_i16"
				( attribute "BOM_COST" "PROC_VRD_VCCIN_CPU0"
					( Origin gFrontEnd )
				)
				( attribute "CDS_LIB" "mstr_discrete"
					( Origin gPackager )
				)
				( attribute "CDS_LOCATION" "C6R3"
					( Origin gPackager )
				)
				( attribute "CDS_SEC" "1"
					( Origin gPackager )
				)
				( attribute "LOCATION" "C6R3"
					( Origin gFrontEnd )
				)
				( attribute "MATERIAL" "ALUM"
					( Origin gFrontEnd )
				)
				( attribute "PACK_TYPE" "3018"
					( Origin gFrontEnd )
				)
				( attribute "PART_NUMBER" "699013-049"
					( Origin gFrontEnd )
				)
				( attribute "PHYS_PAGE" "203"
					( Origin gFrontEnd )
				)
				( attribute "ROOM" "PVCCIN_CPU0_DECAP_VR"
					( Origin gFrontEnd )
				)
				( attribute "ROT" "0"
					( Origin gFrontEnd )
				)
				( attribute "SEC" "1"
					( Origin gFrontEnd )
				)
				( attribute "SEC_TYPE" "3018"
					( Origin gFrontEnd )
				)
				( attribute "TOLERANCE" "20%"
					( Origin gFrontEnd )
				)
				( attribute "VALUE" "470UF"
					( Origin gFrontEnd )
				)
				( attribute "VER" "1"
					( Origin gFrontEnd )
				)
				( attribute "VOLTAGE" "2.5V"
					( Units "uVoltage" "V" 1.000000)
					( Origin gFrontEnd )
				)
				( attribute "XY" "(-925,2600)"
					( Origin gFrontEnd )
				)
				( attribute "CHIPS_PART_NAME" "CAPP"
					( Origin gPackager )
				)
				( attribute "CDS_PART_NAME" "CAPP_3018-470UF,2.5V,20%,ALUM,A"
					( Origin gPackager )
				)
				( attribute "GROUP" "PWR_BULK_CAP"
					( Origin gFrontEnd )
				)
				( objectStatus "C6R3" )
			)
			( gate "@baseboard_fab2_lib.baseboard_fab2(sch_1):page203_i18"
				( attribute "BOM_COST" "PROC_VRD_VCCIN_CPU0"
					( Origin gFrontEnd )
				)
				( attribute "CDS_LIB" "mstr_discrete"
					( Origin gPackager )
				)
				( attribute "CDS_LOCATION" "C6R9"
					( Origin gPackager )
				)
				( attribute "CDS_SEC" "1"
					( Origin gPackager )
				)
				( attribute "LOCATION" "C6R9"
					( Origin gFrontEnd )
				)
				( attribute "MATERIAL" "ALUM"
					( Origin gFrontEnd )
				)
				( attribute "PACK_TYPE" "3018"
					( Origin gFrontEnd )
				)
				( attribute "PART_NUMBER" "699013-049"
					( Origin gFrontEnd )
				)
				( attribute "PHYS_PAGE" "203"
					( Origin gFrontEnd )
				)
				( attribute "ROOM" "PVCCIN_CPU0_DECAP_VR"
					( Origin gFrontEnd )
				)
				( attribute "ROT" "0"
					( Origin gFrontEnd )
				)
				( attribute "SEC" "1"
					( Origin gFrontEnd )
				)
				( attribute "SEC_TYPE" "3018"
					( Origin gFrontEnd )
				)
				( attribute "TOLERANCE" "20%"
					( Origin gFrontEnd )
				)
				( attribute "VALUE" "470UF"
					( Origin gFrontEnd )
				)
				( attribute "VER" "1"
					( Origin gFrontEnd )
				)
				( attribute "VOLTAGE" "2.5V"
					( Units "uVoltage" "V" 1.000000)
					( Origin gFrontEnd )
				)
				( attribute "XY" "(-1400,2600)"
					( Origin gFrontEnd )
				)
				( attribute "CHIPS_PART_NAME" "CAPP"
					( Origin gPackager )
				)
				( attribute "CDS_PART_NAME" "CAPP_3018-470UF,2.5V,20%,ALUM,A"
					( Origin gPackager )
				)
				( attribute "GROUP" "PWR_BULK_CAP"
					( Origin gFrontEnd )
				)
				( objectStatus "C6R9" )
			)
			( gate "@baseboard_fab2_lib.baseboard_fab2(sch_1):page204_i104"
				( attribute "CDS_LIB" "w_hdl"
					( Origin gPackager )
				)
				( attribute "CDS_LMAN_SYM_OUTLINE" "-75,100,75,-100"
					( Origin gPackager )
				)
				( attribute "LOCATION" "L4C3"
					( Origin gFrontEnd )
				)
				( attribute "PACK_TYPE" "DISCRET-GB2"
					( Origin gFrontEnd )
				)
				( attribute "PART_NUMBER" "068.1202N.M001"
					( Origin gFrontEnd )
				)
				( attribute "PHYS_PAGE" "204"
					( Origin gFrontEnd )
				)
				( attribute "ROT" "1"
					( Origin gFrontEnd )
				)
				( attribute "SEC" "1"
					( Origin gFrontEnd )
				)
				( attribute "SEC_TYPE" "DISCRET-GB2"
					( Origin gFrontEnd )
				)
				( attribute "VALUE" "IND-120NH-30-GP"
					( Origin gFrontEnd )
				)
				( attribute "VER" "1"
					( Origin gFrontEnd )
				)
				( attribute "XY" "(-1050,3650)"
					( Origin gFrontEnd )
				)
				( attribute "CHIPS_PART_NAME" "IND-120NH-30-GP"
					( Origin gPackager )
				)
				( attribute "CDS_PART_NAME" "IND-120NH-30-GP_DISCRET-GB2-INA"
					( Origin gPackager )
				)
				( attribute "CDS_LOCATION" "L4C3"
					( Origin gPackager )
				)
				( attribute "CDS_SEC" "1"
					( Origin gPackager )
				)
				( attribute "ATTRIBUTE" "120NH"
					( Origin gFrontEnd )
				)
				( attribute "PACK_SIZE" "DCR=0.17MOHM"
					( Origin gFrontEnd )
				)
				( attribute "RATED" "ISAT=94A@25C"
					( Origin gFrontEnd )
				)
				( attribute "TYPE" "IRMS=66A@DELTA_T<40C"
					( Origin gFrontEnd )
				)
				( objectStatus "L4C3" )
			)
			( gate "@baseboard_fab2_lib.baseboard_fab2(sch_1):page203_i25"
				( attribute "BOM_COST" "PROC_VRD_VCCIN_CPU0"
					( Origin gFrontEnd )
				)
				( attribute "CDS_LIB" "dev_discrete"
					( Origin gPackager )
				)
				( attribute "CDS_LOCATION" "C6P3"
					( Origin gPackager )
				)
				( attribute "CDS_SEC" "1"
					( Origin gPackager )
				)
				( attribute "LOCATION" "C6P3"
					( Origin gFrontEnd )
				)
				( attribute "MATERIAL" "X6S"
					( Origin gFrontEnd )
				)
				( attribute "PACK_TYPE" "0603V"
					( Origin gFrontEnd )
				)
				( attribute "PART_NUMBER" "E15431-004"
					( Origin gFrontEnd )
				)
				( attribute "PHYS_PAGE" "203"
					( Origin gFrontEnd )
				)
				( attribute "ROOM" "PVCCIN_CPU0_PWR_VR"
					( Origin gFrontEnd )
				)
				( attribute "ROT" "0"
					( Origin gFrontEnd )
				)
				( attribute "SEC" "1"
					( Origin gFrontEnd )
				)
				( attribute "SEC_TYPE" "0603V"
					( Origin gFrontEnd )
				)
				( attribute "TOLERANCE" "20%"
					( Origin gFrontEnd )
				)
				( attribute "VALUE" "22.0UF"
					( Origin gFrontEnd )
				)
				( attribute "VER" "1"
					( Origin gFrontEnd )
				)
				( attribute "VOLTAGE" "4V"
					( Units "uVoltage" "V" 1.000000)
					( Origin gFrontEnd )
				)
				( attribute "XY" "(-700,725)"
					( Origin gFrontEnd )
				)
				( attribute "CHIPS_PART_NAME" "CAP_A"
					( Origin gPackager )
				)
				( attribute "CDS_PART_NAME" "CAP_A_0603V-22.0UF,4V,20%,X6S,A"
					( Origin gPackager )
				)
				( attribute "GROUP" "PWR_MLCC_CAP"
					( Origin gFrontEnd )
				)
				( objectStatus "C6P3" )
			)
			( gate "@baseboard_fab2_lib.baseboard_fab2(sch_1):page203_i28"
				( attribute "BOM_COST" "PROC_VRD_VCCIN_CPU0"
					( Origin gFrontEnd )
				)
				( attribute "CDS_LIB" "mstr_discrete"
					( Origin gPackager )
				)
				( attribute "CDS_LOCATION" "C6P23"
					( Origin gPackager )
				)
				( attribute "CDS_SEC" "1"
					( Origin gPackager )
				)
				( attribute "LOCATION" "C6P23"
					( Origin gFrontEnd )
				)
				( attribute "MATERIAL" "ALUM"
					( Origin gFrontEnd )
				)
				( attribute "PACK_TYPE" "3018"
					( Origin gFrontEnd )
				)
				( attribute "PART_NUMBER" "699013-049"
					( Origin gFrontEnd )
				)
				( attribute "PHYS_PAGE" "203"
					( Origin gFrontEnd )
				)
				( attribute "ROOM" "PVCCIN_CPU0_DECAP_VR"
					( Origin gFrontEnd )
				)
				( attribute "ROT" "0"
					( Origin gFrontEnd )
				)
				( attribute "SEC" "1"
					( Origin gFrontEnd )
				)
				( attribute "SEC_TYPE" "3018"
					( Origin gFrontEnd )
				)
				( attribute "TOLERANCE" "20%"
					( Origin gFrontEnd )
				)
				( attribute "VALUE" "470UF"
					( Origin gFrontEnd )
				)
				( attribute "VER" "1"
					( Origin gFrontEnd )
				)
				( attribute "VOLTAGE" "2.5V"
					( Units "uVoltage" "V" 1.000000)
					( Origin gFrontEnd )
				)
				( attribute "XY" "(-1850,2600)"
					( Origin gFrontEnd )
				)
				( attribute "CHIPS_PART_NAME" "CAPP"
					( Origin gPackager )
				)
				( attribute "CDS_PART_NAME" "CAPP_3018-470UF,2.5V,20%,ALUM,A"
					( Origin gPackager )
				)
				( attribute "GROUP" "PWR_BULK_CAP"
					( Origin gFrontEnd )
				)
				( objectStatus "C6P23" )
			)
			( gate "@baseboard_fab2_lib.baseboard_fab2(sch_1):page203_i29"
				( attribute "BOM_COST" "PROC_VRD_VCCIN_CPU0"
					( Origin gFrontEnd )
				)
				( attribute "CDS_LIB" "mstr_discrete"
					( Origin gPackager )
				)
				( attribute "CDS_LOCATION" "C6P14"
					( Origin gPackager )
				)
				( attribute "CDS_SEC" "1"
					( Origin gPackager )
				)
				( attribute "LOCATION" "C6P14"
					( Origin gFrontEnd )
				)
				( attribute "MATERIAL" "ALUM"
					( Origin gFrontEnd )
				)
				( attribute "PACK_TYPE" "3018"
					( Origin gFrontEnd )
				)
				( attribute "PART_NUMBER" "699013-049"
					( Origin gFrontEnd )
				)
				( attribute "PHYS_PAGE" "203"
					( Origin gFrontEnd )
				)
				( attribute "ROOM" "PVCCIN_CPU0_DECAP_VR"
					( Origin gFrontEnd )
				)
				( attribute "ROT" "0"
					( Origin gFrontEnd )
				)
				( attribute "SEC" "1"
					( Origin gFrontEnd )
				)
				( attribute "SEC_TYPE" "3018"
					( Origin gFrontEnd )
				)
				( attribute "TOLERANCE" "20%"
					( Origin gFrontEnd )
				)
				( attribute "VALUE" "470UF"
					( Origin gFrontEnd )
				)
				( attribute "VER" "1"
					( Origin gFrontEnd )
				)
				( attribute "VOLTAGE" "2.5V"
					( Units "uVoltage" "V" 1.000000)
					( Origin gFrontEnd )
				)
				( attribute "XY" "(-2300,2600)"
					( Origin gFrontEnd )
				)
				( attribute "CHIPS_PART_NAME" "CAPP"
					( Origin gPackager )
				)
				( attribute "CDS_PART_NAME" "CAPP_3018-470UF,2.5V,20%,ALUM,A"
					( Origin gPackager )
				)
				( attribute "GROUP" "PWR_BULK_CAP"
					( Origin gFrontEnd )
				)
				( objectStatus "C6P14" )
			)
			( gate "@baseboard_fab2_lib.baseboard_fab2(sch_1):page203_i30"
				( attribute "BOM_COST" "PROC_VRD_VCCIN_CPU0"
					( Origin gFrontEnd )
				)
				( attribute "CDS_LIB" "mstr_discrete"
					( Origin gPackager )
				)
				( attribute "CDS_LOCATION" "C6P18"
					( Origin gPackager )
				)
				( attribute "CDS_SEC" "1"
					( Origin gPackager )
				)
				( attribute "LOCATION" "C6P18"
					( Origin gFrontEnd )
				)
				( attribute "MATERIAL" "ALUM"
					( Origin gFrontEnd )
				)
				( attribute "PACK_TYPE" "3018"
					( Origin gFrontEnd )
				)
				( attribute "PART_NUMBER" "699013-049"
					( Origin gFrontEnd )
				)
				( attribute "PHYS_PAGE" "203"
					( Origin gFrontEnd )
				)
				( attribute "ROOM" "PVCCIN_CPU0_DECAP_VR"
					( Origin gFrontEnd )
				)
				( attribute "ROT" "0"
					( Origin gFrontEnd )
				)
				( attribute "SEC" "1"
					( Origin gFrontEnd )
				)
				( attribute "SEC_TYPE" "3018"
					( Origin gFrontEnd )
				)
				( attribute "TOLERANCE" "20%"
					( Origin gFrontEnd )
				)
				( attribute "VALUE" "470UF"
					( Origin gFrontEnd )
				)
				( attribute "VER" "1"
					( Origin gFrontEnd )
				)
				( attribute "VOLTAGE" "2.5V"
					( Units "uVoltage" "V" 1.000000)
					( Origin gFrontEnd )
				)
				( attribute "XY" "(-2750,2600)"
					( Origin gFrontEnd )
				)
				( attribute "CHIPS_PART_NAME" "CAPP"
					( Origin gPackager )
				)
				( attribute "CDS_PART_NAME" "CAPP_3018-470UF,2.5V,20%,ALUM,A"
					( Origin gPackager )
				)
				( attribute "GROUP" "PWR_BULK_CAP"
					( Origin gFrontEnd )
				)
				( objectStatus "C6P18" )
			)
			( gate "@baseboard_fab2_lib.baseboard_fab2(sch_1):page203_i32"
				( attribute "BOM_COST" "PROC_VRD_VCCIN_CPU0"
					( Origin gFrontEnd )
				)
				( attribute "CDS_LIB" "mstr_discrete"
					( Origin gPackager )
				)
				( attribute "CDS_LOCATION" "C6P8"
					( Origin gPackager )
				)
				( attribute "CDS_SEC" "1"
					( Origin gPackager )
				)
				( attribute "LOCATION" "C6P8"
					( Origin gFrontEnd )
				)
				( attribute "MATERIAL" "ALUM"
					( Origin gFrontEnd )
				)
				( attribute "PACK_TYPE" "3018"
					( Origin gFrontEnd )
				)
				( attribute "PART_NUMBER" "699013-049"
					( Origin gFrontEnd )
				)
				( attribute "PHYS_PAGE" "203"
					( Origin gFrontEnd )
				)
				( attribute "ROOM" "PVCCIN_CPU0_DECAP_VR"
					( Origin gFrontEnd )
				)
				( attribute "ROT" "0"
					( Origin gFrontEnd )
				)
				( attribute "SEC" "1"
					( Origin gFrontEnd )
				)
				( attribute "SEC_TYPE" "3018"
					( Origin gFrontEnd )
				)
				( attribute "TOLERANCE" "20%"
					( Origin gFrontEnd )
				)
				( attribute "VALUE" "470UF"
					( Origin gFrontEnd )
				)
				( attribute "VER" "1"
					( Origin gFrontEnd )
				)
				( attribute "VOLTAGE" "2.5V"
					( Units "uVoltage" "V" 1.000000)
					( Origin gFrontEnd )
				)
				( attribute "XY" "(-3200,2600)"
					( Origin gFrontEnd )
				)
				( attribute "CHIPS_PART_NAME" "CAPP"
					( Origin gPackager )
				)
				( attribute "CDS_PART_NAME" "CAPP_3018-470UF,2.5V,20%,ALUM,A"
					( Origin gPackager )
				)
				( attribute "GROUP" "PWR_BULK_CAP"
					( Origin gFrontEnd )
				)
				( objectStatus "C6P8" )
			)
			( gate "@baseboard_fab2_lib.baseboard_fab2(sch_1):page203_i34"
				( attribute "BOM_COST" "PROC_VRD_VCCIN_CPU0"
					( Origin gFrontEnd )
				)
				( attribute "CDS_LIB" "mstr_discrete"
					( Origin gPackager )
				)
				( attribute "CDS_LOCATION" "C6N9"
					( Origin gPackager )
				)
				( attribute "CDS_SEC" "1"
					( Origin gPackager )
				)
				( attribute "LOCATION" "C6N9"
					( Origin gFrontEnd )
				)
				( attribute "MATERIAL" "ALUM"
					( Origin gFrontEnd )
				)
				( attribute "PACK_TYPE" "3018"
					( Origin gFrontEnd )
				)
				( attribute "PART_NUMBER" "699013-049"
					( Origin gFrontEnd )
				)
				( attribute "PHYS_PAGE" "203"
					( Origin gFrontEnd )
				)
				( attribute "ROOM" "PVCCIN_CPU0_DECAP_VR"
					( Origin gFrontEnd )
				)
				( attribute "ROT" "0"
					( Origin gFrontEnd )
				)
				( attribute "SEC" "1"
					( Origin gFrontEnd )
				)
				( attribute "SEC_TYPE" "3018"
					( Origin gFrontEnd )
				)
				( attribute "TOLERANCE" "20%"
					( Origin gFrontEnd )
				)
				( attribute "VALUE" "470UF"
					( Origin gFrontEnd )
				)
				( attribute "VER" "1"
					( Origin gFrontEnd )
				)
				( attribute "VOLTAGE" "2.5V"
					( Units "uVoltage" "V" 1.000000)
					( Origin gFrontEnd )
				)
				( attribute "XY" "(-3625,2600)"
					( Origin gFrontEnd )
				)
				( attribute "CHIPS_PART_NAME" "CAPP"
					( Origin gPackager )
				)
				( attribute "CDS_PART_NAME" "CAPP_3018-470UF,2.5V,20%,ALUM,A"
					( Origin gPackager )
				)
				( attribute "GROUP" "PWR_BULK_CAP"
					( Origin gFrontEnd )
				)
				( objectStatus "C6N9" )
			)
			( gate "@baseboard_fab2_lib.baseboard_fab2(sch_1):page202_i108"
				( attribute "BOM_COST" "PROC_SIDEBAND"
					( Origin gFrontEnd )
				)
				( attribute "CDS_LIB" "mstr_discrete"
					( Origin gPackager )
				)
				( attribute "CDS_LOCATION" "R6R6"
					( Origin gPackager )
				)
				( attribute "CDS_SEC" "1"
					( Origin gPackager )
				)
				( attribute "LOCATION" "R6R6"
					( Origin gFrontEnd )
				)
				( attribute "MATERIAL" "CHIP"
					( Origin gFrontEnd )
				)
				( attribute "PACK_TYPE" "0402"
					( Origin gFrontEnd )
				)
				( attribute "PART_NUMBER" "G21497-005"
					( Origin gFrontEnd )
				)
				( attribute "PHYS_PAGE" "202"
					( Origin gFrontEnd )
				)
				( attribute "ROOM" "CPU0"
					( Origin gFrontEnd )
				)
				( attribute "ROT" "0"
					( Origin gFrontEnd )
				)
				( attribute "SEC" "1"
					( Origin gFrontEnd )
				)
				( attribute "SEC_TYPE" "0402"
					( Origin gFrontEnd )
				)
				( attribute "TOLERANCE" "5%"
					( Origin gFrontEnd )
				)
				( attribute "VALUE" "0.0"
					( Origin gFrontEnd )
				)
				( attribute "VER" "1"
					( Origin gFrontEnd )
				)
				( attribute "WATTAGE" "1/16W"
					( Origin gFrontEnd )
				)
				( attribute "XY" "(-5625,1975)"
					( Origin gFrontEnd )
				)
				( attribute "CHIPS_PART_NAME" "RES"
					( Origin gPackager )
				)
				( attribute "CDS_PART_NAME" "RES_0402-0.0,5%,1/16W,CHIP,G21A"
					( Origin gPackager )
				)
				( objectStatus "R6R6" )
			)
			( gate "@baseboard_fab2_lib.baseboard_fab2(sch_1):page203_i40"
				( attribute "CDS_LIB" "mstr_discrete"
					( Origin gPackager )
				)
				( attribute "CDS_LOCATION" "C4D13"
					( Origin gPackager )
				)
				( attribute "CDS_SEC" "1"
					( Origin gPackager )
				)
				( attribute "LOCATION" "C4D13"
					( Origin gFrontEnd )
				)
				( attribute "MATERIAL" "X7R"
					( Origin gFrontEnd )
				)
				( attribute "PACK_TYPE" "0402"
					( Origin gFrontEnd )
				)
				( attribute "PART_NUMBER" "A36096-155"
					( Origin gFrontEnd )
				)
				( attribute "PHYS_PAGE" "203"
					( Origin gFrontEnd )
				)
				( attribute "ROOM" "PVCCIN_CPU0_PWR_VR"
					( Origin gFrontEnd )
				)
				( attribute "ROT" "0"
					( Origin gFrontEnd )
				)
				( attribute "SEC" "1"
					( Origin gFrontEnd )
				)
				( attribute "SEC_TYPE" "0402"
					( Origin gFrontEnd )
				)
				( attribute "TOLERANCE" "10%"
					( Origin gFrontEnd )
				)
				( attribute "VALUE" "0.22UF"
					( Origin gFrontEnd )
				)
				( attribute "VER" "1"
					( Origin gFrontEnd )
				)
				( attribute "VOLTAGE" "16V"
					( Units "uVoltage" "V" 1.000000)
					( Origin gFrontEnd )
				)
				( attribute "XY" "(-4600,4150)"
					( Origin gFrontEnd )
				)
				( attribute "CHIPS_PART_NAME" "CAP"
					( Origin gPackager )
				)
				( attribute "CDS_PART_NAME" "CAP_0402-0.22UF,16V,10%,X7R,A3A"
					( Origin gPackager )
				)
				( objectStatus "C4D13" )
			)
			( gate "@baseboard_fab2_lib.baseboard_fab2(sch_1):page202_i112"
				( attribute "CDS_LIB" "w_hdl"
					( Origin gPackager )
				)
				( attribute "CDS_LMAN_SYM_OUTLINE" "-50,25,50,-25"
					( Origin gPackager )
				)
				( attribute "LOCATION" "C4E6"
					( Origin gFrontEnd )
				)
				( attribute "PACK_TYPE" "SMD-BCG6"
					( Origin gFrontEnd )
				)
				( attribute "PART_NUMBER" "78.10523.8FL"
					( Origin gFrontEnd )
				)
				( attribute "PHYS_PAGE" "202"
					( Origin gFrontEnd )
				)
				( attribute "ROT" "0"
					( Origin gFrontEnd )
				)
				( attribute "SEC" "1"
					( Origin gFrontEnd )
				)
				( attribute "SEC_TYPE" "SMD-BCG6"
					( Origin gFrontEnd )
				)
				( attribute "VALUE" "SC1U10V2KX-4-GP"
					( Origin gFrontEnd )
				)
				( attribute "VER" "1"
					( Origin gFrontEnd )
				)
				( attribute "XY" "(-5275,4075)"
					( Origin gFrontEnd )
				)
				( attribute "CHIPS_PART_NAME" "SC1U10V2KX-4-GP"
					( Origin gPackager )
				)
				( attribute "CDS_PART_NAME" "SC1U10V2KX-4-GP_SMD-BCG6-SC1U1A"
					( Origin gPackager )
				)
				( attribute "ATTRIBUTE" "1UF"
					( Origin gFrontEnd )
				)
				( attribute "PACK_SIZE" "0402"
					( Origin gFrontEnd )
				)
				( attribute "RATED" "10V"
					( Origin gFrontEnd )
				)
				( attribute "TOLERANCE" "10%"
					( Origin gFrontEnd )
				)
				( attribute "CDS_LOCATION" "C4E6"
					( Origin gPackager )
				)
				( attribute "CDS_SEC" "1"
					( Origin gPackager )
				)
				( objectStatus "C4E6" )
			)
			( gate "@baseboard_fab2_lib.baseboard_fab2(sch_1):page203_i42"
				( attribute "CDS_LIB" "mstr_discrete"
					( Origin gPackager )
				)
				( attribute "CDS_LOCATION" "C4D28"
					( Origin gPackager )
				)
				( attribute "LOCATION" "C4D28"
					( Origin gFrontEnd )
				)
				( attribute "MATERIAL" "X7R"
					( Origin gFrontEnd )
				)
				( attribute "NO_XNET_CONNECTION" "1"
					( Origin gFrontEnd )
				)
				( attribute "PACK_TYPE" "0402"
					( Origin gFrontEnd )
				)
				( attribute "PART_NUMBER" "A36096-104"
					( Origin gFrontEnd )
				)
				( attribute "PHYS_PAGE" "203"
					( Origin gFrontEnd )
				)
				( attribute "ROOM" "PVCCIN_CPU0_PWR_VR"
					( Origin gFrontEnd )
				)
				( attribute "ROT" "2"
					( Origin gFrontEnd )
				)
				( attribute "SEC" "1"
					( Origin gFrontEnd )
				)
				( attribute "SEC_TYPE" "0402"
					( Origin gFrontEnd )
				)
				( attribute "SPOF" "TRUE"
					( Origin gFrontEnd )
				)
				( attribute "TOLERANCE" "10%"
					( Origin gFrontEnd )
				)
				( attribute "VALUE" "0.220UF"
					( Origin gFrontEnd )
				)
				( attribute "VER" "1"
					( Origin gFrontEnd )
				)
				( attribute "VOLTAGE" "16V"
					( Units "uVoltage" "V" 1.000000)
					( Origin gFrontEnd )
				)
				( attribute "XY" "(-5800,3550)"
					( Origin gFrontEnd )
				)
				( attribute "CHIPS_PART_NAME" "CAP"
					( Origin gPackager )
				)
				( attribute "CDS_PART_NAME" "CAP_0402-0.220UF,16V,10%,X7R,AA"
					( Origin gPackager )
				)
				( attribute "CDS_SEC" "1"
					( Origin gPackager )
				)
				( objectStatus "C4D28" )
			)
			( gate "@baseboard_fab2_lib.baseboard_fab2(sch_1):page203_i45"
				( attribute "CDS_LIB" "mstr_discrete"
					( Origin gPackager )
				)
				( attribute "CDS_LOCATION" "C4D16"
					( Origin gPackager )
				)
				( attribute "CDS_SEC" "1"
					( Origin gPackager )
				)
				( attribute "LOCATION" "C4D16"
					( Origin gFrontEnd )
				)
				( attribute "MATERIAL" "X6S"
					( Origin gFrontEnd )
				)
				( attribute "PACK_TYPE" "0402"
					( Origin gFrontEnd )
				)
				( attribute "PART_NUMBER" "D97712-011"
					( Origin gFrontEnd )
				)
				( attribute "PHYS_PAGE" "203"
					( Origin gFrontEnd )
				)
				( attribute "ROOM" "PVCCIN_CPU0_PWR_VR"
					( Origin gFrontEnd )
				)
				( attribute "ROT" "0"
					( Origin gFrontEnd )
				)
				( attribute "SEC" "1"
					( Origin gFrontEnd )
				)
				( attribute "SEC_TYPE" "0402"
					( Origin gFrontEnd )
				)
				( attribute "TOLERANCE" "10%"
					( Origin gFrontEnd )
				)
				( attribute "VALUE" "1.0UF"
					( Origin gFrontEnd )
				)
				( attribute "VER" "1"
					( Origin gFrontEnd )
				)
				( attribute "VOLTAGE" "16V"
					( Units "uVoltage" "V" 1.000000)
					( Origin gFrontEnd )
				)
				( attribute "XY" "(-5475,4150)"
					( Origin gFrontEnd )
				)
				( attribute "CHIPS_PART_NAME" "CAP"
					( Origin gPackager )
				)
				( attribute "CDS_PART_NAME" "CAP_0402-1.0UF,16V,10%,X6S,D97A"
					( Origin gPackager )
				)
				( objectStatus "C4D16" )
			)
			( gate "@baseboard_fab2_lib.baseboard_fab2(sch_1):page203_i46"
				( attribute "CDS_LIB" "dev_discrete"
					( Origin gPackager )
				)
				( attribute "CDS_LOCATION" "C4D35"
					( Origin gPackager )
				)
				( attribute "CDS_SEC" "1"
					( Origin gPackager )
				)
				( attribute "LOCATION" "C4D35"
					( Origin gFrontEnd )
				)
				( attribute "MATERIAL" "X7R"
					( Origin gFrontEnd )
				)
				( attribute "PACK_TYPE" "0402V"
					( Origin gFrontEnd )
				)
				( attribute "PART_NUMBER" "A36096-030"
					( Origin gFrontEnd )
				)
				( attribute "PHYS_PAGE" "203"
					( Origin gFrontEnd )
				)
				( attribute "ROOM" "PVCCIN_CPU0_PWR_VR"
					( Origin gFrontEnd )
				)
				( attribute "ROT" "0"
					( Origin gFrontEnd )
				)
				( attribute "SEC" "1"
					( Origin gFrontEnd )
				)
				( attribute "SEC_TYPE" "0402V"
					( Origin gFrontEnd )
				)
				( attribute "TOLERANCE" "10%"
					( Origin gFrontEnd )
				)
				( attribute "VALUE" "0.1UF"
					( Origin gFrontEnd )
				)
				( attribute "VER" "1"
					( Origin gFrontEnd )
				)
				( attribute "VOLTAGE" "16V"
					( Units "uVoltage" "V" 1.000000)
					( Origin gFrontEnd )
				)
				( attribute "XY" "(-5775,4150)"
					( Origin gFrontEnd )
				)
				( attribute "CHIPS_PART_NAME" "CAP_A"
					( Origin gPackager )
				)
				( attribute "CDS_PART_NAME" "CAP_A_0402V-0.1UF,16V,10%,X7R,A"
					( Origin gPackager )
				)
				( objectStatus "C4D35" )
			)
			( gate "@baseboard_fab2_lib.baseboard_fab2(sch_1):page203_i47"
				( attribute "CDS_LIB" "mstr_discrete"
					( Origin gPackager )
				)
				( attribute "CDS_LOCATION" "C4D30"
					( Origin gPackager )
				)
				( attribute "CDS_SEC" "1"
					( Origin gPackager )
				)
				( attribute "LOCATION" "C4D30"
					( Origin gFrontEnd )
				)
				( attribute "MATERIAL" "X6S"
					( Origin gFrontEnd )
				)
				( attribute "PACK_TYPE" "0402"
					( Origin gFrontEnd )
				)
				( attribute "PART_NUMBER" "D97712-011"
					( Origin gFrontEnd )
				)
				( attribute "PHYS_PAGE" "203"
					( Origin gFrontEnd )
				)
				( attribute "ROOM" "PVCCIN_CPU0_PWR_VR"
					( Origin gFrontEnd )
				)
				( attribute "ROT" "0"
					( Origin gFrontEnd )
				)
				( attribute "SEC" "1"
					( Origin gFrontEnd )
				)
				( attribute "SEC_TYPE" "0402"
					( Origin gFrontEnd )
				)
				( attribute "TOLERANCE" "10%"
					( Origin gFrontEnd )
				)
				( attribute "VALUE" "1.0UF"
					( Origin gFrontEnd )
				)
				( attribute "VER" "1"
					( Origin gFrontEnd )
				)
				( attribute "VOLTAGE" "16V"
					( Units "uVoltage" "V" 1.000000)
					( Origin gFrontEnd )
				)
				( attribute "XY" "(-6050,4150)"
					( Origin gFrontEnd )
				)
				( attribute "CHIPS_PART_NAME" "CAP"
					( Origin gPackager )
				)
				( attribute "CDS_PART_NAME" "CAP_0402-1.0UF,16V,10%,X6S,D97A"
					( Origin gPackager )
				)
				( objectStatus "C4D30" )
			)
			( gate "@baseboard_fab2_lib.baseboard_fab2(sch_1):page203_i48"
				( attribute "CDS_LIB" "mstr_discrete"
					( Origin gPackager )
				)
				( attribute "CDS_LOCATION" "C4D5"
					( Origin gPackager )
				)
				( attribute "CDS_SEC" "1"
					( Origin gPackager )
				)
				( attribute "LOCATION" "C4D5"
					( Origin gFrontEnd )
				)
				( attribute "MATERIAL" "X7R"
					( Origin gFrontEnd )
				)
				( attribute "PACK_TYPE" "0402"
					( Origin gFrontEnd )
				)
				( attribute "PART_NUMBER" "A36096-155"
					( Origin gFrontEnd )
				)
				( attribute "PHYS_PAGE" "203"
					( Origin gFrontEnd )
				)
				( attribute "ROOM" "PVCCIN_CPU0_PWR_VR"
					( Origin gFrontEnd )
				)
				( attribute "ROT" "0"
					( Origin gFrontEnd )
				)
				( attribute "SEC" "1"
					( Origin gFrontEnd )
				)
				( attribute "SEC_TYPE" "0402"
					( Origin gFrontEnd )
				)
				( attribute "TOLERANCE" "10%"
					( Origin gFrontEnd )
				)
				( attribute "VALUE" "0.22UF"
					( Origin gFrontEnd )
				)
				( attribute "VER" "1"
					( Origin gFrontEnd )
				)
				( attribute "VOLTAGE" "16V"
					( Units "uVoltage" "V" 1.000000)
					( Origin gFrontEnd )
				)
				( attribute "XY" "(-4825,1475)"
					( Origin gFrontEnd )
				)
				( attribute "CHIPS_PART_NAME" "CAP"
					( Origin gPackager )
				)
				( attribute "CDS_PART_NAME" "CAP_0402-0.22UF,16V,10%,X7R,A3A"
					( Origin gPackager )
				)
				( objectStatus "C4D5" )
			)
			( gate "@baseboard_fab2_lib.baseboard_fab2(sch_1):page202_i111"
				( attribute "CDS_LIB" "w_hdl"
					( Origin gPackager )
				)
				( attribute "CDS_LMAN_SYM_OUTLINE" "-50,25,50,-25"
					( Origin gPackager )
				)
				( attribute "LOCATION" "C4E25"
					( Origin gFrontEnd )
				)
				( attribute "PACK_TYPE" "SMD-BCG6"
					( Origin gFrontEnd )
				)
				( attribute "PART_NUMBER" "78.10523.8FL"
					( Origin gFrontEnd )
				)
				( attribute "PHYS_PAGE" "202"
					( Origin gFrontEnd )
				)
				( attribute "ROT" "0"
					( Origin gFrontEnd )
				)
				( attribute "SEC" "1"
					( Origin gFrontEnd )
				)
				( attribute "SEC_TYPE" "SMD-BCG6"
					( Origin gFrontEnd )
				)
				( attribute "VALUE" "SC1U10V2KX-4-GP"
					( Origin gFrontEnd )
				)
				( attribute "VER" "1"
					( Origin gFrontEnd )
				)
				( attribute "XY" "(-5275,1425)"
					( Origin gFrontEnd )
				)
				( attribute "CHIPS_PART_NAME" "SC1U10V2KX-4-GP"
					( Origin gPackager )
				)
				( attribute "CDS_PART_NAME" "SC1U10V2KX-4-GP_SMD-BCG6-SC1U1A"
					( Origin gPackager )
				)
				( attribute "CDS_LOCATION" "C4E25"
					( Origin gPackager )
				)
				( attribute "CDS_SEC" "1"
					( Origin gPackager )
				)
				( attribute "ATTRIBUTE" "1UF"
					( Origin gFrontEnd )
				)
				( attribute "PACK_SIZE" "0402"
					( Origin gFrontEnd )
				)
				( attribute "RATED" "10V"
					( Origin gFrontEnd )
				)
				( attribute "TOLERANCE" "10%"
					( Origin gFrontEnd )
				)
				( objectStatus "C4E25" )
			)
			( gate "@baseboard_fab2_lib.baseboard_fab2(sch_1):page202_i107"
				( attribute "BOM_COST" "PROC_SIDEBAND"
					( Origin gFrontEnd )
				)
				( attribute "CDS_LIB" "mstr_discrete"
					( Origin gPackager )
				)
				( attribute "CDS_LOCATION" "R6R2"
					( Origin gPackager )
				)
				( attribute "CDS_SEC" "1"
					( Origin gPackager )
				)
				( attribute "LOCATION" "R6R2"
					( Origin gFrontEnd )
				)
				( attribute "MATERIAL" "CHIP"
					( Origin gFrontEnd )
				)
				( attribute "PACK_TYPE" "0402"
					( Origin gFrontEnd )
				)
				( attribute "PART_NUMBER" "G21497-005"
					( Origin gFrontEnd )
				)
				( attribute "PHYS_PAGE" "202"
					( Origin gFrontEnd )
				)
				( attribute "ROOM" "CPU0"
					( Origin gFrontEnd )
				)
				( attribute "ROT" "0"
					( Origin gFrontEnd )
				)
				( attribute "SEC" "1"
					( Origin gFrontEnd )
				)
				( attribute "SEC_TYPE" "0402"
					( Origin gFrontEnd )
				)
				( attribute "TOLERANCE" "5%"
					( Origin gFrontEnd )
				)
				( attribute "VALUE" "0.0"
					( Origin gFrontEnd )
				)
				( attribute "VER" "1"
					( Origin gFrontEnd )
				)
				( attribute "WATTAGE" "1/16W"
					( Origin gFrontEnd )
				)
				( attribute "XY" "(-5550,4625)"
					( Origin gFrontEnd )
				)
				( attribute "CHIPS_PART_NAME" "RES"
					( Origin gPackager )
				)
				( attribute "CDS_PART_NAME" "RES_0402-0.0,5%,1/16W,CHIP,G21A"
					( Origin gPackager )
				)
				( objectStatus "R6R2" )
			)
			( gate "@baseboard_fab2_lib.baseboard_fab2(sch_1):page203_i51"
				( attribute "CDS_LIB" "mstr_discrete"
					( Origin gPackager )
				)
				( attribute "CDS_LOCATION" "C4D7"
					( Origin gPackager )
				)
				( attribute "CDS_SEC" "1"
					( Origin gPackager )
				)
				( attribute "LOCATION" "C4D7"
					( Origin gFrontEnd )
				)
				( attribute "MATERIAL" "X6S"
					( Origin gFrontEnd )
				)
				( attribute "PACK_TYPE" "0402"
					( Origin gFrontEnd )
				)
				( attribute "PART_NUMBER" "D97712-011"
					( Origin gFrontEnd )
				)
				( attribute "PHYS_PAGE" "203"
					( Origin gFrontEnd )
				)
				( attribute "ROOM" "PVCCIN_CPU0_PWR_VR"
					( Origin gFrontEnd )
				)
				( attribute "ROT" "0"
					( Origin gFrontEnd )
				)
				( attribute "SEC" "1"
					( Origin gFrontEnd )
				)
				( attribute "SEC_TYPE" "0402"
					( Origin gFrontEnd )
				)
				( attribute "TOLERANCE" "10%"
					( Origin gFrontEnd )
				)
				( attribute "VALUE" "1.0UF"
					( Origin gFrontEnd )
				)
				( attribute "VER" "1"
					( Origin gFrontEnd )
				)
				( attribute "VOLTAGE" "16V"
					( Units "uVoltage" "V" 1.000000)
					( Origin gFrontEnd )
				)
				( attribute "XY" "(-5675,1475)"
					( Origin gFrontEnd )
				)
				( attribute "CHIPS_PART_NAME" "CAP"
					( Origin gPackager )
				)
				( attribute "CDS_PART_NAME" "CAP_0402-1.0UF,16V,10%,X6S,D97A"
					( Origin gPackager )
				)
				( objectStatus "C4D7" )
			)
			( gate "@baseboard_fab2_lib.baseboard_fab2(sch_1):page203_i52"
				( attribute "CDS_LIB" "dev_discrete"
					( Origin gPackager )
				)
				( attribute "CDS_LOCATION" "C4D11"
					( Origin gPackager )
				)
				( attribute "CDS_SEC" "1"
					( Origin gPackager )
				)
				( attribute "LOCATION" "C4D11"
					( Origin gFrontEnd )
				)
				( attribute "MATERIAL" "X7R"
					( Origin gFrontEnd )
				)
				( attribute "PACK_TYPE" "0402V"
					( Origin gFrontEnd )
				)
				( attribute "PART_NUMBER" "A36096-030"
					( Origin gFrontEnd )
				)
				( attribute "PHYS_PAGE" "203"
					( Origin gFrontEnd )
				)
				( attribute "ROOM" "PVCCIN_CPU0_PWR_VR"
					( Origin gFrontEnd )
				)
				( attribute "ROT" "0"
					( Origin gFrontEnd )
				)
				( attribute "SEC" "1"
					( Origin gFrontEnd )
				)
				( attribute "SEC_TYPE" "0402V"
					( Origin gFrontEnd )
				)
				( attribute "TOLERANCE" "10%"
					( Origin gFrontEnd )
				)
				( attribute "VALUE" "0.1UF"
					( Origin gFrontEnd )
				)
				( attribute "VER" "1"
					( Origin gFrontEnd )
				)
				( attribute "VOLTAGE" "16V"
					( Units "uVoltage" "V" 1.000000)
					( Origin gFrontEnd )
				)
				( attribute "XY" "(-5975,1475)"
					( Origin gFrontEnd )
				)
				( attribute "CHIPS_PART_NAME" "CAP_A"
					( Origin gPackager )
				)
				( attribute "CDS_PART_NAME" "CAP_A_0402V-0.1UF,16V,10%,X7R,A"
					( Origin gPackager )
				)
				( objectStatus "C4D11" )
			)
			( gate "@baseboard_fab2_lib.baseboard_fab2(sch_1):page203_i53"
				( attribute "CDS_LIB" "mstr_discrete"
					( Origin gPackager )
				)
				( attribute "CDS_LOCATION" "C4D10"
					( Origin gPackager )
				)
				( attribute "CDS_SEC" "1"
					( Origin gPackager )
				)
				( attribute "LOCATION" "C4D10"
					( Origin gFrontEnd )
				)
				( attribute "MATERIAL" "X6S"
					( Origin gFrontEnd )
				)
				( attribute "PACK_TYPE" "0402"
					( Origin gFrontEnd )
				)
				( attribute "PART_NUMBER" "D97712-011"
					( Origin gFrontEnd )
				)
				( attribute "PHYS_PAGE" "203"
					( Origin gFrontEnd )
				)
				( attribute "ROOM" "PVCCIN_CPU0_PWR_VR"
					( Origin gFrontEnd )
				)
				( attribute "ROT" "0"
					( Origin gFrontEnd )
				)
				( attribute "SEC" "1"
					( Origin gFrontEnd )
				)
				( attribute "SEC_TYPE" "0402"
					( Origin gFrontEnd )
				)
				( attribute "TOLERANCE" "10%"
					( Origin gFrontEnd )
				)
				( attribute "VALUE" "1.0UF"
					( Origin gFrontEnd )
				)
				( attribute "VER" "1"
					( Origin gFrontEnd )
				)
				( attribute "VOLTAGE" "16V"
					( Units "uVoltage" "V" 1.000000)
					( Origin gFrontEnd )
				)
				( attribute "XY" "(-6250,1475)"
					( Origin gFrontEnd )
				)
				( attribute "CHIPS_PART_NAME" "CAP"
					( Origin gPackager )
				)
				( attribute "CDS_PART_NAME" "CAP_0402-1.0UF,16V,10%,X6S,D97A"
					( Origin gPackager )
				)
				( objectStatus "C4D10" )
			)
			( gate "@baseboard_fab2_lib.baseboard_fab2(sch_1):page203_i54"
				( attribute "CDS_LIB" "mstr_discrete"
					( Origin gPackager )
				)
				( attribute "CDS_LOCATION" "C6P19"
					( Origin gPackager )
				)
				( attribute "CDS_SEC" "1"
					( Origin gPackager )
				)
				( attribute "LOCATION" "C6P19"
					( Origin gFrontEnd )
				)
				( attribute "MATERIAL" "X6S"
					( Origin gFrontEnd )
				)
				( attribute "PACK_TYPE" "0805"
					( Origin gFrontEnd )
				)
				( attribute "PART_NUMBER" "C95333-007"
					( Origin gFrontEnd )
				)
				( attribute "PHYS_PAGE" "203"
					( Origin gFrontEnd )
				)
				( attribute "ROOM" "PVCCIN_CPU0_PWR_VR"
					( Origin gFrontEnd )
				)
				( attribute "ROT" "0"
					( Origin gFrontEnd )
				)
				( attribute "SEC" "1"
					( Origin gFrontEnd )
				)
				( attribute "SEC_TYPE" "0805"
					( Origin gFrontEnd )
				)
				( attribute "TOLERANCE" "10%"
					( Origin gFrontEnd )
				)
				( attribute "VALUE" "10UF"
					( Origin gFrontEnd )
				)
				( attribute "VER" "1"
					( Origin gFrontEnd )
				)
				( attribute "VOLTAGE" "16V"
					( Units "uVoltage" "V" 1.000000)
					( Origin gFrontEnd )
				)
				( attribute "XY" "(-7000,4175)"
					( Origin gFrontEnd )
				)
				( attribute "CHIPS_PART_NAME" "CAP"
					( Origin gPackager )
				)
				( attribute "CDS_PART_NAME" "CAP_0805-10UF,16V,10%,X6S,C953A"
					( Origin gPackager )
				)
				( objectStatus "C6P19" )
			)
			( gate "@baseboard_fab2_lib.baseboard_fab2(sch_1):page203_i57"
				( attribute "CDS_LIB" "mstr_discrete"
					( Origin gPackager )
				)
				( attribute "CDS_LOCATION" "C6P20"
					( Origin gPackager )
				)
				( attribute "CDS_SEC" "1"
					( Origin gPackager )
				)
				( attribute "LOCATION" "C6P20"
					( Origin gFrontEnd )
				)
				( attribute "MATERIAL" "X6S"
					( Origin gFrontEnd )
				)
				( attribute "PACK_TYPE" "0805"
					( Origin gFrontEnd )
				)
				( attribute "PART_NUMBER" "C95333-007"
					( Origin gFrontEnd )
				)
				( attribute "PHYS_PAGE" "203"
					( Origin gFrontEnd )
				)
				( attribute "ROOM" "PVCCIN_CPU0_PWR_VR"
					( Origin gFrontEnd )
				)
				( attribute "ROT" "0"
					( Origin gFrontEnd )
				)
				( attribute "SEC" "1"
					( Origin gFrontEnd )
				)
				( attribute "SEC_TYPE" "0805"
					( Origin gFrontEnd )
				)
				( attribute "TOLERANCE" "10%"
					( Origin gFrontEnd )
				)
				( attribute "VALUE" "10UF"
					( Origin gFrontEnd )
				)
				( attribute "VER" "1"
					( Origin gFrontEnd )
				)
				( attribute "VOLTAGE" "16V"
					( Units "uVoltage" "V" 1.000000)
					( Origin gFrontEnd )
				)
				( attribute "XY" "(-6550,1475)"
					( Origin gFrontEnd )
				)
				( attribute "CHIPS_PART_NAME" "CAP"
					( Origin gPackager )
				)
				( attribute "CDS_PART_NAME" "CAP_0805-10UF,16V,10%,X6S,C953A"
					( Origin gPackager )
				)
				( objectStatus "C6P20" )
			)
			( gate "@baseboard_fab2_lib.baseboard_fab2(sch_1):page203_i58"
				( attribute "CDS_LIB" "mstr_discrete"
					( Origin gPackager )
				)
				( attribute "CDS_LOCATION" "C6P15"
					( Origin gPackager )
				)
				( attribute "CDS_SEC" "1"
					( Origin gPackager )
				)
				( attribute "LOCATION" "C6P15"
					( Origin gFrontEnd )
				)
				( attribute "MATERIAL" "X6S"
					( Origin gFrontEnd )
				)
				( attribute "PACK_TYPE" "0805"
					( Origin gFrontEnd )
				)
				( attribute "PART_NUMBER" "C95333-007"
					( Origin gFrontEnd )
				)
				( attribute "PHYS_PAGE" "203"
					( Origin gFrontEnd )
				)
				( attribute "ROOM" "PVCCIN_CPU0_PWR_VR"
					( Origin gFrontEnd )
				)
				( attribute "ROT" "0"
					( Origin gFrontEnd )
				)
				( attribute "SEC" "1"
					( Origin gFrontEnd )
				)
				( attribute "SEC_TYPE" "0805"
					( Origin gFrontEnd )
				)
				( attribute "TOLERANCE" "10%"
					( Origin gFrontEnd )
				)
				( attribute "VALUE" "10UF"
					( Origin gFrontEnd )
				)
				( attribute "VER" "1"
					( Origin gFrontEnd )
				)
				( attribute "VOLTAGE" "16V"
					( Units "uVoltage" "V" 1.000000)
					( Origin gFrontEnd )
				)
				( attribute "XY" "(-6825,1475)"
					( Origin gFrontEnd )
				)
				( attribute "CHIPS_PART_NAME" "CAP"
					( Origin gPackager )
				)
				( attribute "CDS_PART_NAME" "CAP_0805-10UF,16V,10%,X6S,C953A"
					( Origin gPackager )
				)
				( objectStatus "C6P15" )
			)
			( gate "@baseboard_fab2_lib.baseboard_fab2(sch_1):page203_i59"
				( attribute "CDS_LIB" "mstr_discrete"
					( Origin gPackager )
				)
				( attribute "CDS_LOCATION" "C6P7"
					( Origin gPackager )
				)
				( attribute "CDS_SEC" "1"
					( Origin gPackager )
				)
				( attribute "LOCATION" "C6P7"
					( Origin gFrontEnd )
				)
				( attribute "MATERIAL" "X6S"
					( Origin gFrontEnd )
				)
				( attribute "PACK_TYPE" "0805"
					( Origin gFrontEnd )
				)
				( attribute "PART_NUMBER" "C95333-007"
					( Origin gFrontEnd )
				)
				( attribute "PHYS_PAGE" "203"
					( Origin gFrontEnd )
				)
				( attribute "ROOM" "PVCCIN_CPU0_PWR_VR"
					( Origin gFrontEnd )
				)
				( attribute "ROT" "0"
					( Origin gFrontEnd )
				)
				( attribute "SEC" "1"
					( Origin gFrontEnd )
				)
				( attribute "SEC_TYPE" "0805"
					( Origin gFrontEnd )
				)
				( attribute "TOLERANCE" "10%"
					( Origin gFrontEnd )
				)
				( attribute "VALUE" "10UF"
					( Origin gFrontEnd )
				)
				( attribute "VER" "1"
					( Origin gFrontEnd )
				)
				( attribute "VOLTAGE" "16V"
					( Units "uVoltage" "V" 1.000000)
					( Origin gFrontEnd )
				)
				( attribute "XY" "(-7100,1475)"
					( Origin gFrontEnd )
				)
				( attribute "CHIPS_PART_NAME" "CAP"
					( Origin gPackager )
				)
				( attribute "CDS_PART_NAME" "CAP_0805-10UF,16V,10%,X6S,C953A"
					( Origin gPackager )
				)
				( objectStatus "C6P7" )
			)
			( gate "@baseboard_fab2_lib.baseboard_fab2(sch_1):page203_i66"
				( attribute "BOM_COST" "PROC_VRD_VCCIN_CPU0"
					( Origin gFrontEnd )
				)
				( attribute "CDS_LIB" "dev_discrete"
					( Origin gPackager )
				)
				( attribute "CDS_LOCATION" "C6P21"
					( Origin gPackager )
				)
				( attribute "CDS_SEC" "1"
					( Origin gPackager )
				)
				( attribute "LOCATION" "C6P21"
					( Origin gFrontEnd )
				)
				( attribute "MATERIAL" "X6S"
					( Origin gFrontEnd )
				)
				( attribute "PACK_TYPE" "0603V"
					( Origin gFrontEnd )
				)
				( attribute "PART_NUMBER" "E15431-004"
					( Origin gFrontEnd )
				)
				( attribute "PHYS_PAGE" "203"
					( Origin gFrontEnd )
				)
				( attribute "ROOM" "PVCCIN_CPU0_PWR_VR"
					( Origin gFrontEnd )
				)
				( attribute "ROT" "0"
					( Origin gFrontEnd )
				)
				( attribute "SEC" "1"
					( Origin gFrontEnd )
				)
				( attribute "SEC_TYPE" "0603V"
					( Origin gFrontEnd )
				)
				( attribute "TOLERANCE" "20%"
					( Origin gFrontEnd )
				)
				( attribute "VALUE" "22.0UF"
					( Origin gFrontEnd )
				)
				( attribute "VER" "1"
					( Origin gFrontEnd )
				)
				( attribute "VOLTAGE" "4V"
					( Units "uVoltage" "V" 1.000000)
					( Origin gFrontEnd )
				)
				( attribute "XY" "(-800,3450)"
					( Origin gFrontEnd )
				)
				( attribute "CHIPS_PART_NAME" "CAP_A"
					( Origin gPackager )
				)
				( attribute "CDS_PART_NAME" "CAP_A_0603V-22.0UF,4V,20%,X6S,A"
					( Origin gPackager )
				)
				( attribute "GROUP" "PWR_MLCC_CAP"
					( Origin gFrontEnd )
				)
				( objectStatus "C6P21" )
			)
			( gate "@baseboard_fab2_lib.baseboard_fab2(sch_1):page203_i67"
				( attribute "BOM_COST" "PROC_VRD_VCCIN_CPU0"
					( Origin gFrontEnd )
				)
				( attribute "CDS_LIB" "mstr_discrete"
					( Origin gPackager )
				)
				( attribute "CDS_LOCATION" "R4E13"
					( Origin gPackager )
				)
				( attribute "CDS_SEC" "1"
					( Origin gPackager )
				)
				( attribute "LOCATION" "R4E13"
					( Origin gFrontEnd )
				)
				( attribute "MATERIAL" "CHIP"
					( Origin gFrontEnd )
				)
				( attribute "PACK_TYPE" "0603"
					( Origin gFrontEnd )
				)
				( attribute "PART_NUMBER" "G22026-038"
					( Origin gFrontEnd )
				)
				( attribute "PHYS_PAGE" "203"
					( Origin gFrontEnd )
				)
				( attribute "ROOM" "PVCCIN_CPU0_DECAP_VR"
					( Origin gFrontEnd )
				)
				( attribute "ROT" "0"
					( Origin gFrontEnd )
				)
				( attribute "SEC" "1"
					( Origin gFrontEnd )
				)
				( attribute "SEC_TYPE" "0603"
					( Origin gFrontEnd )
				)
				( attribute "TOLERANCE" "1%"
					( Origin gFrontEnd )
				)
				( attribute "VALUE" "100.0"
					( Origin gFrontEnd )
				)
				( attribute "VER" "2"
					( Origin gFrontEnd )
				)
				( attribute "WATTAGE" "1/10W"
					( Origin gFrontEnd )
				)
				( attribute "XY" "(-475,2550)"
					( Origin gFrontEnd )
				)
				( attribute "CHIPS_PART_NAME" "RES"
					( Origin gPackager )
				)
				( attribute "CDS_PART_NAME" "RES_0603-100.0,1%,1/10W,CHIP,GA"
					( Origin gPackager )
				)
				( objectStatus "R4E13" )
			)
			( gate "@baseboard_fab2_lib.baseboard_fab2(sch_1):page203_i68"
				( attribute "CDS_LIB" "dev_discrete"
					( Origin gPackager )
				)
				( attribute "CDS_LOCATION" "C4D34"
					( Origin gPackager )
				)
				( attribute "CDS_SEC" "1"
					( Origin gPackager )
				)
				( attribute "LOCATION" "C4D34"
					( Origin gFrontEnd )
				)
				( attribute "MATERIAL" "X6S"
					( Origin gFrontEnd )
				)
				( attribute "PACK_TYPE" "0603V"
					( Origin gFrontEnd )
				)
				( attribute "PART_NUMBER" "E15431-004"
					( Origin gFrontEnd )
				)
				( attribute "PHYS_PAGE" "203"
					( Origin gFrontEnd )
				)
				( attribute "ROT" "0"
					( Origin gFrontEnd )
				)
				( attribute "SEC" "1"
					( Origin gFrontEnd )
				)
				( attribute "SEC_TYPE" "0603V"
					( Origin gFrontEnd )
				)
				( attribute "TOLERANCE" "20%"
					( Origin gFrontEnd )
				)
				( attribute "VALUE" "22.0UF"
					( Origin gFrontEnd )
				)
				( attribute "VER" "1"
					( Origin gFrontEnd )
				)
				( attribute "VOLTAGE" "4V"
					( Units "uVoltage" "V" 1.000000)
					( Origin gFrontEnd )
				)
				( attribute "XY" "(-500,3450)"
					( Origin gFrontEnd )
				)
				( attribute "CHIPS_PART_NAME" "CAP_A"
					( Origin gPackager )
				)
				( attribute "CDS_PART_NAME" "CAP_A_0603V-22.0UF,4V,20%,X6S,A"
					( Origin gPackager )
				)
				( attribute "GROUP" "PWR_MLCC_CAP"
					( Origin gFrontEnd )
				)
				( objectStatus "C4D34" )
			)
			( gate "@baseboard_fab2_lib.baseboard_fab2(sch_1):page203_i69"
				( attribute "CDS_LIB" "dev_discrete"
					( Origin gPackager )
				)
				( attribute "CDS_LOCATION" "C4D4"
					( Origin gPackager )
				)
				( attribute "CDS_SEC" "1"
					( Origin gPackager )
				)
				( attribute "LOCATION" "C4D4"
					( Origin gFrontEnd )
				)
				( attribute "MATERIAL" "X6S"
					( Origin gFrontEnd )
				)
				( attribute "PACK_TYPE" "0603V"
					( Origin gFrontEnd )
				)
				( attribute "PART_NUMBER" "E15431-004"
					( Origin gFrontEnd )
				)
				( attribute "PHYS_PAGE" "203"
					( Origin gFrontEnd )
				)
				( attribute "ROT" "0"
					( Origin gFrontEnd )
				)
				( attribute "SEC" "1"
					( Origin gFrontEnd )
				)
				( attribute "SEC_TYPE" "0603V"
					( Origin gFrontEnd )
				)
				( attribute "TOLERANCE" "20%"
					( Origin gFrontEnd )
				)
				( attribute "VALUE" "22.0UF"
					( Origin gFrontEnd )
				)
				( attribute "VER" "1"
					( Origin gFrontEnd )
				)
				( attribute "VOLTAGE" "4V"
					( Units "uVoltage" "V" 1.000000)
					( Origin gFrontEnd )
				)
				( attribute "XY" "(-450,725)"
					( Origin gFrontEnd )
				)
				( attribute "CHIPS_PART_NAME" "CAP_A"
					( Origin gPackager )
				)
				( attribute "CDS_PART_NAME" "CAP_A_0603V-22.0UF,4V,20%,X6S,A"
					( Origin gPackager )
				)
				( attribute "GROUP" "PWR_MLCC_CAP"
					( Origin gFrontEnd )
				)
				( objectStatus "C4D4" )
			)
			( gate "@baseboard_fab2_lib.baseboard_fab2(sch_1):page203_i70"
				( attribute "CDS_LIB" "mstr_discrete"
					( Origin gPackager )
				)
				( attribute "CDS_LOCATION" "EU4D3"
					( Origin gPackager )
				)
				( attribute "CDS_SEC" "1"
					( Origin gPackager )
				)
				( attribute "LOCATION" "EU4D3"
					( Origin gFrontEnd )
				)
				( attribute "MATERIAL" "IC"
					( Origin gFrontEnd )
				)
				( attribute "PACK_TYPE" "SM"
					( Origin gFrontEnd )
				)
				( attribute "PART_NUMBER" "H73688-001"
					( Origin gFrontEnd )
				)
				( attribute "PHYS_PAGE" "203"
					( Origin gFrontEnd )
				)
				( attribute "ROT" "0"
					( Origin gFrontEnd )
				)
				( attribute "SEC" "1"
					( Origin gFrontEnd )
				)
				( attribute "SEC_TYPE" "SM"
					( Origin gFrontEnd )
				)
				( attribute "VALUE" "IR35411"
					( Origin gFrontEnd )
				)
				( attribute "VER" "1"
					( Origin gFrontEnd )
				)
				( attribute "XY" "(-3100,3925)"
					( Origin gFrontEnd )
				)
				( attribute "CHIPS_PART_NAME" "IR354XX"
					( Origin gPackager )
				)
				( attribute "CDS_PART_NAME" "IR354XX_SM-IR35411,IC,H73688-0A"
					( Origin gPackager )
				)
				( objectStatus "EU4D3" )
			)
			( gate "@baseboard_fab2_lib.baseboard_fab2(sch_1):page203_i71"
				( attribute "CDS_LIB" "mstr_discrete"
					( Origin gPackager )
				)
				( attribute "CDS_LOCATION" "EU4D1"
					( Origin gPackager )
				)
				( attribute "CDS_SEC" "1"
					( Origin gPackager )
				)
				( attribute "LOCATION" "EU4D1"
					( Origin gFrontEnd )
				)
				( attribute "MATERIAL" "IC"
					( Origin gFrontEnd )
				)
				( attribute "PACK_TYPE" "SM"
					( Origin gFrontEnd )
				)
				( attribute "PART_NUMBER" "H73688-001"
					( Origin gFrontEnd )
				)
				( attribute "PHYS_PAGE" "203"
					( Origin gFrontEnd )
				)
				( attribute "ROT" "0"
					( Origin gFrontEnd )
				)
				( attribute "SEC" "1"
					( Origin gPackager )
				)
				( attribute "VALUE" "IR35411"
					( Origin gFrontEnd )
				)
				( attribute "VER" "1"
					( Origin gFrontEnd )
				)
				( attribute "XY" "(-3125,1200)"
					( Origin gFrontEnd )
				)
				( attribute "CHIPS_PART_NAME" "IR354XX"
					( Origin gPackager )
				)
				( attribute "CDS_PART_NAME" "IR354XX_SM-IR35411,IC,H73688-0A"
					( Origin gPackager )
				)
				( objectStatus "EU4D1" )
			)
			( gate "@baseboard_fab2_lib.baseboard_fab2(sch_1):page203_i89"
				( attribute "CDS_LIB" "mstr_discrete"
					( Origin gPackager )
				)
				( attribute "CDS_LOCATION" "R4D72"
					( Origin gPackager )
				)
				( attribute "LOCATION" "R4D72"
					( Origin gFrontEnd )
				)
				( attribute "MATERIAL" "EMPTY"
					( Origin gFrontEnd )
				)
				( attribute "PACK_TYPE" "0402"
					( Origin gFrontEnd )
				)
				( attribute "PART_NUMBER" "G21796-187"
					( Origin gFrontEnd )
				)
				( attribute "PHYS_PAGE" "203"
					( Origin gFrontEnd )
				)
				( attribute "ROT" "0"
					( Origin gFrontEnd )
				)
				( attribute "SEC" "1"
					( Origin gFrontEnd )
				)
				( attribute "TOLERANCE" "1%"
					( Origin gFrontEnd )
				)
				( attribute "VALUE" "68.1K"
					( Origin gFrontEnd )
				)
				( attribute "VER" "2"
					( Origin gFrontEnd )
				)
				( attribute "WATTAGE" "1/16W"
					( Origin gFrontEnd )
				)
				( attribute "XY" "(-400,4100)"
					( Origin gFrontEnd )
				)
				( attribute "CHIPS_PART_NAME" "RES"
					( Origin gPackager )
				)
				( attribute "CDS_PART_NAME" "RES_0402-68.1K,1%,1/16W,EMPTY,A"
					( Origin gPackager )
				)
				( attribute "SEC_TYPE" "0402"
					( Origin gFrontEnd )
				)
				( attribute "CDS_SEC" "1"
					( Origin gPackager )
				)
				( objectStatus "R4D72" )
			)
			( gate "@baseboard_fab2_lib.baseboard_fab2(sch_1):page203_i91"
				( attribute "CDS_LIB" "mstr_discrete"
					( Origin gPackager )
				)
				( attribute "CDS_LOCATION" "R4D71"
					( Origin gPackager )
				)
				( attribute "LOCATION" "R4D71"
					( Origin gFrontEnd )
				)
				( attribute "MATERIAL" "EMPTY"
					( Origin gFrontEnd )
				)
				( attribute "PACK_TYPE" "0402"
					( Origin gFrontEnd )
				)
				( attribute "PART_NUMBER" "G21796-187"
					( Origin gFrontEnd )
				)
				( attribute "PHYS_PAGE" "203"
					( Origin gFrontEnd )
				)
				( attribute "ROT" "0"
					( Origin gFrontEnd )
				)
				( attribute "SEC" "1"
					( Origin gFrontEnd )
				)
				( attribute "TOLERANCE" "1%"
					( Origin gFrontEnd )
				)
				( attribute "VALUE" "68.1K"
					( Origin gFrontEnd )
				)
				( attribute "VER" "2"
					( Origin gFrontEnd )
				)
				( attribute "WATTAGE" "1/16W"
					( Origin gFrontEnd )
				)
				( attribute "XY" "(-375,1400)"
					( Origin gFrontEnd )
				)
				( attribute "CHIPS_PART_NAME" "RES"
					( Origin gPackager )
				)
				( attribute "CDS_PART_NAME" "RES_0402-68.1K,1%,1/16W,EMPTY,A"
					( Origin gPackager )
				)
				( attribute "SEC_TYPE" "0402"
					( Origin gFrontEnd )
				)
				( attribute "CDS_SEC" "1"
					( Origin gPackager )
				)
				( objectStatus "R4D71" )
			)
			( gate "@baseboard_fab2_lib.baseboard_fab2(sch_1):page207_i107"
				( attribute "CDS_LIB" "w_hdl"
					( Origin gPackager )
				)
				( attribute "CDS_LMAN_SYM_OUTLINE" "-75,100,75,-100"
					( Origin gPackager )
				)
				( attribute "LOCATION" "L1E1"
					( Origin gFrontEnd )
				)
				( attribute "PACK_TYPE" "DISCRET-GB2"
					( Origin gFrontEnd )
				)
				( attribute "PART_NUMBER" "068.1202N.M001"
					( Origin gFrontEnd )
				)
				( attribute "PHYS_PAGE" "207"
					( Origin gFrontEnd )
				)
				( attribute "ROT" "1"
					( Origin gFrontEnd )
				)
				( attribute "SEC" "1"
					( Origin gFrontEnd )
				)
				( attribute "SEC_TYPE" "DISCRET-GB2"
					( Origin gFrontEnd )
				)
				( attribute "VALUE" "IND-120NH-30-GP"
					( Origin gFrontEnd )
				)
				( attribute "VER" "1"
					( Origin gFrontEnd )
				)
				( attribute "XY" "(-1475,3575)"
					( Origin gFrontEnd )
				)
				( attribute "CHIPS_PART_NAME" "IND-120NH-30-GP"
					( Origin gPackager )
				)
				( attribute "CDS_PART_NAME" "IND-120NH-30-GP_DISCRET-GB2-INA"
					( Origin gPackager )
				)
				( attribute "CDS_LOCATION" "L1E1"
					( Origin gPackager )
				)
				( attribute "CDS_SEC" "1"
					( Origin gPackager )
				)
				( attribute "ATTRIBUTE" "120NH"
					( Origin gFrontEnd )
				)
				( attribute "PACK_SIZE" "DCR=0.17MOHM"
					( Origin gFrontEnd )
				)
				( attribute "RATED" "ISAT=94A@25C"
					( Origin gFrontEnd )
				)
				( attribute "TYPE" "IRMS=66A@DELTA_T<40C"
					( Origin gFrontEnd )
				)
				( objectStatus "L1E1" )
			)
			( gate "@baseboard_fab2_lib.baseboard_fab2(sch_1):page204_i9"
				( attribute "BOM_COST" "PROC_VRD_VCCIN_CPU0"
					( Origin gFrontEnd )
				)
				( attribute "CDS_LIB" "dev_discrete"
					( Origin gPackager )
				)
				( attribute "CDS_LOCATION" "C4D12"
					( Origin gPackager )
				)
				( attribute "CDS_SEC" "1"
					( Origin gPackager )
				)
				( attribute "LOCATION" "C4D12"
					( Origin gFrontEnd )
				)
				( attribute "MATERIAL" "X6S"
					( Origin gFrontEnd )
				)
				( attribute "PACK_TYPE" "0603V"
					( Origin gFrontEnd )
				)
				( attribute "PART_NUMBER" "E15431-004"
					( Origin gFrontEnd )
				)
				( attribute "PHYS_PAGE" "204"
					( Origin gFrontEnd )
				)
				( attribute "ROOM" "PVCCIN_CPU0_PWR_VR"
					( Origin gFrontEnd )
				)
				( attribute "ROT" "0"
					( Origin gFrontEnd )
				)
				( attribute "SEC" "1"
					( Origin gFrontEnd )
				)
				( attribute "SEC_TYPE" "0603V"
					( Origin gFrontEnd )
				)
				( attribute "TOLERANCE" "20%"
					( Origin gFrontEnd )
				)
				( attribute "VALUE" "22.0UF"
					( Origin gFrontEnd )
				)
				( attribute "VER" "1"
					( Origin gFrontEnd )
				)
				( attribute "VOLTAGE" "4V"
					( Units "uVoltage" "V" 1.000000)
					( Origin gFrontEnd )
				)
				( attribute "XY" "(-700,3425)"
					( Origin gFrontEnd )
				)
				( attribute "CHIPS_PART_NAME" "CAP_A"
					( Origin gPackager )
				)
				( attribute "CDS_PART_NAME" "CAP_A_0603V-22.0UF,4V,20%,X6S,A"
					( Origin gPackager )
				)
				( attribute "GROUP" "PWR_MLCC_CAP"
					( Origin gFrontEnd )
				)
				( objectStatus "C4D12" )
			)
			( gate "@baseboard_fab2_lib.baseboard_fab2(sch_1):page204_i18"
				( attribute "CDS_LIB" "mstr_discrete"
					( Origin gPackager )
				)
				( attribute "CDS_LOCATION" "C4D47"
					( Origin gPackager )
				)
				( attribute "CDS_SEC" "1"
					( Origin gPackager )
				)
				( attribute "LOCATION" "C4D47"
					( Origin gFrontEnd )
				)
				( attribute "MATERIAL" "X7R"
					( Origin gFrontEnd )
				)
				( attribute "PACK_TYPE" "0402"
					( Origin gFrontEnd )
				)
				( attribute "PART_NUMBER" "A36096-155"
					( Origin gFrontEnd )
				)
				( attribute "PHYS_PAGE" "204"
					( Origin gFrontEnd )
				)
				( attribute "ROOM" "PVCCIN_CPU0_PWR_VR"
					( Origin gFrontEnd )
				)
				( attribute "ROT" "0"
					( Origin gFrontEnd )
				)
				( attribute "SEC" "1"
					( Origin gFrontEnd )
				)
				( attribute "SEC_TYPE" "0402"
					( Origin gFrontEnd )
				)
				( attribute "TOLERANCE" "10%"
					( Origin gFrontEnd )
				)
				( attribute "VALUE" "0.22UF"
					( Origin gFrontEnd )
				)
				( attribute "VER" "1"
					( Origin gFrontEnd )
				)
				( attribute "VOLTAGE" "16V"
					( Units "uVoltage" "V" 1.000000)
					( Origin gFrontEnd )
				)
				( attribute "XY" "(-4875,4200)"
					( Origin gFrontEnd )
				)
				( attribute "CHIPS_PART_NAME" "CAP"
					( Origin gPackager )
				)
				( attribute "CDS_PART_NAME" "CAP_0402-0.22UF,16V,10%,X7R,A3A"
					( Origin gPackager )
				)
				( objectStatus "C4D47" )
			)
			( gate "@baseboard_fab2_lib.baseboard_fab2(sch_1):page203_i132"
				( attribute "CDS_LIB" "w_hdl"
					( Origin gPackager )
				)
				( attribute "CDS_LMAN_SYM_OUTLINE" "-50,25,50,-25"
					( Origin gPackager )
				)
				( attribute "LOCATION" "C4D14"
					( Origin gFrontEnd )
				)
				( attribute "PACK_TYPE" "SMD-BCG6"
					( Origin gFrontEnd )
				)
				( attribute "PART_NUMBER" "78.10523.8FL"
					( Origin gFrontEnd )
				)
				( attribute "PHYS_PAGE" "203"
					( Origin gFrontEnd )
				)
				( attribute "ROT" "0"
					( Origin gFrontEnd )
				)
				( attribute "SEC" "1"
					( Origin gFrontEnd )
				)
				( attribute "SEC_TYPE" "SMD-BCG6"
					( Origin gFrontEnd )
				)
				( attribute "VALUE" "SC1U10V2KX-4-GP"
					( Origin gFrontEnd )
				)
				( attribute "VER" "1"
					( Origin gFrontEnd )
				)
				( attribute "XY" "(-5050,4150)"
					( Origin gFrontEnd )
				)
				( attribute "CHIPS_PART_NAME" "SC1U10V2KX-4-GP"
					( Origin gPackager )
				)
				( attribute "CDS_PART_NAME" "SC1U10V2KX-4-GP_SMD-BCG6-SC1U1A"
					( Origin gPackager )
				)
				( attribute "CDS_LOCATION" "C4D14"
					( Origin gPackager )
				)
				( attribute "CDS_SEC" "1"
					( Origin gPackager )
				)
				( attribute "ATTRIBUTE" "1UF"
					( Origin gFrontEnd )
				)
				( attribute "PACK_SIZE" "0402"
					( Origin gFrontEnd )
				)
				( attribute "RATED" "10V"
					( Origin gFrontEnd )
				)
				( attribute "TOLERANCE" "10%"
					( Origin gFrontEnd )
				)
				( objectStatus "C4D14" )
			)
			( gate "@baseboard_fab2_lib.baseboard_fab2(sch_1):page204_i22"
				( attribute "CDS_LIB" "mstr_discrete"
					( Origin gPackager )
				)
				( attribute "CDS_LOCATION" "C4C17"
					( Origin gPackager )
				)
				( attribute "CDS_SEC" "1"
					( Origin gPackager )
				)
				( attribute "LOCATION" "C4C17"
					( Origin gFrontEnd )
				)
				( attribute "MATERIAL" "X7R"
					( Origin gFrontEnd )
				)
				( attribute "NO_XNET_CONNECTION" "1"
					( Origin gFrontEnd )
				)
				( attribute "PACK_TYPE" "0402"
					( Origin gFrontEnd )
				)
				( attribute "PART_NUMBER" "A36096-104"
					( Origin gFrontEnd )
				)
				( attribute "PHYS_PAGE" "204"
					( Origin gFrontEnd )
				)
				( attribute "ROOM" "PVCCIN_CPU0_PWR_VR"
					( Origin gFrontEnd )
				)
				( attribute "ROT" "2"
					( Origin gFrontEnd )
				)
				( attribute "SEC" "1"
					( Origin gFrontEnd )
				)
				( attribute "SEC_TYPE" "0402"
					( Origin gFrontEnd )
				)
				( attribute "SPOF" "TRUE"
					( Origin gFrontEnd )
				)
				( attribute "TOLERANCE" "10%"
					( Origin gFrontEnd )
				)
				( attribute "VALUE" "0.220UF"
					( Origin gFrontEnd )
				)
				( attribute "VER" "1"
					( Origin gFrontEnd )
				)
				( attribute "VOLTAGE" "16V"
					( Units "uVoltage" "V" 1.000000)
					( Origin gFrontEnd )
				)
				( attribute "XY" "(-5825,3575)"
					( Origin gFrontEnd )
				)
				( attribute "CHIPS_PART_NAME" "CAP"
					( Origin gPackager )
				)
				( attribute "CDS_PART_NAME" "CAP_0402-0.220UF,16V,10%,X7R,AA"
					( Origin gPackager )
				)
				( objectStatus "C4C17" )
			)
			( gate "@baseboard_fab2_lib.baseboard_fab2(sch_1):page207_i105"
				( attribute "BOM_COST" "PROC_SIDEBAND"
					( Origin gFrontEnd )
				)
				( attribute "CDS_LIB" "mstr_discrete"
					( Origin gPackager )
				)
				( attribute "CDS_LOCATION" "R9R11"
					( Origin gPackager )
				)
				( attribute "CDS_SEC" "1"
					( Origin gPackager )
				)
				( attribute "LOCATION" "R9R11"
					( Origin gFrontEnd )
				)
				( attribute "MATERIAL" "CHIP"
					( Origin gFrontEnd )
				)
				( attribute "PACK_TYPE" "0402"
					( Origin gFrontEnd )
				)
				( attribute "PART_NUMBER" "G21497-005"
					( Origin gFrontEnd )
				)
				( attribute "PHYS_PAGE" "207"
					( Origin gFrontEnd )
				)
				( attribute "ROOM" "CPU0"
					( Origin gFrontEnd )
				)
				( attribute "ROT" "0"
					( Origin gFrontEnd )
				)
				( attribute "SEC" "1"
					( Origin gFrontEnd )
				)
				( attribute "SEC_TYPE" "0402"
					( Origin gFrontEnd )
				)
				( attribute "TOLERANCE" "5%"
					( Origin gFrontEnd )
				)
				( attribute "VALUE" "0.0"
					( Origin gFrontEnd )
				)
				( attribute "VER" "1"
					( Origin gFrontEnd )
				)
				( attribute "WATTAGE" "1/16W"
					( Origin gFrontEnd )
				)
				( attribute "XY" "(-5300,2050)"
					( Origin gFrontEnd )
				)
				( attribute "CHIPS_PART_NAME" "RES"
					( Origin gPackager )
				)
				( attribute "CDS_PART_NAME" "RES_0402-0.0,5%,1/16W,CHIP,G21A"
					( Origin gPackager )
				)
				( objectStatus "R9R11" )
			)
			( gate "@baseboard_fab2_lib.baseboard_fab2(sch_1):page204_i34"
				( attribute "CDS_LIB" "mstr_discrete"
					( Origin gPackager )
				)
				( attribute "CDS_LOCATION" "C4D46"
					( Origin gPackager )
				)
				( attribute "CDS_SEC" "1"
					( Origin gPackager )
				)
				( attribute "LOCATION" "C4D46"
					( Origin gFrontEnd )
				)
				( attribute "MATERIAL" "X6S"
					( Origin gFrontEnd )
				)
				( attribute "PACK_TYPE" "0402"
					( Origin gFrontEnd )
				)
				( attribute "PART_NUMBER" "D97712-011"
					( Origin gFrontEnd )
				)
				( attribute "PHYS_PAGE" "204"
					( Origin gFrontEnd )
				)
				( attribute "ROOM" "PVCCIN_CPU0_PWR_VR"
					( Origin gFrontEnd )
				)
				( attribute "ROT" "0"
					( Origin gFrontEnd )
				)
				( attribute "SEC" "1"
					( Origin gFrontEnd )
				)
				( attribute "SEC_TYPE" "0402"
					( Origin gFrontEnd )
				)
				( attribute "TOLERANCE" "10%"
					( Origin gFrontEnd )
				)
				( attribute "VALUE" "1.0UF"
					( Origin gFrontEnd )
				)
				( attribute "VER" "1"
					( Origin gFrontEnd )
				)
				( attribute "VOLTAGE" "16V"
					( Units "uVoltage" "V" 1.000000)
					( Origin gFrontEnd )
				)
				( attribute "XY" "(-5700,4175)"
					( Origin gFrontEnd )
				)
				( attribute "CHIPS_PART_NAME" "CAP"
					( Origin gPackager )
				)
				( attribute "CDS_PART_NAME" "CAP_0402-1.0UF,16V,10%,X6S,D97A"
					( Origin gPackager )
				)
				( objectStatus "C4D46" )
			)
			( gate "@baseboard_fab2_lib.baseboard_fab2(sch_1):page204_i35"
				( attribute "CDS_LIB" "dev_discrete"
					( Origin gPackager )
				)
				( attribute "CDS_LOCATION" "C4C19"
					( Origin gPackager )
				)
				( attribute "CDS_SEC" "1"
					( Origin gPackager )
				)
				( attribute "LOCATION" "C4C19"
					( Origin gFrontEnd )
				)
				( attribute "MATERIAL" "X7R"
					( Origin gFrontEnd )
				)
				( attribute "PACK_TYPE" "0402V"
					( Origin gFrontEnd )
				)
				( attribute "PART_NUMBER" "A36096-030"
					( Origin gFrontEnd )
				)
				( attribute "PHYS_PAGE" "204"
					( Origin gFrontEnd )
				)
				( attribute "ROOM" "PVCCIN_CPU0_PWR_VR"
					( Origin gFrontEnd )
				)
				( attribute "ROT" "0"
					( Origin gFrontEnd )
				)
				( attribute "SEC" "1"
					( Origin gFrontEnd )
				)
				( attribute "SEC_TYPE" "0402V"
					( Origin gFrontEnd )
				)
				( attribute "TOLERANCE" "10%"
					( Origin gFrontEnd )
				)
				( attribute "VALUE" "0.1UF"
					( Origin gFrontEnd )
				)
				( attribute "VER" "1"
					( Origin gFrontEnd )
				)
				( attribute "VOLTAGE" "16V"
					( Units "uVoltage" "V" 1.000000)
					( Origin gFrontEnd )
				)
				( attribute "XY" "(-6000,4175)"
					( Origin gFrontEnd )
				)
				( attribute "CHIPS_PART_NAME" "CAP_A"
					( Origin gPackager )
				)
				( attribute "CDS_PART_NAME" "CAP_A_0402V-0.1UF,16V,10%,X7R,A"
					( Origin gPackager )
				)
				( objectStatus "C4C19" )
			)
			( gate "@baseboard_fab2_lib.baseboard_fab2(sch_1):page204_i36"
				( attribute "CDS_LIB" "mstr_discrete"
					( Origin gPackager )
				)
				( attribute "CDS_LOCATION" "C4C18"
					( Origin gPackager )
				)
				( attribute "CDS_SEC" "1"
					( Origin gPackager )
				)
				( attribute "LOCATION" "C4C18"
					( Origin gFrontEnd )
				)
				( attribute "MATERIAL" "X6S"
					( Origin gFrontEnd )
				)
				( attribute "PACK_TYPE" "0402"
					( Origin gFrontEnd )
				)
				( attribute "PART_NUMBER" "D97712-011"
					( Origin gFrontEnd )
				)
				( attribute "PHYS_PAGE" "204"
					( Origin gFrontEnd )
				)
				( attribute "ROOM" "PVCCIN_CPU0_PWR_VR"
					( Origin gFrontEnd )
				)
				( attribute "ROT" "0"
					( Origin gFrontEnd )
				)
				( attribute "SEC" "1"
					( Origin gFrontEnd )
				)
				( attribute "SEC_TYPE" "0402"
					( Origin gFrontEnd )
				)
				( attribute "TOLERANCE" "10%"
					( Origin gFrontEnd )
				)
				( attribute "VALUE" "1.0UF"
					( Origin gFrontEnd )
				)
				( attribute "VER" "1"
					( Origin gFrontEnd )
				)
				( attribute "VOLTAGE" "16V"
					( Units "uVoltage" "V" 1.000000)
					( Origin gFrontEnd )
				)
				( attribute "XY" "(-6300,4175)"
					( Origin gFrontEnd )
				)
				( attribute "CHIPS_PART_NAME" "CAP"
					( Origin gPackager )
				)
				( attribute "CDS_PART_NAME" "CAP_0402-1.0UF,16V,10%,X6S,D97A"
					( Origin gPackager )
				)
				( objectStatus "C4C18" )
			)
			( gate "@baseboard_fab2_lib.baseboard_fab2(sch_1):page204_i37"
				( attribute "CDS_LIB" "mstr_discrete"
					( Origin gPackager )
				)
				( attribute "CDS_LOCATION" "C6N10"
					( Origin gPackager )
				)
				( attribute "CDS_SEC" "1"
					( Origin gPackager )
				)
				( attribute "LOCATION" "C6N10"
					( Origin gFrontEnd )
				)
				( attribute "MATERIAL" "X6S"
					( Origin gFrontEnd )
				)
				( attribute "PACK_TYPE" "0805"
					( Origin gFrontEnd )
				)
				( attribute "PART_NUMBER" "C95333-007"
					( Origin gFrontEnd )
				)
				( attribute "PHYS_PAGE" "204"
					( Origin gFrontEnd )
				)
				( attribute "ROOM" "PVCCIN_CPU0_PWR_VR"
					( Origin gFrontEnd )
				)
				( attribute "ROT" "0"
					( Origin gFrontEnd )
				)
				( attribute "SEC" "1"
					( Origin gFrontEnd )
				)
				( attribute "SEC_TYPE" "0805"
					( Origin gFrontEnd )
				)
				( attribute "TOLERANCE" "10%"
					( Origin gFrontEnd )
				)
				( attribute "VALUE" "10UF"
					( Origin gFrontEnd )
				)
				( attribute "VER" "1"
					( Origin gFrontEnd )
				)
				( attribute "VOLTAGE" "16V"
					( Units "uVoltage" "V" 1.000000)
					( Origin gFrontEnd )
				)
				( attribute "XY" "(-6600,4175)"
					( Origin gFrontEnd )
				)
				( attribute "CHIPS_PART_NAME" "CAP"
					( Origin gPackager )
				)
				( attribute "CDS_PART_NAME" "CAP_0805-10UF,16V,10%,X6S,C953A"
					( Origin gPackager )
				)
				( objectStatus "C6N10" )
			)
			( gate "@baseboard_fab2_lib.baseboard_fab2(sch_1):page204_i38"
				( attribute "CDS_LIB" "mstr_discrete"
					( Origin gPackager )
				)
				( attribute "CDS_LOCATION" "C6P17"
					( Origin gPackager )
				)
				( attribute "CDS_SEC" "1"
					( Origin gPackager )
				)
				( attribute "LOCATION" "C6P17"
					( Origin gFrontEnd )
				)
				( attribute "MATERIAL" "X6S"
					( Origin gFrontEnd )
				)
				( attribute "PACK_TYPE" "0805"
					( Origin gFrontEnd )
				)
				( attribute "PART_NUMBER" "C95333-007"
					( Origin gFrontEnd )
				)
				( attribute "PHYS_PAGE" "204"
					( Origin gFrontEnd )
				)
				( attribute "ROOM" "PVCCIN_CPU0_PWR_VR"
					( Origin gFrontEnd )
				)
				( attribute "ROT" "0"
					( Origin gFrontEnd )
				)
				( attribute "SEC" "1"
					( Origin gFrontEnd )
				)
				( attribute "SEC_TYPE" "0805"
					( Origin gFrontEnd )
				)
				( attribute "TOLERANCE" "10%"
					( Origin gFrontEnd )
				)
				( attribute "VALUE" "10UF"
					( Origin gFrontEnd )
				)
				( attribute "VER" "1"
					( Origin gFrontEnd )
				)
				( attribute "VOLTAGE" "16V"
					( Units "uVoltage" "V" 1.000000)
					( Origin gFrontEnd )
				)
				( attribute "XY" "(-6900,4175)"
					( Origin gFrontEnd )
				)
				( attribute "CHIPS_PART_NAME" "CAP"
					( Origin gPackager )
				)
				( attribute "CDS_PART_NAME" "CAP_0805-10UF,16V,10%,X6S,C953A"
					( Origin gPackager )
				)
				( objectStatus "C6P17" )
			)
			( gate "@baseboard_fab2_lib.baseboard_fab2(sch_1):page204_i42"
				( attribute "CDS_LIB" "mstr_discrete"
					( Origin gPackager )
				)
				( attribute "CDS_LOCATION" "C6N11"
					( Origin gPackager )
				)
				( attribute "CDS_SEC" "1"
					( Origin gPackager )
				)
				( attribute "LOCATION" "C6N11"
					( Origin gFrontEnd )
				)
				( attribute "MATERIAL" "X6S"
					( Origin gFrontEnd )
				)
				( attribute "PACK_TYPE" "0805"
					( Origin gFrontEnd )
				)
				( attribute "PART_NUMBER" "C95333-007"
					( Origin gFrontEnd )
				)
				( attribute "PHYS_PAGE" "204"
					( Origin gFrontEnd )
				)
				( attribute "ROOM" "PVCCIN_CPU0_PWR_VR"
					( Origin gFrontEnd )
				)
				( attribute "ROT" "0"
					( Origin gFrontEnd )
				)
				( attribute "SEC" "1"
					( Origin gFrontEnd )
				)
				( attribute "SEC_TYPE" "0805"
					( Origin gFrontEnd )
				)
				( attribute "TOLERANCE" "10%"
					( Origin gFrontEnd )
				)
				( attribute "VALUE" "10UF"
					( Origin gFrontEnd )
				)
				( attribute "VER" "1"
					( Origin gFrontEnd )
				)
				( attribute "VOLTAGE" "16V"
					( Units "uVoltage" "V" 1.000000)
					( Origin gFrontEnd )
				)
				( attribute "XY" "(-7200,4175)"
					( Origin gFrontEnd )
				)
				( attribute "CHIPS_PART_NAME" "CAP"
					( Origin gPackager )
				)
				( attribute "CDS_PART_NAME" "CAP_0805-10UF,16V,10%,X6S,C953A"
					( Origin gPackager )
				)
				( objectStatus "C6N11" )
			)
			( gate "@baseboard_fab2_lib.baseboard_fab2(sch_1):page209_i81"
				( attribute "CDS_LIB" "w_hdl"
					( Origin gPackager )
				)
				( attribute "CDS_LMAN_SYM_OUTLINE" "-75,100,75,-100"
					( Origin gPackager )
				)
				( attribute "LOCATION" "L1B2"
					( Origin gFrontEnd )
				)
				( attribute "PACK_TYPE" "DISCRET-GC2"
					( Origin gFrontEnd )
				)
				( attribute "PART_NUMBER" "068.8001N.M001"
					( Origin gFrontEnd )
				)
				( attribute "PHYS_PAGE" "209"
					( Origin gFrontEnd )
				)
				( attribute "ROT" "1"
					( Origin gFrontEnd )
				)
				( attribute "SEC" "1"
					( Origin gFrontEnd )
				)
				( attribute "SEC_TYPE" "DISCRET-GC2"
					( Origin gFrontEnd )
				)
				( attribute "VALUE" "IND-80NH-1-GP"
					( Origin gFrontEnd )
				)
				( attribute "VER" "1"
					( Origin gFrontEnd )
				)
				( attribute "XY" "(-3050,2275)"
					( Origin gFrontEnd )
				)
				( attribute "CHIPS_PART_NAME" "IND-80NH-1-GP"
					( Origin gPackager )
				)
				( attribute "CDS_PART_NAME" "IND-80NH-1-GP_DISCRET-GC2-IND-A"
					( Origin gPackager )
				)
				( attribute "CDS_LOCATION" "L1B2"
					( Origin gPackager )
				)
				( attribute "CDS_SEC" "1"
					( Origin gPackager )
				)
				( attribute "ATTRIBUTE" "80NH"
					( Origin gFrontEnd )
				)
				( attribute "PACK_SIZE" "DCR=0.22MOHM"
					( Origin gFrontEnd )
				)
				( attribute "RATED" "ISAT=50A@25C"
					( Origin gFrontEnd )
				)
				( attribute "TYPE" "IRMS=34A@DELTA_T<45C"
					( Origin gFrontEnd )
				)
				( objectStatus "L1B2" )
			)
			( gate "@baseboard_fab2_lib.baseboard_fab2(sch_1):page204_i48"
				( attribute "CDS_LIB" "mstr_discrete"
					( Origin gPackager )
				)
				( attribute "CDS_LOCATION" "C4D2"
					( Origin gPackager )
				)
				( attribute "CDS_SEC" "1"
					( Origin gPackager )
				)
				( attribute "LOCATION" "C4D2"
					( Origin gFrontEnd )
				)
				( attribute "MATERIAL" "OSCON"
					( Origin gFrontEnd )
				)
				( attribute "PACK_TYPE" "2626"
					( Origin gFrontEnd )
				)
				( attribute "PART_NUMBER" "A31228-047"
					( Origin gFrontEnd )
				)
				( attribute "PHYS_PAGE" "204"
					( Origin gFrontEnd )
				)
				( attribute "ROOM" "PVCCIN_CPU0_FILTER_VR"
					( Origin gFrontEnd )
				)
				( attribute "ROT" "0"
					( Origin gFrontEnd )
				)
				( attribute "SEC" "1"
					( Origin gFrontEnd )
				)
				( attribute "SEC_TYPE" "2626"
					( Origin gFrontEnd )
				)
				( attribute "TOLERANCE" "20%"
					( Origin gFrontEnd )
				)
				( attribute "VALUE" "270UF"
					( Origin gFrontEnd )
				)
				( attribute "VER" "1"
					( Origin gFrontEnd )
				)
				( attribute "VOLTAGE" "16V"
					( Units "uVoltage" "V" 1.000000)
					( Origin gFrontEnd )
				)
				( attribute "XY" "(-925,1975)"
					( Origin gFrontEnd )
				)
				( attribute "CHIPS_PART_NAME" "CAPP"
					( Origin gPackager )
				)
				( attribute "CDS_PART_NAME" "CAPP_2626-270UF,16V,20%,OSCON,A"
					( Origin gPackager )
				)
				( objectStatus "C4D2" )
			)
			( gate "@baseboard_fab2_lib.baseboard_fab2(sch_1):page204_i50"
				( attribute "CDS_LIB" "mstr_discrete"
					( Origin gPackager )
				)
				( attribute "CDS_LOCATION" "C4E16"
					( Origin gPackager )
				)
				( attribute "CDS_SEC" "1"
					( Origin gPackager )
				)
				( attribute "LOCATION" "C4E16"
					( Origin gFrontEnd )
				)
				( attribute "MATERIAL" "OSCON"
					( Origin gFrontEnd )
				)
				( attribute "PACK_TYPE" "2626"
					( Origin gFrontEnd )
				)
				( attribute "PART_NUMBER" "A31228-047"
					( Origin gFrontEnd )
				)
				( attribute "PHYS_PAGE" "204"
					( Origin gFrontEnd )
				)
				( attribute "ROOM" "PVCCIN_CPU0_FILTER_VR"
					( Origin gFrontEnd )
				)
				( attribute "ROT" "0"
					( Origin gFrontEnd )
				)
				( attribute "SEC" "1"
					( Origin gFrontEnd )
				)
				( attribute "SEC_TYPE" "2626"
					( Origin gFrontEnd )
				)
				( attribute "TOLERANCE" "20%"
					( Origin gFrontEnd )
				)
				( attribute "VALUE" "270UF"
					( Origin gFrontEnd )
				)
				( attribute "VER" "1"
					( Origin gFrontEnd )
				)
				( attribute "VOLTAGE" "16V"
					( Units "uVoltage" "V" 1.000000)
					( Origin gFrontEnd )
				)
				( attribute "XY" "(-1400,2000)"
					( Origin gFrontEnd )
				)
				( attribute "CHIPS_PART_NAME" "CAPP"
					( Origin gPackager )
				)
				( attribute "CDS_PART_NAME" "CAPP_2626-270UF,16V,20%,OSCON,A"
					( Origin gPackager )
				)
				( objectStatus "C4E16" )
			)
			( gate "@baseboard_fab2_lib.baseboard_fab2(sch_1):page138_i194"
				( attribute "BOM_COST" "SM_CONTROLLER"
					( Origin gFrontEnd )
				)
				( attribute "CDS_LIB" "mstr_discrete"
					( Origin gPackager )
				)
				( attribute "CDS_LOCATION" "R8W5"
					( Origin gPackager )
				)
				( attribute "CDS_SEC" "1"
					( Origin gPackager )
				)
				( attribute "LOCATION" "R8W5"
					( Origin gFrontEnd )
				)
				( attribute "MATERIAL" "CHIP"
					( Origin gFrontEnd )
				)
				( attribute "PACK_TYPE" "0402"
					( Origin gFrontEnd )
				)
				( attribute "PART_NUMBER" "G21796-173"
					( Origin gFrontEnd )
				)
				( attribute "PHYS_PAGE" "138"
					( Origin gFrontEnd )
				)
				( attribute "ROOM" "SMBUS"
					( Origin gFrontEnd )
				)
				( attribute "ROT" "0"
					( Origin gFrontEnd )
				)
				( attribute "SEC" "1"
					( Origin gFrontEnd )
				)
				( attribute "SEC_TYPE" "0402"
					( Origin gFrontEnd )
				)
				( attribute "TOLERANCE" "1%"
					( Origin gFrontEnd )
				)
				( attribute "VALUE" "20.0"
					( Origin gFrontEnd )
				)
				( attribute "VER" "1"
					( Origin gFrontEnd )
				)
				( attribute "WATTAGE" "1/16W"
					( Origin gFrontEnd )
				)
				( attribute "XY" "(-4000,2800)"
					( Origin gFrontEnd )
				)
				( attribute "CHIPS_PART_NAME" "RES"
					( Origin gPackager )
				)
				( attribute "CDS_PART_NAME" "RES_0402-20.0,1%,1/16W,CHIP,G2A"
					( Origin gPackager )
				)
				( objectStatus "R8W5" )
			)
			( gate "@baseboard_fab2_lib.baseboard_fab2(sch_1):page138_i195"
				( attribute "BOM_COST" "SM_CONTROLLER"
					( Origin gFrontEnd )
				)
				( attribute "CDS_LIB" "mstr_discrete"
					( Origin gPackager )
				)
				( attribute "CDS_LOCATION" "R8W4"
					( Origin gPackager )
				)
				( attribute "CDS_SEC" "1"
					( Origin gPackager )
				)
				( attribute "LOCATION" "R8W4"
					( Origin gFrontEnd )
				)
				( attribute "MATERIAL" "CHIP"
					( Origin gFrontEnd )
				)
				( attribute "PACK_TYPE" "0402"
					( Origin gFrontEnd )
				)
				( attribute "PART_NUMBER" "G21796-173"
					( Origin gFrontEnd )
				)
				( attribute "PHYS_PAGE" "138"
					( Origin gFrontEnd )
				)
				( attribute "ROOM" "SMBUS"
					( Origin gFrontEnd )
				)
				( attribute "ROT" "0"
					( Origin gFrontEnd )
				)
				( attribute "SEC" "1"
					( Origin gFrontEnd )
				)
				( attribute "SEC_TYPE" "0402"
					( Origin gFrontEnd )
				)
				( attribute "TOLERANCE" "1%"
					( Origin gFrontEnd )
				)
				( attribute "VALUE" "20.0"
					( Origin gFrontEnd )
				)
				( attribute "VER" "1"
					( Origin gFrontEnd )
				)
				( attribute "WATTAGE" "1/16W"
					( Origin gFrontEnd )
				)
				( attribute "XY" "(-4000,2950)"
					( Origin gFrontEnd )
				)
				( attribute "CHIPS_PART_NAME" "RES"
					( Origin gPackager )
				)
				( attribute "CDS_PART_NAME" "RES_0402-20.0,1%,1/16W,CHIP,G2A"
					( Origin gPackager )
				)
				( objectStatus "R8W4" )
			)
			( gate "@baseboard_fab2_lib.baseboard_fab2(sch_1):page204_i60"
				( attribute "BOM_COST" "PROC_VRD_VCCIN_CPU0"
					( Origin gFrontEnd )
				)
				( attribute "CDS_LIB" "mstr_discrete"
					( Origin gPackager )
				)
				( attribute "CDS_LOCATION" "R4E14"
					( Origin gPackager )
				)
				( attribute "CDS_SEC" "1"
					( Origin gPackager )
				)
				( attribute "LOCATION" "R4E14"
					( Origin gFrontEnd )
				)
				( attribute "MATERIAL" "CHIP"
					( Origin gFrontEnd )
				)
				( attribute "PACK_TYPE" "0402"
					( Origin gFrontEnd )
				)
				( attribute "PART_NUMBER" "G21796-017"
					( Origin gFrontEnd )
				)
				( attribute "PHYS_PAGE" "204"
					( Origin gFrontEnd )
				)
				( attribute "ROOM" "PVCCIN_CPU0_VSENSE_VR"
					( Origin gFrontEnd )
				)
				( attribute "ROT" "0"
					( Origin gFrontEnd )
				)
				( attribute "SEC" "1"
					( Origin gPackager )
				)
				( attribute "TOLERANCE" "1%"
					( Origin gFrontEnd )
				)
				( attribute "VALUE" "100.0"
					( Origin gFrontEnd )
				)
				( attribute "VER" "1"
					( Origin gFrontEnd )
				)
				( attribute "WATTAGE" "1/16W"
					( Origin gFrontEnd )
				)
				( attribute "XY" "(-5475,2225)"
					( Origin gFrontEnd )
				)
				( attribute "CHIPS_PART_NAME" "RES"
					( Origin gPackager )
				)
				( attribute "CDS_PART_NAME" "RES_0402-100.0,1%,1/16W,CHIP,GA"
					( Origin gPackager )
				)
				( objectStatus "R4E14" )
			)
			( gate "@baseboard_fab2_lib.baseboard_fab2(sch_1):page204_i61"
				( attribute "BOM_COST" "PROC_VRD_VCCIN_CPU0"
					( Origin gFrontEnd )
				)
				( attribute "CDS_LIB" "mstr_discrete"
					( Origin gPackager )
				)
				( attribute "CDS_LOCATION" "R4E16"
					( Origin gPackager )
				)
				( attribute "CDS_SEC" "1"
					( Origin gPackager )
				)
				( attribute "LOCATION" "R4E16"
					( Origin gFrontEnd )
				)
				( attribute "MATERIAL" "CHIP"
					( Origin gFrontEnd )
				)
				( attribute "NO_XNET_CONNECTION" "1"
					( Origin gFrontEnd )
				)
				( attribute "PACK_TYPE" "0402"
					( Origin gFrontEnd )
				)
				( attribute "PART_NUMBER" "G21497-005"
					( Origin gFrontEnd )
				)
				( attribute "PHYS_PAGE" "204"
					( Origin gFrontEnd )
				)
				( attribute "ROOM" "PVCCIN_CPU0_VSENSE_VR"
					( Origin gFrontEnd )
				)
				( attribute "ROT" "0"
					( Origin gFrontEnd )
				)
				( attribute "SEC" "1"
					( Origin gPackager )
				)
				( attribute "TOLERANCE" "5%"
					( Origin gFrontEnd )
				)
				( attribute "VALUE" "0.0"
					( Origin gFrontEnd )
				)
				( attribute "VER" "1"
					( Origin gFrontEnd )
				)
				( attribute "WATTAGE" "1/16W"
					( Origin gFrontEnd )
				)
				( attribute "XY" "(-5475,1825)"
					( Origin gFrontEnd )
				)
				( attribute "CHIPS_PART_NAME" "RES"
					( Origin gPackager )
				)
				( attribute "CDS_PART_NAME" "RES_0402-0.0,5%,1/16W,CHIP,G21A"
					( Origin gPackager )
				)
				( objectStatus "R4E16" )
			)
			( gate "@baseboard_fab2_lib.baseboard_fab2(sch_1):page204_i62"
				( attribute "BOM_COST" "PROC_VRD_VCCIN_CPU0"
					( Origin gFrontEnd )
				)
				( attribute "CDS_LIB" "mstr_discrete"
					( Origin gPackager )
				)
				( attribute "CDS_LOCATION" "R4E17"
					( Origin gPackager )
				)
				( attribute "CDS_SEC" "1"
					( Origin gPackager )
				)
				( attribute "LOCATION" "R4E17"
					( Origin gFrontEnd )
				)
				( attribute "MATERIAL" "CHIP"
					( Origin gFrontEnd )
				)
				( attribute "NO_XNET_CONNECTION" "1"
					( Origin gFrontEnd )
				)
				( attribute "PACK_TYPE" "0402"
					( Origin gFrontEnd )
				)
				( attribute "PART_NUMBER" "G21497-005"
					( Origin gFrontEnd )
				)
				( attribute "PHYS_PAGE" "204"
					( Origin gFrontEnd )
				)
				( attribute "ROOM" "PVCCIN_CPU0_VSENSE_VR"
					( Origin gFrontEnd )
				)
				( attribute "ROT" "0"
					( Origin gFrontEnd )
				)
				( attribute "SEC" "1"
					( Origin gPackager )
				)
				( attribute "TOLERANCE" "5%"
					( Origin gFrontEnd )
				)
				( attribute "VALUE" "0.0"
					( Origin gFrontEnd )
				)
				( attribute "VER" "1"
					( Origin gFrontEnd )
				)
				( attribute "WATTAGE" "1/16W"
					( Origin gFrontEnd )
				)
				( attribute "XY" "(-5450,1375)"
					( Origin gFrontEnd )
				)
				( attribute "CHIPS_PART_NAME" "RES"
					( Origin gPackager )
				)
				( attribute "CDS_PART_NAME" "RES_0402-0.0,5%,1/16W,CHIP,G21A"
					( Origin gPackager )
				)
				( objectStatus "R4E17" )
			)
			( gate "@baseboard_fab2_lib.baseboard_fab2(sch_1):page204_i63"
				( attribute "BOM_COST" "PROC_VRD_VCCIN_CPU0"
					( Origin gFrontEnd )
				)
				( attribute "CDS_LIB" "mstr_discrete"
					( Origin gPackager )
				)
				( attribute "CDS_LOCATION" "R4E15"
					( Origin gPackager )
				)
				( attribute "CDS_SEC" "1"
					( Origin gPackager )
				)
				( attribute "LOCATION" "R4E15"
					( Origin gFrontEnd )
				)
				( attribute "MATERIAL" "EMPTY"
					( Origin gFrontEnd )
				)
				( attribute "NO_XNET_CONNECTION" "1"
					( Origin gFrontEnd )
				)
				( attribute "PACK_TYPE" "0402"
					( Origin gFrontEnd )
				)
				( attribute "PART_NUMBER" "G21796-026"
					( Origin gFrontEnd )
				)
				( attribute "PHYS_PAGE" "204"
					( Origin gFrontEnd )
				)
				( attribute "ROOM" "PVCCIN_CPU0_VSENSE_VR"
					( Origin gFrontEnd )
				)
				( attribute "ROT" "0"
					( Origin gFrontEnd )
				)
				( attribute "SEC" "1"
					( Origin gPackager )
				)
				( attribute "TOLERANCE" "1%"
					( Origin gFrontEnd )
				)
				( attribute "VALUE" "1.00K"
					( Origin gFrontEnd )
				)
				( attribute "VER" "2"
					( Origin gFrontEnd )
				)
				( attribute "WATTAGE" "1/16W"
					( Origin gFrontEnd )
				)
				( attribute "XY" "(-6275,1625)"
					( Origin gFrontEnd )
				)
				( attribute "CHIPS_PART_NAME" "RES"
					( Origin gPackager )
				)
				( attribute "CDS_PART_NAME" "RES_0402-1.00K,1%,1/16W,EMPTY,A"
					( Origin gPackager )
				)
				( objectStatus "R4E15" )
			)
			( gate "@baseboard_fab2_lib.baseboard_fab2(sch_1):page204_i64"
				( attribute "BOM_COST" "PROC_VRD_VCCIN_CPU0"
					( Origin gFrontEnd )
				)
				( attribute "CDS_LIB" "mstr_discrete"
					( Origin gPackager )
				)
				( attribute "CDS_LOCATION" "R4E18"
					( Origin gPackager )
				)
				( attribute "CDS_SEC" "1"
					( Origin gPackager )
				)
				( attribute "LOCATION" "R4E18"
					( Origin gFrontEnd )
				)
				( attribute "MATERIAL" "CHIP"
					( Origin gFrontEnd )
				)
				( attribute "PACK_TYPE" "0402"
					( Origin gFrontEnd )
				)
				( attribute "PART_NUMBER" "G21796-017"
					( Origin gFrontEnd )
				)
				( attribute "PHYS_PAGE" "204"
					( Origin gFrontEnd )
				)
				( attribute "ROOM" "PVCCIN_CPU0_VSENSE_VR"
					( Origin gFrontEnd )
				)
				( attribute "ROT" "0"
					( Origin gFrontEnd )
				)
				( attribute "SEC" "1"
					( Origin gPackager )
				)
				( attribute "TOLERANCE" "1%"
					( Origin gFrontEnd )
				)
				( attribute "VALUE" "100.0"
					( Origin gFrontEnd )
				)
				( attribute "VER" "1"
					( Origin gFrontEnd )
				)
				( attribute "WATTAGE" "1/16W"
					( Origin gFrontEnd )
				)
				( attribute "XY" "(-5450,975)"
					( Origin gFrontEnd )
				)
				( attribute "CHIPS_PART_NAME" "RES"
					( Origin gPackager )
				)
				( attribute "CDS_PART_NAME" "RES_0402-100.0,1%,1/16W,CHIP,GA"
					( Origin gPackager )
				)
				( objectStatus "R4E18" )
			)
			( gate "@baseboard_fab2_lib.baseboard_fab2(sch_1):page204_i67"
				( attribute "CDS_LIB" "mstr_discrete"
					( Origin gPackager )
				)
				( attribute "CDS_LOCATION" "C4C12"
					( Origin gPackager )
				)
				( attribute "CDS_SEC" "1"
					( Origin gPackager )
				)
				( attribute "LOCATION" "C4C12"
					( Origin gFrontEnd )
				)
				( attribute "MATERIAL" "OSCON"
					( Origin gFrontEnd )
				)
				( attribute "PACK_TYPE" "2626"
					( Origin gFrontEnd )
				)
				( attribute "PART_NUMBER" "A31228-047"
					( Origin gFrontEnd )
				)
				( attribute "PHYS_PAGE" "204"
					( Origin gFrontEnd )
				)
				( attribute "ROOM" "PVCCIN_CPU0_FILTER_VR"
					( Origin gFrontEnd )
				)
				( attribute "ROT" "0"
					( Origin gFrontEnd )
				)
				( attribute "SEC" "1"
					( Origin gFrontEnd )
				)
				( attribute "SEC_TYPE" "2626"
					( Origin gFrontEnd )
				)
				( attribute "TOLERANCE" "20%"
					( Origin gFrontEnd )
				)
				( attribute "VALUE" "270UF"
					( Origin gFrontEnd )
				)
				( attribute "VER" "1"
					( Origin gFrontEnd )
				)
				( attribute "VOLTAGE" "16V"
					( Units "uVoltage" "V" 1.000000)
					( Origin gFrontEnd )
				)
				( attribute "XY" "(-575,1975)"
					( Origin gFrontEnd )
				)
				( attribute "CHIPS_PART_NAME" "CAPP"
					( Origin gPackager )
				)
				( attribute "CDS_PART_NAME" "CAPP_2626-270UF,16V,20%,OSCON,A"
					( Origin gPackager )
				)
				( objectStatus "C4C12" )
			)
			( gate "@baseboard_fab2_lib.baseboard_fab2(sch_1):page204_i70"
				( attribute "CDS_LIB" "dev_discrete"
					( Origin gPackager )
				)
				( attribute "CDS_LOCATION" "C6R2"
					( Origin gPackager )
				)
				( attribute "CDS_SEC" "1"
					( Origin gPackager )
				)
				( attribute "LOCATION" "C6R2"
					( Origin gFrontEnd )
				)
				( attribute "MATERIAL" "X6S"
					( Origin gFrontEnd )
				)
				( attribute "PACK_TYPE" "0603V"
					( Origin gFrontEnd )
				)
				( attribute "PART_NUMBER" "E15431-004"
					( Origin gFrontEnd )
				)
				( attribute "PHYS_PAGE" "204"
					( Origin gFrontEnd )
				)
				( attribute "ROT" "0"
					( Origin gFrontEnd )
				)
				( attribute "SEC" "1"
					( Origin gFrontEnd )
				)
				( attribute "SEC_TYPE" "0603V"
					( Origin gFrontEnd )
				)
				( attribute "TOLERANCE" "20%"
					( Origin gFrontEnd )
				)
				( attribute "VALUE" "22.0UF"
					( Origin gFrontEnd )
				)
				( attribute "VER" "1"
					( Origin gFrontEnd )
				)
				( attribute "VOLTAGE" "4V"
					( Units "uVoltage" "V" 1.000000)
					( Origin gFrontEnd )
				)
				( attribute "XY" "(-400,3425)"
					( Origin gFrontEnd )
				)
				( attribute "CHIPS_PART_NAME" "CAP_A"
					( Origin gPackager )
				)
				( attribute "CDS_PART_NAME" "CAP_A_0603V-22.0UF,4V,20%,X6S,A"
					( Origin gPackager )
				)
				( attribute "GROUP" "PWR_MLCC_CAP"
					( Origin gFrontEnd )
				)
				( objectStatus "C6R2" )
			)
			( gate "@baseboard_fab2_lib.baseboard_fab2(sch_1):page204_i71"
				( attribute "CDS_LIB" "mstr_discrete"
					( Origin gPackager )
				)
				( attribute "CDS_LOCATION" "EU4C2"
					( Origin gPackager )
				)
				( attribute "CDS_SEC" "1"
					( Origin gPackager )
				)
				( attribute "LOCATION" "EU4C2"
					( Origin gFrontEnd )
				)
				( attribute "MATERIAL" "IC"
					( Origin gFrontEnd )
				)
				( attribute "PACK_TYPE" "SM"
					( Origin gFrontEnd )
				)
				( attribute "PART_NUMBER" "H73688-001"
					( Origin gFrontEnd )
				)
				( attribute "PHYS_PAGE" "204"
					( Origin gFrontEnd )
				)
				( attribute "ROT" "0"
					( Origin gFrontEnd )
				)
				( attribute "SEC" "1"
					( Origin gPackager )
				)
				( attribute "VALUE" "IR35411"
					( Origin gFrontEnd )
				)
				( attribute "VER" "1"
					( Origin gFrontEnd )
				)
				( attribute "XY" "(-3125,3925)"
					( Origin gFrontEnd )
				)
				( attribute "CHIPS_PART_NAME" "IR354XX"
					( Origin gPackager )
				)
				( attribute "CDS_PART_NAME" "IR354XX_SM-IR35411,IC,H73688-0A"
					( Origin gPackager )
				)
				( objectStatus "EU4C2" )
			)
			( gate "@baseboard_fab2_lib.baseboard_fab2(sch_1):page204_i83"
				( attribute "CDS_LIB" "mstr_discrete"
					( Origin gPackager )
				)
				( attribute "CDS_LOCATION" "R4D68"
					( Origin gPackager )
				)
				( attribute "CDS_SEC" "1"
					( Origin gPackager )
				)
				( attribute "LOCATION" "R4D68"
					( Origin gFrontEnd )
				)
				( attribute "MATERIAL" "EMPTY"
					( Origin gFrontEnd )
				)
				( attribute "PACK_TYPE" "0402"
					( Origin gFrontEnd )
				)
				( attribute "PART_NUMBER" "G21796-187"
					( Origin gFrontEnd )
				)
				( attribute "PHYS_PAGE" "204"
					( Origin gFrontEnd )
				)
				( attribute "ROT" "0"
					( Origin gFrontEnd )
				)
				( attribute "SEC" "1"
					( Origin gFrontEnd )
				)
				( attribute "SEC_TYPE" "0402"
					( Origin gFrontEnd )
				)
				( attribute "TOLERANCE" "1%"
					( Origin gFrontEnd )
				)
				( attribute "VALUE" "68.1K"
					( Origin gFrontEnd )
				)
				( attribute "VER" "2"
					( Origin gFrontEnd )
				)
				( attribute "WATTAGE" "1/16W"
					( Origin gFrontEnd )
				)
				( attribute "XY" "(-400,4075)"
					( Origin gFrontEnd )
				)
				( attribute "CHIPS_PART_NAME" "RES"
					( Origin gPackager )
				)
				( attribute "CDS_PART_NAME" "RES_0402-68.1K,1%,1/16W,EMPTY,A"
					( Origin gPackager )
				)
				( objectStatus "R4D68" )
			)
			( gate "@baseboard_fab2_lib.baseboard_fab2(sch_1):page205_i5"
				( attribute "BOM_COST" "PROC_VRD_VCCIN_CPU0"
					( Origin gFrontEnd )
				)
				( attribute "CDS_LIB" "dev_discrete"
					( Origin gPackager )
				)
				( attribute "CDS_LOCATION" "C6N7"
					( Origin gPackager )
				)
				( attribute "CDS_SEC" "1"
					( Origin gPackager )
				)
				( attribute "LOCATION" "C6N7"
					( Origin gFrontEnd )
				)
				( attribute "MATERIAL" "X6S"
					( Origin gFrontEnd )
				)
				( attribute "PACK_TYPE" "0603V"
					( Origin gFrontEnd )
				)
				( attribute "PART_NUMBER" "E15431-004"
					( Origin gFrontEnd )
				)
				( attribute "PHYS_PAGE" "205"
					( Origin gFrontEnd )
				)
				( attribute "ROOM" "PVSA_CPU0_PWR_VR"
					( Origin gFrontEnd )
				)
				( attribute "ROT" "0"
					( Origin gFrontEnd )
				)
				( attribute "SEC" "1"
					( Origin gFrontEnd )
				)
				( attribute "SEC_TYPE" "0603V"
					( Origin gFrontEnd )
				)
				( attribute "TOLERANCE" "20%"
					( Origin gFrontEnd )
				)
				( attribute "VALUE" "22.0UF"
					( Origin gFrontEnd )
				)
				( attribute "VER" "1"
					( Origin gFrontEnd )
				)
				( attribute "VOLTAGE" "4V"
					( Units "uVoltage" "V" 1.000000)
					( Origin gFrontEnd )
				)
				( attribute "XY" "(-950,3075)"
					( Origin gFrontEnd )
				)
				( attribute "CHIPS_PART_NAME" "CAP_A"
					( Origin gPackager )
				)
				( attribute "CDS_PART_NAME" "CAP_A_0603V-22.0UF,4V,20%,X6S,A"
					( Origin gPackager )
				)
				( objectStatus "C6N7" )
			)
			( gate "@baseboard_fab2_lib.baseboard_fab2(sch_1):page210_i72"
				( attribute "CDS_LIB" "w_hdl"
					( Origin gPackager )
				)
				( attribute "CDS_LMAN_SYM_OUTLINE" "-75,100,75,-100"
					( Origin gPackager )
				)
				( attribute "LOCATION" "L1C1"
					( Origin gFrontEnd )
				)
				( attribute "PACK_TYPE" "DISCRET-GB1"
					( Origin gFrontEnd )
				)
				( attribute "PART_NUMBER" "068.3012N.M001"
					( Origin gFrontEnd )
				)
				( attribute "PHYS_PAGE" "210"
					( Origin gFrontEnd )
				)
				( attribute "ROT" "1"
					( Origin gFrontEnd )
				)
				( attribute "SEC" "1"
					( Origin gFrontEnd )
				)
				( attribute "SEC_TYPE" "DISCRET-GB1"
					( Origin gFrontEnd )
				)
				( attribute "VALUE" "IND-300NH-20-GP"
					( Origin gFrontEnd )
				)
				( attribute "VER" "1"
					( Origin gFrontEnd )
				)
				( attribute "XY" "(-1625,3325)"
					( Origin gFrontEnd )
				)
				( attribute "CHIPS_PART_NAME" "IND-300NH-20-GP"
					( Origin gPackager )
				)
				( attribute "CDS_PART_NAME" "IND-300NH-20-GP_DISCRET-GB1-INA"
					( Origin gPackager )
				)
				( attribute "CDS_LOCATION" "L1C1"
					( Origin gPackager )
				)
				( attribute "CDS_SEC" "1"
					( Origin gPackager )
				)
				( attribute "ATTRIBUTE" "300NH"
					( Origin gFrontEnd )
				)
				( attribute "PACK_SIZE" "DCR=0.17MOHM"
					( Origin gFrontEnd )
				)
				( attribute "RATED" "ISAT=33A@25C"
					( Origin gFrontEnd )
				)
				( attribute "TYPE" "IRMS=66A@DELTA_T<40C"
					( Origin gFrontEnd )
				)
				( objectStatus "L1C1" )
			)
			( gate "@baseboard_fab2_lib.baseboard_fab2(sch_1):page205_i12"
				( attribute "BOM_COST" "PROC_VRD_VCCIN_CPU0"
					( Origin gFrontEnd )
				)
				( attribute "CDS_LIB" "mstr_discrete"
					( Origin gPackager )
				)
				( attribute "CDS_LOCATION" "C6N1"
					( Origin gPackager )
				)
				( attribute "CDS_SEC" "1"
					( Origin gPackager )
				)
				( attribute "LOCATION" "C6N1"
					( Origin gFrontEnd )
				)
				( attribute "MATERIAL" "ALUM"
					( Origin gFrontEnd )
				)
				( attribute "PACK_TYPE" "3018"
					( Origin gFrontEnd )
				)
				( attribute "PART_NUMBER" "699013-049"
					( Origin gFrontEnd )
				)
				( attribute "PHYS_PAGE" "205"
					( Origin gFrontEnd )
				)
				( attribute "ROOM" "PVSA_CPU0_DECAP_VR"
					( Origin gFrontEnd )
				)
				( attribute "ROT" "0"
					( Origin gFrontEnd )
				)
				( attribute "SEC" "1"
					( Origin gFrontEnd )
				)
				( attribute "SEC_TYPE" "3018"
					( Origin gFrontEnd )
				)
				( attribute "TOLERANCE" "20%"
					( Origin gFrontEnd )
				)
				( attribute "VALUE" "470UF"
					( Origin gFrontEnd )
				)
				( attribute "VER" "1"
					( Origin gFrontEnd )
				)
				( attribute "VOLTAGE" "2.5V"
					( Units "uVoltage" "V" 1.000000)
					( Origin gFrontEnd )
				)
				( attribute "XY" "(-2000,1350)"
					( Origin gFrontEnd )
				)
				( attribute "CHIPS_PART_NAME" "CAPP"
					( Origin gPackager )
				)
				( attribute "CDS_PART_NAME" "CAPP_3018-470UF,2.5V,20%,ALUM,A"
					( Origin gPackager )
				)
				( attribute "GROUP" "PWR_BULK_CAP"
					( Origin gFrontEnd )
				)
				( objectStatus "C6N1" )
			)
			( gate "@baseboard_fab2_lib.baseboard_fab2(sch_1):page205_i14"
				( attribute "BOM_COST" "PROC_VRD_VCCIN_CPU0"
					( Origin gFrontEnd )
				)
				( attribute "CDS_LIB" "mstr_discrete"
					( Origin gPackager )
				)
				( attribute "CDS_LOCATION" "C6N4"
					( Origin gPackager )
				)
				( attribute "CDS_SEC" "1"
					( Origin gPackager )
				)
				( attribute "LOCATION" "C6N4"
					( Origin gFrontEnd )
				)
				( attribute "MATERIAL" "ALUM"
					( Origin gFrontEnd )
				)
				( attribute "PACK_TYPE" "3018"
					( Origin gFrontEnd )
				)
				( attribute "PART_NUMBER" "699013-049"
					( Origin gFrontEnd )
				)
				( attribute "PHYS_PAGE" "205"
					( Origin gFrontEnd )
				)
				( attribute "ROOM" "PVSA_CPU0_DECAP_VR"
					( Origin gFrontEnd )
				)
				( attribute "ROT" "2"
					( Origin gFrontEnd )
				)
				( attribute "SEC" "1"
					( Origin gFrontEnd )
				)
				( attribute "SEC_TYPE" "3018"
					( Origin gFrontEnd )
				)
				( attribute "TOLERANCE" "20%"
					( Origin gFrontEnd )
				)
				( attribute "VALUE" "470UF"
					( Origin gFrontEnd )
				)
				( attribute "VER" "1"
					( Origin gFrontEnd )
				)
				( attribute "VOLTAGE" "2.5V"
					( Units "uVoltage" "V" 1.000000)
					( Origin gFrontEnd )
				)
				( attribute "XY" "(-2650,1350)"
					( Origin gFrontEnd )
				)
				( attribute "CHIPS_PART_NAME" "CAPP"
					( Origin gPackager )
				)
				( attribute "CDS_PART_NAME" "CAPP_3018-470UF,2.5V,20%,ALUM,A"
					( Origin gPackager )
				)
				( attribute "GROUP" "PWR_BULK_CAP"
					( Origin gFrontEnd )
				)
				( objectStatus "C6N4" )
			)
			( gate "@baseboard_fab2_lib.baseboard_fab2(sch_1):page205_i16"
				( attribute "CDS_LIB" "mstr_discrete"
					( Origin gPackager )
				)
				( attribute "CDS_LOCATION" "C4C5"
					( Origin gPackager )
				)
				( attribute "CDS_SEC" "1"
					( Origin gPackager )
				)
				( attribute "LOCATION" "C4C5"
					( Origin gFrontEnd )
				)
				( attribute "MATERIAL" "X7R"
					( Origin gFrontEnd )
				)
				( attribute "PACK_TYPE" "0402"
					( Origin gFrontEnd )
				)
				( attribute "PART_NUMBER" "A36096-155"
					( Origin gFrontEnd )
				)
				( attribute "PHYS_PAGE" "205"
					( Origin gFrontEnd )
				)
				( attribute "ROOM" "PVSA_CPU0_PWR_VR"
					( Origin gFrontEnd )
				)
				( attribute "ROT" "0"
					( Origin gFrontEnd )
				)
				( attribute "SEC" "1"
					( Origin gFrontEnd )
				)
				( attribute "SEC_TYPE" "0402"
					( Origin gFrontEnd )
				)
				( attribute "TOLERANCE" "10%"
					( Origin gFrontEnd )
				)
				( attribute "VALUE" "0.22UF"
					( Origin gFrontEnd )
				)
				( attribute "VER" "1"
					( Origin gFrontEnd )
				)
				( attribute "VOLTAGE" "16V"
					( Units "uVoltage" "V" 1.000000)
					( Origin gFrontEnd )
				)
				( attribute "XY" "(-5300,4200)"
					( Origin gFrontEnd )
				)
				( attribute "CHIPS_PART_NAME" "CAP"
					( Origin gPackager )
				)
				( attribute "CDS_PART_NAME" "CAP_0402-0.22UF,16V,10%,X7R,A3A"
					( Origin gPackager )
				)
				( objectStatus "C4C5" )
			)
			( gate "@baseboard_fab2_lib.baseboard_fab2(sch_1):page204_i113"
				( attribute "CDS_LIB" "w_hdl"
					( Origin gPackager )
				)
				( attribute "CDS_LMAN_SYM_OUTLINE" "-50,25,50,-25"
					( Origin gPackager )
				)
				( attribute "LOCATION" "C4C14"
					( Origin gFrontEnd )
				)
				( attribute "PACK_TYPE" "SMD-BCG6"
					( Origin gFrontEnd )
				)
				( attribute "PART_NUMBER" "78.10523.8FL"
					( Origin gFrontEnd )
				)
				( attribute "PHYS_PAGE" "204"
					( Origin gFrontEnd )
				)
				( attribute "ROT" "0"
					( Origin gFrontEnd )
				)
				( attribute "SEC" "1"
					( Origin gFrontEnd )
				)
				( attribute "SEC_TYPE" "SMD-BCG6"
					( Origin gFrontEnd )
				)
				( attribute "VALUE" "SC1U10V2KX-4-GP"
					( Origin gFrontEnd )
				)
				( attribute "VER" "1"
					( Origin gFrontEnd )
				)
				( attribute "XY" "(-5200,4150)"
					( Origin gFrontEnd )
				)
				( attribute "CHIPS_PART_NAME" "SC1U10V2KX-4-GP"
					( Origin gPackager )
				)
				( attribute "CDS_PART_NAME" "SC1U10V2KX-4-GP_SMD-BCG6-SC1U1A"
					( Origin gPackager )
				)
				( attribute "CDS_LOCATION" "C4C14"
					( Origin gPackager )
				)
				( attribute "CDS_SEC" "1"
					( Origin gPackager )
				)
				( attribute "ATTRIBUTE" "1UF"
					( Origin gFrontEnd )
				)
				( attribute "PACK_SIZE" "0402"
					( Origin gFrontEnd )
				)
				( attribute "RATED" "10V"
					( Origin gFrontEnd )
				)
				( attribute "TOLERANCE" "10%"
					( Origin gFrontEnd )
				)
				( objectStatus "C4C14" )
			)
			( gate "@baseboard_fab2_lib.baseboard_fab2(sch_1):page204_i103"
				( attribute "BOM_COST" "PROC_SIDEBAND"
					( Origin gFrontEnd )
				)
				( attribute "CDS_LIB" "mstr_discrete"
					( Origin gPackager )
				)
				( attribute "CDS_LOCATION" "R6P47"
					( Origin gPackager )
				)
				( attribute "CDS_SEC" "1"
					( Origin gPackager )
				)
				( attribute "LOCATION" "R6P47"
					( Origin gFrontEnd )
				)
				( attribute "MATERIAL" "CHIP"
					( Origin gFrontEnd )
				)
				( attribute "PACK_TYPE" "0402"
					( Origin gFrontEnd )
				)
				( attribute "PART_NUMBER" "G21497-005"
					( Origin gFrontEnd )
				)
				( attribute "PHYS_PAGE" "204"
					( Origin gFrontEnd )
				)
				( attribute "ROOM" "CPU0"
					( Origin gFrontEnd )
				)
				( attribute "ROT" "0"
					( Origin gFrontEnd )
				)
				( attribute "SEC" "1"
					( Origin gFrontEnd )
				)
				( attribute "SEC_TYPE" "0402"
					( Origin gFrontEnd )
				)
				( attribute "TOLERANCE" "5%"
					( Origin gFrontEnd )
				)
				( attribute "VALUE" "0.0"
					( Origin gFrontEnd )
				)
				( attribute "VER" "1"
					( Origin gFrontEnd )
				)
				( attribute "WATTAGE" "1/16W"
					( Origin gFrontEnd )
				)
				( attribute "XY" "(-5550,4750)"
					( Origin gFrontEnd )
				)
				( attribute "CHIPS_PART_NAME" "RES"
					( Origin gPackager )
				)
				( attribute "CDS_PART_NAME" "RES_0402-0.0,5%,1/16W,CHIP,G21A"
					( Origin gPackager )
				)
				( objectStatus "R6P47" )
			)
			( gate "@baseboard_fab2_lib.baseboard_fab2(sch_1):page205_i20"
				( attribute "CDS_LIB" "mstr_discrete"
					( Origin gPackager )
				)
				( attribute "CDS_LOCATION" "C4C6"
					( Origin gPackager )
				)
				( attribute "CDS_SEC" "1"
					( Origin gPackager )
				)
				( attribute "LOCATION" "C4C6"
					( Origin gFrontEnd )
				)
				( attribute "MATERIAL" "X6S"
					( Origin gFrontEnd )
				)
				( attribute "PACK_TYPE" "0402"
					( Origin gFrontEnd )
				)
				( attribute "PART_NUMBER" "D97712-011"
					( Origin gFrontEnd )
				)
				( attribute "PHYS_PAGE" "205"
					( Origin gFrontEnd )
				)
				( attribute "ROOM" "PVSA_CPU0_PWR_VR"
					( Origin gFrontEnd )
				)
				( attribute "ROT" "0"
					( Origin gFrontEnd )
				)
				( attribute "SEC" "1"
					( Origin gFrontEnd )
				)
				( attribute "SEC_TYPE" "0402"
					( Origin gFrontEnd )
				)
				( attribute "TOLERANCE" "10%"
					( Origin gFrontEnd )
				)
				( attribute "VALUE" "1.0UF"
					( Origin gFrontEnd )
				)
				( attribute "VER" "1"
					( Origin gFrontEnd )
				)
				( attribute "VOLTAGE" "16V"
					( Units "uVoltage" "V" 1.000000)
					( Origin gFrontEnd )
				)
				( attribute "XY" "(-6000,4200)"
					( Origin gFrontEnd )
				)
				( attribute "CHIPS_PART_NAME" "CAP"
					( Origin gPackager )
				)
				( attribute "CDS_PART_NAME" "CAP_0402-1.0UF,16V,10%,X6S,D97A"
					( Origin gPackager )
				)
				( objectStatus "C4C6" )
			)
			( gate "@baseboard_fab2_lib.baseboard_fab2(sch_1):page205_i24"
				( attribute "BOM_COST" "PROC_VRD_VCCIN_CPU0"
					( Origin gFrontEnd )
				)
				( attribute "CDS_LIB" "mstr_discrete"
					( Origin gPackager )
				)
				( attribute "CDS_LOCATION" "R4C5"
					( Origin gPackager )
				)
				( attribute "CDS_SEC" "1"
					( Origin gPackager )
				)
				( attribute "LOCATION" "R4C5"
					( Origin gFrontEnd )
				)
				( attribute "MATERIAL" "CHIP"
					( Origin gFrontEnd )
				)
				( attribute "PACK_TYPE" "0402"
					( Origin gFrontEnd )
				)
				( attribute "PART_NUMBER" "G21796-017"
					( Origin gFrontEnd )
				)
				( attribute "PHYS_PAGE" "205"
					( Origin gFrontEnd )
				)
				( attribute "ROOM" "PVSA_CPU0_VSENSE_VR"
					( Origin gFrontEnd )
				)
				( attribute "ROT" "0"
					( Origin gFrontEnd )
				)
				( attribute "SEC" "1"
					( Origin gFrontEnd )
				)
				( attribute "SEC_TYPE" "0402"
					( Origin gFrontEnd )
				)
				( attribute "TOLERANCE" "1%"
					( Origin gFrontEnd )
				)
				( attribute "VALUE" "100.0"
					( Origin gFrontEnd )
				)
				( attribute "VER" "1"
					( Origin gFrontEnd )
				)
				( attribute "WATTAGE" "1/16W"
					( Origin gFrontEnd )
				)
				( attribute "XY" "(-5100,2425)"
					( Origin gFrontEnd )
				)
				( attribute "CHIPS_PART_NAME" "RES"
					( Origin gPackager )
				)
				( attribute "CDS_PART_NAME" "RES_0402-100.0,1%,1/16W,CHIP,GA"
					( Origin gPackager )
				)
				( objectStatus "R4C5" )
			)
			( gate "@baseboard_fab2_lib.baseboard_fab2(sch_1):page205_i25"
				( attribute "CDS_LIB" "mstr_discrete"
					( Origin gPackager )
				)
				( attribute "CDS_LOCATION" "C4C8"
					( Origin gPackager )
				)
				( attribute "CDS_SEC" "1"
					( Origin gPackager )
				)
				( attribute "LOCATION" "C4C8"
					( Origin gFrontEnd )
				)
				( attribute "MATERIAL" "X7R"
					( Origin gFrontEnd )
				)
				( attribute "PACK_TYPE" "0402"
					( Origin gFrontEnd )
				)
				( attribute "PART_NUMBER" "A36096-104"
					( Origin gFrontEnd )
				)
				( attribute "PHYS_PAGE" "205"
					( Origin gFrontEnd )
				)
				( attribute "ROOM" "PVSA_CPU0_PWR_VR"
					( Origin gFrontEnd )
				)
				( attribute "ROT" "2"
					( Origin gFrontEnd )
				)
				( attribute "SEC" "1"
					( Origin gFrontEnd )
				)
				( attribute "SEC_TYPE" "0402"
					( Origin gFrontEnd )
				)
				( attribute "SPOF" "TRUE"
					( Origin gFrontEnd )
				)
				( attribute "TOLERANCE" "10%"
					( Origin gFrontEnd )
				)
				( attribute "VALUE" "0.220UF"
					( Origin gFrontEnd )
				)
				( attribute "VER" "1"
					( Origin gFrontEnd )
				)
				( attribute "VOLTAGE" "16V"
					( Units "uVoltage" "V" 1.000000)
					( Origin gFrontEnd )
				)
				( attribute "XY" "(-6050,3550)"
					( Origin gFrontEnd )
				)
				( attribute "CHIPS_PART_NAME" "CAP"
					( Origin gPackager )
				)
				( attribute "CDS_PART_NAME" "CAP_0402-0.220UF,16V,10%,X7R,AA"
					( Origin gPackager )
				)
				( objectStatus "C4C8" )
			)
			( gate "@baseboard_fab2_lib.baseboard_fab2(sch_1):page205_i26"
				( attribute "BOM_COST" "PROC_VRD_VCCIN_CPU0"
					( Origin gFrontEnd )
				)
				( attribute "CDS_LIB" "mstr_discrete"
					( Origin gPackager )
				)
				( attribute "CDS_LOCATION" "R4C4"
					( Origin gPackager )
				)
				( attribute "CDS_SEC" "1"
					( Origin gPackager )
				)
				( attribute "LOCATION" "R4C4"
					( Origin gFrontEnd )
				)
				( attribute "MATERIAL" "CHIP"
					( Origin gFrontEnd )
				)
				( attribute "PACK_TYPE" "0402"
					( Origin gFrontEnd )
				)
				( attribute "PART_NUMBER" "G21497-005"
					( Origin gFrontEnd )
				)
				( attribute "PHYS_PAGE" "205"
					( Origin gFrontEnd )
				)
				( attribute "ROOM" "PVSA_CPU0_VSENSE_VR"
					( Origin gFrontEnd )
				)
				( attribute "ROT" "0"
					( Origin gFrontEnd )
				)
				( attribute "SEC" "1"
					( Origin gFrontEnd )
				)
				( attribute "SEC_TYPE" "0402"
					( Origin gFrontEnd )
				)
				( attribute "TOLERANCE" "5%"
					( Origin gFrontEnd )
				)
				( attribute "VALUE" "0.0"
					( Origin gFrontEnd )
				)
				( attribute "VER" "1"
					( Origin gFrontEnd )
				)
				( attribute "WATTAGE" "1/16W"
					( Origin gFrontEnd )
				)
				( attribute "XY" "(-5075,2025)"
					( Origin gFrontEnd )
				)
				( attribute "CHIPS_PART_NAME" "RES"
					( Origin gPackager )
				)
				( attribute "CDS_PART_NAME" "RES_0402-0.0,5%,1/16W,CHIP,G21A"
					( Origin gPackager )
				)
				( objectStatus "R4C4" )
			)
			( gate "@baseboard_fab2_lib.baseboard_fab2(sch_1):page205_i29"
				( attribute "BOM_COST" "PROC_VRD_VCCIN_CPU0"
					( Origin gFrontEnd )
				)
				( attribute "CDS_LIB" "mstr_discrete"
					( Origin gPackager )
				)
				( attribute "CDS_LOCATION" "R4C1"
					( Origin gPackager )
				)
				( attribute "CDS_SEC" "1"
					( Origin gPackager )
				)
				( attribute "LOCATION" "R4C1"
					( Origin gFrontEnd )
				)
				( attribute "MATERIAL" "CHIP"
					( Origin gFrontEnd )
				)
				( attribute "PACK_TYPE" "0402"
					( Origin gFrontEnd )
				)
				( attribute "PART_NUMBER" "G21796-017"
					( Origin gFrontEnd )
				)
				( attribute "PHYS_PAGE" "205"
					( Origin gFrontEnd )
				)
				( attribute "ROOM" "PVSA_CPU0_VSENSE_VR"
					( Origin gFrontEnd )
				)
				( attribute "ROT" "0"
					( Origin gFrontEnd )
				)
				( attribute "SEC" "1"
					( Origin gFrontEnd )
				)
				( attribute "SEC_TYPE" "0402"
					( Origin gFrontEnd )
				)
				( attribute "TOLERANCE" "1%"
					( Origin gFrontEnd )
				)
				( attribute "VALUE" "100.0"
					( Origin gFrontEnd )
				)
				( attribute "VER" "1"
					( Origin gFrontEnd )
				)
				( attribute "WATTAGE" "1/16W"
					( Origin gFrontEnd )
				)
				( attribute "XY" "(-5075,1200)"
					( Origin gFrontEnd )
				)
				( attribute "CHIPS_PART_NAME" "RES"
					( Origin gPackager )
				)
				( attribute "CDS_PART_NAME" "RES_0402-100.0,1%,1/16W,CHIP,GA"
					( Origin gPackager )
				)
				( objectStatus "R4C1" )
			)
			( gate "@baseboard_fab2_lib.baseboard_fab2(sch_1):page205_i30"
				( attribute "BOM_COST" "PROC_VRD_VCCIN_CPU0"
					( Origin gFrontEnd )
				)
				( attribute "CDS_LIB" "mstr_discrete"
					( Origin gPackager )
				)
				( attribute "CDS_LOCATION" "R4C2"
					( Origin gPackager )
				)
				( attribute "CDS_SEC" "1"
					( Origin gPackager )
				)
				( attribute "LOCATION" "R4C2"
					( Origin gFrontEnd )
				)
				( attribute "MATERIAL" "CHIP"
					( Origin gFrontEnd )
				)
				( attribute "PACK_TYPE" "0402"
					( Origin gFrontEnd )
				)
				( attribute "PART_NUMBER" "G21497-005"
					( Origin gFrontEnd )
				)
				( attribute "PHYS_PAGE" "205"
					( Origin gFrontEnd )
				)
				( attribute "ROOM" "PVSA_CPU0_VSENSE_VR"
					( Origin gFrontEnd )
				)
				( attribute "ROT" "0"
					( Origin gFrontEnd )
				)
				( attribute "SEC" "1"
					( Origin gFrontEnd )
				)
				( attribute "SEC_TYPE" "0402"
					( Origin gFrontEnd )
				)
				( attribute "TOLERANCE" "5%"
					( Origin gFrontEnd )
				)
				( attribute "VALUE" "0.0"
					( Origin gFrontEnd )
				)
				( attribute "VER" "1"
					( Origin gFrontEnd )
				)
				( attribute "WATTAGE" "1/16W"
					( Origin gFrontEnd )
				)
				( attribute "XY" "(-5075,1575)"
					( Origin gFrontEnd )
				)
				( attribute "CHIPS_PART_NAME" "RES"
					( Origin gPackager )
				)
				( attribute "CDS_PART_NAME" "RES_0402-0.0,5%,1/16W,CHIP,G21A"
					( Origin gPackager )
				)
				( objectStatus "R4C2" )
			)
			( gate "@baseboard_fab2_lib.baseboard_fab2(sch_1):page205_i31"
				( attribute "CDS_LIB" "dev_discrete"
					( Origin gPackager )
				)
				( attribute "CDS_LOCATION" "C4C10"
					( Origin gPackager )
				)
				( attribute "CDS_SEC" "1"
					( Origin gPackager )
				)
				( attribute "LOCATION" "C4C10"
					( Origin gFrontEnd )
				)
				( attribute "MATERIAL" "X7R"
					( Origin gFrontEnd )
				)
				( attribute "PACK_TYPE" "0402V"
					( Origin gFrontEnd )
				)
				( attribute "PART_NUMBER" "A36096-030"
					( Origin gFrontEnd )
				)
				( attribute "PHYS_PAGE" "205"
					( Origin gFrontEnd )
				)
				( attribute "ROOM" "PVSA_CPU0_PWR_VR"
					( Origin gFrontEnd )
				)
				( attribute "ROT" "0"
					( Origin gFrontEnd )
				)
				( attribute "SEC" "1"
					( Origin gFrontEnd )
				)
				( attribute "SEC_TYPE" "0402V"
					( Origin gFrontEnd )
				)
				( attribute "TOLERANCE" "10%"
					( Origin gFrontEnd )
				)
				( attribute "VALUE" "0.1UF"
					( Origin gFrontEnd )
				)
				( attribute "VER" "1"
					( Origin gFrontEnd )
				)
				( attribute "VOLTAGE" "16V"
					( Units "uVoltage" "V" 1.000000)
					( Origin gFrontEnd )
				)
				( attribute "XY" "(-6250,4200)"
					( Origin gFrontEnd )
				)
				( attribute "CHIPS_PART_NAME" "CAP_A"
					( Origin gPackager )
				)
				( attribute "CDS_PART_NAME" "CAP_A_0402V-0.1UF,16V,10%,X7R,A"
					( Origin gPackager )
				)
				( objectStatus "C4C10" )
			)
			( gate "@baseboard_fab2_lib.baseboard_fab2(sch_1):page205_i32"
				( attribute "CDS_LIB" "mstr_discrete"
					( Origin gPackager )
				)
				( attribute "CDS_LOCATION" "C4C9"
					( Origin gPackager )
				)
				( attribute "CDS_SEC" "1"
					( Origin gPackager )
				)
				( attribute "LOCATION" "C4C9"
					( Origin gFrontEnd )
				)
				( attribute "MATERIAL" "X6S"
					( Origin gFrontEnd )
				)
				( attribute "PACK_TYPE" "0402"
					( Origin gFrontEnd )
				)
				( attribute "PART_NUMBER" "D97712-011"
					( Origin gFrontEnd )
				)
				( attribute "PHYS_PAGE" "205"
					( Origin gFrontEnd )
				)
				( attribute "ROOM" "PVSA_CPU0_PWR_VR"
					( Origin gFrontEnd )
				)
				( attribute "ROT" "0"
					( Origin gFrontEnd )
				)
				( attribute "SEC" "1"
					( Origin gFrontEnd )
				)
				( attribute "SEC_TYPE" "0402"
					( Origin gFrontEnd )
				)
				( attribute "TOLERANCE" "10%"
					( Origin gFrontEnd )
				)
				( attribute "VALUE" "1.0UF"
					( Origin gFrontEnd )
				)
				( attribute "VER" "1"
					( Origin gFrontEnd )
				)
				( attribute "VOLTAGE" "16V"
					( Units "uVoltage" "V" 1.000000)
					( Origin gFrontEnd )
				)
				( attribute "XY" "(-6475,4200)"
					( Origin gFrontEnd )
				)
				( attribute "CHIPS_PART_NAME" "CAP"
					( Origin gPackager )
				)
				( attribute "CDS_PART_NAME" "CAP_0402-1.0UF,16V,10%,X6S,D97A"
					( Origin gPackager )
				)
				( objectStatus "C4C9" )
			)
			( gate "@baseboard_fab2_lib.baseboard_fab2(sch_1):page205_i33"
				( attribute "CDS_LIB" "mstr_discrete"
					( Origin gPackager )
				)
				( attribute "CDS_LOCATION" "C6N2"
					( Origin gPackager )
				)
				( attribute "CDS_SEC" "1"
					( Origin gPackager )
				)
				( attribute "LOCATION" "C6N2"
					( Origin gFrontEnd )
				)
				( attribute "MATERIAL" "X6S"
					( Origin gFrontEnd )
				)
				( attribute "PACK_TYPE" "0805"
					( Origin gFrontEnd )
				)
				( attribute "PART_NUMBER" "C95333-007"
					( Origin gFrontEnd )
				)
				( attribute "PHYS_PAGE" "205"
					( Origin gFrontEnd )
				)
				( attribute "ROOM" "PVSA_CPU0_PWR_VR"
					( Origin gFrontEnd )
				)
				( attribute "ROT" "0"
					( Origin gFrontEnd )
				)
				( attribute "SEC" "1"
					( Origin gFrontEnd )
				)
				( attribute "SEC_TYPE" "0805"
					( Origin gFrontEnd )
				)
				( attribute "TOLERANCE" "10%"
					( Origin gFrontEnd )
				)
				( attribute "VALUE" "10UF"
					( Origin gFrontEnd )
				)
				( attribute "VER" "1"
					( Origin gFrontEnd )
				)
				( attribute "VOLTAGE" "16V"
					( Units "uVoltage" "V" 1.000000)
					( Origin gFrontEnd )
				)
				( attribute "XY" "(-6700,4200)"
					( Origin gFrontEnd )
				)
				( attribute "CHIPS_PART_NAME" "CAP"
					( Origin gPackager )
				)
				( attribute "CDS_PART_NAME" "CAP_0805-10UF,16V,10%,X6S,C953A"
					( Origin gPackager )
				)
				( objectStatus "C6N2" )
			)
			( gate "@baseboard_fab2_lib.baseboard_fab2(sch_1):page205_i34"
				( attribute "CDS_LIB" "mstr_discrete"
					( Origin gPackager )
				)
				( attribute "CDS_LOCATION" "C6N3"
					( Origin gPackager )
				)
				( attribute "CDS_SEC" "1"
					( Origin gPackager )
				)
				( attribute "LOCATION" "C6N3"
					( Origin gFrontEnd )
				)
				( attribute "MATERIAL" "X6S"
					( Origin gFrontEnd )
				)
				( attribute "PACK_TYPE" "0805"
					( Origin gFrontEnd )
				)
				( attribute "PART_NUMBER" "C95333-007"
					( Origin gFrontEnd )
				)
				( attribute "PHYS_PAGE" "205"
					( Origin gFrontEnd )
				)
				( attribute "ROOM" "PVSA_CPU0_PWR_VR"
					( Origin gFrontEnd )
				)
				( attribute "ROT" "0"
					( Origin gFrontEnd )
				)
				( attribute "SEC" "1"
					( Origin gFrontEnd )
				)
				( attribute "SEC_TYPE" "0805"
					( Origin gFrontEnd )
				)
				( attribute "TOLERANCE" "10%"
					( Origin gFrontEnd )
				)
				( attribute "VALUE" "10UF"
					( Origin gFrontEnd )
				)
				( attribute "VER" "1"
					( Origin gFrontEnd )
				)
				( attribute "VOLTAGE" "16V"
					( Units "uVoltage" "V" 1.000000)
					( Origin gFrontEnd )
				)
				( attribute "XY" "(-6925,4200)"
					( Origin gFrontEnd )
				)
				( attribute "CHIPS_PART_NAME" "CAP"
					( Origin gPackager )
				)
				( attribute "CDS_PART_NAME" "CAP_0805-10UF,16V,10%,X6S,C953A"
					( Origin gPackager )
				)
				( objectStatus "C6N3" )
			)
			( gate "@baseboard_fab2_lib.baseboard_fab2(sch_1):page205_i35"
				( attribute "CDS_LIB" "mstr_discrete"
					( Origin gPackager )
				)
				( attribute "CDS_LOCATION" "C6N6"
					( Origin gPackager )
				)
				( attribute "CDS_SEC" "1"
					( Origin gPackager )
				)
				( attribute "LOCATION" "C6N6"
					( Origin gFrontEnd )
				)
				( attribute "MATERIAL" "X6S"
					( Origin gFrontEnd )
				)
				( attribute "PACK_TYPE" "0805"
					( Origin gFrontEnd )
				)
				( attribute "PART_NUMBER" "C95333-007"
					( Origin gFrontEnd )
				)
				( attribute "PHYS_PAGE" "205"
					( Origin gFrontEnd )
				)
				( attribute "ROOM" "PVSA_CPU0_PWR_VR"
					( Origin gFrontEnd )
				)
				( attribute "ROT" "0"
					( Origin gFrontEnd )
				)
				( attribute "SEC" "1"
					( Origin gFrontEnd )
				)
				( attribute "SEC_TYPE" "0805"
					( Origin gFrontEnd )
				)
				( attribute "TOLERANCE" "10%"
					( Origin gFrontEnd )
				)
				( attribute "VALUE" "10UF"
					( Origin gFrontEnd )
				)
				( attribute "VER" "1"
					( Origin gFrontEnd )
				)
				( attribute "VOLTAGE" "16V"
					( Units "uVoltage" "V" 1.000000)
					( Origin gFrontEnd )
				)
				( attribute "XY" "(-7175,4200)"
					( Origin gFrontEnd )
				)
				( attribute "CHIPS_PART_NAME" "CAP"
					( Origin gPackager )
				)
				( attribute "CDS_PART_NAME" "CAP_0805-10UF,16V,10%,X6S,C953A"
					( Origin gPackager )
				)
				( objectStatus "C6N6" )
			)
			( gate "@baseboard_fab2_lib.baseboard_fab2(sch_1):page205_i37"
				( attribute "BOM_COST" "PROC_VRD_VCCIN_CPU0"
					( Origin gFrontEnd )
				)
				( attribute "CDS_LIB" "mstr_discrete"
					( Origin gPackager )
				)
				( attribute "CDS_LOCATION" "R4C3"
					( Origin gPackager )
				)
				( attribute "CDS_SEC" "1"
					( Origin gPackager )
				)
				( attribute "LOCATION" "R4C3"
					( Origin gFrontEnd )
				)
				( attribute "MATERIAL" "EMPTY"
					( Origin gFrontEnd )
				)
				( attribute "NO_XNET_CONNECTION" "1"
					( Origin gFrontEnd )
				)
				( attribute "PACK_TYPE" "0402"
					( Origin gFrontEnd )
				)
				( attribute "PART_NUMBER" "G21796-026"
					( Origin gFrontEnd )
				)
				( attribute "PHYS_PAGE" "205"
					( Origin gFrontEnd )
				)
				( attribute "ROOM" "PVSA_CPU0_VSENSE_VR"
					( Origin gFrontEnd )
				)
				( attribute "ROT" "0"
					( Origin gFrontEnd )
				)
				( attribute "SEC" "1"
					( Origin gFrontEnd )
				)
				( attribute "SEC_TYPE" "0402"
					( Origin gFrontEnd )
				)
				( attribute "TOLERANCE" "1%"
					( Origin gFrontEnd )
				)
				( attribute "VALUE" "1.00K"
					( Origin gFrontEnd )
				)
				( attribute "VER" "2"
					( Origin gFrontEnd )
				)
				( attribute "WATTAGE" "1/16W"
					( Origin gFrontEnd )
				)
				( attribute "XY" "(-5750,1825)"
					( Origin gFrontEnd )
				)
				( attribute "CHIPS_PART_NAME" "RES"
					( Origin gPackager )
				)
				( attribute "CDS_PART_NAME" "RES_0402-1.00K,1%,1/16W,EMPTY,A"
					( Origin gPackager )
				)
				( objectStatus "R4C3" )
			)
			( gate "@baseboard_fab2_lib.baseboard_fab2(sch_1):page205_i43"
				( attribute "CDS_LIB" "dev_discrete"
					( Origin gPackager )
				)
				( attribute "CDS_LOCATION" "C4C11"
					( Origin gPackager )
				)
				( attribute "CDS_SEC" "1"
					( Origin gPackager )
				)
				( attribute "LOCATION" "C4C11"
					( Origin gFrontEnd )
				)
				( attribute "MATERIAL" "X6S"
					( Origin gFrontEnd )
				)
				( attribute "PACK_TYPE" "0603V"
					( Origin gFrontEnd )
				)
				( attribute "PART_NUMBER" "E15431-004"
					( Origin gFrontEnd )
				)
				( attribute "PHYS_PAGE" "205"
					( Origin gFrontEnd )
				)
				( attribute "ROT" "0"
					( Origin gFrontEnd )
				)
				( attribute "SEC" "1"
					( Origin gFrontEnd )
				)
				( attribute "SEC_TYPE" "0603V"
					( Origin gFrontEnd )
				)
				( attribute "TOLERANCE" "20%"
					( Origin gFrontEnd )
				)
				( attribute "VALUE" "22.0UF"
					( Origin gFrontEnd )
				)
				( attribute "VER" "1"
					( Origin gFrontEnd )
				)
				( attribute "VOLTAGE" "4V"
					( Units "uVoltage" "V" 1.000000)
					( Origin gFrontEnd )
				)
				( attribute "XY" "(-600,3075)"
					( Origin gFrontEnd )
				)
				( attribute "CHIPS_PART_NAME" "CAP_A"
					( Origin gPackager )
				)
				( attribute "CDS_PART_NAME" "CAP_A_0603V-22.0UF,4V,20%,X6S,A"
					( Origin gPackager )
				)
				( objectStatus "C4C11" )
			)
			( gate "@baseboard_fab2_lib.baseboard_fab2(sch_1):page205_i45"
				( attribute "CDS_LIB" "mstr_discrete"
					( Origin gPackager )
				)
				( attribute "CDS_LOCATION" "R6N4"
					( Origin gPackager )
				)
				( attribute "LOCATION" "R6N4"
					( Origin gFrontEnd )
				)
				( attribute "MATERIAL" "CHIP"
					( Origin gFrontEnd )
				)
				( attribute "PACK_TYPE" "0402"
					( Origin gFrontEnd )
				)
				( attribute "PART_NUMBER" "G21796-208"
					( Origin gFrontEnd )
				)
				( attribute "PHYS_PAGE" "205"
					( Origin gFrontEnd )
				)
				( attribute "ROT" "0"
					( Origin gFrontEnd )
				)
				( attribute "SEC" "1"
					( Origin gFrontEnd )
				)
				( attribute "TOLERANCE" "1.0%"
					( Origin gFrontEnd )
				)
				( attribute "VALUE" "51.1"
					( Origin gFrontEnd )
				)
				( attribute "VER" "2"
					( Origin gFrontEnd )
				)
				( attribute "WATTAGE" "1/16W"
					( Origin gFrontEnd )
				)
				( attribute "XY" "(-275,3075)"
					( Origin gFrontEnd )
				)
				( attribute "CHIPS_PART_NAME" "RES"
					( Origin gPackager )
				)
				( attribute "CDS_PART_NAME" "RES_0402-51.1,1.0%,1/16W,CHIP,A"
					( Origin gPackager )
				)
				( attribute "SEC_TYPE" "0402"
					( Origin gFrontEnd )
				)
				( attribute "CDS_SEC" "1"
					( Origin gPackager )
				)
				( objectStatus "R6N4" )
			)
			( gate "@baseboard_fab2_lib.baseboard_fab2(sch_1):page205_i46"
				( attribute "CDS_LIB" "mstr_discrete"
					( Origin gPackager )
				)
				( attribute "CDS_LOCATION" "EU4C1"
					( Origin gPackager )
				)
				( attribute "CDS_SEC" "1"
					( Origin gPackager )
				)
				( attribute "LOCATION" "EU4C1"
					( Origin gFrontEnd )
				)
				( attribute "MATERIAL" "IC"
					( Origin gFrontEnd )
				)
				( attribute "PACK_TYPE" "SM"
					( Origin gFrontEnd )
				)
				( attribute "PART_NUMBER" "H73684-001"
					( Origin gFrontEnd )
				)
				( attribute "PHYS_PAGE" "205"
					( Origin gFrontEnd )
				)
				( attribute "ROT" "0"
					( Origin gFrontEnd )
				)
				( attribute "SEC" "1"
					( Origin gPackager )
				)
				( attribute "VALUE" "IR35412"
					( Origin gFrontEnd )
				)
				( attribute "VER" "1"
					( Origin gFrontEnd )
				)
				( attribute "XY" "(-3150,3925)"
					( Origin gFrontEnd )
				)
				( attribute "CHIPS_PART_NAME" "IR354XX"
					( Origin gPackager )
				)
				( attribute "CDS_PART_NAME" "IR354XX_SM-IR35412,IC,H73684-0A"
					( Origin gPackager )
				)
				( objectStatus "EU4C1" )
			)
			( gate "@baseboard_fab2_lib.baseboard_fab2(sch_1):page205_i62"
				( attribute "CDS_LIB" "mstr_discrete"
					( Origin gPackager )
				)
				( attribute "CDS_LOCATION" "R4C13"
					( Origin gPackager )
				)
				( attribute "CDS_SEC" "1"
					( Origin gPackager )
				)
				( attribute "LOCATION" "R4C13"
					( Origin gFrontEnd )
				)
				( attribute "MATERIAL" "EMPTY"
					( Origin gFrontEnd )
				)
				( attribute "PACK_TYPE" "0402"
					( Origin gFrontEnd )
				)
				( attribute "PART_NUMBER" "G21796-187"
					( Origin gFrontEnd )
				)
				( attribute "PHYS_PAGE" "205"
					( Origin gFrontEnd )
				)
				( attribute "ROT" "0"
					( Origin gFrontEnd )
				)
				( attribute "SEC" "1"
					( Origin gPackager )
				)
				( attribute "TOLERANCE" "1%"
					( Origin gFrontEnd )
				)
				( attribute "VALUE" "68.1K"
					( Origin gFrontEnd )
				)
				( attribute "VER" "2"
					( Origin gFrontEnd )
				)
				( attribute "WATTAGE" "1/16W"
					( Origin gFrontEnd )
				)
				( attribute "XY" "(-775,4100)"
					( Origin gFrontEnd )
				)
				( attribute "CHIPS_PART_NAME" "RES"
					( Origin gPackager )
				)
				( attribute "CDS_PART_NAME" "RES_0402-68.1K,1%,1/16W,EMPTY,A"
					( Origin gPackager )
				)
				( objectStatus "R4C13" )
			)
			( gate "@baseboard_fab2_lib.baseboard_fab2(sch_1):page206_i4"
				( attribute "CDS_LIB" "mstr_discrete"
					( Origin gPackager )
				)
				( attribute "CDS_LOCATION" "R9P1"
					( Origin gPackager )
				)
				( attribute "CDS_SEC" "1"
					( Origin gPackager )
				)
				( attribute "LOCATION" "R9P1"
					( Origin gFrontEnd )
				)
				( attribute "MATERIAL" "CHIP"
					( Origin gFrontEnd )
				)
				( attribute "PACK_TYPE" "0402"
					( Origin gFrontEnd )
				)
				( attribute "PART_NUMBER" "G21796-017"
					( Origin gFrontEnd )
				)
				( attribute "PHYS_PAGE" "206"
					( Origin gFrontEnd )
				)
				( attribute "ROOM" "PVCCIN_CPU1_VR"
					( Origin gFrontEnd )
				)
				( attribute "ROT" "0"
					( Origin gFrontEnd )
				)
				( attribute "SEC" "1"
					( Origin gFrontEnd )
				)
				( attribute "SEC_TYPE" "0402"
					( Origin gFrontEnd )
				)
				( attribute "TOLERANCE" "1%"
					( Origin gFrontEnd )
				)
				( attribute "VALUE" "100.0"
					( Origin gFrontEnd )
				)
				( attribute "VER" "2"
					( Origin gFrontEnd )
				)
				( attribute "WATTAGE" "1/16W"
					( Origin gFrontEnd )
				)
				( attribute "XY" "(-1375,3750)"
					( Origin gFrontEnd )
				)
				( attribute "CHIPS_PART_NAME" "RES"
					( Origin gPackager )
				)
				( attribute "CDS_PART_NAME" "RES_0402-100.0,1%,1/16W,CHIP,GA"
					( Origin gPackager )
				)
				( objectStatus "R9P1" )
			)
			( gate "@baseboard_fab2_lib.baseboard_fab2(sch_1):page206_i6"
				( attribute "CDS_LIB" "mstr_discrete"
					( Origin gPackager )
				)
				( attribute "CDS_LOCATION" "R1D6"
					( Origin gPackager )
				)
				( attribute "CDS_SEC" "1"
					( Origin gPackager )
				)
				( attribute "LOCATION" "R1D6"
					( Origin gFrontEnd )
				)
				( attribute "MATERIAL" "CHIP"
					( Origin gFrontEnd )
				)
				( attribute "PACK_TYPE" "0402"
					( Origin gFrontEnd )
				)
				( attribute "PART_NUMBER" "G21796-026"
					( Origin gFrontEnd )
				)
				( attribute "PHYS_PAGE" "206"
					( Origin gFrontEnd )
				)
				( attribute "ROOM" "PVCCIN_CPU1_VR"
					( Origin gFrontEnd )
				)
				( attribute "ROT" "2"
					( Origin gFrontEnd )
				)
				( attribute "SEC" "1"
					( Origin gFrontEnd )
				)
				( attribute "SEC_TYPE" "0402"
					( Origin gFrontEnd )
				)
				( attribute "TOLERANCE" "1%"
					( Origin gFrontEnd )
				)
				( attribute "VALUE" "1.00K"
					( Origin gFrontEnd )
				)
				( attribute "VER" "2"
					( Origin gFrontEnd )
				)
				( attribute "WATTAGE" "1/16W"
					( Origin gFrontEnd )
				)
				( attribute "XY" "(-3150,4000)"
					( Origin gFrontEnd )
				)
				( attribute "CHIPS_PART_NAME" "RES"
					( Origin gPackager )
				)
				( attribute "CDS_PART_NAME" "RES_0402-1.00K,1%,1/16W,CHIP,GA"
					( Origin gPackager )
				)
				( objectStatus "R1D6" )
			)
			( gate "@baseboard_fab2_lib.baseboard_fab2(sch_1):page235_i246"
				( attribute "CDS_LIB" "mstr_discrete"
					( Origin gPackager )
				)
				( attribute "CDS_LOCATION" "C4W4"
					( Origin gPackager )
				)
				( attribute "CDS_SEC" "1"
					( Origin gPackager )
				)
				( attribute "LOCATION" "C4W4"
					( Origin gFrontEnd )
				)
				( attribute "MATERIAL" "X7R"
					( Origin gFrontEnd )
				)
				( attribute "PACK_TYPE" "0402LF"
					( Origin gFrontEnd )
				)
				( attribute "PART_NUMBER" "A36096-050"
					( Origin gFrontEnd )
				)
				( attribute "PHYS_PAGE" "235"
					( Origin gFrontEnd )
				)
				( attribute "ROOM" "PVCCIN_CPU0_VR"
					( Origin gFrontEnd )
				)
				( attribute "ROT" "0"
					( Origin gFrontEnd )
				)
				( attribute "SEC" "1"
					( Origin gFrontEnd )
				)
				( attribute "SEC_TYPE" "0402LF"
					( Origin gFrontEnd )
				)
				( attribute "TOLERANCE" "10%"
					( Origin gFrontEnd )
				)
				( attribute "VALUE" "220PF"
					( Origin gFrontEnd )
				)
				( attribute "VER" "1"
					( Origin gFrontEnd )
				)
				( attribute "VOLTAGE" "50V"
					( Units "uVoltage" "V" 1.000000)
					( Origin gFrontEnd )
				)
				( attribute "XY" "(-10000,2350)"
					( Origin gFrontEnd )
				)
				( attribute "CHIPS_PART_NAME" "CAP"
					( Origin gPackager )
				)
				( attribute "CDS_PART_NAME" "CAP_0402LF-220PF,50V,10%,X7R,AA"
					( Origin gPackager )
				)
				( objectStatus "C4W4" )
			)
			( gate "@baseboard_fab2_lib.baseboard_fab2(sch_1):page206_i29"
				( attribute "CDS_LIB" "dev_discrete"
					( Origin gPackager )
				)
				( attribute "CDS_LOCATION" "C1C13"
					( Origin gPackager )
				)
				( attribute "LOCATION" "C1C13"
					( Origin gFrontEnd )
				)
				( attribute "MATERIAL" "X6S"
					( Origin gFrontEnd )
				)
				( attribute "PACK_TYPE" "0402V"
					( Origin gFrontEnd )
				)
				( attribute "PART_NUMBER" "D97712-004"
					( Origin gFrontEnd )
				)
				( attribute "PHYS_PAGE" "206"
					( Origin gFrontEnd )
				)
				( attribute "ROOM" "PVCCIN_CPU1_VR"
					( Origin gFrontEnd )
				)
				( attribute "ROT" "0"
					( Origin gFrontEnd )
				)
				( attribute "SEC" "1"
					( Origin gFrontEnd )
				)
				( attribute "TOLERANCE" "10%"
					( Origin gFrontEnd )
				)
				( attribute "VALUE" "1.0UF"
					( Origin gFrontEnd )
				)
				( attribute "VER" "1"
					( Origin gFrontEnd )
				)
				( attribute "VOLTAGE" "6.3V"
					( Units "uVoltage" "V" 1.000000)
					( Origin gFrontEnd )
				)
				( attribute "XY" "(-1575,1000)"
					( Origin gFrontEnd )
				)
				( attribute "CHIPS_PART_NAME" "CAP_A"
					( Origin gPackager )
				)
				( attribute "CDS_PART_NAME" "CAP_A_0402V-1.0UF,6.3V,10%,X6SA"
					( Origin gPackager )
				)
				( attribute "SEC_TYPE" "0402V"
					( Origin gFrontEnd )
				)
				( attribute "CDS_SEC" "1"
					( Origin gPackager )
				)
				( objectStatus "C1C13" )
			)
			( gate "@baseboard_fab2_lib.baseboard_fab2(sch_1):page206_i31"
				( attribute "CDS_LIB" "dev_discrete"
					( Origin gPackager )
				)
				( attribute "CDS_LOCATION" "C1C14"
					( Origin gPackager )
				)
				( attribute "CDS_SEC" "1"
					( Origin gPackager )
				)
				( attribute "LOCATION" "C1C14"
					( Origin gFrontEnd )
				)
				( attribute "MATERIAL" "X7R"
					( Origin gFrontEnd )
				)
				( attribute "PACK_TYPE" "0402V"
					( Origin gFrontEnd )
				)
				( attribute "PART_NUMBER" "A36096-030"
					( Origin gFrontEnd )
				)
				( attribute "PHYS_PAGE" "206"
					( Origin gFrontEnd )
				)
				( attribute "ROOM" "PVCCIN_CPU1_VR"
					( Origin gFrontEnd )
				)
				( attribute "ROT" "0"
					( Origin gFrontEnd )
				)
				( attribute "SEC" "1"
					( Origin gFrontEnd )
				)
				( attribute "SEC_TYPE" "0402V"
					( Origin gFrontEnd )
				)
				( attribute "TOLERANCE" "10%"
					( Origin gFrontEnd )
				)
				( attribute "VALUE" "0.1UF"
					( Origin gFrontEnd )
				)
				( attribute "VER" "1"
					( Origin gFrontEnd )
				)
				( attribute "VOLTAGE" "16V"
					( Units "uVoltage" "V" 1.000000)
					( Origin gFrontEnd )
				)
				( attribute "XY" "(-1975,1000)"
					( Origin gFrontEnd )
				)
				( attribute "CHIPS_PART_NAME" "CAP_A"
					( Origin gPackager )
				)
				( attribute "CDS_PART_NAME" "CAP_A_0402V-0.1UF,16V,10%,X7R,A"
					( Origin gPackager )
				)
				( objectStatus "C1C14" )
			)
			( gate "@baseboard_fab2_lib.baseboard_fab2(sch_1):page206_i33"
				( attribute "CDS_LIB" "mstr_discrete"
					( Origin gPackager )
				)
				( attribute "CDS_LOCATION" "R1D53"
					( Origin gPackager )
				)
				( attribute "CDS_SEC" "1"
					( Origin gPackager )
				)
				( attribute "LOCATION" "R1D53"
					( Origin gFrontEnd )
				)
				( attribute "MATERIAL" "EMPTY"
					( Origin gFrontEnd )
				)
				( attribute "PACK_TYPE" "0402"
					( Origin gFrontEnd )
				)
				( attribute "PART_NUMBER" "G21796-311"
					( Origin gFrontEnd )
				)
				( attribute "PHYS_PAGE" "206"
					( Origin gFrontEnd )
				)
				( attribute "ROOM" "PVCCIN_CPU1_VR"
					( Origin gFrontEnd )
				)
				( attribute "ROT" "0"
					( Origin gFrontEnd )
				)
				( attribute "SEC" "1"
					( Origin gFrontEnd )
				)
				( attribute "SEC_TYPE" "0402"
					( Origin gFrontEnd )
				)
				( attribute "TOLERANCE" "1.0%"
					( Origin gFrontEnd )
				)
				( attribute "VALUE" "2.26K"
					( Origin gFrontEnd )
				)
				( attribute "VER" "2"
					( Origin gFrontEnd )
				)
				( attribute "WATTAGE" "1/16W"
					( Origin gFrontEnd )
				)
				( attribute "XY" "(-2375,4125)"
					( Origin gFrontEnd )
				)
				( attribute "CHIPS_PART_NAME" "RES"
					( Origin gPackager )
				)
				( attribute "CDS_PART_NAME" "RES_0402-2.26K,1.0%,1/16W,EMPTA"
					( Origin gPackager )
				)
				( objectStatus "R1D53" )
			)
			( gate "@baseboard_fab2_lib.baseboard_fab2(sch_1):page206_i34"
				( attribute "CDS_LIB" "mstr_discrete"
					( Origin gPackager )
				)
				( attribute "CDS_LOCATION" "R1C18"
					( Origin gPackager )
				)
				( attribute "CDS_SEC" "1"
					( Origin gPackager )
				)
				( attribute "LOCATION" "R1C18"
					( Origin gFrontEnd )
				)
				( attribute "MATERIAL" "EMPTY"
					( Origin gFrontEnd )
				)
				( attribute "PACK_TYPE" "0402"
					( Origin gFrontEnd )
				)
				( attribute "PART_NUMBER" "G21796-311"
					( Origin gFrontEnd )
				)
				( attribute "PHYS_PAGE" "206"
					( Origin gFrontEnd )
				)
				( attribute "ROOM" "PVCCIN_CPU1_VR"
					( Origin gFrontEnd )
				)
				( attribute "ROT" "0"
					( Origin gFrontEnd )
				)
				( attribute "SEC" "1"
					( Origin gFrontEnd )
				)
				( attribute "SEC_TYPE" "0402"
					( Origin gFrontEnd )
				)
				( attribute "TOLERANCE" "1.0%"
					( Origin gFrontEnd )
				)
				( attribute "VALUE" "2.26K"
					( Origin gFrontEnd )
				)
				( attribute "VER" "2"
					( Origin gFrontEnd )
				)
				( attribute "WATTAGE" "1/16W"
					( Origin gFrontEnd )
				)
				( attribute "XY" "(-2225,3750)"
					( Origin gFrontEnd )
				)
				( attribute "CHIPS_PART_NAME" "RES"
					( Origin gPackager )
				)
				( attribute "CDS_PART_NAME" "RES_0402-2.26K,1.0%,1/16W,EMPTA"
					( Origin gPackager )
				)
				( objectStatus "R1C18" )
			)
			( gate "@baseboard_fab2_lib.baseboard_fab2(sch_1):page206_i35"
				( attribute "CDS_LIB" "mstr_discrete"
					( Origin gPackager )
				)
				( attribute "CDS_LOCATION" "R1C28"
					( Origin gPackager )
				)
				( attribute "CDS_SEC" "1"
					( Origin gPackager )
				)
				( attribute "LOCATION" "R1C28"
					( Origin gFrontEnd )
				)
				( attribute "MATERIAL" "CHIP"
					( Origin gFrontEnd )
				)
				( attribute "PACK_TYPE" "0402"
					( Origin gFrontEnd )
				)
				( attribute "PART_NUMBER" "G21796-026"
					( Origin gFrontEnd )
				)
				( attribute "PHYS_PAGE" "206"
					( Origin gFrontEnd )
				)
				( attribute "ROOM" "PVCCIN_CPU1_VR"
					( Origin gFrontEnd )
				)
				( attribute "ROT" "0"
					( Origin gFrontEnd )
				)
				( attribute "SEC" "1"
					( Origin gFrontEnd )
				)
				( attribute "SEC_TYPE" "0402"
					( Origin gFrontEnd )
				)
				( attribute "TOLERANCE" "1%"
					( Origin gFrontEnd )
				)
				( attribute "VALUE" "1.00K"
					( Origin gFrontEnd )
				)
				( attribute "VER" "2"
					( Origin gFrontEnd )
				)
				( attribute "WATTAGE" "1/16W"
					( Origin gFrontEnd )
				)
				( attribute "XY" "(-2725,3925)"
					( Origin gFrontEnd )
				)
				( attribute "CHIPS_PART_NAME" "RES"
					( Origin gPackager )
				)
				( attribute "CDS_PART_NAME" "RES_0402-1.00K,1%,1/16W,CHIP,GA"
					( Origin gPackager )
				)
				( objectStatus "R1C28" )
			)
			( gate "@baseboard_fab2_lib.baseboard_fab2(sch_1):page206_i36"
				( attribute "CDS_LIB" "mstr_discrete"
					( Origin gPackager )
				)
				( attribute "CDS_LOCATION" "R1D8"
					( Origin gPackager )
				)
				( attribute "CDS_SEC" "1"
					( Origin gPackager )
				)
				( attribute "LOCATION" "R1D8"
					( Origin gFrontEnd )
				)
				( attribute "MATERIAL" "CHIP"
					( Origin gFrontEnd )
				)
				( attribute "PACK_TYPE" "0402"
					( Origin gFrontEnd )
				)
				( attribute "PART_NUMBER" "G21796-026"
					( Origin gFrontEnd )
				)
				( attribute "PHYS_PAGE" "206"
					( Origin gFrontEnd )
				)
				( attribute "ROOM" "PVCCIN_CPU1_VR"
					( Origin gFrontEnd )
				)
				( attribute "ROT" "2"
					( Origin gFrontEnd )
				)
				( attribute "SEC" "1"
					( Origin gFrontEnd )
				)
				( attribute "SEC_TYPE" "0402"
					( Origin gFrontEnd )
				)
				( attribute "TOLERANCE" "1%"
					( Origin gFrontEnd )
				)
				( attribute "VALUE" "1.00K"
					( Origin gFrontEnd )
				)
				( attribute "VER" "2"
					( Origin gFrontEnd )
				)
				( attribute "WATTAGE" "1/16W"
					( Origin gFrontEnd )
				)
				( attribute "XY" "(-2875,3925)"
					( Origin gFrontEnd )
				)
				( attribute "CHIPS_PART_NAME" "RES"
					( Origin gPackager )
				)
				( attribute "CDS_PART_NAME" "RES_0402-1.00K,1%,1/16W,CHIP,GA"
					( Origin gPackager )
				)
				( objectStatus "R1D8" )
			)
			( gate "@baseboard_fab2_lib.baseboard_fab2(sch_1):page206_i37"
				( attribute "CDS_LIB" "mstr_discrete"
					( Origin gPackager )
				)
				( attribute "CDS_LOCATION" "R1D3"
					( Origin gPackager )
				)
				( attribute "CDS_SEC" "1"
					( Origin gPackager )
				)
				( attribute "LOCATION" "R1D3"
					( Origin gFrontEnd )
				)
				( attribute "MATERIAL" "CHIP"
					( Origin gFrontEnd )
				)
				( attribute "PACK_TYPE" "0402"
					( Origin gFrontEnd )
				)
				( attribute "PART_NUMBER" "G21497-005"
					( Origin gFrontEnd )
				)
				( attribute "PHYS_PAGE" "206"
					( Origin gFrontEnd )
				)
				( attribute "ROOM" "PVCCIN_CPU1_VR"
					( Origin gFrontEnd )
				)
				( attribute "ROT" "0"
					( Origin gFrontEnd )
				)
				( attribute "SEC" "1"
					( Origin gFrontEnd )
				)
				( attribute "SEC_TYPE" "0402"
					( Origin gFrontEnd )
				)
				( attribute "TOLERANCE" "5%"
					( Origin gFrontEnd )
				)
				( attribute "VALUE" "0.0"
					( Origin gFrontEnd )
				)
				( attribute "VER" "1"
					( Origin gFrontEnd )
				)
				( attribute "WATTAGE" "1/16W"
					( Origin gFrontEnd )
				)
				( attribute "XY" "(-2125,2925)"
					( Origin gFrontEnd )
				)
				( attribute "CHIPS_PART_NAME" "RES"
					( Origin gPackager )
				)
				( attribute "CDS_PART_NAME" "RES_0402-0.0,5%,1/16W,CHIP,G21A"
					( Origin gPackager )
				)
				( objectStatus "R1D3" )
			)
			( gate "@baseboard_fab2_lib.baseboard_fab2(sch_1):page206_i38"
				( attribute "CDS_LIB" "mstr_discrete"
					( Origin gPackager )
				)
				( attribute "CDS_LOCATION" "R1D2"
					( Origin gPackager )
				)
				( attribute "CDS_SEC" "1"
					( Origin gPackager )
				)
				( attribute "LOCATION" "R1D2"
					( Origin gFrontEnd )
				)
				( attribute "MATERIAL" "CHIP"
					( Origin gFrontEnd )
				)
				( attribute "PACK_TYPE" "0402"
					( Origin gFrontEnd )
				)
				( attribute "PART_NUMBER" "G21497-005"
					( Origin gFrontEnd )
				)
				( attribute "PHYS_PAGE" "206"
					( Origin gFrontEnd )
				)
				( attribute "ROOM" "PVCCIN_CPU1_VR"
					( Origin gFrontEnd )
				)
				( attribute "ROT" "0"
					( Origin gFrontEnd )
				)
				( attribute "SEC" "1"
					( Origin gFrontEnd )
				)
				( attribute "SEC_TYPE" "0402"
					( Origin gFrontEnd )
				)
				( attribute "TOLERANCE" "5%"
					( Origin gFrontEnd )
				)
				( attribute "VALUE" "0.0"
					( Origin gFrontEnd )
				)
				( attribute "VER" "1"
					( Origin gFrontEnd )
				)
				( attribute "WATTAGE" "1/16W"
					( Origin gFrontEnd )
				)
				( attribute "XY" "(-2500,2775)"
					( Origin gFrontEnd )
				)
				( attribute "CHIPS_PART_NAME" "RES"
					( Origin gPackager )
				)
				( attribute "CDS_PART_NAME" "RES_0402-0.0,5%,1/16W,CHIP,G21A"
					( Origin gPackager )
				)
				( objectStatus "R1D2" )
			)
			( gate "@baseboard_fab2_lib.baseboard_fab2(sch_1):page206_i41"
				( attribute "CDS_LIB" "dev_discrete"
					( Origin gPackager )
				)
				( attribute "CDS_LOCATION" "C1C7"
					( Origin gPackager )
				)
				( attribute "CDS_SEC" "1"
					( Origin gPackager )
				)
				( attribute "LOCATION" "C1C7"
					( Origin gFrontEnd )
				)
				( attribute "MATERIAL" "X6S"
					( Origin gFrontEnd )
				)
				( attribute "PACK_TYPE" "0402V"
					( Origin gFrontEnd )
				)
				( attribute "PART_NUMBER" "D97712-004"
					( Origin gFrontEnd )
				)
				( attribute "PHYS_PAGE" "206"
					( Origin gFrontEnd )
				)
				( attribute "ROOM" "PVCCIN_CPU1_VR"
					( Origin gFrontEnd )
				)
				( attribute "ROT" "0"
					( Origin gFrontEnd )
				)
				( attribute "SEC" "1"
					( Origin gPackager )
				)
				( attribute "TOLERANCE" "10%"
					( Origin gFrontEnd )
				)
				( attribute "VALUE" "1.0UF"
					( Origin gFrontEnd )
				)
				( attribute "VER" "1"
					( Origin gFrontEnd )
				)
				( attribute "VOLTAGE" "6.3V"
					( Units "uVoltage" "V" 1.000000)
					( Origin gFrontEnd )
				)
				( attribute "XY" "(-3650,3925)"
					( Origin gFrontEnd )
				)
				( attribute "CHIPS_PART_NAME" "CAP_A"
					( Origin gPackager )
				)
				( attribute "CDS_PART_NAME" "CAP_A_0402V-1.0UF,6.3V,10%,X6SA"
					( Origin gPackager )
				)
				( objectStatus "C1C7" )
			)
			( gate "@baseboard_fab2_lib.baseboard_fab2(sch_1):page206_i42"
				( attribute "CDS_LIB" "dev_discrete"
					( Origin gPackager )
				)
				( attribute "CDS_LOCATION" "C1C9"
					( Origin gPackager )
				)
				( attribute "CDS_SEC" "1"
					( Origin gPackager )
				)
				( attribute "LOCATION" "C1C9"
					( Origin gFrontEnd )
				)
				( attribute "MATERIAL" "X7R"
					( Origin gFrontEnd )
				)
				( attribute "PACK_TYPE" "0402V"
					( Origin gFrontEnd )
				)
				( attribute "PART_NUMBER" "A36096-030"
					( Origin gFrontEnd )
				)
				( attribute "PHYS_PAGE" "206"
					( Origin gFrontEnd )
				)
				( attribute "ROOM" "PVCCIN_CPU1_VR"
					( Origin gFrontEnd )
				)
				( attribute "ROT" "0"
					( Origin gFrontEnd )
				)
				( attribute "SEC" "1"
					( Origin gFrontEnd )
				)
				( attribute "SEC_TYPE" "0402V"
					( Origin gFrontEnd )
				)
				( attribute "TOLERANCE" "10%"
					( Origin gFrontEnd )
				)
				( attribute "VALUE" "0.1UF"
					( Origin gFrontEnd )
				)
				( attribute "VER" "1"
					( Origin gFrontEnd )
				)
				( attribute "VOLTAGE" "16V"
					( Units "uVoltage" "V" 1.000000)
					( Origin gFrontEnd )
				)
				( attribute "XY" "(-4050,3925)"
					( Origin gFrontEnd )
				)
				( attribute "CHIPS_PART_NAME" "CAP_A"
					( Origin gPackager )
				)
				( attribute "CDS_PART_NAME" "CAP_A_0402V-0.1UF,16V,10%,X7R,A"
					( Origin gPackager )
				)
				( objectStatus "C1C9" )
			)
			( gate "@baseboard_fab2_lib.baseboard_fab2(sch_1):page206_i46"
				( attribute "CDS_LIB" "mstr_discrete"
					( Origin gPackager )
				)
				( attribute "CDS_LOCATION" "R1C14"
					( Origin gPackager )
				)
				( attribute "CDS_SEC" "1"
					( Origin gPackager )
				)
				( attribute "LOCATION" "R1C14"
					( Origin gFrontEnd )
				)
				( attribute "MATERIAL" "CHIP"
					( Origin gFrontEnd )
				)
				( attribute "PACK_TYPE" "0402"
					( Origin gFrontEnd )
				)
				( attribute "PART_NUMBER" "G21497-005"
					( Origin gFrontEnd )
				)
				( attribute "PHYS_PAGE" "206"
					( Origin gFrontEnd )
				)
				( attribute "ROOM" "PVCCIN_CPU1_VR"
					( Origin gFrontEnd )
				)
				( attribute "ROT" "0"
					( Origin gFrontEnd )
				)
				( attribute "SEC" "1"
					( Origin gFrontEnd )
				)
				( attribute "SEC_TYPE" "0402"
					( Origin gFrontEnd )
				)
				( attribute "TOLERANCE" "5%"
					( Origin gFrontEnd )
				)
				( attribute "VALUE" "0.0"
					( Origin gFrontEnd )
				)
				( attribute "VER" "2"
					( Origin gFrontEnd )
				)
				( attribute "WATTAGE" "1/16W"
					( Origin gFrontEnd )
				)
				( attribute "XY" "(-4350,4275)"
					( Origin gFrontEnd )
				)
				( attribute "CHIPS_PART_NAME" "RES"
					( Origin gPackager )
				)
				( attribute "CDS_PART_NAME" "RES_0402-0.0,5%,1/16W,CHIP,G21A"
					( Origin gPackager )
				)
				( objectStatus "R1C14" )
			)
			( gate "@baseboard_fab2_lib.baseboard_fab2(sch_1):page206_i49"
				( attribute "CDS_LIB" "mstr_discrete"
					( Origin gPackager )
				)
				( attribute "CDS_LOCATION" "R1C13"
					( Origin gPackager )
				)
				( attribute "CDS_SEC" "1"
					( Origin gPackager )
				)
				( attribute "LOCATION" "R1C13"
					( Origin gFrontEnd )
				)
				( attribute "MATERIAL" "CHIP"
					( Origin gFrontEnd )
				)
				( attribute "PACK_TYPE" "0402"
					( Origin gFrontEnd )
				)
				( attribute "PART_NUMBER" "G21796-160"
					( Origin gFrontEnd )
				)
				( attribute "PHYS_PAGE" "206"
					( Origin gFrontEnd )
				)
				( attribute "ROOM" "PVCCIN_CPU1_VR"
					( Origin gFrontEnd )
				)
				( attribute "ROT" "0"
					( Origin gFrontEnd )
				)
				( attribute "SEC" "1"
					( Origin gFrontEnd )
				)
				( attribute "SEC_TYPE" "0402"
					( Origin gFrontEnd )
				)
				( attribute "TOLERANCE" "1%"
					( Origin gFrontEnd )
				)
				( attribute "VALUE" "100.0K"
					( Origin gFrontEnd )
				)
				( attribute "VER" "2"
					( Origin gFrontEnd )
				)
				( attribute "WATTAGE" "1/16W"
					( Origin gFrontEnd )
				)
				( attribute "XY" "(-6150,4575)"
					( Origin gFrontEnd )
				)
				( attribute "CHIPS_PART_NAME" "RES"
					( Origin gPackager )
				)
				( attribute "CDS_PART_NAME" "RES_0402-100.0K,1%,1/16W,CHIP,B"
					( Origin gPackager )
				)
				( objectStatus "R1C13" )
			)
			( gate "@baseboard_fab2_lib.baseboard_fab2(sch_1):page206_i53"
				( attribute "CDS_LIB" "mstr_discrete"
					( Origin gPackager )
				)
				( attribute "CDS_LOCATION" "R9P2"
					( Origin gPackager )
				)
				( attribute "CDS_SEC" "1"
					( Origin gPackager )
				)
				( attribute "LOCATION" "R9P2"
					( Origin gFrontEnd )
				)
				( attribute "MATERIAL" "CHIP"
					( Origin gFrontEnd )
				)
				( attribute "PACK_TYPE" "0402"
					( Origin gFrontEnd )
				)
				( attribute "PART_NUMBER" "G21796-047"
					( Origin gFrontEnd )
				)
				( attribute "PHYS_PAGE" "206"
					( Origin gFrontEnd )
				)
				( attribute "ROOM" "PVCCIN_CPU1_VR"
					( Origin gFrontEnd )
				)
				( attribute "ROT" "0"
					( Origin gFrontEnd )
				)
				( attribute "SEC" "1"
					( Origin gFrontEnd )
				)
				( attribute "SEC_TYPE" "0402"
					( Origin gFrontEnd )
				)
				( attribute "TOLERANCE" "1%"
					( Origin gFrontEnd )
				)
				( attribute "VALUE" "49.9"
					( Origin gFrontEnd )
				)
				( attribute "VER" "2"
					( Origin gFrontEnd )
				)
				( attribute "WATTAGE" "1/16W"
					( Origin gFrontEnd )
				)
				( attribute "XY" "(-5650,4450)"
					( Origin gFrontEnd )
				)
				( attribute "CHIPS_PART_NAME" "RES"
					( Origin gPackager )
				)
				( attribute "CDS_PART_NAME" "RES_0402-49.9,1%,1/16W,CHIP,G2A"
					( Origin gPackager )
				)
				( objectStatus "R9P2" )
			)
			( gate "@baseboard_fab2_lib.baseboard_fab2(sch_1):page206_i54"
				( attribute "CDS_LIB" "mstr_discrete"
					( Origin gPackager )
				)
				( attribute "CDS_LOCATION" "R1D9"
					( Origin gPackager )
				)
				( attribute "CDS_SEC" "1"
					( Origin gPackager )
				)
				( attribute "LOCATION" "R1D9"
					( Origin gFrontEnd )
				)
				( attribute "MATERIAL" "CHIP"
					( Origin gFrontEnd )
				)
				( attribute "PACK_TYPE" "0402"
					( Origin gFrontEnd )
				)
				( attribute "PART_NUMBER" "G21796-009"
					( Origin gFrontEnd )
				)
				( attribute "PHYS_PAGE" "206"
					( Origin gFrontEnd )
				)
				( attribute "ROOM" "PVCCIN_CPU1_VR"
					( Origin gFrontEnd )
				)
				( attribute "ROT" "0"
					( Origin gFrontEnd )
				)
				( attribute "SEC" "1"
					( Origin gPackager )
				)
				( attribute "TOLERANCE" "1%"
					( Origin gFrontEnd )
				)
				( attribute "VALUE" "150.0"
					( Origin gFrontEnd )
				)
				( attribute "VER" "1"
					( Origin gFrontEnd )
				)
				( attribute "WATTAGE" "1/16W"
					( Origin gFrontEnd )
				)
				( attribute "XY" "(-5375,3900)"
					( Origin gFrontEnd )
				)
				( attribute "CHIPS_PART_NAME" "RES"
					( Origin gPackager )
				)
				( attribute "CDS_PART_NAME" "RES_0402-150.0,1%,1/16W,CHIP,GA"
					( Origin gPackager )
				)
				( objectStatus "R1D9" )
			)
			( gate "@baseboard_fab2_lib.baseboard_fab2(sch_1):page206_i56"
				( attribute "CDS_LIB" "mstr_discrete"
					( Origin gPackager )
				)
				( attribute "CDS_LOCATION" "R1C16"
					( Origin gPackager )
				)
				( attribute "CDS_SEC" "1"
					( Origin gPackager )
				)
				( attribute "LOCATION" "R1C16"
					( Origin gFrontEnd )
				)
				( attribute "MATERIAL" "CHIP"
					( Origin gFrontEnd )
				)
				( attribute "PACK_TYPE" "0402"
					( Origin gFrontEnd )
				)
				( attribute "PART_NUMBER" "G21796-003"
					( Origin gFrontEnd )
				)
				( attribute "PHYS_PAGE" "206"
					( Origin gFrontEnd )
				)
				( attribute "ROOM" "PVCCIN_CPU1_VR"
					( Origin gFrontEnd )
				)
				( attribute "ROT" "0"
					( Origin gFrontEnd )
				)
				( attribute "SEC" "1"
					( Origin gFrontEnd )
				)
				( attribute "SEC_TYPE" "0402"
					( Origin gFrontEnd )
				)
				( attribute "TOLERANCE" "1%"
					( Origin gFrontEnd )
				)
				( attribute "VALUE" "1.5K"
					( Origin gFrontEnd )
				)
				( attribute "VER" "2"
					( Origin gFrontEnd )
				)
				( attribute "WATTAGE" "1/16W"
					( Origin gFrontEnd )
				)
				( attribute "XY" "(-6150,4225)"
					( Origin gFrontEnd )
				)
				( attribute "CHIPS_PART_NAME" "RES"
					( Origin gPackager )
				)
				( attribute "CDS_PART_NAME" "RES_0402-1.5K,1%,1/16W,CHIP,G2A"
					( Origin gPackager )
				)
				( objectStatus "R1C16" )
			)
			( gate "@baseboard_fab2_lib.baseboard_fab2(sch_1):page206_i68"
				( attribute "CDS_LIB" "mstr_discrete"
					( Origin gPackager )
				)
				( attribute "CDS_LOCATION" "C1C16"
					( Origin gPackager )
				)
				( attribute "CDS_SEC" "1"
					( Origin gPackager )
				)
				( attribute "LOCATION" "C1C16"
					( Origin gFrontEnd )
				)
				( attribute "MATERIAL" "X7R"
					( Origin gFrontEnd )
				)
				( attribute "NO_XNET_CONNECTION" "1"
					( Origin gFrontEnd )
				)
				( attribute "PACK_TYPE" "0402LF"
					( Origin gFrontEnd )
				)
				( attribute "PART_NUMBER" "A36096-050"
					( Origin gFrontEnd )
				)
				( attribute "PHYS_PAGE" "206"
					( Origin gFrontEnd )
				)
				( attribute "ROOM" "PVCCIN_CPU1_VR"
					( Origin gFrontEnd )
				)
				( attribute "ROT" "0"
					( Origin gFrontEnd )
				)
				( attribute "SEC" "1"
					( Origin gFrontEnd )
				)
				( attribute "SEC_TYPE" "0402LF"
					( Origin gFrontEnd )
				)
				( attribute "TOLERANCE" "10%"
					( Origin gFrontEnd )
				)
				( attribute "VALUE" "220PF"
					( Origin gFrontEnd )
				)
				( attribute "VER" "1"
					( Origin gFrontEnd )
				)
				( attribute "VOLTAGE" "50V"
					( Units "uVoltage" "V" 1.000000)
					( Origin gFrontEnd )
				)
				( attribute "XY" "(-5650,2075)"
					( Origin gFrontEnd )
				)
				( attribute "CHIPS_PART_NAME" "CAP"
					( Origin gPackager )
				)
				( attribute "CDS_PART_NAME" "CAP_0402LF-220PF,50V,10%,X7R,AA"
					( Origin gPackager )
				)
				( objectStatus "C1C16" )
			)
			( gate "@baseboard_fab2_lib.baseboard_fab2(sch_1):page206_i69"
				( attribute "CDS_LIB" "mstr_discrete"
					( Origin gPackager )
				)
				( attribute "CDS_LOCATION" "C1C10"
					( Origin gPackager )
				)
				( attribute "CDS_SEC" "1"
					( Origin gPackager )
				)
				( attribute "LOCATION" "C1C10"
					( Origin gFrontEnd )
				)
				( attribute "MATERIAL" "X7R"
					( Origin gFrontEnd )
				)
				( attribute "PACK_TYPE" "0402LF"
					( Origin gFrontEnd )
				)
				( attribute "PART_NUMBER" "A36096-050"
					( Origin gFrontEnd )
				)
				( attribute "PHYS_PAGE" "206"
					( Origin gFrontEnd )
				)
				( attribute "ROOM" "PVCCIN_CPU1_VR"
					( Origin gFrontEnd )
				)
				( attribute "ROT" "0"
					( Origin gFrontEnd )
				)
				( attribute "SEC" "1"
					( Origin gFrontEnd )
				)
				( attribute "SEC_TYPE" "0402LF"
					( Origin gFrontEnd )
				)
				( attribute "TOLERANCE" "10%"
					( Origin gFrontEnd )
				)
				( attribute "VALUE" "220PF"
					( Origin gFrontEnd )
				)
				( attribute "VER" "1"
					( Origin gFrontEnd )
				)
				( attribute "VOLTAGE" "50V"
					( Units "uVoltage" "V" 1.000000)
					( Origin gFrontEnd )
				)
				( attribute "XY" "(-5925,1275)"
					( Origin gFrontEnd )
				)
				( attribute "CHIPS_PART_NAME" "CAP"
					( Origin gPackager )
				)
				( attribute "CDS_PART_NAME" "CAP_0402LF-220PF,50V,10%,X7R,AA"
					( Origin gPackager )
				)
				( objectStatus "C1C10" )
			)
			( gate "@baseboard_fab2_lib.baseboard_fab2(sch_1):page206_i71"
				( attribute "CDS_LIB" "mstr_discrete"
					( Origin gPackager )
				)
				( attribute "CDS_LOCATION" "C1C11"
					( Origin gPackager )
				)
				( attribute "CDS_SEC" "1"
					( Origin gPackager )
				)
				( attribute "LOCATION" "C1C11"
					( Origin gFrontEnd )
				)
				( attribute "MATERIAL" "X7R"
					( Origin gFrontEnd )
				)
				( attribute "PACK_TYPE" "0402LF"
					( Origin gFrontEnd )
				)
				( attribute "PART_NUMBER" "A36096-050"
					( Origin gFrontEnd )
				)
				( attribute "PHYS_PAGE" "206"
					( Origin gFrontEnd )
				)
				( attribute "ROOM" "PVCCIN_CPU1_VR"
					( Origin gFrontEnd )
				)
				( attribute "ROT" "2"
					( Origin gFrontEnd )
				)
				( attribute "SEC" "1"
					( Origin gFrontEnd )
				)
				( attribute "SEC_TYPE" "0402LF"
					( Origin gFrontEnd )
				)
				( attribute "TOLERANCE" "10%"
					( Origin gFrontEnd )
				)
				( attribute "VALUE" "220PF"
					( Origin gFrontEnd )
				)
				( attribute "VER" "1"
					( Origin gFrontEnd )
				)
				( attribute "VOLTAGE" "50V"
					( Units "uVoltage" "V" 1.000000)
					( Origin gFrontEnd )
				)
				( attribute "XY" "(-6150,650)"
					( Origin gFrontEnd )
				)
				( attribute "CHIPS_PART_NAME" "CAP"
					( Origin gPackager )
				)
				( attribute "CDS_PART_NAME" "CAP_0402LF-220PF,50V,10%,X7R,AA"
					( Origin gPackager )
				)
				( objectStatus "C1C11" )
			)
			( gate "@baseboard_fab2_lib.baseboard_fab2(sch_1):page211_i103"
				( attribute "BOM_COST" "SM_THERM"
					( Origin gFrontEnd )
				)
				( attribute "CDS_LIB" "dev_discrete"
					( Origin gPackager )
				)
				( attribute "CDS_LOCATION" "C3P2"
					( Origin gPackager )
				)
				( attribute "CDS_SEC" "1"
					( Origin gPackager )
				)
				( attribute "LOCATION" "C3P2"
					( Origin gFrontEnd )
				)
				( attribute "MATERIAL" "X7R"
					( Origin gFrontEnd )
				)
				( attribute "PACK_TYPE" "0402V"
					( Origin gFrontEnd )
				)
				( attribute "PART_NUMBER" "A36096-030"
					( Origin gFrontEnd )
				)
				( attribute "PHYS_PAGE" "211"
					( Origin gFrontEnd )
				)
				( attribute "ROOM" "CPU_FANS"
					( Origin gFrontEnd )
				)
				( attribute "ROT" "0"
					( Origin gFrontEnd )
				)
				( attribute "SEC" "1"
					( Origin gFrontEnd )
				)
				( attribute "SEC_TYPE" "0402V"
					( Origin gFrontEnd )
				)
				( attribute "TOLERANCE" "10%"
					( Origin gFrontEnd )
				)
				( attribute "VALUE" "0.1UF"
					( Origin gFrontEnd )
				)
				( attribute "VER" "1"
					( Origin gFrontEnd )
				)
				( attribute "VOLTAGE" "16V"
					( Units "uVoltage" "V" 1.000000)
					( Origin gFrontEnd )
				)
				( attribute "XY" "(-2850,4300)"
					( Origin gFrontEnd )
				)
				( attribute "CHIPS_PART_NAME" "CAP_A"
					( Origin gPackager )
				)
				( attribute "CDS_PART_NAME" "CAP_A_0402V-0.1UF,16V,10%,X7R,A"
					( Origin gPackager )
				)
				( objectStatus "C3P2" )
			)
			( gate "@baseboard_fab2_lib.baseboard_fab2(sch_1):page206_i77"
				( attribute "CDS_LIB" "mstr_discrete"
					( Origin gPackager )
				)
				( attribute "CDS_LOCATION" "R1C21"
					( Origin gPackager )
				)
				( attribute "CDS_SEC" "1"
					( Origin gPackager )
				)
				( attribute "LOCATION" "R1C21"
					( Origin gFrontEnd )
				)
				( attribute "MATERIAL" "CHIP"
					( Origin gFrontEnd )
				)
				( attribute "NO_XNET_CONNECTION" "1"
					( Origin gFrontEnd )
				)
				( attribute "PACK_TYPE" "0402"
					( Origin gFrontEnd )
				)
				( attribute "PART_NUMBER" "G21796-066"
					( Origin gFrontEnd )
				)
				( attribute "PHYS_PAGE" "206"
					( Origin gFrontEnd )
				)
				( attribute "ROOM" "PVCCIN_CPU1_VR"
					( Origin gFrontEnd )
				)
				( attribute "ROT" "0"
					( Origin gFrontEnd )
				)
				( attribute "SEC" "1"
					( Origin gFrontEnd )
				)
				( attribute "SEC_TYPE" "0402"
					( Origin gFrontEnd )
				)
				( attribute "TOLERANCE" "1%"
					( Origin gFrontEnd )
				)
				( attribute "VALUE" "10.0"
					( Origin gFrontEnd )
				)
				( attribute "VER" "1"
					( Origin gFrontEnd )
				)
				( attribute "WATTAGE" "1/16W"
					( Origin gFrontEnd )
				)
				( attribute "XY" "(-6350,2075)"
					( Origin gFrontEnd )
				)
				( attribute "CHIPS_PART_NAME" "RES"
					( Origin gPackager )
				)
				( attribute "CDS_PART_NAME" "RES_0402-10.0,1%,1/16W,CHIP,G2A"
					( Origin gPackager )
				)
				( objectStatus "R1C21" )
			)
			( gate "@baseboard_fab2_lib.baseboard_fab2(sch_1):page206_i78"
				( attribute "CDS_LIB" "mstr_discrete"
					( Origin gPackager )
				)
				( attribute "CDS_LOCATION" "C1D1"
					( Origin gPackager )
				)
				( attribute "CDS_SEC" "1"
					( Origin gPackager )
				)
				( attribute "LOCATION" "C1D1"
					( Origin gFrontEnd )
				)
				( attribute "MATERIAL" "X7R"
					( Origin gFrontEnd )
				)
				( attribute "NO_XNET_CONNECTION" "1"
					( Origin gFrontEnd )
				)
				( attribute "PACK_TYPE" "0402LF"
					( Origin gFrontEnd )
				)
				( attribute "PART_NUMBER" "A36096-050"
					( Origin gFrontEnd )
				)
				( attribute "PHYS_PAGE" "206"
					( Origin gFrontEnd )
				)
				( attribute "ROOM" "PVCCIN_CPU1_VR"
					( Origin gFrontEnd )
				)
				( attribute "ROT" "0"
					( Origin gFrontEnd )
				)
				( attribute "SEC" "1"
					( Origin gFrontEnd )
				)
				( attribute "SEC_TYPE" "0402LF"
					( Origin gFrontEnd )
				)
				( attribute "TOLERANCE" "10%"
					( Origin gFrontEnd )
				)
				( attribute "VALUE" "220PF"
					( Origin gFrontEnd )
				)
				( attribute "VER" "1"
					( Origin gFrontEnd )
				)
				( attribute "VOLTAGE" "50V"
					( Units "uVoltage" "V" 1.000000)
					( Origin gFrontEnd )
				)
				( attribute "XY" "(-6550,2375)"
					( Origin gFrontEnd )
				)
				( attribute "CHIPS_PART_NAME" "CAP"
					( Origin gPackager )
				)
				( attribute "CDS_PART_NAME" "CAP_0402LF-220PF,50V,10%,X7R,AA"
					( Origin gPackager )
				)
				( objectStatus "C1D1" )
			)
			( gate "@baseboard_fab2_lib.baseboard_fab2(sch_1):page206_i79"
				( attribute "CDS_LIB" "mstr_discrete"
					( Origin gPackager )
				)
				( attribute "CDS_LOCATION" "R1D4"
					( Origin gPackager )
				)
				( attribute "CDS_SEC" "1"
					( Origin gPackager )
				)
				( attribute "LOCATION" "R1D4"
					( Origin gFrontEnd )
				)
				( attribute "MATERIAL" "CHIP"
					( Origin gFrontEnd )
				)
				( attribute "NO_XNET_CONNECTION" "1"
					( Origin gFrontEnd )
				)
				( attribute "PACK_TYPE" "0402"
					( Origin gFrontEnd )
				)
				( attribute "PART_NUMBER" "G21796-066"
					( Origin gFrontEnd )
				)
				( attribute "PHYS_PAGE" "206"
					( Origin gFrontEnd )
				)
				( attribute "ROOM" "PVCCIN_CPU1_VR"
					( Origin gFrontEnd )
				)
				( attribute "ROT" "0"
					( Origin gFrontEnd )
				)
				( attribute "SEC" "1"
					( Origin gFrontEnd )
				)
				( attribute "SEC_TYPE" "0402"
					( Origin gFrontEnd )
				)
				( attribute "TOLERANCE" "1%"
					( Origin gFrontEnd )
				)
				( attribute "VALUE" "10.0"
					( Origin gFrontEnd )
				)
				( attribute "VER" "1"
					( Origin gFrontEnd )
				)
				( attribute "WATTAGE" "1/16W"
					( Origin gFrontEnd )
				)
				( attribute "XY" "(-6775,2575)"
					( Origin gFrontEnd )
				)
				( attribute "CHIPS_PART_NAME" "RES"
					( Origin gPackager )
				)
				( attribute "CDS_PART_NAME" "RES_0402-10.0,1%,1/16W,CHIP,G2A"
					( Origin gPackager )
				)
				( objectStatus "R1D4" )
			)
			( gate "@baseboard_fab2_lib.baseboard_fab2(sch_1):page206_i111"
				( attribute "CDS_LIB" "mstr_discrete"
					( Origin gPackager )
				)
				( attribute "CDS_LOCATION" "R9N7"
					( Origin gPackager )
				)
				( attribute "CDS_SEC" "1"
					( Origin gPackager )
				)
				( attribute "LOCATION" "R9N7"
					( Origin gFrontEnd )
				)
				( attribute "MATERIAL" "CHIP"
					( Origin gFrontEnd )
				)
				( attribute "PACK_TYPE" "0402"
					( Origin gFrontEnd )
				)
				( attribute "PART_NUMBER" "G21796-043"
					( Origin gFrontEnd )
				)
				( attribute "PHYS_PAGE" "206"
					( Origin gFrontEnd )
				)
				( attribute "ROOM" "PVCCIN_CPU1_VR"
					( Origin gFrontEnd )
				)
				( attribute "ROT" "0"
					( Origin gFrontEnd )
				)
				( attribute "SEC" "1"
					( Origin gFrontEnd )
				)
				( attribute "SEC_TYPE" "0402"
					( Origin gFrontEnd )
				)
				( attribute "TOLERANCE" "1%"
					( Origin gFrontEnd )
				)
				( attribute "VALUE" "3.16K"
					( Origin gFrontEnd )
				)
				( attribute "VER" "2"
					( Origin gFrontEnd )
				)
				( attribute "WATTAGE" "1/16W"
					( Origin gFrontEnd )
				)
				( attribute "XY" "(-4500,925)"
					( Origin gFrontEnd )
				)
				( attribute "CHIPS_PART_NAME" "RES"
					( Origin gPackager )
				)
				( attribute "CDS_PART_NAME" "RES_0402-3.16K,1%,1/16W,CHIP,GA"
					( Origin gPackager )
				)
				( objectStatus "R9N7" )
			)
			( gate "@baseboard_fab2_lib.baseboard_fab2(sch_1):page206_i112"
				( attribute "CDS_LIB" "mstr_discrete"
					( Origin gPackager )
				)
				( attribute "CDS_LOCATION" "R9N8"
					( Origin gPackager )
				)
				( attribute "CDS_SEC" "1"
					( Origin gPackager )
				)
				( attribute "LOCATION" "R9N8"
					( Origin gFrontEnd )
				)
				( attribute "MATERIAL" "CHIP"
					( Origin gFrontEnd )
				)
				( attribute "PACK_TYPE" "0402"
					( Origin gFrontEnd )
				)
				( attribute "PART_NUMBER" "G21796-082"
					( Origin gFrontEnd )
				)
				( attribute "PHYS_PAGE" "206"
					( Origin gFrontEnd )
				)
				( attribute "ROOM" "PVCCIN_CPU1_VR"
					( Origin gFrontEnd )
				)
				( attribute "ROT" "0"
					( Origin gFrontEnd )
				)
				( attribute "SEC" "1"
					( Origin gFrontEnd )
				)
				( attribute "SEC_TYPE" "0402"
					( Origin gFrontEnd )
				)
				( attribute "TOLERANCE" "1%"
					( Origin gFrontEnd )
				)
				( attribute "VALUE" "4.02K"
					( Origin gFrontEnd )
				)
				( attribute "VER" "2"
					( Origin gFrontEnd )
				)
				( attribute "WATTAGE" "1/16W"
					( Origin gFrontEnd )
				)
				( attribute "XY" "(-4825,925)"
					( Origin gFrontEnd )
				)
				( attribute "CHIPS_PART_NAME" "RES"
					( Origin gPackager )
				)
				( attribute "CDS_PART_NAME" "RES_0402-4.02K,1%,1/16W,CHIP,GA"
					( Origin gPackager )
				)
				( objectStatus "R9N8" )
			)
			( gate "@baseboard_fab2_lib.baseboard_fab2(sch_1):page206_i113"
				( attribute "CDS_LIB" "mstr_discrete"
					( Origin gPackager )
				)
				( attribute "CDS_LOCATION" "R1C30"
					( Origin gPackager )
				)
				( attribute "CDS_SEC" "1"
					( Origin gPackager )
				)
				( attribute "LOCATION" "R1C30"
					( Origin gFrontEnd )
				)
				( attribute "MATERIAL" "CHIP"
					( Origin gFrontEnd )
				)
				( attribute "PACK_TYPE" "0402"
					( Origin gFrontEnd )
				)
				( attribute "PART_NUMBER" "G21796-250"
					( Origin gFrontEnd )
				)
				( attribute "PHYS_PAGE" "206"
					( Origin gFrontEnd )
				)
				( attribute "ROOM" "PVCCIN_CPU1_VR"
					( Origin gFrontEnd )
				)
				( attribute "ROT" "0"
					( Origin gFrontEnd )
				)
				( attribute "SEC" "1"
					( Origin gFrontEnd )
				)
				( attribute "SEC_TYPE" "0402"
					( Origin gFrontEnd )
				)
				( attribute "TOLERANCE" "1.0%"
					( Origin gFrontEnd )
				)
				( attribute "VALUE" "22.1"
					( Origin gFrontEnd )
				)
				( attribute "VER" "1"
					( Origin gFrontEnd )
				)
				( attribute "WATTAGE" "1/16W"
					( Origin gFrontEnd )
				)
				( attribute "XY" "(-1200,3375)"
					( Origin gFrontEnd )
				)
				( attribute "CHIPS_PART_NAME" "RES"
					( Origin gPackager )
				)
				( attribute "CDS_PART_NAME" "RES_0402-22.1,1.0%,1/16W,CHIP,A"
					( Origin gPackager )
				)
				( objectStatus "R1C30" )
			)
			( gate "@baseboard_fab2_lib.baseboard_fab2(sch_1):page206_i114"
				( attribute "CDS_LIB" "mstr_discrete"
					( Origin gPackager )
				)
				( attribute "CDS_LOCATION" "C1C23"
					( Origin gPackager )
				)
				( attribute "CDS_SEC" "1"
					( Origin gPackager )
				)
				( attribute "LOCATION" "C1C23"
					( Origin gFrontEnd )
				)
				( attribute "MATERIAL" "X7R"
					( Origin gFrontEnd )
				)
				( attribute "PACK_TYPE" "0402LF"
					( Origin gFrontEnd )
				)
				( attribute "PART_NUMBER" "A36096-046"
					( Origin gFrontEnd )
				)
				( attribute "PHYS_PAGE" "206"
					( Origin gFrontEnd )
				)
				( attribute "ROOM" "PVCCIN_CPU1_VR"
					( Origin gFrontEnd )
				)
				( attribute "ROT" "0"
					( Origin gFrontEnd )
				)
				( attribute "SEC" "1"
					( Origin gFrontEnd )
				)
				( attribute "SEC_TYPE" "0402LF"
					( Origin gFrontEnd )
				)
				( attribute "TOLERANCE" "10%"
					( Origin gFrontEnd )
				)
				( attribute "VALUE" "1000PF"
					( Origin gFrontEnd )
				)
				( attribute "VER" "1"
					( Origin gFrontEnd )
				)
				( attribute "VOLTAGE" "50V"
					( Units "uVoltage" "V" 1.000000)
					( Origin gFrontEnd )
				)
				( attribute "XY" "(-1450,2150)"
					( Origin gFrontEnd )
				)
				( attribute "CHIPS_PART_NAME" "CAP"
					( Origin gPackager )
				)
				( attribute "CDS_PART_NAME" "CAP_0402LF-1000PF,50V,10%,X7R,A"
					( Origin gPackager )
				)
				( objectStatus "C1C23" )
			)
			( gate "@baseboard_fab2_lib.baseboard_fab2(sch_1):page206_i116"
				( attribute "CDS_LIB" "mstr_discrete"
					( Origin gPackager )
				)
				( attribute "CDS_LOCATION" "R1D1"
					( Origin gPackager )
				)
				( attribute "CDS_SEC" "1"
					( Origin gPackager )
				)
				( attribute "LOCATION" "R1D1"
					( Origin gFrontEnd )
				)
				( attribute "MATERIAL" "CHIP"
					( Origin gFrontEnd )
				)
				( attribute "PACK_TYPE" "0402"
					( Origin gFrontEnd )
				)
				( attribute "PART_NUMBER" "G21796-074"
					( Origin gFrontEnd )
				)
				( attribute "PHYS_PAGE" "206"
					( Origin gFrontEnd )
				)
				( attribute "ROT" "0"
					( Origin gFrontEnd )
				)
				( attribute "SEC" "1"
					( Origin gFrontEnd )
				)
				( attribute "SEC_TYPE" "0402"
					( Origin gFrontEnd )
				)
				( attribute "TOLERANCE" "1%"
					( Origin gFrontEnd )
				)
				( attribute "VALUE" "33.2"
					( Origin gFrontEnd )
				)
				( attribute "VER" "1"
					( Origin gFrontEnd )
				)
				( attribute "WATTAGE" "1/16W"
					( Origin gFrontEnd )
				)
				( attribute "XY" "(-2175,2725)"
					( Origin gFrontEnd )
				)
				( attribute "CHIPS_PART_NAME" "RES"
					( Origin gPackager )
				)
				( attribute "CDS_PART_NAME" "RES_0402-33.2,1%,1/16W,CHIP,G2A"
					( Origin gPackager )
				)
				( objectStatus "R1D1" )
			)
			( gate "@baseboard_fab2_lib.baseboard_fab2(sch_1):page206_i117"
				( attribute "CDS_LIB" "mstr_discrete"
					( Origin gPackager )
				)
				( attribute "CDS_LOCATION" "R9P3"
					( Origin gPackager )
				)
				( attribute "CDS_SEC" "1"
					( Origin gPackager )
				)
				( attribute "LOCATION" "R9P3"
					( Origin gFrontEnd )
				)
				( attribute "MATERIAL" "CHIP"
					( Origin gFrontEnd )
				)
				( attribute "PACK_TYPE" "0402"
					( Origin gFrontEnd )
				)
				( attribute "PART_NUMBER" "G21796-074"
					( Origin gFrontEnd )
				)
				( attribute "PHYS_PAGE" "206"
					( Origin gFrontEnd )
				)
				( attribute "ROT" "0"
					( Origin gFrontEnd )
				)
				( attribute "SEC" "1"
					( Origin gFrontEnd )
				)
				( attribute "SEC_TYPE" "0402"
					( Origin gFrontEnd )
				)
				( attribute "TOLERANCE" "1%"
					( Origin gFrontEnd )
				)
				( attribute "VALUE" "33.2"
					( Origin gFrontEnd )
				)
				( attribute "VER" "1"
					( Origin gFrontEnd )
				)
				( attribute "WATTAGE" "1/16W"
					( Origin gFrontEnd )
				)
				( attribute "XY" "(-2375,3025)"
					( Origin gFrontEnd )
				)
				( attribute "CHIPS_PART_NAME" "RES"
					( Origin gPackager )
				)
				( attribute "CDS_PART_NAME" "RES_0402-33.2,1%,1/16W,CHIP,G2A"
					( Origin gPackager )
				)
				( objectStatus "R9P3" )
			)
			( gate "@baseboard_fab2_lib.baseboard_fab2(sch_1):page206_i119"
				( attribute "CDS_LIB" "mstr_discrete"
					( Origin gPackager )
				)
				( attribute "CDS_LOCATION" "R9N16"
					( Origin gPackager )
				)
				( attribute "CDS_SEC" "1"
					( Origin gPackager )
				)
				( attribute "LOCATION" "R9N16"
					( Origin gFrontEnd )
				)
				( attribute "MATERIAL" "CHIP"
					( Origin gFrontEnd )
				)
				( attribute "PACK_TYPE" "0402"
					( Origin gFrontEnd )
				)
				( attribute "PART_NUMBER" "G21497-005"
					( Origin gFrontEnd )
				)
				( attribute "PHYS_PAGE" "206"
					( Origin gFrontEnd )
				)
				( attribute "ROOM" "PVCCIN_CPU0_VR"
					( Origin gFrontEnd )
				)
				( attribute "ROT" "0"
					( Origin gFrontEnd )
				)
				( attribute "SEC" "1"
					( Origin gFrontEnd )
				)
				( attribute "SEC_TYPE" "0402"
					( Origin gFrontEnd )
				)
				( attribute "TOLERANCE" "5%"
					( Origin gFrontEnd )
				)
				( attribute "VALUE" "0.0"
					( Origin gFrontEnd )
				)
				( attribute "VER" "1"
					( Origin gFrontEnd )
				)
				( attribute "WATTAGE" "1/16W"
					( Origin gFrontEnd )
				)
				( attribute "XY" "(-5200,2275)"
					( Origin gFrontEnd )
				)
				( attribute "CHIPS_PART_NAME" "RES"
					( Origin gPackager )
				)
				( attribute "CDS_PART_NAME" "RES_0402-0.0,5%,1/16W,CHIP,G21A"
					( Origin gPackager )
				)
				( objectStatus "R9N16" )
			)
			( gate "@baseboard_fab2_lib.baseboard_fab2(sch_1):page206_i120"
				( attribute "BOM_COST" "SM_CONTROLLER"
					( Origin gFrontEnd )
				)
				( attribute "CDS_LIB" "mstr_discrete"
					( Origin gPackager )
				)
				( attribute "CDS_LOCATION" "R9N14"
					( Origin gPackager )
				)
				( attribute "CDS_SEC" "1"
					( Origin gPackager )
				)
				( attribute "LOCATION" "R9N14"
					( Origin gFrontEnd )
				)
				( attribute "MATERIAL" "CHIP"
					( Origin gFrontEnd )
				)
				( attribute "PACK_TYPE" "0402"
					( Origin gFrontEnd )
				)
				( attribute "PART_NUMBER" "G21796-026"
					( Origin gFrontEnd )
				)
				( attribute "PHYS_PAGE" "206"
					( Origin gFrontEnd )
				)
				( attribute "ROOM" "BMC"
					( Origin gFrontEnd )
				)
				( attribute "ROT" "0"
					( Origin gFrontEnd )
				)
				( attribute "SEC" "1"
					( Origin gFrontEnd )
				)
				( attribute "SEC_TYPE" "0402"
					( Origin gFrontEnd )
				)
				( attribute "TOLERANCE" "1%"
					( Origin gFrontEnd )
				)
				( attribute "VALUE" "1.00K"
					( Origin gFrontEnd )
				)
				( attribute "VER" "2"
					( Origin gFrontEnd )
				)
				( attribute "WATTAGE" "1/16W"
					( Origin gFrontEnd )
				)
				( attribute "XY" "(-4650,4400)"
					( Origin gFrontEnd )
				)
				( attribute "CHIPS_PART_NAME" "RES"
					( Origin gPackager )
				)
				( attribute "CDS_PART_NAME" "RES_0402-1.00K,1%,1/16W,CHIP,GA"
					( Origin gPackager )
				)
				( objectStatus "R9N14" )
			)
			( gate "@baseboard_fab2_lib.baseboard_fab2(sch_1):page206_i130"
				( attribute "CDS_LIB" "mstr_controller"
					( Origin gPackager )
				)
				( attribute "CDS_LMAN_SYM_OUTLINE" "-400,900,400,-900"
					( Origin gPackager )
				)
				( attribute "CDS_LOCATION" "EU1C2"
					( Origin gPackager )
				)
				( attribute "CDS_SEC" "1"
					( Origin gPackager )
				)
				( attribute "LOCATION" "EU1C2"
					( Origin gFrontEnd )
				)
				( attribute "MATERIAL" "IC"
					( Origin gFrontEnd )
				)
				( attribute "PACK_TYPE" "QFN"
					( Origin gFrontEnd )
				)
				( attribute "PART_NUMBER" "H79206-001"
					( Origin gFrontEnd )
				)
				( attribute "PHYS_PAGE" "206"
					( Origin gFrontEnd )
				)
				( attribute "ROT" "0"
					( Origin gFrontEnd )
				)
				( attribute "SEC" "1"
					( Origin gFrontEnd )
				)
				( attribute "SEC_TYPE" "QFN"
					( Origin gFrontEnd )
				)
				( attribute "VER" "1"
					( Origin gFrontEnd )
				)
				( attribute "XY" "(-3825,2625)"
					( Origin gFrontEnd )
				)
				( attribute "CHIPS_PART_NAME" "PXE1610B"
					( Origin gPackager )
				)
				( attribute "CDS_PART_NAME" "PXE1610B_QFN-IC,H79206-001"
					( Origin gPackager )
				)
				( objectStatus "EU1C2" )
			)
			( gate "@baseboard_fab2_lib.baseboard_fab2(sch_1):page207_i8"
				( attribute "BOM_COST" "PROC_VRD_VCCIN_CPU0"
					( Origin gFrontEnd )
				)
				( attribute "CDS_LIB" "dev_discrete"
					( Origin gPackager )
				)
				( attribute "CDS_LOCATION" "C9R8"
					( Origin gPackager )
				)
				( attribute "CDS_SEC" "1"
					( Origin gPackager )
				)
				( attribute "LOCATION" "C9R8"
					( Origin gFrontEnd )
				)
				( attribute "MATERIAL" "X6S"
					( Origin gFrontEnd )
				)
				( attribute "PACK_TYPE" "0603V"
					( Origin gFrontEnd )
				)
				( attribute "PART_NUMBER" "E15431-004"
					( Origin gFrontEnd )
				)
				( attribute "PHYS_PAGE" "207"
					( Origin gFrontEnd )
				)
				( attribute "ROOM" "PVCCIN_CPU1_PWR_VR"
					( Origin gFrontEnd )
				)
				( attribute "ROT" "0"
					( Origin gFrontEnd )
				)
				( attribute "SEC" "1"
					( Origin gFrontEnd )
				)
				( attribute "SEC_TYPE" "0603V"
					( Origin gFrontEnd )
				)
				( attribute "TOLERANCE" "20%"
					( Origin gFrontEnd )
				)
				( attribute "VALUE" "22.0UF"
					( Origin gFrontEnd )
				)
				( attribute "VER" "1"
					( Origin gFrontEnd )
				)
				( attribute "VOLTAGE" "4V"
					( Units "uVoltage" "V" 1.000000)
					( Origin gFrontEnd )
				)
				( attribute "XY" "(-1100,3350)"
					( Origin gFrontEnd )
				)
				( attribute "CHIPS_PART_NAME" "CAP_A"
					( Origin gPackager )
				)
				( attribute "CDS_PART_NAME" "CAP_A_0603V-22.0UF,4V,20%,X6S,A"
					( Origin gPackager )
				)
				( attribute "GROUP" "PWR_MLCC_CAP"
					( Origin gFrontEnd )
				)
				( objectStatus "C9R8" )
			)
			( gate "@baseboard_fab2_lib.baseboard_fab2(sch_1):page207_i18"
				( attribute "BOM_COST" "PROC_VRD_VCCIN_CPU0"
					( Origin gFrontEnd )
				)
				( attribute "CDS_LIB" "dev_discrete"
					( Origin gPackager )
				)
				( attribute "CDS_LOCATION" "C1E3"
					( Origin gPackager )
				)
				( attribute "CDS_SEC" "1"
					( Origin gPackager )
				)
				( attribute "LOCATION" "C1E3"
					( Origin gFrontEnd )
				)
				( attribute "MATERIAL" "X6S"
					( Origin gFrontEnd )
				)
				( attribute "PACK_TYPE" "0603V"
					( Origin gFrontEnd )
				)
				( attribute "PART_NUMBER" "E15431-004"
					( Origin gFrontEnd )
				)
				( attribute "PHYS_PAGE" "207"
					( Origin gFrontEnd )
				)
				( attribute "ROOM" "PVCCIN_CPU1_PWR_VR"
					( Origin gFrontEnd )
				)
				( attribute "ROT" "0"
					( Origin gFrontEnd )
				)
				( attribute "SEC" "1"
					( Origin gFrontEnd )
				)
				( attribute "SEC_TYPE" "0603V"
					( Origin gFrontEnd )
				)
				( attribute "TOLERANCE" "20%"
					( Origin gFrontEnd )
				)
				( attribute "VALUE" "22.0UF"
					( Origin gFrontEnd )
				)
				( attribute "VER" "1"
					( Origin gFrontEnd )
				)
				( attribute "VOLTAGE" "4V"
					( Units "uVoltage" "V" 1.000000)
					( Origin gFrontEnd )
				)
				( attribute "XY" "(-1100,750)"
					( Origin gFrontEnd )
				)
				( attribute "CHIPS_PART_NAME" "CAP_A"
					( Origin gPackager )
				)
				( attribute "CDS_PART_NAME" "CAP_A_0603V-22.0UF,4V,20%,X6S,A"
					( Origin gPackager )
				)
				( attribute "GROUP" "PWR_MLCC_CAP"
					( Origin gFrontEnd )
				)
				( objectStatus "C1E3" )
			)
			( gate "@baseboard_fab2_lib.baseboard_fab2(sch_1):page207_i20"
				( attribute "CDS_LIB" "mstr_discrete"
					( Origin gPackager )
				)
				( attribute "CDS_LOCATION" "EU1E2"
					( Origin gPackager )
				)
				( attribute "CDS_SEC" "1"
					( Origin gPackager )
				)
				( attribute "LOCATION" "EU1E2"
					( Origin gFrontEnd )
				)
				( attribute "MATERIAL" "IC"
					( Origin gFrontEnd )
				)
				( attribute "PACK_TYPE" "SM"
					( Origin gFrontEnd )
				)
				( attribute "PART_NUMBER" "H73688-001"
					( Origin gFrontEnd )
				)
				( attribute "PHYS_PAGE" "207"
					( Origin gFrontEnd )
				)
				( attribute "ROOM" "PVCCIN_CPU1_PWR_VR"
					( Origin gFrontEnd )
				)
				( attribute "ROT" "0"
					( Origin gFrontEnd )
				)
				( attribute "SEC" "1"
					( Origin gFrontEnd )
				)
				( attribute "SEC_TYPE" "SM"
					( Origin gFrontEnd )
				)
				( attribute "VALUE" "IR35411"
					( Origin gFrontEnd )
				)
				( attribute "VER" "1"
					( Origin gFrontEnd )
				)
				( attribute "XY" "(-3125,3850)"
					( Origin gFrontEnd )
				)
				( attribute "CHIPS_PART_NAME" "IR354XX"
					( Origin gPackager )
				)
				( attribute "CDS_PART_NAME" "IR354XX_SM-IR35411,IC,H73688-0A"
					( Origin gPackager )
				)
				( objectStatus "EU1E2" )
			)
			( gate "@baseboard_fab2_lib.baseboard_fab2(sch_1):page208_i115"
				( attribute "BOM_COST" "PROC_SIDEBAND"
					( Origin gFrontEnd )
				)
				( attribute "CDS_LIB" "mstr_discrete"
					( Origin gPackager )
				)
				( attribute "CDS_LOCATION" "R9P8"
					( Origin gPackager )
				)
				( attribute "CDS_SEC" "1"
					( Origin gPackager )
				)
				( attribute "LOCATION" "R9P8"
					( Origin gFrontEnd )
				)
				( attribute "MATERIAL" "CHIP"
					( Origin gFrontEnd )
				)
				( attribute "PACK_TYPE" "0402"
					( Origin gFrontEnd )
				)
				( attribute "PART_NUMBER" "G21497-005"
					( Origin gFrontEnd )
				)
				( attribute "PHYS_PAGE" "208"
					( Origin gFrontEnd )
				)
				( attribute "ROOM" "CPU0"
					( Origin gFrontEnd )
				)
				( attribute "ROT" "0"
					( Origin gFrontEnd )
				)
				( attribute "SEC" "1"
					( Origin gFrontEnd )
				)
				( attribute "SEC_TYPE" "0402"
					( Origin gFrontEnd )
				)
				( attribute "TOLERANCE" "5%"
					( Origin gFrontEnd )
				)
				( attribute "VALUE" "0.0"
					( Origin gFrontEnd )
				)
				( attribute "VER" "1"
					( Origin gFrontEnd )
				)
				( attribute "WATTAGE" "1/16W"
					( Origin gFrontEnd )
				)
				( attribute "XY" "(-5450,2025)"
					( Origin gFrontEnd )
				)
				( attribute "CHIPS_PART_NAME" "RES"
					( Origin gPackager )
				)
				( attribute "CDS_PART_NAME" "RES_0402-0.0,5%,1/16W,CHIP,G21A"
					( Origin gPackager )
				)
				( objectStatus "R9P8" )
			)
			( gate "@baseboard_fab2_lib.baseboard_fab2(sch_1):page207_i28"
				( attribute "CDS_LIB" "mstr_discrete"
					( Origin gPackager )
				)
				( attribute "CDS_LOCATION" "C1E7"
					( Origin gPackager )
				)
				( attribute "CDS_SEC" "1"
					( Origin gPackager )
				)
				( attribute "LOCATION" "C1E7"
					( Origin gFrontEnd )
				)
				( attribute "MATERIAL" "X7R"
					( Origin gFrontEnd )
				)
				( attribute "PACK_TYPE" "0402"
					( Origin gFrontEnd )
				)
				( attribute "PART_NUMBER" "A36096-155"
					( Origin gFrontEnd )
				)
				( attribute "PHYS_PAGE" "207"
					( Origin gFrontEnd )
				)
				( attribute "ROOM" "PVCCIN_CPU1_PWR_VR"
					( Origin gFrontEnd )
				)
				( attribute "ROT" "0"
					( Origin gFrontEnd )
				)
				( attribute "SEC" "1"
					( Origin gFrontEnd )
				)
				( attribute "SEC_TYPE" "0402"
					( Origin gFrontEnd )
				)
				( attribute "TOLERANCE" "10%"
					( Origin gFrontEnd )
				)
				( attribute "VALUE" "0.22UF"
					( Origin gFrontEnd )
				)
				( attribute "VER" "1"
					( Origin gFrontEnd )
				)
				( attribute "VOLTAGE" "16V"
					( Units "uVoltage" "V" 1.000000)
					( Origin gFrontEnd )
				)
				( attribute "XY" "(-4725,4150)"
					( Origin gFrontEnd )
				)
				( attribute "CHIPS_PART_NAME" "CAP"
					( Origin gPackager )
				)
				( attribute "CDS_PART_NAME" "CAP_0402-0.22UF,16V,10%,X7R,A3A"
					( Origin gPackager )
				)
				( objectStatus "C1E7" )
			)
			( gate "@baseboard_fab2_lib.baseboard_fab2(sch_1):page224_i155"
				( attribute "CDS_LIB" "w_hdl"
					( Origin gPackager )
				)
				( attribute "CDS_LMAN_SYM_OUTLINE" "-50,25,50,-25"
					( Origin gPackager )
				)
				( attribute "LOCATION" "C1G4"
					( Origin gFrontEnd )
				)
				( attribute "PACK_TYPE" "SMD-BCG6"
					( Origin gFrontEnd )
				)
				( attribute "PART_NUMBER" "78.10523.8FL"
					( Origin gFrontEnd )
				)
				( attribute "PHYS_PAGE" "224"
					( Origin gFrontEnd )
				)
				( attribute "ROT" "0"
					( Origin gFrontEnd )
				)
				( attribute "SEC" "1"
					( Origin gFrontEnd )
				)
				( attribute "SEC_TYPE" "SMD-BCG6"
					( Origin gFrontEnd )
				)
				( attribute "VALUE" "SC1U10V2KX-4-GP"
					( Origin gFrontEnd )
				)
				( attribute "VER" "1"
					( Origin gFrontEnd )
				)
				( attribute "XY" "(-375,2500)"
					( Origin gFrontEnd )
				)
				( attribute "CHIPS_PART_NAME" "SC1U10V2KX-4-GP"
					( Origin gPackager )
				)
				( attribute "CDS_PART_NAME" "SC1U10V2KX-4-GP_SMD-BCG6-SC1U1A"
					( Origin gPackager )
				)
				( attribute "CDS_LOCATION" "C1G4"
					( Origin gPackager )
				)
				( attribute "CDS_SEC" "1"
					( Origin gPackager )
				)
				( attribute "ATTRIBUTE" "1UF"
					( Origin gFrontEnd )
				)
				( attribute "PACK_SIZE" "0402"
					( Origin gFrontEnd )
				)
				( attribute "RATED" "10V"
					( Origin gFrontEnd )
				)
				( attribute "TOLERANCE" "10%"
					( Origin gFrontEnd )
				)
				( objectStatus "C1G4" )
			)
			( gate "@baseboard_fab2_lib.baseboard_fab2(sch_1):page207_i30"
				( attribute "CDS_LIB" "mstr_discrete"
					( Origin gPackager )
				)
				( attribute "CDS_LOCATION" "C1E11"
					( Origin gPackager )
				)
				( attribute "CDS_SEC" "1"
					( Origin gPackager )
				)
				( attribute "LOCATION" "C1E11"
					( Origin gFrontEnd )
				)
				( attribute "MATERIAL" "X7R"
					( Origin gFrontEnd )
				)
				( attribute "NO_XNET_CONNECTION" "1"
					( Origin gFrontEnd )
				)
				( attribute "PACK_TYPE" "0402"
					( Origin gFrontEnd )
				)
				( attribute "PART_NUMBER" "A36096-104"
					( Origin gFrontEnd )
				)
				( attribute "PHYS_PAGE" "207"
					( Origin gFrontEnd )
				)
				( attribute "ROOM" "PVCCIN_CPU1_PWR_VR"
					( Origin gFrontEnd )
				)
				( attribute "ROT" "2"
					( Origin gFrontEnd )
				)
				( attribute "SEC" "1"
					( Origin gFrontEnd )
				)
				( attribute "SEC_TYPE" "0402"
					( Origin gFrontEnd )
				)
				( attribute "SPOF" "TRUE"
					( Origin gFrontEnd )
				)
				( attribute "TOLERANCE" "10%"
					( Origin gFrontEnd )
				)
				( attribute "VALUE" "0.220UF"
					( Origin gFrontEnd )
				)
				( attribute "VER" "1"
					( Origin gFrontEnd )
				)
				( attribute "VOLTAGE" "16V"
					( Units "uVoltage" "V" 1.000000)
					( Origin gFrontEnd )
				)
				( attribute "XY" "(-5675,3500)"
					( Origin gFrontEnd )
				)
				( attribute "CHIPS_PART_NAME" "CAP"
					( Origin gPackager )
				)
				( attribute "CDS_PART_NAME" "CAP_0402-0.220UF,16V,10%,X7R,AA"
					( Origin gPackager )
				)
				( objectStatus "C1E11" )
			)
			( gate "@baseboard_fab2_lib.baseboard_fab2(sch_1):page207_i32"
				( attribute "CDS_LIB" "mstr_discrete"
					( Origin gPackager )
				)
				( attribute "CDS_LOCATION" "C1E8"
					( Origin gPackager )
				)
				( attribute "CDS_SEC" "1"
					( Origin gPackager )
				)
				( attribute "LOCATION" "C1E8"
					( Origin gFrontEnd )
				)
				( attribute "MATERIAL" "X6S"
					( Origin gFrontEnd )
				)
				( attribute "PACK_TYPE" "0402"
					( Origin gFrontEnd )
				)
				( attribute "PART_NUMBER" "D97712-011"
					( Origin gFrontEnd )
				)
				( attribute "PHYS_PAGE" "207"
					( Origin gFrontEnd )
				)
				( attribute "ROOM" "PVCCIN_CPU1_PWR_VR"
					( Origin gFrontEnd )
				)
				( attribute "ROT" "0"
					( Origin gFrontEnd )
				)
				( attribute "SEC" "1"
					( Origin gFrontEnd )
				)
				( attribute "SEC_TYPE" "0402"
					( Origin gFrontEnd )
				)
				( attribute "TOLERANCE" "10%"
					( Origin gFrontEnd )
				)
				( attribute "VALUE" "1.0UF"
					( Origin gFrontEnd )
				)
				( attribute "VER" "1"
					( Origin gFrontEnd )
				)
				( attribute "VOLTAGE" "16V"
					( Units "uVoltage" "V" 1.000000)
					( Origin gFrontEnd )
				)
				( attribute "XY" "(-5550,4100)"
					( Origin gFrontEnd )
				)
				( attribute "CHIPS_PART_NAME" "CAP"
					( Origin gPackager )
				)
				( attribute "CDS_PART_NAME" "CAP_0402-1.0UF,16V,10%,X6S,D97A"
					( Origin gPackager )
				)
				( objectStatus "C1E8" )
			)
			( gate "@baseboard_fab2_lib.baseboard_fab2(sch_1):page207_i33"
				( attribute "CDS_LIB" "dev_discrete"
					( Origin gPackager )
				)
				( attribute "CDS_LOCATION" "C1E14"
					( Origin gPackager )
				)
				( attribute "CDS_SEC" "1"
					( Origin gPackager )
				)
				( attribute "LOCATION" "C1E14"
					( Origin gFrontEnd )
				)
				( attribute "MATERIAL" "X7R"
					( Origin gFrontEnd )
				)
				( attribute "PACK_TYPE" "0402V"
					( Origin gFrontEnd )
				)
				( attribute "PART_NUMBER" "A36096-030"
					( Origin gFrontEnd )
				)
				( attribute "PHYS_PAGE" "207"
					( Origin gFrontEnd )
				)
				( attribute "ROOM" "PVCCIN_CPU1_PWR_VR"
					( Origin gFrontEnd )
				)
				( attribute "ROT" "0"
					( Origin gFrontEnd )
				)
				( attribute "SEC" "1"
					( Origin gFrontEnd )
				)
				( attribute "SEC_TYPE" "0402V"
					( Origin gFrontEnd )
				)
				( attribute "TOLERANCE" "10%"
					( Origin gFrontEnd )
				)
				( attribute "VALUE" "0.1UF"
					( Origin gFrontEnd )
				)
				( attribute "VER" "1"
					( Origin gFrontEnd )
				)
				( attribute "VOLTAGE" "16V"
					( Units "uVoltage" "V" 1.000000)
					( Origin gFrontEnd )
				)
				( attribute "XY" "(-5850,4125)"
					( Origin gFrontEnd )
				)
				( attribute "CHIPS_PART_NAME" "CAP_A"
					( Origin gPackager )
				)
				( attribute "CDS_PART_NAME" "CAP_A_0402V-0.1UF,16V,10%,X7R,A"
					( Origin gPackager )
				)
				( objectStatus "C1E14" )
			)
			( gate "@baseboard_fab2_lib.baseboard_fab2(sch_1):page207_i34"
				( attribute "CDS_LIB" "mstr_discrete"
					( Origin gPackager )
				)
				( attribute "CDS_LOCATION" "C1E13"
					( Origin gPackager )
				)
				( attribute "CDS_SEC" "1"
					( Origin gPackager )
				)
				( attribute "LOCATION" "C1E13"
					( Origin gFrontEnd )
				)
				( attribute "MATERIAL" "X6S"
					( Origin gFrontEnd )
				)
				( attribute "PACK_TYPE" "0402"
					( Origin gFrontEnd )
				)
				( attribute "PART_NUMBER" "D97712-011"
					( Origin gFrontEnd )
				)
				( attribute "PHYS_PAGE" "207"
					( Origin gFrontEnd )
				)
				( attribute "ROOM" "PVCCIN_CPU1_PWR_VR"
					( Origin gFrontEnd )
				)
				( attribute "ROT" "0"
					( Origin gFrontEnd )
				)
				( attribute "SEC" "1"
					( Origin gFrontEnd )
				)
				( attribute "SEC_TYPE" "0402"
					( Origin gFrontEnd )
				)
				( attribute "TOLERANCE" "10%"
					( Origin gFrontEnd )
				)
				( attribute "VALUE" "1.0UF"
					( Origin gFrontEnd )
				)
				( attribute "VER" "1"
					( Origin gFrontEnd )
				)
				( attribute "VOLTAGE" "16V"
					( Units "uVoltage" "V" 1.000000)
					( Origin gFrontEnd )
				)
				( attribute "XY" "(-6150,4125)"
					( Origin gFrontEnd )
				)
				( attribute "CHIPS_PART_NAME" "CAP"
					( Origin gPackager )
				)
				( attribute "CDS_PART_NAME" "CAP_0402-1.0UF,16V,10%,X6S,D97A"
					( Origin gPackager )
				)
				( objectStatus "C1E13" )
			)
			( gate "@baseboard_fab2_lib.baseboard_fab2(sch_1):page207_i36"
				( attribute "CDS_LIB" "mstr_discrete"
					( Origin gPackager )
				)
				( attribute "CDS_LOCATION" "C1E25"
					( Origin gPackager )
				)
				( attribute "CDS_SEC" "1"
					( Origin gPackager )
				)
				( attribute "LOCATION" "C1E25"
					( Origin gFrontEnd )
				)
				( attribute "MATERIAL" "X7R"
					( Origin gFrontEnd )
				)
				( attribute "PACK_TYPE" "0402"
					( Origin gFrontEnd )
				)
				( attribute "PART_NUMBER" "A36096-155"
					( Origin gFrontEnd )
				)
				( attribute "PHYS_PAGE" "207"
					( Origin gFrontEnd )
				)
				( attribute "ROOM" "PVCCIN_CPU1_PWR_VR"
					( Origin gFrontEnd )
				)
				( attribute "ROT" "0"
					( Origin gFrontEnd )
				)
				( attribute "SEC" "1"
					( Origin gFrontEnd )
				)
				( attribute "SEC_TYPE" "0402"
					( Origin gFrontEnd )
				)
				( attribute "TOLERANCE" "10%"
					( Origin gFrontEnd )
				)
				( attribute "VALUE" "0.22UF"
					( Origin gFrontEnd )
				)
				( attribute "VER" "1"
					( Origin gFrontEnd )
				)
				( attribute "VOLTAGE" "16V"
					( Units "uVoltage" "V" 1.000000)
					( Origin gFrontEnd )
				)
				( attribute "XY" "(-4600,1575)"
					( Origin gFrontEnd )
				)
				( attribute "CHIPS_PART_NAME" "CAP"
					( Origin gPackager )
				)
				( attribute "CDS_PART_NAME" "CAP_0402-0.22UF,16V,10%,X7R,A3A"
					( Origin gPackager )
				)
				( objectStatus "C1E25" )
			)
			( gate "@baseboard_fab2_lib.baseboard_fab2(sch_1):page224_i154"
				( attribute "CDS_LIB" "w_hdl"
					( Origin gPackager )
				)
				( attribute "CDS_LMAN_SYM_OUTLINE" "-50,25,50,-25"
					( Origin gPackager )
				)
				( attribute "LOCATION" "C1F21"
					( Origin gFrontEnd )
				)
				( attribute "PACK_TYPE" "SMD-BCG6"
					( Origin gFrontEnd )
				)
				( attribute "PART_NUMBER" "78.10523.8FL"
					( Origin gFrontEnd )
				)
				( attribute "PHYS_PAGE" "224"
					( Origin gFrontEnd )
				)
				( attribute "ROT" "0"
					( Origin gFrontEnd )
				)
				( attribute "SEC" "1"
					( Origin gFrontEnd )
				)
				( attribute "SEC_TYPE" "SMD-BCG6"
					( Origin gFrontEnd )
				)
				( attribute "VALUE" "SC1U10V2KX-4-GP"
					( Origin gFrontEnd )
				)
				( attribute "VER" "1"
					( Origin gFrontEnd )
				)
				( attribute "XY" "(-250,150)"
					( Origin gFrontEnd )
				)
				( attribute "CHIPS_PART_NAME" "SC1U10V2KX-4-GP"
					( Origin gPackager )
				)
				( attribute "CDS_PART_NAME" "SC1U10V2KX-4-GP_SMD-BCG6-SC1U1A"
					( Origin gPackager )
				)
				( attribute "CDS_LOCATION" "C1F21"
					( Origin gPackager )
				)
				( attribute "CDS_SEC" "1"
					( Origin gPackager )
				)
				( attribute "ATTRIBUTE" "1UF"
					( Origin gFrontEnd )
				)
				( attribute "PACK_SIZE" "0402"
					( Origin gFrontEnd )
				)
				( attribute "RATED" "10V"
					( Origin gFrontEnd )
				)
				( attribute "TOLERANCE" "10%"
					( Origin gFrontEnd )
				)
				( attribute "BOM_SS" "NOPOP"
					( Origin gFrontEnd )
				)
				( objectStatus "C1F21" )
			)
			( gate "@baseboard_fab2_lib.baseboard_fab2(sch_1):page207_i38"
				( attribute "CDS_LIB" "mstr_discrete"
					( Origin gPackager )
				)
				( attribute "CDS_LOCATION" "C1D36"
					( Origin gPackager )
				)
				( attribute "CDS_SEC" "1"
					( Origin gPackager )
				)
				( attribute "LOCATION" "C1D36"
					( Origin gFrontEnd )
				)
				( attribute "MATERIAL" "X7R"
					( Origin gFrontEnd )
				)
				( attribute "NO_XNET_CONNECTION" "1"
					( Origin gFrontEnd )
				)
				( attribute "PACK_TYPE" "0402"
					( Origin gFrontEnd )
				)
				( attribute "PART_NUMBER" "A36096-104"
					( Origin gFrontEnd )
				)
				( attribute "PHYS_PAGE" "207"
					( Origin gFrontEnd )
				)
				( attribute "ROOM" "PVCCIN_CPU1_PWR_VR"
					( Origin gFrontEnd )
				)
				( attribute "ROT" "2"
					( Origin gFrontEnd )
				)
				( attribute "SEC" "1"
					( Origin gFrontEnd )
				)
				( attribute "SEC_TYPE" "0402"
					( Origin gFrontEnd )
				)
				( attribute "SPOF" "TRUE"
					( Origin gFrontEnd )
				)
				( attribute "TOLERANCE" "10%"
					( Origin gFrontEnd )
				)
				( attribute "VALUE" "0.220UF"
					( Origin gFrontEnd )
				)
				( attribute "VER" "1"
					( Origin gFrontEnd )
				)
				( attribute "VOLTAGE" "16V"
					( Units "uVoltage" "V" 1.000000)
					( Origin gFrontEnd )
				)
				( attribute "XY" "(-5550,875)"
					( Origin gFrontEnd )
				)
				( attribute "CHIPS_PART_NAME" "CAP"
					( Origin gPackager )
				)
				( attribute "CDS_PART_NAME" "CAP_0402-0.220UF,16V,10%,X7R,AA"
					( Origin gPackager )
				)
				( objectStatus "C1D36" )
			)
			( gate "@baseboard_fab2_lib.baseboard_fab2(sch_1):page208_i114"
				( attribute "BOM_COST" "PROC_SIDEBAND"
					( Origin gFrontEnd )
				)
				( attribute "CDS_LIB" "mstr_discrete"
					( Origin gPackager )
				)
				( attribute "CDS_LOCATION" "R9P22"
					( Origin gPackager )
				)
				( attribute "CDS_SEC" "1"
					( Origin gPackager )
				)
				( attribute "LOCATION" "R9P22"
					( Origin gFrontEnd )
				)
				( attribute "MATERIAL" "CHIP"
					( Origin gFrontEnd )
				)
				( attribute "PACK_TYPE" "0402"
					( Origin gFrontEnd )
				)
				( attribute "PART_NUMBER" "G21497-005"
					( Origin gFrontEnd )
				)
				( attribute "PHYS_PAGE" "208"
					( Origin gFrontEnd )
				)
				( attribute "ROOM" "CPU0"
					( Origin gFrontEnd )
				)
				( attribute "ROT" "0"
					( Origin gFrontEnd )
				)
				( attribute "SEC" "1"
					( Origin gFrontEnd )
				)
				( attribute "SEC_TYPE" "0402"
					( Origin gFrontEnd )
				)
				( attribute "TOLERANCE" "5%"
					( Origin gFrontEnd )
				)
				( attribute "VALUE" "0.0"
					( Origin gFrontEnd )
				)
				( attribute "VER" "1"
					( Origin gFrontEnd )
				)
				( attribute "WATTAGE" "1/16W"
					( Origin gFrontEnd )
				)
				( attribute "XY" "(-5350,4700)"
					( Origin gFrontEnd )
				)
				( attribute "CHIPS_PART_NAME" "RES"
					( Origin gPackager )
				)
				( attribute "CDS_PART_NAME" "RES_0402-0.0,5%,1/16W,CHIP,G21A"
					( Origin gPackager )
				)
				( objectStatus "R9P22" )
			)
			( gate "@baseboard_fab2_lib.baseboard_fab2(sch_1):page207_i40"
				( attribute "CDS_LIB" "mstr_discrete"
					( Origin gPackager )
				)
				( attribute "CDS_LOCATION" "C1E24"
					( Origin gPackager )
				)
				( attribute "CDS_SEC" "1"
					( Origin gPackager )
				)
				( attribute "LOCATION" "C1E24"
					( Origin gFrontEnd )
				)
				( attribute "MATERIAL" "X6S"
					( Origin gFrontEnd )
				)
				( attribute "PACK_TYPE" "0402"
					( Origin gFrontEnd )
				)
				( attribute "PART_NUMBER" "D97712-011"
					( Origin gFrontEnd )
				)
				( attribute "PHYS_PAGE" "207"
					( Origin gFrontEnd )
				)
				( attribute "ROOM" "PVCCIN_CPU1_PWR_VR"
					( Origin gFrontEnd )
				)
				( attribute "ROT" "0"
					( Origin gFrontEnd )
				)
				( attribute "SEC" "1"
					( Origin gFrontEnd )
				)
				( attribute "SEC_TYPE" "0402"
					( Origin gFrontEnd )
				)
				( attribute "TOLERANCE" "10%"
					( Origin gFrontEnd )
				)
				( attribute "VALUE" "1.0UF"
					( Origin gFrontEnd )
				)
				( attribute "VER" "1"
					( Origin gFrontEnd )
				)
				( attribute "VOLTAGE" "16V"
					( Units "uVoltage" "V" 1.000000)
					( Origin gFrontEnd )
				)
				( attribute "XY" "(-5450,1525)"
					( Origin gFrontEnd )
				)
				( attribute "CHIPS_PART_NAME" "CAP"
					( Origin gPackager )
				)
				( attribute "CDS_PART_NAME" "CAP_0402-1.0UF,16V,10%,X6S,D97A"
					( Origin gPackager )
				)
				( objectStatus "C1E24" )
			)
			( gate "@baseboard_fab2_lib.baseboard_fab2(sch_1):page207_i41"
				( attribute "CDS_LIB" "dev_discrete"
					( Origin gPackager )
				)
				( attribute "CDS_LOCATION" "C1D34"
					( Origin gPackager )
				)
				( attribute "CDS_SEC" "1"
					( Origin gPackager )
				)
				( attribute "LOCATION" "C1D34"
					( Origin gFrontEnd )
				)
				( attribute "MATERIAL" "X7R"
					( Origin gFrontEnd )
				)
				( attribute "PACK_TYPE" "0402V"
					( Origin gFrontEnd )
				)
				( attribute "PART_NUMBER" "A36096-030"
					( Origin gFrontEnd )
				)
				( attribute "PHYS_PAGE" "207"
					( Origin gFrontEnd )
				)
				( attribute "ROOM" "PVCCIN_CPU1_PWR_VR"
					( Origin gFrontEnd )
				)
				( attribute "ROT" "0"
					( Origin gFrontEnd )
				)
				( attribute "SEC" "1"
					( Origin gFrontEnd )
				)
				( attribute "SEC_TYPE" "0402V"
					( Origin gFrontEnd )
				)
				( attribute "TOLERANCE" "10%"
					( Origin gFrontEnd )
				)
				( attribute "VALUE" "0.1UF"
					( Origin gFrontEnd )
				)
				( attribute "VER" "1"
					( Origin gFrontEnd )
				)
				( attribute "VOLTAGE" "16V"
					( Units "uVoltage" "V" 1.000000)
					( Origin gFrontEnd )
				)
				( attribute "XY" "(-5725,1525)"
					( Origin gFrontEnd )
				)
				( attribute "CHIPS_PART_NAME" "CAP_A"
					( Origin gPackager )
				)
				( attribute "CDS_PART_NAME" "CAP_A_0402V-0.1UF,16V,10%,X7R,A"
					( Origin gPackager )
				)
				( objectStatus "C1D34" )
			)
			( gate "@baseboard_fab2_lib.baseboard_fab2(sch_1):page207_i42"
				( attribute "CDS_LIB" "mstr_discrete"
					( Origin gPackager )
				)
				( attribute "CDS_LOCATION" "C1D35"
					( Origin gPackager )
				)
				( attribute "CDS_SEC" "1"
					( Origin gPackager )
				)
				( attribute "LOCATION" "C1D35"
					( Origin gFrontEnd )
				)
				( attribute "MATERIAL" "X6S"
					( Origin gFrontEnd )
				)
				( attribute "PACK_TYPE" "0402"
					( Origin gFrontEnd )
				)
				( attribute "PART_NUMBER" "D97712-011"
					( Origin gFrontEnd )
				)
				( attribute "PHYS_PAGE" "207"
					( Origin gFrontEnd )
				)
				( attribute "ROOM" "PVCCIN_CPU1_PWR_VR"
					( Origin gFrontEnd )
				)
				( attribute "ROT" "0"
					( Origin gFrontEnd )
				)
				( attribute "SEC" "1"
					( Origin gFrontEnd )
				)
				( attribute "SEC_TYPE" "0402"
					( Origin gFrontEnd )
				)
				( attribute "TOLERANCE" "10%"
					( Origin gFrontEnd )
				)
				( attribute "VALUE" "1.0UF"
					( Origin gFrontEnd )
				)
				( attribute "VER" "1"
					( Origin gFrontEnd )
				)
				( attribute "VOLTAGE" "16V"
					( Units "uVoltage" "V" 1.000000)
					( Origin gFrontEnd )
				)
				( attribute "XY" "(-6025,1550)"
					( Origin gFrontEnd )
				)
				( attribute "CHIPS_PART_NAME" "CAP"
					( Origin gPackager )
				)
				( attribute "CDS_PART_NAME" "CAP_0402-1.0UF,16V,10%,X6S,D97A"
					( Origin gPackager )
				)
				( objectStatus "C1D35" )
			)
			( gate "@baseboard_fab2_lib.baseboard_fab2(sch_1):page207_i43"
				( attribute "CDS_LIB" "mstr_discrete"
					( Origin gPackager )
				)
				( attribute "CDS_LOCATION" "C9R7"
					( Origin gPackager )
				)
				( attribute "CDS_SEC" "1"
					( Origin gPackager )
				)
				( attribute "LOCATION" "C9R7"
					( Origin gFrontEnd )
				)
				( attribute "MATERIAL" "X6S"
					( Origin gFrontEnd )
				)
				( attribute "PACK_TYPE" "0805"
					( Origin gFrontEnd )
				)
				( attribute "PART_NUMBER" "C95333-007"
					( Origin gFrontEnd )
				)
				( attribute "PHYS_PAGE" "207"
					( Origin gFrontEnd )
				)
				( attribute "ROOM" "PVCCIN_CPU1_PWR_VR"
					( Origin gFrontEnd )
				)
				( attribute "ROT" "0"
					( Origin gFrontEnd )
				)
				( attribute "SEC" "1"
					( Origin gFrontEnd )
				)
				( attribute "SEC_TYPE" "0805"
					( Origin gFrontEnd )
				)
				( attribute "TOLERANCE" "10%"
					( Origin gFrontEnd )
				)
				( attribute "VALUE" "10UF"
					( Origin gFrontEnd )
				)
				( attribute "VER" "1"
					( Origin gFrontEnd )
				)
				( attribute "VOLTAGE" "16V"
					( Units "uVoltage" "V" 1.000000)
					( Origin gFrontEnd )
				)
				( attribute "XY" "(-6425,4125)"
					( Origin gFrontEnd )
				)
				( attribute "CHIPS_PART_NAME" "CAP"
					( Origin gPackager )
				)
				( attribute "CDS_PART_NAME" "CAP_0805-10UF,16V,10%,X6S,C953A"
					( Origin gPackager )
				)
				( objectStatus "C9R7" )
			)
			( gate "@baseboard_fab2_lib.baseboard_fab2(sch_1):page207_i44"
				( attribute "CDS_LIB" "mstr_discrete"
					( Origin gPackager )
				)
				( attribute "CDS_LOCATION" "C9R10"
					( Origin gPackager )
				)
				( attribute "CDS_SEC" "1"
					( Origin gPackager )
				)
				( attribute "LOCATION" "C9R10"
					( Origin gFrontEnd )
				)
				( attribute "MATERIAL" "X6S"
					( Origin gFrontEnd )
				)
				( attribute "PACK_TYPE" "0805"
					( Origin gFrontEnd )
				)
				( attribute "PART_NUMBER" "C95333-007"
					( Origin gFrontEnd )
				)
				( attribute "PHYS_PAGE" "207"
					( Origin gFrontEnd )
				)
				( attribute "ROOM" "PVCCIN_CPU1_PWR_VR"
					( Origin gFrontEnd )
				)
				( attribute "ROT" "0"
					( Origin gFrontEnd )
				)
				( attribute "SEC" "1"
					( Origin gFrontEnd )
				)
				( attribute "SEC_TYPE" "0805"
					( Origin gFrontEnd )
				)
				( attribute "TOLERANCE" "10%"
					( Origin gFrontEnd )
				)
				( attribute "VALUE" "10UF"
					( Origin gFrontEnd )
				)
				( attribute "VER" "1"
					( Origin gFrontEnd )
				)
				( attribute "VOLTAGE" "16V"
					( Units "uVoltage" "V" 1.000000)
					( Origin gFrontEnd )
				)
				( attribute "XY" "(-6725,4125)"
					( Origin gFrontEnd )
				)
				( attribute "CHIPS_PART_NAME" "CAP"
					( Origin gPackager )
				)
				( attribute "CDS_PART_NAME" "CAP_0805-10UF,16V,10%,X6S,C953A"
					( Origin gPackager )
				)
				( objectStatus "C9R10" )
			)
			( gate "@baseboard_fab2_lib.baseboard_fab2(sch_1):page207_i48"
				( attribute "CDS_LIB" "mstr_discrete"
					( Origin gPackager )
				)
				( attribute "CDS_LOCATION" "C9R11"
					( Origin gPackager )
				)
				( attribute "LOCATION" "C9R11"
					( Origin gFrontEnd )
				)
				( attribute "MATERIAL" "X6S"
					( Origin gFrontEnd )
				)
				( attribute "PACK_TYPE" "0805"
					( Origin gFrontEnd )
				)
				( attribute "PART_NUMBER" "C95333-007"
					( Origin gFrontEnd )
				)
				( attribute "PHYS_PAGE" "207"
					( Origin gFrontEnd )
				)
				( attribute "ROOM" "PVCCIN_CPU1_PWR_VR"
					( Origin gFrontEnd )
				)
				( attribute "ROT" "0"
					( Origin gFrontEnd )
				)
				( attribute "SEC" "1"
					( Origin gFrontEnd )
				)
				( attribute "SEC_TYPE" "0805"
					( Origin gFrontEnd )
				)
				( attribute "TOLERANCE" "10%"
					( Origin gFrontEnd )
				)
				( attribute "VALUE" "10UF"
					( Origin gFrontEnd )
				)
				( attribute "VER" "1"
					( Origin gFrontEnd )
				)
				( attribute "VOLTAGE" "16V"
					( Units "uVoltage" "V" 1.000000)
					( Origin gFrontEnd )
				)
				( attribute "XY" "(-7025,4125)"
					( Origin gFrontEnd )
				)
				( attribute "CHIPS_PART_NAME" "CAP"
					( Origin gPackager )
				)
				( attribute "CDS_PART_NAME" "CAP_0805-10UF,16V,10%,X6S,C953A"
					( Origin gPackager )
				)
				( attribute "CDS_SEC" "1"
					( Origin gPackager )
				)
				( objectStatus "C9R11" )
			)
			( gate "@baseboard_fab2_lib.baseboard_fab2(sch_1):page207_i50"
				( attribute "CDS_LIB" "mstr_discrete"
					( Origin gPackager )
				)
				( attribute "CDS_LOCATION" "C9P22"
					( Origin gPackager )
				)
				( attribute "CDS_SEC" "1"
					( Origin gPackager )
				)
				( attribute "LOCATION" "C9P22"
					( Origin gFrontEnd )
				)
				( attribute "MATERIAL" "X6S"
					( Origin gFrontEnd )
				)
				( attribute "PACK_TYPE" "0805"
					( Origin gFrontEnd )
				)
				( attribute "PART_NUMBER" "C95333-007"
					( Origin gFrontEnd )
				)
				( attribute "PHYS_PAGE" "207"
					( Origin gFrontEnd )
				)
				( attribute "ROOM" "PVCCIN_CPU1_PWR_VR"
					( Origin gFrontEnd )
				)
				( attribute "ROT" "0"
					( Origin gFrontEnd )
				)
				( attribute "SEC" "1"
					( Origin gFrontEnd )
				)
				( attribute "SEC_TYPE" "0805"
					( Origin gFrontEnd )
				)
				( attribute "TOLERANCE" "10%"
					( Origin gFrontEnd )
				)
				( attribute "VALUE" "10UF"
					( Origin gFrontEnd )
				)
				( attribute "VER" "1"
					( Origin gFrontEnd )
				)
				( attribute "VOLTAGE" "16V"
					( Units "uVoltage" "V" 1.000000)
					( Origin gFrontEnd )
				)
				( attribute "XY" "(-6300,1550)"
					( Origin gFrontEnd )
				)
				( attribute "CHIPS_PART_NAME" "CAP"
					( Origin gPackager )
				)
				( attribute "CDS_PART_NAME" "CAP_0805-10UF,16V,10%,X6S,C953A"
					( Origin gPackager )
				)
				( objectStatus "C9P22" )
			)
			( gate "@baseboard_fab2_lib.baseboard_fab2(sch_1):page207_i51"
				( attribute "CDS_LIB" "mstr_discrete"
					( Origin gPackager )
				)
				( attribute "CDS_LOCATION" "C9P25"
					( Origin gPackager )
				)
				( attribute "CDS_SEC" "1"
					( Origin gPackager )
				)
				( attribute "LOCATION" "C9P25"
					( Origin gFrontEnd )
				)
				( attribute "MATERIAL" "X6S"
					( Origin gFrontEnd )
				)
				( attribute "PACK_TYPE" "0805"
					( Origin gFrontEnd )
				)
				( attribute "PART_NUMBER" "C95333-007"
					( Origin gFrontEnd )
				)
				( attribute "PHYS_PAGE" "207"
					( Origin gFrontEnd )
				)
				( attribute "ROOM" "PVCCIN_CPU1_PWR_VR"
					( Origin gFrontEnd )
				)
				( attribute "ROT" "0"
					( Origin gFrontEnd )
				)
				( attribute "SEC" "1"
					( Origin gFrontEnd )
				)
				( attribute "SEC_TYPE" "0805"
					( Origin gFrontEnd )
				)
				( attribute "TOLERANCE" "10%"
					( Origin gFrontEnd )
				)
				( attribute "VALUE" "10UF"
					( Origin gFrontEnd )
				)
				( attribute "VER" "1"
					( Origin gFrontEnd )
				)
				( attribute "VOLTAGE" "16V"
					( Units "uVoltage" "V" 1.000000)
					( Origin gFrontEnd )
				)
				( attribute "XY" "(-6575,1550)"
					( Origin gFrontEnd )
				)
				( attribute "CHIPS_PART_NAME" "CAP"
					( Origin gPackager )
				)
				( attribute "CDS_PART_NAME" "CAP_0805-10UF,16V,10%,X6S,C953A"
					( Origin gPackager )
				)
				( objectStatus "C9P25" )
			)
			( gate "@baseboard_fab2_lib.baseboard_fab2(sch_1):page207_i54"
				( attribute "CDS_LIB" "mstr_discrete"
					( Origin gPackager )
				)
				( attribute "CDS_LOCATION" "C9P26"
					( Origin gPackager )
				)
				( attribute "CDS_SEC" "1"
					( Origin gPackager )
				)
				( attribute "LOCATION" "C9P26"
					( Origin gFrontEnd )
				)
				( attribute "MATERIAL" "X6S"
					( Origin gFrontEnd )
				)
				( attribute "PACK_TYPE" "0805"
					( Origin gFrontEnd )
				)
				( attribute "PART_NUMBER" "C95333-007"
					( Origin gFrontEnd )
				)
				( attribute "PHYS_PAGE" "207"
					( Origin gFrontEnd )
				)
				( attribute "ROOM" "PVCCIN_CPU1_PWR_VR"
					( Origin gFrontEnd )
				)
				( attribute "ROT" "0"
					( Origin gFrontEnd )
				)
				( attribute "SEC" "1"
					( Origin gFrontEnd )
				)
				( attribute "SEC_TYPE" "0805"
					( Origin gFrontEnd )
				)
				( attribute "TOLERANCE" "10%"
					( Origin gFrontEnd )
				)
				( attribute "VALUE" "10UF"
					( Origin gFrontEnd )
				)
				( attribute "VER" "1"
					( Origin gFrontEnd )
				)
				( attribute "VOLTAGE" "16V"
					( Units "uVoltage" "V" 1.000000)
					( Origin gFrontEnd )
				)
				( attribute "XY" "(-6875,1550)"
					( Origin gFrontEnd )
				)
				( attribute "CHIPS_PART_NAME" "CAP"
					( Origin gPackager )
				)
				( attribute "CDS_PART_NAME" "CAP_0805-10UF,16V,10%,X6S,C953A"
					( Origin gPackager )
				)
				( objectStatus "C9P26" )
			)
			( gate "@baseboard_fab2_lib.baseboard_fab2(sch_1):page207_i58"
				( attribute "CDS_LIB" "dev_discrete"
					( Origin gPackager )
				)
				( attribute "CDS_LOCATION" "C1E9"
					( Origin gPackager )
				)
				( attribute "CDS_SEC" "1"
					( Origin gPackager )
				)
				( attribute "LOCATION" "C1E9"
					( Origin gFrontEnd )
				)
				( attribute "MATERIAL" "X6S"
					( Origin gFrontEnd )
				)
				( attribute "PACK_TYPE" "0603V"
					( Origin gFrontEnd )
				)
				( attribute "PART_NUMBER" "E15431-004"
					( Origin gFrontEnd )
				)
				( attribute "PHYS_PAGE" "207"
					( Origin gFrontEnd )
				)
				( attribute "ROT" "0"
					( Origin gFrontEnd )
				)
				( attribute "SEC" "1"
					( Origin gFrontEnd )
				)
				( attribute "SEC_TYPE" "0603V"
					( Origin gFrontEnd )
				)
				( attribute "TOLERANCE" "20%"
					( Origin gFrontEnd )
				)
				( attribute "VALUE" "22.0UF"
					( Origin gFrontEnd )
				)
				( attribute "VER" "1"
					( Origin gFrontEnd )
				)
				( attribute "VOLTAGE" "4V"
					( Units "uVoltage" "V" 1.000000)
					( Origin gFrontEnd )
				)
				( attribute "XY" "(-650,3350)"
					( Origin gFrontEnd )
				)
				( attribute "CHIPS_PART_NAME" "CAP_A"
					( Origin gPackager )
				)
				( attribute "CDS_PART_NAME" "CAP_A_0603V-22.0UF,4V,20%,X6S,A"
					( Origin gPackager )
				)
				( attribute "GROUP" "PWR_MLCC_CAP"
					( Origin gFrontEnd )
				)
				( objectStatus "C1E9" )
			)
			( gate "@baseboard_fab2_lib.baseboard_fab2(sch_1):page207_i59"
				( attribute "CDS_LIB" "dev_discrete"
					( Origin gPackager )
				)
				( attribute "CDS_LOCATION" "C9P3"
					( Origin gPackager )
				)
				( attribute "CDS_SEC" "1"
					( Origin gPackager )
				)
				( attribute "LOCATION" "C9P3"
					( Origin gFrontEnd )
				)
				( attribute "MATERIAL" "X6S"
					( Origin gFrontEnd )
				)
				( attribute "PACK_TYPE" "0603V"
					( Origin gFrontEnd )
				)
				( attribute "PART_NUMBER" "E15431-004"
					( Origin gFrontEnd )
				)
				( attribute "PHYS_PAGE" "207"
					( Origin gFrontEnd )
				)
				( attribute "ROT" "0"
					( Origin gFrontEnd )
				)
				( attribute "SEC" "1"
					( Origin gFrontEnd )
				)
				( attribute "SEC_TYPE" "0603V"
					( Origin gFrontEnd )
				)
				( attribute "TOLERANCE" "20%"
					( Origin gFrontEnd )
				)
				( attribute "VALUE" "22.0UF"
					( Origin gFrontEnd )
				)
				( attribute "VER" "1"
					( Origin gFrontEnd )
				)
				( attribute "VOLTAGE" "4V"
					( Units "uVoltage" "V" 1.000000)
					( Origin gFrontEnd )
				)
				( attribute "XY" "(-750,750)"
					( Origin gFrontEnd )
				)
				( attribute "CHIPS_PART_NAME" "CAP_A"
					( Origin gPackager )
				)
				( attribute "CDS_PART_NAME" "CAP_A_0603V-22.0UF,4V,20%,X6S,A"
					( Origin gPackager )
				)
				( attribute "GROUP" "PWR_MLCC_CAP"
					( Origin gFrontEnd )
				)
				( objectStatus "C9P3" )
			)
			( gate "@baseboard_fab2_lib.baseboard_fab2(sch_1):page207_i67"
				( attribute "CDS_LIB" "mstr_discrete"
					( Origin gPackager )
				)
				( attribute "CDS_LOCATION" "R1E13"
					( Origin gPackager )
				)
				( attribute "CDS_SEC" "1"
					( Origin gPackager )
				)
				( attribute "LOCATION" "R1E13"
					( Origin gFrontEnd )
				)
				( attribute "MATERIAL" "EMPTY"
					( Origin gFrontEnd )
				)
				( attribute "PACK_TYPE" "0402"
					( Origin gFrontEnd )
				)
				( attribute "PART_NUMBER" "G21796-187"
					( Origin gFrontEnd )
				)
				( attribute "PHYS_PAGE" "207"
					( Origin gFrontEnd )
				)
				( attribute "ROT" "0"
					( Origin gFrontEnd )
				)
				( attribute "SEC" "1"
					( Origin gPackager )
				)
				( attribute "TOLERANCE" "1%"
					( Origin gFrontEnd )
				)
				( attribute "VALUE" "68.1K"
					( Origin gFrontEnd )
				)
				( attribute "VER" "2"
					( Origin gFrontEnd )
				)
				( attribute "WATTAGE" "1/16W"
					( Origin gFrontEnd )
				)
				( attribute "XY" "(-700,1425)"
					( Origin gFrontEnd )
				)
				( attribute "CHIPS_PART_NAME" "RES"
					( Origin gPackager )
				)
				( attribute "CDS_PART_NAME" "RES_0402-68.1K,1%,1/16W,EMPTY,A"
					( Origin gPackager )
				)
				( objectStatus "R1E13" )
			)
			( gate "@baseboard_fab2_lib.baseboard_fab2(sch_1):page207_i68"
				( attribute "CDS_LIB" "mstr_discrete"
					( Origin gPackager )
				)
				( attribute "CDS_LOCATION" "R1E14"
					( Origin gPackager )
				)
				( attribute "CDS_SEC" "1"
					( Origin gPackager )
				)
				( attribute "LOCATION" "R1E14"
					( Origin gFrontEnd )
				)
				( attribute "MATERIAL" "EMPTY"
					( Origin gFrontEnd )
				)
				( attribute "PACK_TYPE" "0402"
					( Origin gFrontEnd )
				)
				( attribute "PART_NUMBER" "G21796-187"
					( Origin gFrontEnd )
				)
				( attribute "PHYS_PAGE" "207"
					( Origin gFrontEnd )
				)
				( attribute "ROT" "0"
					( Origin gFrontEnd )
				)
				( attribute "SEC" "1"
					( Origin gPackager )
				)
				( attribute "TOLERANCE" "1%"
					( Origin gFrontEnd )
				)
				( attribute "VALUE" "68.1K"
					( Origin gFrontEnd )
				)
				( attribute "VER" "2"
					( Origin gFrontEnd )
				)
				( attribute "WATTAGE" "1/16W"
					( Origin gFrontEnd )
				)
				( attribute "XY" "(-450,4050)"
					( Origin gFrontEnd )
				)
				( attribute "CHIPS_PART_NAME" "RES"
					( Origin gPackager )
				)
				( attribute "CDS_PART_NAME" "RES_0402-68.1K,1%,1/16W,EMPTY,A"
					( Origin gPackager )
				)
				( objectStatus "R1E14" )
			)
			( gate "@baseboard_fab2_lib.baseboard_fab2(sch_1):page208_i7"
				( attribute "BOM_COST" "PROC_VRD_VCCIN_CPU0"
					( Origin gFrontEnd )
				)
				( attribute "CDS_LIB" "mstr_discrete"
					( Origin gPackager )
				)
				( attribute "CDS_LOCATION" "R1E3"
					( Origin gPackager )
				)
				( attribute "CDS_SEC" "1"
					( Origin gPackager )
				)
				( attribute "LOCATION" "R1E3"
					( Origin gFrontEnd )
				)
				( attribute "MATERIAL" "CHIP"
					( Origin gFrontEnd )
				)
				( attribute "PACK_TYPE" "0603"
					( Origin gFrontEnd )
				)
				( attribute "PART_NUMBER" "G22026-038"
					( Origin gFrontEnd )
				)
				( attribute "PHYS_PAGE" "208"
					( Origin gFrontEnd )
				)
				( attribute "ROOM" "PVCCIN_CPU1_DECAP_VR"
					( Origin gFrontEnd )
				)
				( attribute "ROT" "0"
					( Origin gFrontEnd )
				)
				( attribute "SEC" "1"
					( Origin gFrontEnd )
				)
				( attribute "SEC_TYPE" "0603"
					( Origin gFrontEnd )
				)
				( attribute "TOLERANCE" "1%"
					( Origin gFrontEnd )
				)
				( attribute "VALUE" "100.0"
					( Origin gFrontEnd )
				)
				( attribute "VER" "2"
					( Origin gFrontEnd )
				)
				( attribute "WATTAGE" "1/10W"
					( Origin gFrontEnd )
				)
				( attribute "XY" "(-1000,2575)"
					( Origin gFrontEnd )
				)
				( attribute "CHIPS_PART_NAME" "RES"
					( Origin gPackager )
				)
				( attribute "CDS_PART_NAME" "RES_0603-100.0,1%,1/10W,CHIP,GA"
					( Origin gPackager )
				)
				( objectStatus "R1E3" )
			)
			( gate "@baseboard_fab2_lib.baseboard_fab2(sch_1):page208_i9"
				( attribute "BOM_COST" "PROC_VRD_VCCIN_CPU0"
					( Origin gFrontEnd )
				)
				( attribute "CDS_LIB" "dev_discrete"
					( Origin gPackager )
				)
				( attribute "CDS_LOCATION" "C1D14"
					( Origin gPackager )
				)
				( attribute "CDS_SEC" "1"
					( Origin gPackager )
				)
				( attribute "LOCATION" "C1D14"
					( Origin gFrontEnd )
				)
				( attribute "MATERIAL" "X6S"
					( Origin gFrontEnd )
				)
				( attribute "PACK_TYPE" "0603V"
					( Origin gFrontEnd )
				)
				( attribute "PART_NUMBER" "E15431-004"
					( Origin gFrontEnd )
				)
				( attribute "PHYS_PAGE" "208"
					( Origin gFrontEnd )
				)
				( attribute "ROOM" "PVCCIN_CPU1_PWR_VR"
					( Origin gFrontEnd )
				)
				( attribute "ROT" "0"
					( Origin gFrontEnd )
				)
				( attribute "SEC" "1"
					( Origin gFrontEnd )
				)
				( attribute "SEC_TYPE" "0603V"
					( Origin gFrontEnd )
				)
				( attribute "TOLERANCE" "20%"
					( Origin gFrontEnd )
				)
				( attribute "VALUE" "22.0UF"
					( Origin gFrontEnd )
				)
				( attribute "VER" "1"
					( Origin gFrontEnd )
				)
				( attribute "VOLTAGE" "4V"
					( Units "uVoltage" "V" 1.000000)
					( Origin gFrontEnd )
				)
				( attribute "XY" "(-800,3400)"
					( Origin gFrontEnd )
				)
				( attribute "CHIPS_PART_NAME" "CAP_A"
					( Origin gPackager )
				)
				( attribute "CDS_PART_NAME" "CAP_A_0603V-22.0UF,4V,20%,X6S,A"
					( Origin gPackager )
				)
				( attribute "GROUP" "PWR_MLCC_CAP"
					( Origin gFrontEnd )
				)
				( objectStatus "C1D14" )
			)
			( gate "@baseboard_fab2_lib.baseboard_fab2(sch_1):page161_i139"
				( attribute "CDS_LIB" "w_hdl"
					( Origin gPackager )
				)
				( attribute "CDS_LMAN_SYM_OUTLINE" "-75,150,75,-150"
					( Origin gPackager )
				)
				( attribute "CDS_LOCATION" "J1F2"
					( Origin gPackager )
				)
				( attribute "CDS_SEC" "1"
					( Origin gPackager )
				)
				( attribute "LOCATION" "J1F2"
					( Origin gFrontEnd )
				)
				( attribute "PACK_TYPE" "CONN-G7"
					( Origin gFrontEnd )
				)
				( attribute "PART_NUMBER" "021.60521.0104"
					( Origin gFrontEnd )
				)
				( attribute "PHYS_PAGE" "161"
					( Origin gFrontEnd )
				)
				( attribute "ROT" "0"
					( Origin gFrontEnd )
				)
				( attribute "SEC" "1"
					( Origin gFrontEnd )
				)
				( attribute "SEC_TYPE" "CONN-G7"
					( Origin gFrontEnd )
				)
				( attribute "VALUE" "LOTES-CON4-S1-GP"
					( Origin gFrontEnd )
				)
				( attribute "VER" "1"
					( Origin gFrontEnd )
				)
				( attribute "XY" "(-600,3875)"
					( Origin gFrontEnd )
				)
				( attribute "CHIPS_PART_NAME" "LOTES-CON4-S1-GP"
					( Origin gPackager )
				)
				( attribute "CDS_PART_NAME" "LOTES-CON4-S1-GP_CONN-G7-LOTESA"
					( Origin gPackager )
				)
				( objectStatus "J1F2" )
			)
			( gate "@baseboard_fab2_lib.baseboard_fab2(sch_1):page208_i12"
				( attribute "BOM_COST" "PROC_VRD_VCCIN_CPU0"
					( Origin gFrontEnd )
				)
				( attribute "CDS_LIB" "mstr_discrete"
					( Origin gPackager )
				)
				( attribute "CDS_LOCATION" "C9P8"
					( Origin gPackager )
				)
				( attribute "CDS_SEC" "1"
					( Origin gPackager )
				)
				( attribute "LOCATION" "C9P8"
					( Origin gFrontEnd )
				)
				( attribute "MATERIAL" "ALUM"
					( Origin gFrontEnd )
				)
				( attribute "PACK_TYPE" "3018"
					( Origin gFrontEnd )
				)
				( attribute "PART_NUMBER" "699013-049"
					( Origin gFrontEnd )
				)
				( attribute "PHYS_PAGE" "208"
					( Origin gFrontEnd )
				)
				( attribute "ROOM" "PVCCIN_CPU1_DECAP_VR"
					( Origin gFrontEnd )
				)
				( attribute "ROT" "0"
					( Origin gFrontEnd )
				)
				( attribute "SEC" "1"
					( Origin gFrontEnd )
				)
				( attribute "SEC_TYPE" "3018"
					( Origin gFrontEnd )
				)
				( attribute "TOLERANCE" "20%"
					( Origin gFrontEnd )
				)
				( attribute "VALUE" "470UF"
					( Origin gFrontEnd )
				)
				( attribute "VER" "1"
					( Origin gFrontEnd )
				)
				( attribute "VOLTAGE" "2.5V"
					( Units "uVoltage" "V" 1.000000)
					( Origin gFrontEnd )
				)
				( attribute "XY" "(-1450,2650)"
					( Origin gFrontEnd )
				)
				( attribute "CHIPS_PART_NAME" "CAPP"
					( Origin gPackager )
				)
				( attribute "CDS_PART_NAME" "CAPP_3018-470UF,2.5V,20%,ALUM,A"
					( Origin gPackager )
				)
				( attribute "GROUP" "PWR_BULK_CAP"
					( Origin gFrontEnd )
				)
				( objectStatus "C9P8" )
			)
			( gate "@baseboard_fab2_lib.baseboard_fab2(sch_1):page208_i14"
				( attribute "BOM_COST" "PROC_VRD_VCCIN_CPU0"
					( Origin gFrontEnd )
				)
				( attribute "CDS_LIB" "mstr_discrete"
					( Origin gPackager )
				)
				( attribute "CDS_LOCATION" "C9P5"
					( Origin gPackager )
				)
				( attribute "CDS_SEC" "1"
					( Origin gPackager )
				)
				( attribute "LOCATION" "C9P5"
					( Origin gFrontEnd )
				)
				( attribute "MATERIAL" "ALUM"
					( Origin gFrontEnd )
				)
				( attribute "PACK_TYPE" "3018"
					( Origin gFrontEnd )
				)
				( attribute "PART_NUMBER" "699013-049"
					( Origin gFrontEnd )
				)
				( attribute "PHYS_PAGE" "208"
					( Origin gFrontEnd )
				)
				( attribute "ROOM" "PVCCIN_CPU1_DECAP_VR"
					( Origin gFrontEnd )
				)
				( attribute "ROT" "0"
					( Origin gFrontEnd )
				)
				( attribute "SEC" "1"
					( Origin gFrontEnd )
				)
				( attribute "SEC_TYPE" "3018"
					( Origin gFrontEnd )
				)
				( attribute "TOLERANCE" "20%"
					( Origin gFrontEnd )
				)
				( attribute "VALUE" "470UF"
					( Origin gFrontEnd )
				)
				( attribute "VER" "1"
					( Origin gFrontEnd )
				)
				( attribute "VOLTAGE" "2.5V"
					( Units "uVoltage" "V" 1.000000)
					( Origin gFrontEnd )
				)
				( attribute "XY" "(-1925,2650)"
					( Origin gFrontEnd )
				)
				( attribute "CHIPS_PART_NAME" "CAPP"
					( Origin gPackager )
				)
				( attribute "CDS_PART_NAME" "CAPP_3018-470UF,2.5V,20%,ALUM,A"
					( Origin gPackager )
				)
				( attribute "GROUP" "PWR_BULK_CAP"
					( Origin gFrontEnd )
				)
				( objectStatus "C9P5" )
			)
			( gate "@baseboard_fab2_lib.baseboard_fab2(sch_1):page209_i80"
				( attribute "CDS_LIB" "w_hdl"
					( Origin gPackager )
				)
				( attribute "CDS_LMAN_SYM_OUTLINE" "-75,100,75,-100"
					( Origin gPackager )
				)
				( attribute "LOCATION" "L1C2"
					( Origin gFrontEnd )
				)
				( attribute "PACK_TYPE" "DISCRET-GB2"
					( Origin gFrontEnd )
				)
				( attribute "PART_NUMBER" "068.1202N.M001"
					( Origin gFrontEnd )
				)
				( attribute "PHYS_PAGE" "209"
					( Origin gFrontEnd )
				)
				( attribute "ROT" "1"
					( Origin gFrontEnd )
				)
				( attribute "SEC" "1"
					( Origin gFrontEnd )
				)
				( attribute "SEC_TYPE" "DISCRET-GB2"
					( Origin gFrontEnd )
				)
				( attribute "VALUE" "IND-120NH-30-GP"
					( Origin gFrontEnd )
				)
				( attribute "VER" "1"
					( Origin gFrontEnd )
				)
				( attribute "XY" "(-1400,3500)"
					( Origin gFrontEnd )
				)
				( attribute "CHIPS_PART_NAME" "IND-120NH-30-GP"
					( Origin gPackager )
				)
				( attribute "CDS_PART_NAME" "IND-120NH-30-GP_DISCRET-GB2-INA"
					( Origin gPackager )
				)
				( attribute "CDS_LOCATION" "L1C2"
					( Origin gPackager )
				)
				( attribute "CDS_SEC" "1"
					( Origin gPackager )
				)
				( attribute "ATTRIBUTE" "120NH"
					( Origin gFrontEnd )
				)
				( attribute "PACK_SIZE" "DCR=0.17MOHM"
					( Origin gFrontEnd )
				)
				( attribute "RATED" "ISAT=94A@25C"
					( Origin gFrontEnd )
				)
				( attribute "TYPE" "IRMS=66A@DELTA_T<40C"
					( Origin gFrontEnd )
				)
				( objectStatus "L1C2" )
			)
			( gate "@baseboard_fab2_lib.baseboard_fab2(sch_1):page208_i22"
				( attribute "BOM_COST" "PROC_VRD_VCCIN_CPU0"
					( Origin gFrontEnd )
				)
				( attribute "CDS_LIB" "dev_discrete"
					( Origin gPackager )
				)
				( attribute "CDS_LOCATION" "C1D3"
					( Origin gPackager )
				)
				( attribute "CDS_SEC" "1"
					( Origin gPackager )
				)
				( attribute "LOCATION" "C1D3"
					( Origin gFrontEnd )
				)
				( attribute "MATERIAL" "X6S"
					( Origin gFrontEnd )
				)
				( attribute "PACK_TYPE" "0603V"
					( Origin gFrontEnd )
				)
				( attribute "PART_NUMBER" "E15431-004"
					( Origin gFrontEnd )
				)
				( attribute "PHYS_PAGE" "208"
					( Origin gFrontEnd )
				)
				( attribute "ROOM" "PVCCIN_CPU1_PWR_VR"
					( Origin gFrontEnd )
				)
				( attribute "ROT" "0"
					( Origin gFrontEnd )
				)
				( attribute "SEC" "1"
					( Origin gFrontEnd )
				)
				( attribute "SEC_TYPE" "0603V"
					( Origin gFrontEnd )
				)
				( attribute "TOLERANCE" "20%"
					( Origin gFrontEnd )
				)
				( attribute "VALUE" "22.0UF"
					( Origin gFrontEnd )
				)
				( attribute "VER" "1"
					( Origin gFrontEnd )
				)
				( attribute "VOLTAGE" "4V"
					( Units "uVoltage" "V" 1.000000)
					( Origin gFrontEnd )
				)
				( attribute "XY" "(-700,800)"
					( Origin gFrontEnd )
				)
				( attribute "CHIPS_PART_NAME" "CAP_A"
					( Origin gPackager )
				)
				( attribute "CDS_PART_NAME" "CAP_A_0603V-22.0UF,4V,20%,X6S,A"
					( Origin gPackager )
				)
				( attribute "GROUP" "PWR_MLCC_CAP"
					( Origin gFrontEnd )
				)
				( objectStatus "C1D3" )
			)
			( gate "@baseboard_fab2_lib.baseboard_fab2(sch_1):page208_i24"
				( attribute "BOM_COST" "PROC_VRD_VCCIN_CPU0"
					( Origin gFrontEnd )
				)
				( attribute "CDS_LIB" "mstr_discrete"
					( Origin gPackager )
				)
				( attribute "CDS_LOCATION" "C9N24"
					( Origin gPackager )
				)
				( attribute "CDS_SEC" "1"
					( Origin gPackager )
				)
				( attribute "LOCATION" "C9N24"
					( Origin gFrontEnd )
				)
				( attribute "MATERIAL" "ALUM"
					( Origin gFrontEnd )
				)
				( attribute "PACK_TYPE" "3018"
					( Origin gFrontEnd )
				)
				( attribute "PART_NUMBER" "699013-049"
					( Origin gFrontEnd )
				)
				( attribute "PHYS_PAGE" "208"
					( Origin gFrontEnd )
				)
				( attribute "ROOM" "PVCCIN_CPU1_DECAP_VR"
					( Origin gFrontEnd )
				)
				( attribute "ROT" "0"
					( Origin gFrontEnd )
				)
				( attribute "SEC" "1"
					( Origin gFrontEnd )
				)
				( attribute "SEC_TYPE" "3018"
					( Origin gFrontEnd )
				)
				( attribute "TOLERANCE" "20%"
					( Origin gFrontEnd )
				)
				( attribute "VALUE" "470UF"
					( Origin gFrontEnd )
				)
				( attribute "VER" "1"
					( Origin gFrontEnd )
				)
				( attribute "VOLTAGE" "2.5V"
					( Units "uVoltage" "V" 1.000000)
					( Origin gFrontEnd )
				)
				( attribute "XY" "(-2375,2650)"
					( Origin gFrontEnd )
				)
				( attribute "CHIPS_PART_NAME" "CAPP"
					( Origin gPackager )
				)
				( attribute "CDS_PART_NAME" "CAPP_3018-470UF,2.5V,20%,ALUM,A"
					( Origin gPackager )
				)
				( attribute "GROUP" "PWR_BULK_CAP"
					( Origin gFrontEnd )
				)
				( objectStatus "C9N24" )
			)
			( gate "@baseboard_fab2_lib.baseboard_fab2(sch_1):page208_i25"
				( attribute "BOM_COST" "PROC_VRD_VCCIN_CPU0"
					( Origin gFrontEnd )
				)
				( attribute "CDS_LIB" "mstr_discrete"
					( Origin gPackager )
				)
				( attribute "CDS_LOCATION" "C9R9"
					( Origin gPackager )
				)
				( attribute "CDS_SEC" "1"
					( Origin gPackager )
				)
				( attribute "LOCATION" "C9R9"
					( Origin gFrontEnd )
				)
				( attribute "MATERIAL" "ALUM"
					( Origin gFrontEnd )
				)
				( attribute "PACK_TYPE" "3018"
					( Origin gFrontEnd )
				)
				( attribute "PART_NUMBER" "699013-049"
					( Origin gFrontEnd )
				)
				( attribute "PHYS_PAGE" "208"
					( Origin gFrontEnd )
				)
				( attribute "ROOM" "PVCCIN_CPU1_DECAP_VR"
					( Origin gFrontEnd )
				)
				( attribute "ROT" "0"
					( Origin gFrontEnd )
				)
				( attribute "SEC" "1"
					( Origin gFrontEnd )
				)
				( attribute "SEC_TYPE" "3018"
					( Origin gFrontEnd )
				)
				( attribute "TOLERANCE" "20%"
					( Origin gFrontEnd )
				)
				( attribute "VALUE" "470UF"
					( Origin gFrontEnd )
				)
				( attribute "VER" "1"
					( Origin gFrontEnd )
				)
				( attribute "VOLTAGE" "2.5V"
					( Units "uVoltage" "V" 1.000000)
					( Origin gFrontEnd )
				)
				( attribute "XY" "(-2825,2650)"
					( Origin gFrontEnd )
				)
				( attribute "CHIPS_PART_NAME" "CAPP"
					( Origin gPackager )
				)
				( attribute "CDS_PART_NAME" "CAPP_3018-470UF,2.5V,20%,ALUM,A"
					( Origin gPackager )
				)
				( attribute "GROUP" "PWR_BULK_CAP"
					( Origin gFrontEnd )
				)
				( objectStatus "C9R9" )
			)
			( gate "@baseboard_fab2_lib.baseboard_fab2(sch_1):page208_i26"
				( attribute "BOM_COST" "PROC_VRD_VCCIN_CPU0"
					( Origin gFrontEnd )
				)
				( attribute "CDS_LIB" "mstr_discrete"
					( Origin gPackager )
				)
				( attribute "CDS_LOCATION" "C9R3"
					( Origin gPackager )
				)
				( attribute "CDS_SEC" "1"
					( Origin gPackager )
				)
				( attribute "LOCATION" "C9R3"
					( Origin gFrontEnd )
				)
				( attribute "MATERIAL" "ALUM"
					( Origin gFrontEnd )
				)
				( attribute "PACK_TYPE" "3018"
					( Origin gFrontEnd )
				)
				( attribute "PART_NUMBER" "699013-049"
					( Origin gFrontEnd )
				)
				( attribute "PHYS_PAGE" "208"
					( Origin gFrontEnd )
				)
				( attribute "ROOM" "PVCCIN_CPU1_DECAP_VR"
					( Origin gFrontEnd )
				)
				( attribute "ROT" "0"
					( Origin gFrontEnd )
				)
				( attribute "SEC" "1"
					( Origin gFrontEnd )
				)
				( attribute "SEC_TYPE" "3018"
					( Origin gFrontEnd )
				)
				( attribute "TOLERANCE" "20%"
					( Origin gFrontEnd )
				)
				( attribute "VALUE" "470UF"
					( Origin gFrontEnd )
				)
				( attribute "VER" "1"
					( Origin gFrontEnd )
				)
				( attribute "VOLTAGE" "2.5V"
					( Units "uVoltage" "V" 1.000000)
					( Origin gFrontEnd )
				)
				( attribute "XY" "(-3275,2650)"
					( Origin gFrontEnd )
				)
				( attribute "CHIPS_PART_NAME" "CAPP"
					( Origin gPackager )
				)
				( attribute "CDS_PART_NAME" "CAPP_3018-470UF,2.5V,20%,ALUM,A"
					( Origin gPackager )
				)
				( attribute "GROUP" "PWR_BULK_CAP"
					( Origin gFrontEnd )
				)
				( objectStatus "C9R3" )
			)
			( gate "@baseboard_fab2_lib.baseboard_fab2(sch_1):page208_i27"
				( attribute "CDS_LIB" "mstr_discrete"
					( Origin gPackager )
				)
				( attribute "CDS_LOCATION" "EU1D3"
					( Origin gPackager )
				)
				( attribute "LOCATION" "EU1D3"
					( Origin gFrontEnd )
				)
				( attribute "MATERIAL" "IC"
					( Origin gFrontEnd )
				)
				( attribute "PACK_TYPE" "SM"
					( Origin gFrontEnd )
				)
				( attribute "PART_NUMBER" "H73688-001"
					( Origin gFrontEnd )
				)
				( attribute "PHYS_PAGE" "208"
					( Origin gFrontEnd )
				)
				( attribute "ROOM" "PVCCIN_CPU1_PWR_VR"
					( Origin gFrontEnd )
				)
				( attribute "ROT" "0"
					( Origin gFrontEnd )
				)
				( attribute "SEC" "1"
					( Origin gFrontEnd )
				)
				( attribute "SEC_TYPE" "SM"
					( Origin gFrontEnd )
				)
				( attribute "VALUE" "IR35411"
					( Origin gFrontEnd )
				)
				( attribute "VER" "1"
					( Origin gFrontEnd )
				)
				( attribute "XY" "(-3300,3875)"
					( Origin gFrontEnd )
				)
				( attribute "CHIPS_PART_NAME" "IR354XX"
					( Origin gPackager )
				)
				( attribute "CDS_PART_NAME" "IR354XX_SM-IR35411,IC,H73688-0A"
					( Origin gPackager )
				)
				( attribute "CDS_SEC" "1"
					( Origin gPackager )
				)
				( objectStatus "EU1D3" )
			)
			( gate "@baseboard_fab2_lib.baseboard_fab2(sch_1):page208_i28"
				( attribute "BOM_COST" "PROC_VRD_VCCIN_CPU0"
					( Origin gFrontEnd )
				)
				( attribute "CDS_LIB" "mstr_discrete"
					( Origin gPackager )
				)
				( attribute "CDS_LOCATION" "C9P23"
					( Origin gPackager )
				)
				( attribute "CDS_SEC" "1"
					( Origin gPackager )
				)
				( attribute "LOCATION" "C9P23"
					( Origin gFrontEnd )
				)
				( attribute "MATERIAL" "ALUM"
					( Origin gFrontEnd )
				)
				( attribute "PACK_TYPE" "3018"
					( Origin gFrontEnd )
				)
				( attribute "PART_NUMBER" "699013-049"
					( Origin gFrontEnd )
				)
				( attribute "PHYS_PAGE" "208"
					( Origin gFrontEnd )
				)
				( attribute "ROOM" "PVCCIN_CPU1_DECAP_VR"
					( Origin gFrontEnd )
				)
				( attribute "ROT" "0"
					( Origin gFrontEnd )
				)
				( attribute "SEC" "1"
					( Origin gFrontEnd )
				)
				( attribute "SEC_TYPE" "3018"
					( Origin gFrontEnd )
				)
				( attribute "TOLERANCE" "20%"
					( Origin gFrontEnd )
				)
				( attribute "VALUE" "470UF"
					( Origin gFrontEnd )
				)
				( attribute "VER" "1"
					( Origin gFrontEnd )
				)
				( attribute "VOLTAGE" "2.5V"
					( Units "uVoltage" "V" 1.000000)
					( Origin gFrontEnd )
				)
				( attribute "XY" "(-3725,2650)"
					( Origin gFrontEnd )
				)
				( attribute "CHIPS_PART_NAME" "CAPP"
					( Origin gPackager )
				)
				( attribute "CDS_PART_NAME" "CAPP_3018-470UF,2.5V,20%,ALUM,A"
					( Origin gPackager )
				)
				( attribute "GROUP" "PWR_BULK_CAP"
					( Origin gFrontEnd )
				)
				( objectStatus "C9P23" )
			)
			( gate "@baseboard_fab2_lib.baseboard_fab2(sch_1):page208_i30"
				( attribute "BOM_COST" "PROC_VRD_VCCIN_CPU0"
					( Origin gFrontEnd )
				)
				( attribute "CDS_LIB" "mstr_discrete"
					( Origin gPackager )
				)
				( attribute "CDS_LOCATION" "C9P18"
					( Origin gPackager )
				)
				( attribute "CDS_SEC" "1"
					( Origin gPackager )
				)
				( attribute "LOCATION" "C9P18"
					( Origin gFrontEnd )
				)
				( attribute "MATERIAL" "ALUM"
					( Origin gFrontEnd )
				)
				( attribute "PACK_TYPE" "3018"
					( Origin gFrontEnd )
				)
				( attribute "PART_NUMBER" "699013-049"
					( Origin gFrontEnd )
				)
				( attribute "PHYS_PAGE" "208"
					( Origin gFrontEnd )
				)
				( attribute "ROOM" "PVCCIN_CPU1_DECAP_VR"
					( Origin gFrontEnd )
				)
				( attribute "ROT" "0"
					( Origin gFrontEnd )
				)
				( attribute "SEC" "1"
					( Origin gFrontEnd )
				)
				( attribute "SEC_TYPE" "3018"
					( Origin gFrontEnd )
				)
				( attribute "TOLERANCE" "20%"
					( Origin gFrontEnd )
				)
				( attribute "VALUE" "470UF"
					( Origin gFrontEnd )
				)
				( attribute "VER" "1"
					( Origin gFrontEnd )
				)
				( attribute "VOLTAGE" "2.5V"
					( Units "uVoltage" "V" 1.000000)
					( Origin gFrontEnd )
				)
				( attribute "XY" "(-4250,2650)"
					( Origin gFrontEnd )
				)
				( attribute "CHIPS_PART_NAME" "CAPP"
					( Origin gPackager )
				)
				( attribute "CDS_PART_NAME" "CAPP_3018-470UF,2.5V,20%,ALUM,A"
					( Origin gPackager )
				)
				( attribute "GROUP" "PWR_BULK_CAP"
					( Origin gFrontEnd )
				)
				( objectStatus "C9P18" )
			)
			( gate "@baseboard_fab2_lib.baseboard_fab2(sch_1):page216_i146"
				( attribute "BOM_COST" "PROC_SIDEBAND"
					( Origin gFrontEnd )
				)
				( attribute "CDS_LIB" "mstr_discrete"
					( Origin gPackager )
				)
				( attribute "CDS_LOCATION" "R3U9"
					( Origin gPackager )
				)
				( attribute "CDS_SEC" "1"
					( Origin gPackager )
				)
				( attribute "LOCATION" "R3U9"
					( Origin gFrontEnd )
				)
				( attribute "MATERIAL" "CHIP"
					( Origin gFrontEnd )
				)
				( attribute "PACK_TYPE" "0402"
					( Origin gFrontEnd )
				)
				( attribute "PART_NUMBER" "G21497-005"
					( Origin gFrontEnd )
				)
				( attribute "PHYS_PAGE" "216"
					( Origin gFrontEnd )
				)
				( attribute "ROOM" "CPU0"
					( Origin gFrontEnd )
				)
				( attribute "ROT" "0"
					( Origin gFrontEnd )
				)
				( attribute "SEC" "1"
					( Origin gFrontEnd )
				)
				( attribute "SEC_TYPE" "0402"
					( Origin gFrontEnd )
				)
				( attribute "TOLERANCE" "5%"
					( Origin gFrontEnd )
				)
				( attribute "VALUE" "0.0"
					( Origin gFrontEnd )
				)
				( attribute "VER" "1"
					( Origin gFrontEnd )
				)
				( attribute "WATTAGE" "1/16W"
					( Origin gFrontEnd )
				)
				( attribute "XY" "(-600,725)"
					( Origin gFrontEnd )
				)
				( attribute "CHIPS_PART_NAME" "RES"
					( Origin gPackager )
				)
				( attribute "CDS_PART_NAME" "RES_0402-0.0,5%,1/16W,CHIP,G21A"
					( Origin gPackager )
				)
				( attribute "BOM_SS" "NOPOP"
					( Origin gFrontEnd )
				)
				( objectStatus "R3U9" )
			)
			( gate "@baseboard_fab2_lib.baseboard_fab2(sch_1):page208_i38"
				( attribute "CDS_LIB" "mstr_discrete"
					( Origin gPackager )
				)
				( attribute "CDS_LOCATION" "C1D16"
					( Origin gPackager )
				)
				( attribute "CDS_SEC" "1"
					( Origin gPackager )
				)
				( attribute "LOCATION" "C1D16"
					( Origin gFrontEnd )
				)
				( attribute "MATERIAL" "X7R"
					( Origin gFrontEnd )
				)
				( attribute "PACK_TYPE" "0402"
					( Origin gFrontEnd )
				)
				( attribute "PART_NUMBER" "A36096-155"
					( Origin gFrontEnd )
				)
				( attribute "PHYS_PAGE" "208"
					( Origin gFrontEnd )
				)
				( attribute "ROOM" "PVCCIN_CPU1_PWR_VR"
					( Origin gFrontEnd )
				)
				( attribute "ROT" "0"
					( Origin gFrontEnd )
				)
				( attribute "SEC" "1"
					( Origin gFrontEnd )
				)
				( attribute "SEC_TYPE" "0402"
					( Origin gFrontEnd )
				)
				( attribute "TOLERANCE" "10%"
					( Origin gFrontEnd )
				)
				( attribute "VALUE" "0.22UF"
					( Origin gFrontEnd )
				)
				( attribute "VER" "1"
					( Origin gFrontEnd )
				)
				( attribute "VOLTAGE" "16V"
					( Units "uVoltage" "V" 1.000000)
					( Origin gFrontEnd )
				)
				( attribute "XY" "(-4775,4200)"
					( Origin gFrontEnd )
				)
				( attribute "CHIPS_PART_NAME" "CAP"
					( Origin gPackager )
				)
				( attribute "CDS_PART_NAME" "CAP_0402-0.22UF,16V,10%,X7R,A3A"
					( Origin gPackager )
				)
				( objectStatus "C1D16" )
			)
			( gate "@baseboard_fab2_lib.baseboard_fab2(sch_1):page207_i110"
				( attribute "CDS_LIB" "w_hdl"
					( Origin gPackager )
				)
				( attribute "CDS_LMAN_SYM_OUTLINE" "-50,25,50,-25"
					( Origin gPackager )
				)
				( attribute "LOCATION" "C1E6"
					( Origin gFrontEnd )
				)
				( attribute "PACK_TYPE" "SMD-BCG6"
					( Origin gFrontEnd )
				)
				( attribute "PART_NUMBER" "78.10523.8FL"
					( Origin gFrontEnd )
				)
				( attribute "PHYS_PAGE" "207"
					( Origin gFrontEnd )
				)
				( attribute "ROT" "0"
					( Origin gFrontEnd )
				)
				( attribute "SEC" "1"
					( Origin gFrontEnd )
				)
				( attribute "SEC_TYPE" "SMD-BCG6"
					( Origin gFrontEnd )
				)
				( attribute "VALUE" "SC1U10V2KX-4-GP"
					( Origin gFrontEnd )
				)
				( attribute "VER" "1"
					( Origin gFrontEnd )
				)
				( attribute "XY" "(-5100,4125)"
					( Origin gFrontEnd )
				)
				( attribute "CHIPS_PART_NAME" "SC1U10V2KX-4-GP"
					( Origin gPackager )
				)
				( attribute "CDS_PART_NAME" "SC1U10V2KX-4-GP_SMD-BCG6-SC1U1A"
					( Origin gPackager )
				)
				( attribute "CDS_LOCATION" "C1E6"
					( Origin gPackager )
				)
				( attribute "CDS_SEC" "1"
					( Origin gPackager )
				)
				( attribute "ATTRIBUTE" "1UF"
					( Origin gFrontEnd )
				)
				( attribute "PACK_SIZE" "0402"
					( Origin gFrontEnd )
				)
				( attribute "RATED" "10V"
					( Origin gFrontEnd )
				)
				( attribute "TOLERANCE" "10%"
					( Origin gFrontEnd )
				)
				( objectStatus "C1E6" )
			)
			( gate "@baseboard_fab2_lib.baseboard_fab2(sch_1):page208_i40"
				( attribute "CDS_LIB" "mstr_discrete"
					( Origin gPackager )
				)
				( attribute "CDS_LOCATION" "C1D20"
					( Origin gPackager )
				)
				( attribute "CDS_SEC" "1"
					( Origin gPackager )
				)
				( attribute "LOCATION" "C1D20"
					( Origin gFrontEnd )
				)
				( attribute "MATERIAL" "X7R"
					( Origin gFrontEnd )
				)
				( attribute "NO_XNET_CONNECTION" "1"
					( Origin gFrontEnd )
				)
				( attribute "PACK_TYPE" "0402"
					( Origin gFrontEnd )
				)
				( attribute "PART_NUMBER" "A36096-104"
					( Origin gFrontEnd )
				)
				( attribute "PHYS_PAGE" "208"
					( Origin gFrontEnd )
				)
				( attribute "ROOM" "PVCCIN_CPU1_PWR_VR"
					( Origin gFrontEnd )
				)
				( attribute "ROT" "2"
					( Origin gFrontEnd )
				)
				( attribute "SEC" "1"
					( Origin gFrontEnd )
				)
				( attribute "SEC_TYPE" "0402"
					( Origin gFrontEnd )
				)
				( attribute "SPOF" "TRUE"
					( Origin gFrontEnd )
				)
				( attribute "TOLERANCE" "10%"
					( Origin gFrontEnd )
				)
				( attribute "VALUE" "0.220UF"
					( Origin gFrontEnd )
				)
				( attribute "VER" "1"
					( Origin gFrontEnd )
				)
				( attribute "VOLTAGE" "16V"
					( Units "uVoltage" "V" 1.000000)
					( Origin gFrontEnd )
				)
				( attribute "XY" "(-5975,3575)"
					( Origin gFrontEnd )
				)
				( attribute "CHIPS_PART_NAME" "CAP"
					( Origin gPackager )
				)
				( attribute "CDS_PART_NAME" "CAP_0402-0.220UF,16V,10%,X7R,AA"
					( Origin gPackager )
				)
				( objectStatus "C1D20" )
			)
			( gate "@baseboard_fab2_lib.baseboard_fab2(sch_1):page208_i43"
				( attribute "CDS_LIB" "mstr_discrete"
					( Origin gPackager )
				)
				( attribute "CDS_LOCATION" "C1D17"
					( Origin gPackager )
				)
				( attribute "CDS_SEC" "1"
					( Origin gPackager )
				)
				( attribute "LOCATION" "C1D17"
					( Origin gFrontEnd )
				)
				( attribute "MATERIAL" "X6S"
					( Origin gFrontEnd )
				)
				( attribute "PACK_TYPE" "0402"
					( Origin gFrontEnd )
				)
				( attribute "PART_NUMBER" "D97712-011"
					( Origin gFrontEnd )
				)
				( attribute "PHYS_PAGE" "208"
					( Origin gFrontEnd )
				)
				( attribute "ROOM" "PVCCIN_CPU1_PWR_VR"
					( Origin gFrontEnd )
				)
				( attribute "ROT" "0"
					( Origin gFrontEnd )
				)
				( attribute "SEC" "1"
					( Origin gFrontEnd )
				)
				( attribute "SEC_TYPE" "0402"
					( Origin gFrontEnd )
				)
				( attribute "TOLERANCE" "10%"
					( Origin gFrontEnd )
				)
				( attribute "VALUE" "1.0UF"
					( Origin gFrontEnd )
				)
				( attribute "VER" "1"
					( Origin gFrontEnd )
				)
				( attribute "VOLTAGE" "16V"
					( Units "uVoltage" "V" 1.000000)
					( Origin gFrontEnd )
				)
				( attribute "XY" "(-5500,4150)"
					( Origin gFrontEnd )
				)
				( attribute "CHIPS_PART_NAME" "CAP"
					( Origin gPackager )
				)
				( attribute "CDS_PART_NAME" "CAP_0402-1.0UF,16V,10%,X6S,D97A"
					( Origin gPackager )
				)
				( objectStatus "C1D17" )
			)
			( gate "@baseboard_fab2_lib.baseboard_fab2(sch_1):page208_i44"
				( attribute "CDS_LIB" "dev_discrete"
					( Origin gPackager )
				)
				( attribute "CDS_LOCATION" "C1D28"
					( Origin gPackager )
				)
				( attribute "CDS_SEC" "1"
					( Origin gPackager )
				)
				( attribute "LOCATION" "C1D28"
					( Origin gFrontEnd )
				)
				( attribute "MATERIAL" "X7R"
					( Origin gFrontEnd )
				)
				( attribute "PACK_TYPE" "0402V"
					( Origin gFrontEnd )
				)
				( attribute "PART_NUMBER" "A36096-030"
					( Origin gFrontEnd )
				)
				( attribute "PHYS_PAGE" "208"
					( Origin gFrontEnd )
				)
				( attribute "ROOM" "PVCCIN_CPU1_PWR_VR"
					( Origin gFrontEnd )
				)
				( attribute "ROT" "0"
					( Origin gFrontEnd )
				)
				( attribute "SEC" "1"
					( Origin gFrontEnd )
				)
				( attribute "SEC_TYPE" "0402V"
					( Origin gFrontEnd )
				)
				( attribute "TOLERANCE" "10%"
					( Origin gFrontEnd )
				)
				( attribute "VALUE" "0.1UF"
					( Origin gFrontEnd )
				)
				( attribute "VER" "1"
					( Origin gFrontEnd )
				)
				( attribute "VOLTAGE" "16V"
					( Units "uVoltage" "V" 1.000000)
					( Origin gFrontEnd )
				)
				( attribute "XY" "(-5775,4150)"
					( Origin gFrontEnd )
				)
				( attribute "CHIPS_PART_NAME" "CAP_A"
					( Origin gPackager )
				)
				( attribute "CDS_PART_NAME" "CAP_A_0402V-0.1UF,16V,10%,X7R,A"
					( Origin gPackager )
				)
				( objectStatus "C1D28" )
			)
			( gate "@baseboard_fab2_lib.baseboard_fab2(sch_1):page208_i45"
				( attribute "CDS_LIB" "mstr_discrete"
					( Origin gPackager )
				)
				( attribute "CDS_LOCATION" "C1D23"
					( Origin gPackager )
				)
				( attribute "CDS_SEC" "1"
					( Origin gPackager )
				)
				( attribute "LOCATION" "C1D23"
					( Origin gFrontEnd )
				)
				( attribute "MATERIAL" "X6S"
					( Origin gFrontEnd )
				)
				( attribute "PACK_TYPE" "0402"
					( Origin gFrontEnd )
				)
				( attribute "PART_NUMBER" "D97712-011"
					( Origin gFrontEnd )
				)
				( attribute "PHYS_PAGE" "208"
					( Origin gFrontEnd )
				)
				( attribute "ROOM" "PVCCIN_CPU1_PWR_VR"
					( Origin gFrontEnd )
				)
				( attribute "ROT" "0"
					( Origin gFrontEnd )
				)
				( attribute "SEC" "1"
					( Origin gFrontEnd )
				)
				( attribute "SEC_TYPE" "0402"
					( Origin gFrontEnd )
				)
				( attribute "TOLERANCE" "10%"
					( Origin gFrontEnd )
				)
				( attribute "VALUE" "1.0UF"
					( Origin gFrontEnd )
				)
				( attribute "VER" "1"
					( Origin gFrontEnd )
				)
				( attribute "VOLTAGE" "16V"
					( Units "uVoltage" "V" 1.000000)
					( Origin gFrontEnd )
				)
				( attribute "XY" "(-6025,4150)"
					( Origin gFrontEnd )
				)
				( attribute "CHIPS_PART_NAME" "CAP"
					( Origin gPackager )
				)
				( attribute "CDS_PART_NAME" "CAP_0402-1.0UF,16V,10%,X6S,D97A"
					( Origin gPackager )
				)
				( objectStatus "C1D23" )
			)
			( gate "@baseboard_fab2_lib.baseboard_fab2(sch_1):page208_i46"
				( attribute "CDS_LIB" "mstr_discrete"
					( Origin gPackager )
				)
				( attribute "CDS_LOCATION" "C1D6"
					( Origin gPackager )
				)
				( attribute "CDS_SEC" "1"
					( Origin gPackager )
				)
				( attribute "LOCATION" "C1D6"
					( Origin gFrontEnd )
				)
				( attribute "MATERIAL" "X7R"
					( Origin gFrontEnd )
				)
				( attribute "PACK_TYPE" "0402"
					( Origin gFrontEnd )
				)
				( attribute "PART_NUMBER" "A36096-155"
					( Origin gFrontEnd )
				)
				( attribute "PHYS_PAGE" "208"
					( Origin gFrontEnd )
				)
				( attribute "ROOM" "PVCCIN_CPU1_PWR_VR"
					( Origin gFrontEnd )
				)
				( attribute "ROT" "0"
					( Origin gFrontEnd )
				)
				( attribute "SEC" "1"
					( Origin gFrontEnd )
				)
				( attribute "SEC_TYPE" "0402"
					( Origin gFrontEnd )
				)
				( attribute "TOLERANCE" "10%"
					( Origin gFrontEnd )
				)
				( attribute "VALUE" "0.22UF"
					( Origin gFrontEnd )
				)
				( attribute "VER" "1"
					( Origin gFrontEnd )
				)
				( attribute "VOLTAGE" "16V"
					( Units "uVoltage" "V" 1.000000)
					( Origin gFrontEnd )
				)
				( attribute "XY" "(-4800,1575)"
					( Origin gFrontEnd )
				)
				( attribute "CHIPS_PART_NAME" "CAP"
					( Origin gPackager )
				)
				( attribute "CDS_PART_NAME" "CAP_0402-0.22UF,16V,10%,X7R,A3A"
					( Origin gPackager )
				)
				( objectStatus "C1D6" )
			)
			( gate "@baseboard_fab2_lib.baseboard_fab2(sch_1):page207_i109"
				( attribute "CDS_LIB" "w_hdl"
					( Origin gPackager )
				)
				( attribute "CDS_LMAN_SYM_OUTLINE" "-50,25,50,-25"
					( Origin gPackager )
				)
				( attribute "LOCATION" "C1E23"
					( Origin gFrontEnd )
				)
				( attribute "PACK_TYPE" "SMD-BCG6"
					( Origin gFrontEnd )
				)
				( attribute "PART_NUMBER" "78.10523.8FL"
					( Origin gFrontEnd )
				)
				( attribute "PHYS_PAGE" "207"
					( Origin gFrontEnd )
				)
				( attribute "ROT" "0"
					( Origin gFrontEnd )
				)
				( attribute "SEC" "1"
					( Origin gFrontEnd )
				)
				( attribute "SEC_TYPE" "SMD-BCG6"
					( Origin gFrontEnd )
				)
				( attribute "VALUE" "SC1U10V2KX-4-GP"
					( Origin gFrontEnd )
				)
				( attribute "VER" "1"
					( Origin gFrontEnd )
				)
				( attribute "XY" "(-5000,1575)"
					( Origin gFrontEnd )
				)
				( attribute "CHIPS_PART_NAME" "SC1U10V2KX-4-GP"
					( Origin gPackager )
				)
				( attribute "CDS_PART_NAME" "SC1U10V2KX-4-GP_SMD-BCG6-SC1U1A"
					( Origin gPackager )
				)
				( attribute "CDS_LOCATION" "C1E23"
					( Origin gPackager )
				)
				( attribute "CDS_SEC" "1"
					( Origin gPackager )
				)
				( attribute "ATTRIBUTE" "1UF"
					( Origin gFrontEnd )
				)
				( attribute "PACK_SIZE" "0402"
					( Origin gFrontEnd )
				)
				( attribute "RATED" "10V"
					( Origin gFrontEnd )
				)
				( attribute "TOLERANCE" "10%"
					( Origin gFrontEnd )
				)
				( objectStatus "C1E23" )
			)
			( gate "@baseboard_fab2_lib.baseboard_fab2(sch_1):page208_i48"
				( attribute "CDS_LIB" "mstr_discrete"
					( Origin gPackager )
				)
				( attribute "CDS_LOCATION" "C1D10"
					( Origin gPackager )
				)
				( attribute "CDS_SEC" "1"
					( Origin gPackager )
				)
				( attribute "LOCATION" "C1D10"
					( Origin gFrontEnd )
				)
				( attribute "MATERIAL" "X7R"
					( Origin gFrontEnd )
				)
				( attribute "NO_XNET_CONNECTION" "1"
					( Origin gFrontEnd )
				)
				( attribute "PACK_TYPE" "0402"
					( Origin gFrontEnd )
				)
				( attribute "PART_NUMBER" "A36096-104"
					( Origin gFrontEnd )
				)
				( attribute "PHYS_PAGE" "208"
					( Origin gFrontEnd )
				)
				( attribute "ROOM" "PVCCIN_CPU1_PWR_VR"
					( Origin gFrontEnd )
				)
				( attribute "ROT" "2"
					( Origin gFrontEnd )
				)
				( attribute "SEC" "1"
					( Origin gFrontEnd )
				)
				( attribute "SEC_TYPE" "0402"
					( Origin gFrontEnd )
				)
				( attribute "SPOF" "TRUE"
					( Origin gFrontEnd )
				)
				( attribute "TOLERANCE" "10%"
					( Origin gFrontEnd )
				)
				( attribute "VALUE" "0.220UF"
					( Origin gFrontEnd )
				)
				( attribute "VER" "1"
					( Origin gFrontEnd )
				)
				( attribute "VOLTAGE" "16V"
					( Units "uVoltage" "V" 1.000000)
					( Origin gFrontEnd )
				)
				( attribute "XY" "(-5975,900)"
					( Origin gFrontEnd )
				)
				( attribute "CHIPS_PART_NAME" "CAP"
					( Origin gPackager )
				)
				( attribute "CDS_PART_NAME" "CAP_0402-0.220UF,16V,10%,X7R,AA"
					( Origin gPackager )
				)
				( objectStatus "C1D10" )
			)
			( gate "@baseboard_fab2_lib.baseboard_fab2(sch_1):page209_i79"
				( attribute "BOM_COST" "PROC_SIDEBAND"
					( Origin gFrontEnd )
				)
				( attribute "CDS_LIB" "mstr_discrete"
					( Origin gPackager )
				)
				( attribute "CDS_LOCATION" "R9P32"
					( Origin gPackager )
				)
				( attribute "CDS_SEC" "1"
					( Origin gPackager )
				)
				( attribute "LOCATION" "R9P32"
					( Origin gFrontEnd )
				)
				( attribute "MATERIAL" "CHIP"
					( Origin gFrontEnd )
				)
				( attribute "PACK_TYPE" "0402"
					( Origin gFrontEnd )
				)
				( attribute "PART_NUMBER" "G21497-005"
					( Origin gFrontEnd )
				)
				( attribute "PHYS_PAGE" "209"
					( Origin gFrontEnd )
				)
				( attribute "ROOM" "CPU0"
					( Origin gFrontEnd )
				)
				( attribute "ROT" "0"
					( Origin gFrontEnd )
				)
				( attribute "SEC" "1"
					( Origin gFrontEnd )
				)
				( attribute "SEC_TYPE" "0402"
					( Origin gFrontEnd )
				)
				( attribute "TOLERANCE" "5%"
					( Origin gFrontEnd )
				)
				( attribute "VALUE" "0.0"
					( Origin gFrontEnd )
				)
				( attribute "VER" "1"
					( Origin gFrontEnd )
				)
				( attribute "WATTAGE" "1/16W"
					( Origin gFrontEnd )
				)
				( attribute "XY" "(-5425,4650)"
					( Origin gFrontEnd )
				)
				( attribute "CHIPS_PART_NAME" "RES"
					( Origin gPackager )
				)
				( attribute "CDS_PART_NAME" "RES_0402-0.0,5%,1/16W,CHIP,G21A"
					( Origin gPackager )
				)
				( objectStatus "R9P32" )
			)
			( gate "@baseboard_fab2_lib.baseboard_fab2(sch_1):page208_i50"
				( attribute "CDS_LIB" "mstr_discrete"
					( Origin gPackager )
				)
				( attribute "CDS_LOCATION" "C1D7"
					( Origin gPackager )
				)
				( attribute "CDS_SEC" "1"
					( Origin gPackager )
				)
				( attribute "LOCATION" "C1D7"
					( Origin gFrontEnd )
				)
				( attribute "MATERIAL" "X6S"
					( Origin gFrontEnd )
				)
				( attribute "PACK_TYPE" "0402"
					( Origin gFrontEnd )
				)
				( attribute "PART_NUMBER" "D97712-011"
					( Origin gFrontEnd )
				)
				( attribute "PHYS_PAGE" "208"
					( Origin gFrontEnd )
				)
				( attribute "ROOM" "PVCCIN_CPU1_PWR_VR"
					( Origin gFrontEnd )
				)
				( attribute "ROT" "0"
					( Origin gFrontEnd )
				)
				( attribute "SEC" "1"
					( Origin gFrontEnd )
				)
				( attribute "SEC_TYPE" "0402"
					( Origin gFrontEnd )
				)
				( attribute "TOLERANCE" "10%"
					( Origin gFrontEnd )
				)
				( attribute "VALUE" "1.0UF"
					( Origin gFrontEnd )
				)
				( attribute "VER" "1"
					( Origin gFrontEnd )
				)
				( attribute "VOLTAGE" "16V"
					( Units "uVoltage" "V" 1.000000)
					( Origin gFrontEnd )
				)
				( attribute "XY" "(-5700,1575)"
					( Origin gFrontEnd )
				)
				( attribute "CHIPS_PART_NAME" "CAP"
					( Origin gPackager )
				)
				( attribute "CDS_PART_NAME" "CAP_0402-1.0UF,16V,10%,X6S,D97A"
					( Origin gPackager )
				)
				( objectStatus "C1D7" )
			)
			( gate "@baseboard_fab2_lib.baseboard_fab2(sch_1):page208_i51"
				( attribute "CDS_LIB" "dev_discrete"
					( Origin gPackager )
				)
				( attribute "CDS_LOCATION" "C1D13"
					( Origin gPackager )
				)
				( attribute "CDS_SEC" "1"
					( Origin gPackager )
				)
				( attribute "LOCATION" "C1D13"
					( Origin gFrontEnd )
				)
				( attribute "MATERIAL" "X7R"
					( Origin gFrontEnd )
				)
				( attribute "PACK_TYPE" "0402V"
					( Origin gFrontEnd )
				)
				( attribute "PART_NUMBER" "A36096-030"
					( Origin gFrontEnd )
				)
				( attribute "PHYS_PAGE" "208"
					( Origin gFrontEnd )
				)
				( attribute "ROOM" "PVCCIN_CPU1_PWR_VR"
					( Origin gFrontEnd )
				)
				( attribute "ROT" "0"
					( Origin gFrontEnd )
				)
				( attribute "SEC" "1"
					( Origin gFrontEnd )
				)
				( attribute "SEC_TYPE" "0402V"
					( Origin gFrontEnd )
				)
				( attribute "TOLERANCE" "10%"
					( Origin gFrontEnd )
				)
				( attribute "VALUE" "0.1UF"
					( Origin gFrontEnd )
				)
				( attribute "VER" "1"
					( Origin gFrontEnd )
				)
				( attribute "VOLTAGE" "16V"
					( Units "uVoltage" "V" 1.000000)
					( Origin gFrontEnd )
				)
				( attribute "XY" "(-5950,1575)"
					( Origin gFrontEnd )
				)
				( attribute "CHIPS_PART_NAME" "CAP_A"
					( Origin gPackager )
				)
				( attribute "CDS_PART_NAME" "CAP_A_0402V-0.1UF,16V,10%,X7R,A"
					( Origin gPackager )
				)
				( objectStatus "C1D13" )
			)
			( gate "@baseboard_fab2_lib.baseboard_fab2(sch_1):page208_i52"
				( attribute "CDS_LIB" "mstr_discrete"
					( Origin gPackager )
				)
				( attribute "CDS_LOCATION" "C1D12"
					( Origin gPackager )
				)
				( attribute "CDS_SEC" "1"
					( Origin gPackager )
				)
				( attribute "LOCATION" "C1D12"
					( Origin gFrontEnd )
				)
				( attribute "MATERIAL" "X6S"
					( Origin gFrontEnd )
				)
				( attribute "PACK_TYPE" "0402"
					( Origin gFrontEnd )
				)
				( attribute "PART_NUMBER" "D97712-011"
					( Origin gFrontEnd )
				)
				( attribute "PHYS_PAGE" "208"
					( Origin gFrontEnd )
				)
				( attribute "ROOM" "PVCCIN_CPU1_PWR_VR"
					( Origin gFrontEnd )
				)
				( attribute "ROT" "0"
					( Origin gFrontEnd )
				)
				( attribute "SEC" "1"
					( Origin gFrontEnd )
				)
				( attribute "SEC_TYPE" "0402"
					( Origin gFrontEnd )
				)
				( attribute "TOLERANCE" "10%"
					( Origin gFrontEnd )
				)
				( attribute "VALUE" "1.0UF"
					( Origin gFrontEnd )
				)
				( attribute "VER" "1"
					( Origin gFrontEnd )
				)
				( attribute "VOLTAGE" "16V"
					( Units "uVoltage" "V" 1.000000)
					( Origin gFrontEnd )
				)
				( attribute "XY" "(-6250,1575)"
					( Origin gFrontEnd )
				)
				( attribute "CHIPS_PART_NAME" "CAP"
					( Origin gPackager )
				)
				( attribute "CDS_PART_NAME" "CAP_0402-1.0UF,16V,10%,X6S,D97A"
					( Origin gPackager )
				)
				( objectStatus "C1D12" )
			)
			( gate "@baseboard_fab2_lib.baseboard_fab2(sch_1):page208_i53"
				( attribute "CDS_LIB" "mstr_discrete"
					( Origin gPackager )
				)
				( attribute "CDS_LOCATION" "C9P4"
					( Origin gPackager )
				)
				( attribute "CDS_SEC" "1"
					( Origin gPackager )
				)
				( attribute "LOCATION" "C9P4"
					( Origin gFrontEnd )
				)
				( attribute "MATERIAL" "X6S"
					( Origin gFrontEnd )
				)
				( attribute "PACK_TYPE" "0805"
					( Origin gFrontEnd )
				)
				( attribute "PART_NUMBER" "C95333-007"
					( Origin gFrontEnd )
				)
				( attribute "PHYS_PAGE" "208"
					( Origin gFrontEnd )
				)
				( attribute "ROOM" "PVCCIN_CPU1_PWR_VR"
					( Origin gFrontEnd )
				)
				( attribute "ROT" "0"
					( Origin gFrontEnd )
				)
				( attribute "SEC" "1"
					( Origin gFrontEnd )
				)
				( attribute "SEC_TYPE" "0805"
					( Origin gFrontEnd )
				)
				( attribute "TOLERANCE" "10%"
					( Origin gFrontEnd )
				)
				( attribute "VALUE" "10UF"
					( Origin gFrontEnd )
				)
				( attribute "VER" "1"
					( Origin gFrontEnd )
				)
				( attribute "VOLTAGE" "16V"
					( Units "uVoltage" "V" 1.000000)
					( Origin gFrontEnd )
				)
				( attribute "XY" "(-6275,4150)"
					( Origin gFrontEnd )
				)
				( attribute "CHIPS_PART_NAME" "CAP"
					( Origin gPackager )
				)
				( attribute "CDS_PART_NAME" "CAP_0805-10UF,16V,10%,X6S,C953A"
					( Origin gPackager )
				)
				( objectStatus "C9P4" )
			)
			( gate "@baseboard_fab2_lib.baseboard_fab2(sch_1):page208_i54"
				( attribute "CDS_LIB" "mstr_discrete"
					( Origin gPackager )
				)
				( attribute "CDS_LOCATION" "C9P7"
					( Origin gPackager )
				)
				( attribute "CDS_SEC" "1"
					( Origin gPackager )
				)
				( attribute "LOCATION" "C9P7"
					( Origin gFrontEnd )
				)
				( attribute "MATERIAL" "X6S"
					( Origin gFrontEnd )
				)
				( attribute "PACK_TYPE" "0805"
					( Origin gFrontEnd )
				)
				( attribute "PART_NUMBER" "C95333-007"
					( Origin gFrontEnd )
				)
				( attribute "PHYS_PAGE" "208"
					( Origin gFrontEnd )
				)
				( attribute "ROOM" "PVCCIN_CPU1_PWR_VR"
					( Origin gFrontEnd )
				)
				( attribute "ROT" "0"
					( Origin gFrontEnd )
				)
				( attribute "SEC" "1"
					( Origin gFrontEnd )
				)
				( attribute "SEC_TYPE" "0805"
					( Origin gFrontEnd )
				)
				( attribute "TOLERANCE" "10%"
					( Origin gFrontEnd )
				)
				( attribute "VALUE" "10UF"
					( Origin gFrontEnd )
				)
				( attribute "VER" "1"
					( Origin gFrontEnd )
				)
				( attribute "VOLTAGE" "16V"
					( Units "uVoltage" "V" 1.000000)
					( Origin gFrontEnd )
				)
				( attribute "XY" "(-6550,4150)"
					( Origin gFrontEnd )
				)
				( attribute "CHIPS_PART_NAME" "CAP"
					( Origin gPackager )
				)
				( attribute "CDS_PART_NAME" "CAP_0805-10UF,16V,10%,X6S,C953A"
					( Origin gPackager )
				)
				( objectStatus "C9P7" )
			)
			( gate "@baseboard_fab2_lib.baseboard_fab2(sch_1):page208_i55"
				( attribute "CDS_LIB" "mstr_discrete"
					( Origin gPackager )
				)
				( attribute "CDS_LOCATION" "C9P9"
					( Origin gPackager )
				)
				( attribute "CDS_SEC" "1"
					( Origin gPackager )
				)
				( attribute "LOCATION" "C9P9"
					( Origin gFrontEnd )
				)
				( attribute "MATERIAL" "X6S"
					( Origin gFrontEnd )
				)
				( attribute "PACK_TYPE" "0805"
					( Origin gFrontEnd )
				)
				( attribute "PART_NUMBER" "C95333-007"
					( Origin gFrontEnd )
				)
				( attribute "PHYS_PAGE" "208"
					( Origin gFrontEnd )
				)
				( attribute "ROOM" "PVCCIN_CPU1_PWR_VR"
					( Origin gFrontEnd )
				)
				( attribute "ROT" "0"
					( Origin gFrontEnd )
				)
				( attribute "SEC" "1"
					( Origin gFrontEnd )
				)
				( attribute "SEC_TYPE" "0805"
					( Origin gFrontEnd )
				)
				( attribute "TOLERANCE" "10%"
					( Origin gFrontEnd )
				)
				( attribute "VALUE" "10UF"
					( Origin gFrontEnd )
				)
				( attribute "VER" "1"
					( Origin gFrontEnd )
				)
				( attribute "VOLTAGE" "16V"
					( Units "uVoltage" "V" 1.000000)
					( Origin gFrontEnd )
				)
				( attribute "XY" "(-6875,4150)"
					( Origin gFrontEnd )
				)
				( attribute "CHIPS_PART_NAME" "CAP"
					( Origin gPackager )
				)
				( attribute "CDS_PART_NAME" "CAP_0805-10UF,16V,10%,X6S,C953A"
					( Origin gPackager )
				)
				( objectStatus "C9P9" )
			)
			( gate "@baseboard_fab2_lib.baseboard_fab2(sch_1):page208_i58"
				( attribute "CDS_LIB" "mstr_discrete"
					( Origin gPackager )
				)
				( attribute "CDS_LOCATION" "C9P24"
					( Origin gPackager )
				)
				( attribute "CDS_SEC" "1"
					( Origin gPackager )
				)
				( attribute "LOCATION" "C9P24"
					( Origin gFrontEnd )
				)
				( attribute "MATERIAL" "X6S"
					( Origin gFrontEnd )
				)
				( attribute "PACK_TYPE" "0805"
					( Origin gFrontEnd )
				)
				( attribute "PART_NUMBER" "C95333-007"
					( Origin gFrontEnd )
				)
				( attribute "PHYS_PAGE" "208"
					( Origin gFrontEnd )
				)
				( attribute "ROOM" "PVCCIN_CPU1_PWR_VR"
					( Origin gFrontEnd )
				)
				( attribute "ROT" "0"
					( Origin gFrontEnd )
				)
				( attribute "SEC" "1"
					( Origin gFrontEnd )
				)
				( attribute "SEC_TYPE" "0805"
					( Origin gFrontEnd )
				)
				( attribute "TOLERANCE" "10%"
					( Origin gFrontEnd )
				)
				( attribute "VALUE" "10UF"
					( Origin gFrontEnd )
				)
				( attribute "VER" "1"
					( Origin gFrontEnd )
				)
				( attribute "VOLTAGE" "16V"
					( Units "uVoltage" "V" 1.000000)
					( Origin gFrontEnd )
				)
				( attribute "XY" "(-6500,1575)"
					( Origin gFrontEnd )
				)
				( attribute "CHIPS_PART_NAME" "CAP"
					( Origin gPackager )
				)
				( attribute "CDS_PART_NAME" "CAP_0805-10UF,16V,10%,X6S,C953A"
					( Origin gPackager )
				)
				( objectStatus "C9P24" )
			)
			( gate "@baseboard_fab2_lib.baseboard_fab2(sch_1):page208_i59"
				( attribute "CDS_LIB" "mstr_discrete"
					( Origin gPackager )
				)
				( attribute "CDS_LOCATION" "C9P1"
					( Origin gPackager )
				)
				( attribute "CDS_SEC" "1"
					( Origin gPackager )
				)
				( attribute "LOCATION" "C9P1"
					( Origin gFrontEnd )
				)
				( attribute "MATERIAL" "X6S"
					( Origin gFrontEnd )
				)
				( attribute "PACK_TYPE" "0805"
					( Origin gFrontEnd )
				)
				( attribute "PART_NUMBER" "C95333-007"
					( Origin gFrontEnd )
				)
				( attribute "PHYS_PAGE" "208"
					( Origin gFrontEnd )
				)
				( attribute "ROOM" "PVCCIN_CPU1_PWR_VR"
					( Origin gFrontEnd )
				)
				( attribute "ROT" "0"
					( Origin gFrontEnd )
				)
				( attribute "SEC" "1"
					( Origin gFrontEnd )
				)
				( attribute "SEC_TYPE" "0805"
					( Origin gFrontEnd )
				)
				( attribute "TOLERANCE" "10%"
					( Origin gFrontEnd )
				)
				( attribute "VALUE" "10UF"
					( Origin gFrontEnd )
				)
				( attribute "VER" "1"
					( Origin gFrontEnd )
				)
				( attribute "VOLTAGE" "16V"
					( Units "uVoltage" "V" 1.000000)
					( Origin gFrontEnd )
				)
				( attribute "XY" "(-6800,1575)"
					( Origin gFrontEnd )
				)
				( attribute "CHIPS_PART_NAME" "CAP"
					( Origin gPackager )
				)
				( attribute "CDS_PART_NAME" "CAP_0805-10UF,16V,10%,X6S,C953A"
					( Origin gPackager )
				)
				( objectStatus "C9P1" )
			)
			( gate "@baseboard_fab2_lib.baseboard_fab2(sch_1):page208_i60"
				( attribute "CDS_LIB" "mstr_discrete"
					( Origin gPackager )
				)
				( attribute "CDS_LOCATION" "C9P2"
					( Origin gPackager )
				)
				( attribute "CDS_SEC" "1"
					( Origin gPackager )
				)
				( attribute "LOCATION" "C9P2"
					( Origin gFrontEnd )
				)
				( attribute "MATERIAL" "X6S"
					( Origin gFrontEnd )
				)
				( attribute "PACK_TYPE" "0805"
					( Origin gFrontEnd )
				)
				( attribute "PART_NUMBER" "C95333-007"
					( Origin gFrontEnd )
				)
				( attribute "PHYS_PAGE" "208"
					( Origin gFrontEnd )
				)
				( attribute "ROOM" "PVCCIN_CPU1_PWR_VR"
					( Origin gFrontEnd )
				)
				( attribute "ROT" "0"
					( Origin gFrontEnd )
				)
				( attribute "SEC" "1"
					( Origin gFrontEnd )
				)
				( attribute "SEC_TYPE" "0805"
					( Origin gFrontEnd )
				)
				( attribute "TOLERANCE" "10%"
					( Origin gFrontEnd )
				)
				( attribute "VALUE" "10UF"
					( Origin gFrontEnd )
				)
				( attribute "VER" "1"
					( Origin gFrontEnd )
				)
				( attribute "VOLTAGE" "16V"
					( Units "uVoltage" "V" 1.000000)
					( Origin gFrontEnd )
				)
				( attribute "XY" "(-7050,1575)"
					( Origin gFrontEnd )
				)
				( attribute "CHIPS_PART_NAME" "CAP"
					( Origin gPackager )
				)
				( attribute "CDS_PART_NAME" "CAP_0805-10UF,16V,10%,X6S,C953A"
					( Origin gPackager )
				)
				( objectStatus "C9P2" )
			)
			( gate "@baseboard_fab2_lib.baseboard_fab2(sch_1):page208_i66"
				( attribute "CDS_LIB" "dev_discrete"
					( Origin gPackager )
				)
				( attribute "CDS_LOCATION" "C9P10"
					( Origin gPackager )
				)
				( attribute "CDS_SEC" "1"
					( Origin gPackager )
				)
				( attribute "LOCATION" "C9P10"
					( Origin gFrontEnd )
				)
				( attribute "MATERIAL" "X6S"
					( Origin gFrontEnd )
				)
				( attribute "PACK_TYPE" "0603V"
					( Origin gFrontEnd )
				)
				( attribute "PART_NUMBER" "E15431-004"
					( Origin gFrontEnd )
				)
				( attribute "PHYS_PAGE" "208"
					( Origin gFrontEnd )
				)
				( attribute "ROT" "0"
					( Origin gFrontEnd )
				)
				( attribute "SEC" "1"
					( Origin gFrontEnd )
				)
				( attribute "SEC_TYPE" "0603V"
					( Origin gFrontEnd )
				)
				( attribute "TOLERANCE" "20%"
					( Origin gFrontEnd )
				)
				( attribute "VALUE" "22.0UF"
					( Origin gFrontEnd )
				)
				( attribute "VER" "1"
					( Origin gFrontEnd )
				)
				( attribute "VOLTAGE" "4V"
					( Units "uVoltage" "V" 1.000000)
					( Origin gFrontEnd )
				)
				( attribute "XY" "(-400,3400)"
					( Origin gFrontEnd )
				)
				( attribute "CHIPS_PART_NAME" "CAP_A"
					( Origin gPackager )
				)
				( attribute "CDS_PART_NAME" "CAP_A_0603V-22.0UF,4V,20%,X6S,A"
					( Origin gPackager )
				)
				( attribute "GROUP" "PWR_MLCC_CAP"
					( Origin gFrontEnd )
				)
				( objectStatus "C9P10" )
			)
			( gate "@baseboard_fab2_lib.baseboard_fab2(sch_1):page208_i67"
				( attribute "CDS_LIB" "dev_discrete"
					( Origin gPackager )
				)
				( attribute "CDS_LOCATION" "C9R2"
					( Origin gPackager )
				)
				( attribute "CDS_SEC" "1"
					( Origin gPackager )
				)
				( attribute "LOCATION" "C9R2"
					( Origin gFrontEnd )
				)
				( attribute "MATERIAL" "X6S"
					( Origin gFrontEnd )
				)
				( attribute "PACK_TYPE" "0603V"
					( Origin gFrontEnd )
				)
				( attribute "PART_NUMBER" "E15431-004"
					( Origin gFrontEnd )
				)
				( attribute "PHYS_PAGE" "208"
					( Origin gFrontEnd )
				)
				( attribute "ROT" "0"
					( Origin gFrontEnd )
				)
				( attribute "SEC" "1"
					( Origin gFrontEnd )
				)
				( attribute "SEC_TYPE" "0603V"
					( Origin gFrontEnd )
				)
				( attribute "TOLERANCE" "20%"
					( Origin gFrontEnd )
				)
				( attribute "VALUE" "22.0UF"
					( Origin gFrontEnd )
				)
				( attribute "VER" "1"
					( Origin gFrontEnd )
				)
				( attribute "VOLTAGE" "4V"
					( Units "uVoltage" "V" 1.000000)
					( Origin gFrontEnd )
				)
				( attribute "XY" "(-350,800)"
					( Origin gFrontEnd )
				)
				( attribute "CHIPS_PART_NAME" "CAP_A"
					( Origin gPackager )
				)
				( attribute "CDS_PART_NAME" "CAP_A_0603V-22.0UF,4V,20%,X6S,A"
					( Origin gPackager )
				)
				( attribute "GROUP" "PWR_MLCC_CAP"
					( Origin gFrontEnd )
				)
				( objectStatus "C9R2" )
			)
			( gate "@baseboard_fab2_lib.baseboard_fab2(sch_1):page208_i71"
				( attribute "CDS_LIB" "mstr_discrete"
					( Origin gPackager )
				)
				( attribute "CDS_LOCATION" "EU1D1"
					( Origin gPackager )
				)
				( attribute "LOCATION" "EU1D1"
					( Origin gFrontEnd )
				)
				( attribute "MATERIAL" "IC"
					( Origin gFrontEnd )
				)
				( attribute "PACK_TYPE" "SM"
					( Origin gFrontEnd )
				)
				( attribute "PART_NUMBER" "H73688-001"
					( Origin gFrontEnd )
				)
				( attribute "PHYS_PAGE" "208"
					( Origin gFrontEnd )
				)
				( attribute "ROOM" "PVCCIN_CPU1_PWR_VR"
					( Origin gFrontEnd )
				)
				( attribute "ROT" "0"
					( Origin gFrontEnd )
				)
				( attribute "SEC" "1"
					( Origin gFrontEnd )
				)
				( attribute "SEC_TYPE" "SM"
					( Origin gFrontEnd )
				)
				( attribute "VALUE" "IR35411"
					( Origin gFrontEnd )
				)
				( attribute "VER" "1"
					( Origin gFrontEnd )
				)
				( attribute "XY" "(-3250,1275)"
					( Origin gFrontEnd )
				)
				( attribute "CHIPS_PART_NAME" "IR354XX"
					( Origin gPackager )
				)
				( attribute "CDS_PART_NAME" "IR354XX_SM-IR35411,IC,H73688-0A"
					( Origin gPackager )
				)
				( attribute "CDS_SEC" "1"
					( Origin gPackager )
				)
				( objectStatus "EU1D1" )
			)
			( gate "@baseboard_fab2_lib.baseboard_fab2(sch_1):page208_i75"
				( attribute "CDS_LIB" "mstr_discrete"
					( Origin gPackager )
				)
				( attribute "CDS_LOCATION" "R1D54"
					( Origin gPackager )
				)
				( attribute "CDS_SEC" "1"
					( Origin gPackager )
				)
				( attribute "LOCATION" "R1D54"
					( Origin gFrontEnd )
				)
				( attribute "MATERIAL" "EMPTY"
					( Origin gFrontEnd )
				)
				( attribute "PACK_TYPE" "0402"
					( Origin gFrontEnd )
				)
				( attribute "PART_NUMBER" "G21796-187"
					( Origin gFrontEnd )
				)
				( attribute "PHYS_PAGE" "208"
					( Origin gFrontEnd )
				)
				( attribute "ROT" "0"
					( Origin gFrontEnd )
				)
				( attribute "SEC" "1"
					( Origin gPackager )
				)
				( attribute "TOLERANCE" "1%"
					( Origin gFrontEnd )
				)
				( attribute "VALUE" "68.1K"
					( Origin gFrontEnd )
				)
				( attribute "VER" "2"
					( Origin gFrontEnd )
				)
				( attribute "WATTAGE" "1/16W"
					( Origin gFrontEnd )
				)
				( attribute "XY" "(-625,1450)"
					( Origin gFrontEnd )
				)
				( attribute "CHIPS_PART_NAME" "RES"
					( Origin gPackager )
				)
				( attribute "CDS_PART_NAME" "RES_0402-68.1K,1%,1/16W,EMPTY,A"
					( Origin gPackager )
				)
				( objectStatus "R1D54" )
			)
			( gate "@baseboard_fab2_lib.baseboard_fab2(sch_1):page208_i76"
				( attribute "CDS_LIB" "mstr_discrete"
					( Origin gPackager )
				)
				( attribute "CDS_LOCATION" "R1D55"
					( Origin gPackager )
				)
				( attribute "CDS_SEC" "1"
					( Origin gPackager )
				)
				( attribute "LOCATION" "R1D55"
					( Origin gFrontEnd )
				)
				( attribute "MATERIAL" "EMPTY"
					( Origin gFrontEnd )
				)
				( attribute "PACK_TYPE" "0402"
					( Origin gFrontEnd )
				)
				( attribute "PART_NUMBER" "G21796-187"
					( Origin gFrontEnd )
				)
				( attribute "PHYS_PAGE" "208"
					( Origin gFrontEnd )
				)
				( attribute "ROT" "0"
					( Origin gFrontEnd )
				)
				( attribute "SEC" "1"
					( Origin gPackager )
				)
				( attribute "TOLERANCE" "1%"
					( Origin gFrontEnd )
				)
				( attribute "VALUE" "68.1K"
					( Origin gFrontEnd )
				)
				( attribute "VER" "2"
					( Origin gFrontEnd )
				)
				( attribute "WATTAGE" "1/16W"
					( Origin gFrontEnd )
				)
				( attribute "XY" "(-700,4075)"
					( Origin gFrontEnd )
				)
				( attribute "CHIPS_PART_NAME" "RES"
					( Origin gPackager )
				)
				( attribute "CDS_PART_NAME" "RES_0402-68.1K,1%,1/16W,EMPTY,A"
					( Origin gPackager )
				)
				( objectStatus "R1D55" )
			)
			( gate "@baseboard_fab2_lib.baseboard_fab2(sch_1):page209_i3"
				( attribute "BOM_COST" "PROC_VRD_VCCIN_CPU0"
					( Origin gFrontEnd )
				)
				( attribute "CDS_LIB" "mstr_discrete"
					( Origin gPackager )
				)
				( attribute "CDS_LOCATION" "R1E5"
					( Origin gPackager )
				)
				( attribute "CDS_SEC" "1"
					( Origin gPackager )
				)
				( attribute "LOCATION" "R1E5"
					( Origin gFrontEnd )
				)
				( attribute "MATERIAL" "EMPTY"
					( Origin gFrontEnd )
				)
				( attribute "PACK_TYPE" "0402"
					( Origin gFrontEnd )
				)
				( attribute "PART_NUMBER" "G21796-026"
					( Origin gFrontEnd )
				)
				( attribute "PHYS_PAGE" "209"
					( Origin gFrontEnd )
				)
				( attribute "ROOM" "PVCCIN_CPU1_VSENSE_VR"
					( Origin gFrontEnd )
				)
				( attribute "ROT" "0"
					( Origin gFrontEnd )
				)
				( attribute "SEC" "1"
					( Origin gPackager )
				)
				( attribute "TOLERANCE" "1%"
					( Origin gFrontEnd )
				)
				( attribute "VALUE" "1.00K"
					( Origin gFrontEnd )
				)
				( attribute "VER" "2"
					( Origin gFrontEnd )
				)
				( attribute "WATTAGE" "1/16W"
					( Origin gFrontEnd )
				)
				( attribute "XY" "(-6300,1700)"
					( Origin gFrontEnd )
				)
				( attribute "CHIPS_PART_NAME" "RES"
					( Origin gPackager )
				)
				( attribute "CDS_PART_NAME" "RES_0402-1.00K,1%,1/16W,EMPTY,A"
					( Origin gPackager )
				)
				( objectStatus "R1E5" )
			)
			( gate "@baseboard_fab2_lib.baseboard_fab2(sch_1):page209_i5"
				( attribute "CDS_LIB" "mstr_discrete"
					( Origin gPackager )
				)
				( attribute "CDS_LOCATION" "C9N27"
					( Origin gPackager )
				)
				( attribute "CDS_SEC" "1"
					( Origin gPackager )
				)
				( attribute "LOCATION" "C9N27"
					( Origin gFrontEnd )
				)
				( attribute "MATERIAL" "X6S"
					( Origin gFrontEnd )
				)
				( attribute "PACK_TYPE" "0805"
					( Origin gFrontEnd )
				)
				( attribute "PART_NUMBER" "C95333-007"
					( Origin gFrontEnd )
				)
				( attribute "PHYS_PAGE" "209"
					( Origin gFrontEnd )
				)
				( attribute "ROOM" "PVCCIN_CPU1_PWR_VR"
					( Origin gFrontEnd )
				)
				( attribute "ROT" "0"
					( Origin gFrontEnd )
				)
				( attribute "SEC" "1"
					( Origin gFrontEnd )
				)
				( attribute "SEC_TYPE" "0805"
					( Origin gFrontEnd )
				)
				( attribute "TOLERANCE" "10%"
					( Origin gFrontEnd )
				)
				( attribute "VALUE" "10UF"
					( Origin gFrontEnd )
				)
				( attribute "VER" "1"
					( Origin gFrontEnd )
				)
				( attribute "VOLTAGE" "16V"
					( Units "uVoltage" "V" 1.000000)
					( Origin gFrontEnd )
				)
				( attribute "XY" "(-7125,4025)"
					( Origin gFrontEnd )
				)
				( attribute "CHIPS_PART_NAME" "CAP"
					( Origin gPackager )
				)
				( attribute "CDS_PART_NAME" "CAP_0805-10UF,16V,10%,X6S,C953A"
					( Origin gPackager )
				)
				( objectStatus "C9N27" )
			)
			( gate "@baseboard_fab2_lib.baseboard_fab2(sch_1):page209_i7"
				( attribute "CDS_LIB" "mstr_discrete"
					( Origin gPackager )
				)
				( attribute "CDS_LOCATION" "C9N26"
					( Origin gPackager )
				)
				( attribute "CDS_SEC" "1"
					( Origin gPackager )
				)
				( attribute "LOCATION" "C9N26"
					( Origin gFrontEnd )
				)
				( attribute "MATERIAL" "X6S"
					( Origin gFrontEnd )
				)
				( attribute "PACK_TYPE" "0805"
					( Origin gFrontEnd )
				)
				( attribute "PART_NUMBER" "C95333-007"
					( Origin gFrontEnd )
				)
				( attribute "PHYS_PAGE" "209"
					( Origin gFrontEnd )
				)
				( attribute "ROOM" "PVCCIN_CPU1_PWR_VR"
					( Origin gFrontEnd )
				)
				( attribute "ROT" "0"
					( Origin gFrontEnd )
				)
				( attribute "SEC" "1"
					( Origin gFrontEnd )
				)
				( attribute "SEC_TYPE" "0805"
					( Origin gFrontEnd )
				)
				( attribute "TOLERANCE" "10%"
					( Origin gFrontEnd )
				)
				( attribute "VALUE" "10UF"
					( Origin gFrontEnd )
				)
				( attribute "VER" "1"
					( Origin gFrontEnd )
				)
				( attribute "VOLTAGE" "16V"
					( Units "uVoltage" "V" 1.000000)
					( Origin gFrontEnd )
				)
				( attribute "XY" "(-6850,4025)"
					( Origin gFrontEnd )
				)
				( attribute "CHIPS_PART_NAME" "CAP"
					( Origin gPackager )
				)
				( attribute "CDS_PART_NAME" "CAP_0805-10UF,16V,10%,X6S,C953A"
					( Origin gPackager )
				)
				( objectStatus "C9N26" )
			)
			( gate "@baseboard_fab2_lib.baseboard_fab2(sch_1):page209_i8"
				( attribute "CDS_LIB" "mstr_discrete"
					( Origin gPackager )
				)
				( attribute "CDS_LOCATION" "C9N25"
					( Origin gPackager )
				)
				( attribute "CDS_SEC" "1"
					( Origin gPackager )
				)
				( attribute "LOCATION" "C9N25"
					( Origin gFrontEnd )
				)
				( attribute "MATERIAL" "X6S"
					( Origin gFrontEnd )
				)
				( attribute "PACK_TYPE" "0805"
					( Origin gFrontEnd )
				)
				( attribute "PART_NUMBER" "C95333-007"
					( Origin gFrontEnd )
				)
				( attribute "PHYS_PAGE" "209"
					( Origin gFrontEnd )
				)
				( attribute "ROOM" "PVCCIN_CPU1_PWR_VR"
					( Origin gFrontEnd )
				)
				( attribute "ROT" "0"
					( Origin gFrontEnd )
				)
				( attribute "SEC" "1"
					( Origin gFrontEnd )
				)
				( attribute "SEC_TYPE" "0805"
					( Origin gFrontEnd )
				)
				( attribute "TOLERANCE" "10%"
					( Origin gFrontEnd )
				)
				( attribute "VALUE" "10UF"
					( Origin gFrontEnd )
				)
				( attribute "VER" "1"
					( Origin gFrontEnd )
				)
				( attribute "VOLTAGE" "16V"
					( Units "uVoltage" "V" 1.000000)
					( Origin gFrontEnd )
				)
				( attribute "XY" "(-6550,4025)"
					( Origin gFrontEnd )
				)
				( attribute "CHIPS_PART_NAME" "CAP"
					( Origin gPackager )
				)
				( attribute "CDS_PART_NAME" "CAP_0805-10UF,16V,10%,X6S,C953A"
					( Origin gPackager )
				)
				( objectStatus "C9N25" )
			)
			( gate "@baseboard_fab2_lib.baseboard_fab2(sch_1):page209_i9"
				( attribute "BOM_COST" "PROC_VRD_VCCIN_CPU0"
					( Origin gFrontEnd )
				)
				( attribute "CDS_LIB" "mstr_discrete"
					( Origin gPackager )
				)
				( attribute "CDS_LOCATION" "R1E8"
					( Origin gPackager )
				)
				( attribute "CDS_SEC" "1"
					( Origin gPackager )
				)
				( attribute "LOCATION" "R1E8"
					( Origin gFrontEnd )
				)
				( attribute "MATERIAL" "CHIP"
					( Origin gFrontEnd )
				)
				( attribute "PACK_TYPE" "0402"
					( Origin gFrontEnd )
				)
				( attribute "PART_NUMBER" "G21796-017"
					( Origin gFrontEnd )
				)
				( attribute "PHYS_PAGE" "209"
					( Origin gFrontEnd )
				)
				( attribute "ROOM" "PVCCIN_CPU1_VSENSE_VR"
					( Origin gFrontEnd )
				)
				( attribute "ROT" "0"
					( Origin gFrontEnd )
				)
				( attribute "SEC" "1"
					( Origin gPackager )
				)
				( attribute "TOLERANCE" "1%"
					( Origin gFrontEnd )
				)
				( attribute "VALUE" "100.0"
					( Origin gFrontEnd )
				)
				( attribute "VER" "1"
					( Origin gFrontEnd )
				)
				( attribute "WATTAGE" "1/16W"
					( Origin gFrontEnd )
				)
				( attribute "XY" "(-5475,1050)"
					( Origin gFrontEnd )
				)
				( attribute "CHIPS_PART_NAME" "RES"
					( Origin gPackager )
				)
				( attribute "CDS_PART_NAME" "RES_0402-100.0,1%,1/16W,CHIP,GA"
					( Origin gPackager )
				)
				( objectStatus "R1E8" )
			)
			( gate "@baseboard_fab2_lib.baseboard_fab2(sch_1):page209_i10"
				( attribute "BOM_COST" "PROC_VRD_VCCIN_CPU0"
					( Origin gFrontEnd )
				)
				( attribute "CDS_LIB" "mstr_discrete"
					( Origin gPackager )
				)
				( attribute "CDS_LOCATION" "R1E7"
					( Origin gPackager )
				)
				( attribute "CDS_SEC" "1"
					( Origin gPackager )
				)
				( attribute "LOCATION" "R1E7"
					( Origin gFrontEnd )
				)
				( attribute "MATERIAL" "CHIP"
					( Origin gFrontEnd )
				)
				( attribute "PACK_TYPE" "0402"
					( Origin gFrontEnd )
				)
				( attribute "PART_NUMBER" "G21497-005"
					( Origin gFrontEnd )
				)
				( attribute "PHYS_PAGE" "209"
					( Origin gFrontEnd )
				)
				( attribute "ROOM" "PVCCIN_CPU1_VSENSE_VR"
					( Origin gFrontEnd )
				)
				( attribute "ROT" "0"
					( Origin gFrontEnd )
				)
				( attribute "SEC" "1"
					( Origin gPackager )
				)
				( attribute "TOLERANCE" "5%"
					( Origin gFrontEnd )
				)
				( attribute "VALUE" "0.0"
					( Origin gFrontEnd )
				)
				( attribute "VER" "1"
					( Origin gFrontEnd )
				)
				( attribute "WATTAGE" "1/16W"
					( Origin gFrontEnd )
				)
				( attribute "XY" "(-5475,1450)"
					( Origin gFrontEnd )
				)
				( attribute "CHIPS_PART_NAME" "RES"
					( Origin gPackager )
				)
				( attribute "CDS_PART_NAME" "RES_0402-0.0,5%,1/16W,CHIP,G21A"
					( Origin gPackager )
				)
				( objectStatus "R1E7" )
			)
			( gate "@baseboard_fab2_lib.baseboard_fab2(sch_1):page209_i11"
				( attribute "BOM_COST" "PROC_VRD_VCCIN_CPU0"
					( Origin gFrontEnd )
				)
				( attribute "CDS_LIB" "mstr_discrete"
					( Origin gPackager )
				)
				( attribute "CDS_LOCATION" "R1E6"
					( Origin gPackager )
				)
				( attribute "CDS_SEC" "1"
					( Origin gPackager )
				)
				( attribute "LOCATION" "R1E6"
					( Origin gFrontEnd )
				)
				( attribute "MATERIAL" "CHIP"
					( Origin gFrontEnd )
				)
				( attribute "PACK_TYPE" "0402"
					( Origin gFrontEnd )
				)
				( attribute "PART_NUMBER" "G21497-005"
					( Origin gFrontEnd )
				)
				( attribute "PHYS_PAGE" "209"
					( Origin gFrontEnd )
				)
				( attribute "ROOM" "PVCCIN_CPU1_VSENSE_VR"
					( Origin gFrontEnd )
				)
				( attribute "ROT" "0"
					( Origin gFrontEnd )
				)
				( attribute "SEC" "1"
					( Origin gPackager )
				)
				( attribute "TOLERANCE" "5%"
					( Origin gFrontEnd )
				)
				( attribute "VALUE" "0.0"
					( Origin gFrontEnd )
				)
				( attribute "VER" "1"
					( Origin gFrontEnd )
				)
				( attribute "WATTAGE" "1/16W"
					( Origin gFrontEnd )
				)
				( attribute "XY" "(-5500,1900)"
					( Origin gFrontEnd )
				)
				( attribute "CHIPS_PART_NAME" "RES"
					( Origin gPackager )
				)
				( attribute "CDS_PART_NAME" "RES_0402-0.0,5%,1/16W,CHIP,G21A"
					( Origin gPackager )
				)
				( objectStatus "R1E6" )
			)
			( gate "@baseboard_fab2_lib.baseboard_fab2(sch_1):page209_i15"
				( attribute "BOM_COST" "PROC_VRD_VCCIN_CPU0"
					( Origin gFrontEnd )
				)
				( attribute "CDS_LIB" "mstr_discrete"
					( Origin gPackager )
				)
				( attribute "CDS_LOCATION" "R1E4"
					( Origin gPackager )
				)
				( attribute "CDS_SEC" "1"
					( Origin gPackager )
				)
				( attribute "LOCATION" "R1E4"
					( Origin gFrontEnd )
				)
				( attribute "MATERIAL" "CHIP"
					( Origin gFrontEnd )
				)
				( attribute "PACK_TYPE" "0402"
					( Origin gFrontEnd )
				)
				( attribute "PART_NUMBER" "G21796-017"
					( Origin gFrontEnd )
				)
				( attribute "PHYS_PAGE" "209"
					( Origin gFrontEnd )
				)
				( attribute "ROOM" "PVCCIN_CPU1_VSENSE_VR"
					( Origin gFrontEnd )
				)
				( attribute "ROT" "0"
					( Origin gFrontEnd )
				)
				( attribute "SEC" "1"
					( Origin gPackager )
				)
				( attribute "TOLERANCE" "1%"
					( Origin gFrontEnd )
				)
				( attribute "VALUE" "100.0"
					( Origin gFrontEnd )
				)
				( attribute "VER" "1"
					( Origin gFrontEnd )
				)
				( attribute "WATTAGE" "1/16W"
					( Origin gFrontEnd )
				)
				( attribute "XY" "(-5500,2300)"
					( Origin gFrontEnd )
				)
				( attribute "CHIPS_PART_NAME" "RES"
					( Origin gPackager )
				)
				( attribute "CDS_PART_NAME" "RES_0402-100.0,1%,1/16W,CHIP,GA"
					( Origin gPackager )
				)
				( objectStatus "R1E4" )
			)
			( gate "@baseboard_fab2_lib.baseboard_fab2(sch_1):page209_i16"
				( attribute "CDS_LIB" "mstr_discrete"
					( Origin gPackager )
				)
				( attribute "CDS_LOCATION" "C1C26"
					( Origin gPackager )
				)
				( attribute "CDS_SEC" "1"
					( Origin gPackager )
				)
				( attribute "LOCATION" "C1C26"
					( Origin gFrontEnd )
				)
				( attribute "MATERIAL" "X6S"
					( Origin gFrontEnd )
				)
				( attribute "PACK_TYPE" "0402"
					( Origin gFrontEnd )
				)
				( attribute "PART_NUMBER" "D97712-011"
					( Origin gFrontEnd )
				)
				( attribute "PHYS_PAGE" "209"
					( Origin gFrontEnd )
				)
				( attribute "ROOM" "PVCCIN_CPU1_PWR_VR"
					( Origin gFrontEnd )
				)
				( attribute "ROT" "0"
					( Origin gFrontEnd )
				)
				( attribute "SEC" "1"
					( Origin gFrontEnd )
				)
				( attribute "SEC_TYPE" "0402"
					( Origin gFrontEnd )
				)
				( attribute "TOLERANCE" "10%"
					( Origin gFrontEnd )
				)
				( attribute "VALUE" "1.0UF"
					( Origin gFrontEnd )
				)
				( attribute "VER" "1"
					( Origin gFrontEnd )
				)
				( attribute "VOLTAGE" "16V"
					( Units "uVoltage" "V" 1.000000)
					( Origin gFrontEnd )
				)
				( attribute "XY" "(-6225,4025)"
					( Origin gFrontEnd )
				)
				( attribute "CHIPS_PART_NAME" "CAP"
					( Origin gPackager )
				)
				( attribute "CDS_PART_NAME" "CAP_0402-1.0UF,16V,10%,X6S,D97A"
					( Origin gPackager )
				)
				( objectStatus "C1C26" )
			)
			( gate "@baseboard_fab2_lib.baseboard_fab2(sch_1):page209_i17"
				( attribute "CDS_LIB" "dev_discrete"
					( Origin gPackager )
				)
				( attribute "CDS_LOCATION" "C1C25"
					( Origin gPackager )
				)
				( attribute "CDS_SEC" "1"
					( Origin gPackager )
				)
				( attribute "LOCATION" "C1C25"
					( Origin gFrontEnd )
				)
				( attribute "MATERIAL" "X7R"
					( Origin gFrontEnd )
				)
				( attribute "PACK_TYPE" "0402V"
					( Origin gFrontEnd )
				)
				( attribute "PART_NUMBER" "A36096-030"
					( Origin gFrontEnd )
				)
				( attribute "PHYS_PAGE" "209"
					( Origin gFrontEnd )
				)
				( attribute "ROOM" "PVCCIN_CPU1_PWR_VR"
					( Origin gFrontEnd )
				)
				( attribute "ROT" "0"
					( Origin gFrontEnd )
				)
				( attribute "SEC" "1"
					( Origin gFrontEnd )
				)
				( attribute "SEC_TYPE" "0402V"
					( Origin gFrontEnd )
				)
				( attribute "TOLERANCE" "10%"
					( Origin gFrontEnd )
				)
				( attribute "VALUE" "0.1UF"
					( Origin gFrontEnd )
				)
				( attribute "VER" "1"
					( Origin gFrontEnd )
				)
				( attribute "VOLTAGE" "16V"
					( Units "uVoltage" "V" 1.000000)
					( Origin gFrontEnd )
				)
				( attribute "XY" "(-5925,4025)"
					( Origin gFrontEnd )
				)
				( attribute "CHIPS_PART_NAME" "CAP_A"
					( Origin gPackager )
				)
				( attribute "CDS_PART_NAME" "CAP_A_0402V-0.1UF,16V,10%,X7R,A"
					( Origin gPackager )
				)
				( objectStatus "C1C25" )
			)
			( gate "@baseboard_fab2_lib.baseboard_fab2(sch_1):page209_i18"
				( attribute "CDS_LIB" "mstr_discrete"
					( Origin gPackager )
				)
				( attribute "CDS_LOCATION" "C1D32"
					( Origin gPackager )
				)
				( attribute "CDS_SEC" "1"
					( Origin gPackager )
				)
				( attribute "LOCATION" "C1D32"
					( Origin gFrontEnd )
				)
				( attribute "MATERIAL" "X6S"
					( Origin gFrontEnd )
				)
				( attribute "PACK_TYPE" "0402"
					( Origin gFrontEnd )
				)
				( attribute "PART_NUMBER" "D97712-011"
					( Origin gFrontEnd )
				)
				( attribute "PHYS_PAGE" "209"
					( Origin gFrontEnd )
				)
				( attribute "ROOM" "PVCCIN_CPU1_PWR_VR"
					( Origin gFrontEnd )
				)
				( attribute "ROT" "0"
					( Origin gFrontEnd )
				)
				( attribute "SEC" "1"
					( Origin gFrontEnd )
				)
				( attribute "SEC_TYPE" "0402"
					( Origin gFrontEnd )
				)
				( attribute "TOLERANCE" "10%"
					( Origin gFrontEnd )
				)
				( attribute "VALUE" "1.0UF"
					( Origin gFrontEnd )
				)
				( attribute "VER" "1"
					( Origin gFrontEnd )
				)
				( attribute "VOLTAGE" "16V"
					( Units "uVoltage" "V" 1.000000)
					( Origin gFrontEnd )
				)
				( attribute "XY" "(-5625,4025)"
					( Origin gFrontEnd )
				)
				( attribute "CHIPS_PART_NAME" "CAP"
					( Origin gPackager )
				)
				( attribute "CDS_PART_NAME" "CAP_0402-1.0UF,16V,10%,X6S,D97A"
					( Origin gPackager )
				)
				( objectStatus "C1D32" )
			)
			( gate "@baseboard_fab2_lib.baseboard_fab2(sch_1):page209_i20"
				( attribute "CDS_LIB" "mstr_discrete"
					( Origin gPackager )
				)
				( attribute "CDS_LOCATION" "C1C24"
					( Origin gPackager )
				)
				( attribute "CDS_SEC" "1"
					( Origin gPackager )
				)
				( attribute "LOCATION" "C1C24"
					( Origin gFrontEnd )
				)
				( attribute "MATERIAL" "X7R"
					( Origin gFrontEnd )
				)
				( attribute "NO_XNET_CONNECTION" "1"
					( Origin gFrontEnd )
				)
				( attribute "PACK_TYPE" "0402"
					( Origin gFrontEnd )
				)
				( attribute "PART_NUMBER" "A36096-104"
					( Origin gFrontEnd )
				)
				( attribute "PHYS_PAGE" "209"
					( Origin gFrontEnd )
				)
				( attribute "ROOM" "PVCCIN_CPU1_PWR_VR"
					( Origin gFrontEnd )
				)
				( attribute "ROT" "2"
					( Origin gFrontEnd )
				)
				( attribute "SEC" "1"
					( Origin gFrontEnd )
				)
				( attribute "SEC_TYPE" "0402"
					( Origin gFrontEnd )
				)
				( attribute "SPOF" "TRUE"
					( Origin gFrontEnd )
				)
				( attribute "TOLERANCE" "10%"
					( Origin gFrontEnd )
				)
				( attribute "VALUE" "0.220UF"
					( Origin gFrontEnd )
				)
				( attribute "VER" "1"
					( Origin gFrontEnd )
				)
				( attribute "VOLTAGE" "16V"
					( Units "uVoltage" "V" 1.000000)
					( Origin gFrontEnd )
				)
				( attribute "XY" "(-5900,3450)"
					( Origin gFrontEnd )
				)
				( attribute "CHIPS_PART_NAME" "CAP"
					( Origin gPackager )
				)
				( attribute "CDS_PART_NAME" "CAP_0402-0.220UF,16V,10%,X7R,AA"
					( Origin gPackager )
				)
				( objectStatus "C1C24" )
			)
			( gate "@baseboard_fab2_lib.baseboard_fab2(sch_1):page227_i147"
				( attribute "CDS_LIB" "w_hdl"
					( Origin gPackager )
				)
				( attribute "CDS_LMAN_SYM_OUTLINE" "-50,25,50,-25"
					( Origin gPackager )
				)
				( attribute "LOCATION" "C1A11"
					( Origin gFrontEnd )
				)
				( attribute "PACK_TYPE" "SMD-BCG6"
					( Origin gFrontEnd )
				)
				( attribute "PART_NUMBER" "78.10523.8FL"
					( Origin gFrontEnd )
				)
				( attribute "PHYS_PAGE" "227"
					( Origin gFrontEnd )
				)
				( attribute "ROT" "0"
					( Origin gFrontEnd )
				)
				( attribute "SEC" "1"
					( Origin gFrontEnd )
				)
				( attribute "SEC_TYPE" "SMD-BCG6"
					( Origin gFrontEnd )
				)
				( attribute "VALUE" "SC1U10V2KX-4-GP"
					( Origin gFrontEnd )
				)
				( attribute "VER" "1"
					( Origin gFrontEnd )
				)
				( attribute "XY" "(-425,225)"
					( Origin gFrontEnd )
				)
				( attribute "CHIPS_PART_NAME" "SC1U10V2KX-4-GP"
					( Origin gPackager )
				)
				( attribute "CDS_PART_NAME" "SC1U10V2KX-4-GP_SMD-BCG6-SC1U1A"
					( Origin gPackager )
				)
				( attribute "CDS_LOCATION" "C1A11"
					( Origin gPackager )
				)
				( attribute "CDS_SEC" "1"
					( Origin gPackager )
				)
				( attribute "ATTRIBUTE" "1UF"
					( Origin gFrontEnd )
				)
				( attribute "PACK_SIZE" "0402"
					( Origin gFrontEnd )
				)
				( attribute "RATED" "10V"
					( Origin gFrontEnd )
				)
				( attribute "TOLERANCE" "10%"
					( Origin gFrontEnd )
				)
				( attribute "BOM_SS" "NOPOP"
					( Origin gFrontEnd )
				)
				( objectStatus "C1A11" )
			)
			( gate "@baseboard_fab2_lib.baseboard_fab2(sch_1):page209_i22"
				( attribute "CDS_LIB" "mstr_discrete"
					( Origin gPackager )
				)
				( attribute "CDS_LOCATION" "C1D33"
					( Origin gPackager )
				)
				( attribute "CDS_SEC" "1"
					( Origin gPackager )
				)
				( attribute "LOCATION" "C1D33"
					( Origin gFrontEnd )
				)
				( attribute "MATERIAL" "X7R"
					( Origin gFrontEnd )
				)
				( attribute "PACK_TYPE" "0402"
					( Origin gFrontEnd )
				)
				( attribute "PART_NUMBER" "A36096-155"
					( Origin gFrontEnd )
				)
				( attribute "PHYS_PAGE" "209"
					( Origin gFrontEnd )
				)
				( attribute "ROOM" "PVCCIN_CPU1_PWR_VR"
					( Origin gFrontEnd )
				)
				( attribute "ROT" "0"
					( Origin gFrontEnd )
				)
				( attribute "SEC" "1"
					( Origin gFrontEnd )
				)
				( attribute "SEC_TYPE" "0402"
					( Origin gFrontEnd )
				)
				( attribute "TOLERANCE" "10%"
					( Origin gFrontEnd )
				)
				( attribute "VALUE" "0.22UF"
					( Origin gFrontEnd )
				)
				( attribute "VER" "1"
					( Origin gFrontEnd )
				)
				( attribute "VOLTAGE" "16V"
					( Units "uVoltage" "V" 1.000000)
					( Origin gFrontEnd )
				)
				( attribute "XY" "(-4800,4025)"
					( Origin gFrontEnd )
				)
				( attribute "CHIPS_PART_NAME" "CAP"
					( Origin gPackager )
				)
				( attribute "CDS_PART_NAME" "CAP_0402-0.22UF,16V,10%,X7R,A3A"
					( Origin gPackager )
				)
				( objectStatus "C1D33" )
			)
			( gate "@baseboard_fab2_lib.baseboard_fab2(sch_1):page210_i71"
				( attribute "BOM_COST" "PROC_SIDEBAND"
					( Origin gFrontEnd )
				)
				( attribute "CDS_LIB" "mstr_discrete"
					( Origin gPackager )
				)
				( attribute "CDS_LOCATION" "R9N3"
					( Origin gPackager )
				)
				( attribute "CDS_SEC" "1"
					( Origin gPackager )
				)
				( attribute "LOCATION" "R9N3"
					( Origin gFrontEnd )
				)
				( attribute "MATERIAL" "CHIP"
					( Origin gFrontEnd )
				)
				( attribute "PACK_TYPE" "0402"
					( Origin gFrontEnd )
				)
				( attribute "PART_NUMBER" "G21497-005"
					( Origin gFrontEnd )
				)
				( attribute "PHYS_PAGE" "210"
					( Origin gFrontEnd )
				)
				( attribute "ROOM" "CPU0"
					( Origin gFrontEnd )
				)
				( attribute "ROT" "0"
					( Origin gFrontEnd )
				)
				( attribute "SEC" "1"
					( Origin gFrontEnd )
				)
				( attribute "SEC_TYPE" "0402"
					( Origin gFrontEnd )
				)
				( attribute "TOLERANCE" "5%"
					( Origin gFrontEnd )
				)
				( attribute "VALUE" "0.0"
					( Origin gFrontEnd )
				)
				( attribute "VER" "1"
					( Origin gFrontEnd )
				)
				( attribute "WATTAGE" "1/16W"
					( Origin gFrontEnd )
				)
				( attribute "XY" "(-5725,4425)"
					( Origin gFrontEnd )
				)
				( attribute "CHIPS_PART_NAME" "RES"
					( Origin gPackager )
				)
				( attribute "CDS_PART_NAME" "RES_0402-0.0,5%,1/16W,CHIP,G21A"
					( Origin gPackager )
				)
				( objectStatus "R9N3" )
			)
			( gate "@baseboard_fab2_lib.baseboard_fab2(sch_1):page133_i370"
				( attribute "CDS_LIB" "mstr_discrete"
					( Origin gPackager )
				)
				( attribute "CDS_LOCATION" "R3P7"
					( Origin gPackager )
				)
				( attribute "CDS_SEC" "1"
					( Origin gPackager )
				)
				( attribute "LOCATION" "R3P7"
					( Origin gFrontEnd )
				)
				( attribute "MATERIAL" "EMPTY"
					( Origin gFrontEnd )
				)
				( attribute "PACK_TYPE" "0402"
					( Origin gFrontEnd )
				)
				( attribute "PART_NUMBER" "G21796-026"
					( Origin gFrontEnd )
				)
				( attribute "PHYS_PAGE" "133"
					( Origin gFrontEnd )
				)
				( attribute "ROOM" "DEBUG"
					( Origin gFrontEnd )
				)
				( attribute "ROT" "3"
					( Origin gFrontEnd )
				)
				( attribute "SEC" "1"
					( Origin gFrontEnd )
				)
				( attribute "SEC_TYPE" "0402"
					( Origin gFrontEnd )
				)
				( attribute "TOLERANCE" "1%"
					( Origin gFrontEnd )
				)
				( attribute "VALUE" "1.00K"
					( Origin gFrontEnd )
				)
				( attribute "VER" "2"
					( Origin gFrontEnd )
				)
				( attribute "WATTAGE" "1/16W"
					( Origin gFrontEnd )
				)
				( attribute "XY" "(-400,5100)"
					( Origin gFrontEnd )
				)
				( attribute "CHIPS_PART_NAME" "RES"
					( Origin gPackager )
				)
				( attribute "CDS_PART_NAME" "RES_0402-1.00K,1%,1/16W,EMPTY,A"
					( Origin gPackager )
				)
				( objectStatus "R3P7" )
			)
			( gate "@baseboard_fab2_lib.baseboard_fab2(sch_1):page217_i261"
				( attribute "CDS_LIB" "w_hdl"
					( Origin gPackager )
				)
				( attribute "CDS_LMAN_SYM_OUTLINE" "-75,100,75,-100"
					( Origin gPackager )
				)
				( attribute "LOCATION" "L7F2"
					( Origin gFrontEnd )
				)
				( attribute "PACK_TYPE" "DISCRET-G8"
					( Origin gFrontEnd )
				)
				( attribute "PART_NUMBER" "068.1011N.M001"
					( Origin gFrontEnd )
				)
				( attribute "PHYS_PAGE" "217"
					( Origin gFrontEnd )
				)
				( attribute "ROT" "1"
					( Origin gFrontEnd )
				)
				( attribute "SEC" "1"
					( Origin gFrontEnd )
				)
				( attribute "SEC_TYPE" "DISCRET-G8"
					( Origin gFrontEnd )
				)
				( attribute "VALUE" "IND-100NH-35-GP"
					( Origin gFrontEnd )
				)
				( attribute "VER" "1"
					( Origin gFrontEnd )
				)
				( attribute "XY" "(-200,925)"
					( Origin gFrontEnd )
				)
				( attribute "CHIPS_PART_NAME" "IND-100NH-35-GP"
					( Origin gPackager )
				)
				( attribute "CDS_PART_NAME" "IND-100NH-35-GP_DISCRET-G8-INDA"
					( Origin gPackager )
				)
				( attribute "CDS_LOCATION" "L7F2"
					( Origin gPackager )
				)
				( attribute "CDS_SEC" "1"
					( Origin gPackager )
				)
				( attribute "ATTRIBUTE" "100NH"
					( Origin gFrontEnd )
				)
				( attribute "PACK_SIZE" "DCR=0.16MOHM"
					( Origin gFrontEnd )
				)
				( attribute "RATED" "ISAT=16A@25C"
					( Origin gFrontEnd )
				)
				( attribute "TYPE" "IRMS=29A@DELTA_T<45C"
					( Origin gFrontEnd )
				)
				( objectStatus "L7F2" )
			)
			( gate "@baseboard_fab2_lib.baseboard_fab2(sch_1):page209_i35"
				( attribute "CDS_LIB" "mstr_discrete"
					( Origin gPackager )
				)
				( attribute "CDS_LOCATION" "C1C1"
					( Origin gPackager )
				)
				( attribute "CDS_SEC" "1"
					( Origin gPackager )
				)
				( attribute "LOCATION" "C1C1"
					( Origin gFrontEnd )
				)
				( attribute "MATERIAL" "OSCON"
					( Origin gFrontEnd )
				)
				( attribute "PACK_TYPE" "2626"
					( Origin gFrontEnd )
				)
				( attribute "PART_NUMBER" "A31228-047"
					( Origin gFrontEnd )
				)
				( attribute "PHYS_PAGE" "209"
					( Origin gFrontEnd )
				)
				( attribute "ROOM" "PVCCIN_CPU1_FILTER_VR"
					( Origin gFrontEnd )
				)
				( attribute "ROT" "0"
					( Origin gFrontEnd )
				)
				( attribute "SEC" "1"
					( Origin gFrontEnd )
				)
				( attribute "SEC_TYPE" "2626"
					( Origin gFrontEnd )
				)
				( attribute "TOLERANCE" "20%"
					( Origin gFrontEnd )
				)
				( attribute "VALUE" "270UF"
					( Origin gFrontEnd )
				)
				( attribute "VER" "1"
					( Origin gFrontEnd )
				)
				( attribute "VOLTAGE" "16V"
					( Units "uVoltage" "V" 1.000000)
					( Origin gFrontEnd )
				)
				( attribute "XY" "(-1425,2075)"
					( Origin gFrontEnd )
				)
				( attribute "CHIPS_PART_NAME" "CAPP"
					( Origin gPackager )
				)
				( attribute "CDS_PART_NAME" "CAPP_2626-270UF,16V,20%,OSCON,A"
					( Origin gPackager )
				)
				( objectStatus "C1C1" )
			)
			( gate "@baseboard_fab2_lib.baseboard_fab2(sch_1):page209_i37"
				( attribute "CDS_LIB" "mstr_discrete"
					( Origin gPackager )
				)
				( attribute "CDS_LOCATION" "C1E18"
					( Origin gPackager )
				)
				( attribute "CDS_SEC" "1"
					( Origin gPackager )
				)
				( attribute "LOCATION" "C1E18"
					( Origin gFrontEnd )
				)
				( attribute "MATERIAL" "OSCON"
					( Origin gFrontEnd )
				)
				( attribute "PACK_TYPE" "2626"
					( Origin gFrontEnd )
				)
				( attribute "PART_NUMBER" "A31228-047"
					( Origin gFrontEnd )
				)
				( attribute "PHYS_PAGE" "209"
					( Origin gFrontEnd )
				)
				( attribute "ROOM" "PVCCIN_CPU1_FILTER_VR"
					( Origin gFrontEnd )
				)
				( attribute "ROT" "0"
					( Origin gFrontEnd )
				)
				( attribute "SEC" "1"
					( Origin gFrontEnd )
				)
				( attribute "SEC_TYPE" "2626"
					( Origin gFrontEnd )
				)
				( attribute "TOLERANCE" "20%"
					( Origin gFrontEnd )
				)
				( attribute "VALUE" "270UF"
					( Origin gFrontEnd )
				)
				( attribute "VER" "1"
					( Origin gFrontEnd )
				)
				( attribute "VOLTAGE" "16V"
					( Units "uVoltage" "V" 1.000000)
					( Origin gFrontEnd )
				)
				( attribute "XY" "(-950,2050)"
					( Origin gFrontEnd )
				)
				( attribute "CHIPS_PART_NAME" "CAPP"
					( Origin gPackager )
				)
				( attribute "CDS_PART_NAME" "CAPP_2626-270UF,16V,20%,OSCON,A"
					( Origin gPackager )
				)
				( objectStatus "C1E18" )
			)
			( gate "@baseboard_fab2_lib.baseboard_fab2(sch_1):page209_i38"
				( attribute "CDS_LIB" "mstr_discrete"
					( Origin gPackager )
				)
				( attribute "CDS_LOCATION" "C1C2"
					( Origin gPackager )
				)
				( attribute "CDS_SEC" "1"
					( Origin gPackager )
				)
				( attribute "LOCATION" "C1C2"
					( Origin gFrontEnd )
				)
				( attribute "MATERIAL" "OSCON"
					( Origin gFrontEnd )
				)
				( attribute "PACK_TYPE" "2626"
					( Origin gFrontEnd )
				)
				( attribute "PART_NUMBER" "A31228-047"
					( Origin gFrontEnd )
				)
				( attribute "PHYS_PAGE" "209"
					( Origin gFrontEnd )
				)
				( attribute "ROOM" "PVCCIN_CPU1_FILTER_VR"
					( Origin gFrontEnd )
				)
				( attribute "ROT" "0"
					( Origin gFrontEnd )
				)
				( attribute "SEC" "1"
					( Origin gFrontEnd )
				)
				( attribute "SEC_TYPE" "2626"
					( Origin gFrontEnd )
				)
				( attribute "TOLERANCE" "20%"
					( Origin gFrontEnd )
				)
				( attribute "VALUE" "270UF"
					( Origin gFrontEnd )
				)
				( attribute "VER" "1"
					( Origin gFrontEnd )
				)
				( attribute "VOLTAGE" "16V"
					( Units "uVoltage" "V" 1.000000)
					( Origin gFrontEnd )
				)
				( attribute "XY" "(-600,2050)"
					( Origin gFrontEnd )
				)
				( attribute "CHIPS_PART_NAME" "CAPP"
					( Origin gPackager )
				)
				( attribute "CDS_PART_NAME" "CAPP_2626-270UF,16V,20%,OSCON,A"
					( Origin gPackager )
				)
				( objectStatus "C1C2" )
			)
			( gate "@baseboard_fab2_lib.baseboard_fab2(sch_1):page219_i157"
				( attribute "ATTRIBUTE" "120NH"
					( Origin gFrontEnd )
				)
				( attribute "BOM_DS" "068.9002N.1021"
					( Origin gFrontEnd )
				)
				( attribute "BOM_SS" "068.1202N.M001"
					( Origin gFrontEnd )
				)
				( attribute "CDS_LIB" "w_hdl"
					( Origin gPackager )
				)
				( attribute "CDS_LMAN_SYM_OUTLINE" "-75,100,75,-100"
					( Origin gPackager )
				)
				( attribute "CDS_LOCATION" "L7A1"
					( Origin gPackager )
				)
				( attribute "CDS_SEC" "1"
					( Origin gPackager )
				)
				( attribute "DS_VALUE" "90NH"
					( Origin gFrontEnd )
				)
				( attribute "LOCATION" "L7A1"
					( Origin gFrontEnd )
				)
				( attribute "NEW_PACK_SIZE" "DCR=0.17MOHM"
					( Origin gFrontEnd )
				)
				( attribute "NEW_RATED" "DS_ISAT=134A@25C"
					( Origin gFrontEnd )
				)
				( attribute "NEW_TYPE" "IRMS=66A@DELTA_T<40C"
					( Origin gFrontEnd )
				)
				( attribute "PACK_SIZE" "DCR=0.17MOHM"
					( Origin gFrontEnd )
				)
				( attribute "PACK_TYPE" "DISCRET-GB2"
					( Origin gFrontEnd )
				)
				( attribute "PART_NUMBER" "068.1202N.M001"
					( Origin gFrontEnd )
				)
				( attribute "PHYS_PAGE" "219"
					( Origin gFrontEnd )
				)
				( attribute "RATED" "ISAT=94A@25C"
					( Origin gFrontEnd )
				)
				( attribute "ROT" "1"
					( Origin gFrontEnd )
				)
				( attribute "SEC" "1"
					( Origin gFrontEnd )
				)
				( attribute "SEC_TYPE" "DISCRET-GB2"
					( Origin gFrontEnd )
				)
				( attribute "SS_ISAT" "94A@25C"
					( Origin gFrontEnd )
				)
				( attribute "SS_VALUE" "120NH"
					( Origin gFrontEnd )
				)
				( attribute "TYPE" "IRMS=66A@DELTA_T<40C"
					( Origin gFrontEnd )
				)
				( attribute "VALUE" "IND-120NH-30-GP"
					( Origin gFrontEnd )
				)
				( attribute "VER" "1"
					( Origin gFrontEnd )
				)
				( attribute "XY" "(3850,1850)"
					( Origin gFrontEnd )
				)
				( attribute "CHIPS_PART_NAME" "IND-120NH-30-GP"
					( Origin gPackager )
				)
				( attribute "CDS_PART_NAME" "IND-120NH-30-GP_DISCRET-GB2-INA"
					( Origin gPackager )
				)
				( objectStatus "L7A1" )
			)
			( gate "@baseboard_fab2_lib.baseboard_fab2(sch_1):page209_i42"
				( attribute "BOM_COST" "PROC_VRD_VCCIN_CPU0"
					( Origin gFrontEnd )
				)
				( attribute "CDS_LIB" "dev_discrete"
					( Origin gPackager )
				)
				( attribute "CDS_LOCATION" "C1D24"
					( Origin gPackager )
				)
				( attribute "CDS_SEC" "1"
					( Origin gPackager )
				)
				( attribute "LOCATION" "C1D24"
					( Origin gFrontEnd )
				)
				( attribute "MATERIAL" "X6S"
					( Origin gFrontEnd )
				)
				( attribute "PACK_TYPE" "0603V"
					( Origin gFrontEnd )
				)
				( attribute "PART_NUMBER" "E15431-004"
					( Origin gFrontEnd )
				)
				( attribute "PHYS_PAGE" "209"
					( Origin gFrontEnd )
				)
				( attribute "ROOM" "PVCCIN_CPU1_PWR_VR"
					( Origin gFrontEnd )
				)
				( attribute "ROT" "0"
					( Origin gFrontEnd )
				)
				( attribute "SEC" "1"
					( Origin gFrontEnd )
				)
				( attribute "SEC_TYPE" "0603V"
					( Origin gFrontEnd )
				)
				( attribute "TOLERANCE" "20%"
					( Origin gFrontEnd )
				)
				( attribute "VALUE" "22.0UF"
					( Origin gFrontEnd )
				)
				( attribute "VER" "1"
					( Origin gFrontEnd )
				)
				( attribute "VOLTAGE" "4V"
					( Units "uVoltage" "V" 1.000000)
					( Origin gFrontEnd )
				)
				( attribute "XY" "(-750,3250)"
					( Origin gFrontEnd )
				)
				( attribute "CHIPS_PART_NAME" "CAP_A"
					( Origin gPackager )
				)
				( attribute "CDS_PART_NAME" "CAP_A_0603V-22.0UF,4V,20%,X6S,A"
					( Origin gPackager )
				)
				( attribute "GROUP" "PWR_MLCC_CAP"
					( Origin gFrontEnd )
				)
				( objectStatus "C1D24" )
			)
			( gate "@baseboard_fab2_lib.baseboard_fab2(sch_1):page209_i55"
				( attribute "CDS_LIB" "dev_discrete"
					( Origin gPackager )
				)
				( attribute "CDS_LOCATION" "C9P20"
					( Origin gPackager )
				)
				( attribute "CDS_SEC" "1"
					( Origin gPackager )
				)
				( attribute "LOCATION" "C9P20"
					( Origin gFrontEnd )
				)
				( attribute "MATERIAL" "X6S"
					( Origin gFrontEnd )
				)
				( attribute "PACK_TYPE" "0603V"
					( Origin gFrontEnd )
				)
				( attribute "PART_NUMBER" "E15431-004"
					( Origin gFrontEnd )
				)
				( attribute "PHYS_PAGE" "209"
					( Origin gFrontEnd )
				)
				( attribute "ROT" "0"
					( Origin gFrontEnd )
				)
				( attribute "SEC" "1"
					( Origin gFrontEnd )
				)
				( attribute "SEC_TYPE" "0603V"
					( Origin gFrontEnd )
				)
				( attribute "TOLERANCE" "20%"
					( Origin gFrontEnd )
				)
				( attribute "VALUE" "22.0UF"
					( Origin gFrontEnd )
				)
				( attribute "VER" "1"
					( Origin gFrontEnd )
				)
				( attribute "VOLTAGE" "4V"
					( Units "uVoltage" "V" 1.000000)
					( Origin gFrontEnd )
				)
				( attribute "XY" "(-350,3250)"
					( Origin gFrontEnd )
				)
				( attribute "CHIPS_PART_NAME" "CAP_A"
					( Origin gPackager )
				)
				( attribute "CDS_PART_NAME" "CAP_A_0603V-22.0UF,4V,20%,X6S,A"
					( Origin gPackager )
				)
				( attribute "GROUP" "PWR_MLCC_CAP"
					( Origin gFrontEnd )
				)
				( objectStatus "C9P20" )
			)
			( gate "@baseboard_fab2_lib.baseboard_fab2(sch_1):page209_i56"
				( attribute "CDS_LIB" "mstr_discrete"
					( Origin gPackager )
				)
				( attribute "CDS_LOCATION" "EU1C3"
					( Origin gPackager )
				)
				( attribute "CDS_SEC" "1"
					( Origin gPackager )
				)
				( attribute "LOCATION" "EU1C3"
					( Origin gFrontEnd )
				)
				( attribute "MATERIAL" "IC"
					( Origin gFrontEnd )
				)
				( attribute "PACK_TYPE" "SM"
					( Origin gFrontEnd )
				)
				( attribute "PART_NUMBER" "H73688-001"
					( Origin gFrontEnd )
				)
				( attribute "PHYS_PAGE" "209"
					( Origin gFrontEnd )
				)
				( attribute "ROOM" "PVCCIN_CPU1_PWR_VR"
					( Origin gFrontEnd )
				)
				( attribute "ROT" "0"
					( Origin gFrontEnd )
				)
				( attribute "SEC" "1"
					( Origin gFrontEnd )
				)
				( attribute "SEC_TYPE" "SM"
					( Origin gFrontEnd )
				)
				( attribute "VALUE" "IR35411"
					( Origin gFrontEnd )
				)
				( attribute "VER" "1"
					( Origin gFrontEnd )
				)
				( attribute "XY" "(-3250,3775)"
					( Origin gFrontEnd )
				)
				( attribute "CHIPS_PART_NAME" "IR354XX"
					( Origin gPackager )
				)
				( attribute "CDS_PART_NAME" "IR354XX_SM-IR35411,IC,H73688-0A"
					( Origin gPackager )
				)
				( objectStatus "EU1C3" )
			)
			( gate "@baseboard_fab2_lib.baseboard_fab2(sch_1):page209_i59"
				( attribute "CDS_LIB" "mstr_discrete"
					( Origin gPackager )
				)
				( attribute "CDS_LOCATION" "R1D52"
					( Origin gPackager )
				)
				( attribute "CDS_SEC" "1"
					( Origin gPackager )
				)
				( attribute "LOCATION" "R1D52"
					( Origin gFrontEnd )
				)
				( attribute "MATERIAL" "EMPTY"
					( Origin gFrontEnd )
				)
				( attribute "PACK_TYPE" "0402"
					( Origin gFrontEnd )
				)
				( attribute "PART_NUMBER" "G21796-187"
					( Origin gFrontEnd )
				)
				( attribute "PHYS_PAGE" "209"
					( Origin gFrontEnd )
				)
				( attribute "ROT" "0"
					( Origin gFrontEnd )
				)
				( attribute "SEC" "1"
					( Origin gPackager )
				)
				( attribute "TOLERANCE" "1%"
					( Origin gFrontEnd )
				)
				( attribute "VALUE" "68.1K"
					( Origin gFrontEnd )
				)
				( attribute "VER" "2"
					( Origin gFrontEnd )
				)
				( attribute "WATTAGE" "1/16W"
					( Origin gFrontEnd )
				)
				( attribute "XY" "(-1000,3925)"
					( Origin gFrontEnd )
				)
				( attribute "CHIPS_PART_NAME" "RES"
					( Origin gPackager )
				)
				( attribute "CDS_PART_NAME" "RES_0402-68.1K,1%,1/16W,EMPTY,A"
					( Origin gPackager )
				)
				( objectStatus "R1D52" )
			)
			( gate "@baseboard_fab2_lib.baseboard_fab2(sch_1):page210_i8"
				( attribute "BOM_COST" "PROC_VRD_VCCIN_CPU0"
					( Origin gFrontEnd )
				)
				( attribute "CDS_LIB" "dev_discrete"
					( Origin gPackager )
				)
				( attribute "CDS_LOCATION" "C1C19"
					( Origin gPackager )
				)
				( attribute "CDS_SEC" "1"
					( Origin gPackager )
				)
				( attribute "LOCATION" "C1C19"
					( Origin gFrontEnd )
				)
				( attribute "MATERIAL" "X6S"
					( Origin gFrontEnd )
				)
				( attribute "PACK_TYPE" "0603V"
					( Origin gFrontEnd )
				)
				( attribute "PART_NUMBER" "E15431-004"
					( Origin gFrontEnd )
				)
				( attribute "PHYS_PAGE" "210"
					( Origin gFrontEnd )
				)
				( attribute "ROOM" "PVSA_CPU1_PWR_VR"
					( Origin gFrontEnd )
				)
				( attribute "ROT" "0"
					( Origin gFrontEnd )
				)
				( attribute "SEC" "1"
					( Origin gFrontEnd )
				)
				( attribute "SEC_TYPE" "0603V"
					( Origin gFrontEnd )
				)
				( attribute "TOLERANCE" "20%"
					( Origin gFrontEnd )
				)
				( attribute "VALUE" "22.0UF"
					( Origin gFrontEnd )
				)
				( attribute "VER" "1"
					( Origin gFrontEnd )
				)
				( attribute "VOLTAGE" "4V"
					( Units "uVoltage" "V" 1.000000)
					( Origin gFrontEnd )
				)
				( attribute "XY" "(-1300,3100)"
					( Origin gFrontEnd )
				)
				( attribute "CHIPS_PART_NAME" "CAP_A"
					( Origin gPackager )
				)
				( attribute "CDS_PART_NAME" "CAP_A_0603V-22.0UF,4V,20%,X6S,A"
					( Origin gPackager )
				)
				( attribute "GROUP" "PWR_MLCC_CAP"
					( Origin gFrontEnd )
				)
				( objectStatus "C1C19" )
			)
			( gate "@baseboard_fab2_lib.baseboard_fab2(sch_1):page236_i178"
				( attribute "CDS_LIB" "w_hdl"
					( Origin gPackager )
				)
				( attribute "CDS_LMAN_SYM_OUTLINE" "-75,100,75,-100"
					( Origin gPackager )
				)
				( attribute "LOCATION" "L7A2"
					( Origin gFrontEnd )
				)
				( attribute "PACK_TYPE" "DISCRET-GB1"
					( Origin gFrontEnd )
				)
				( attribute "PART_NUMBER" "068.3012N.M001"
					( Origin gFrontEnd )
				)
				( attribute "PHYS_PAGE" "236"
					( Origin gFrontEnd )
				)
				( attribute "ROT" "1"
					( Origin gFrontEnd )
				)
				( attribute "SEC" "1"
					( Origin gFrontEnd )
				)
				( attribute "SEC_TYPE" "DISCRET-GB1"
					( Origin gFrontEnd )
				)
				( attribute "VALUE" "IND-300NH-20-GP"
					( Origin gFrontEnd )
				)
				( attribute "VER" "1"
					( Origin gFrontEnd )
				)
				( attribute "XY" "(11375,4000)"
					( Origin gFrontEnd )
				)
				( attribute "CHIPS_PART_NAME" "IND-300NH-20-GP"
					( Origin gPackager )
				)
				( attribute "CDS_PART_NAME" "IND-300NH-20-GP_DISCRET-GB1-INA"
					( Origin gPackager )
				)
				( attribute "CDS_LOCATION" "L7A2"
					( Origin gPackager )
				)
				( attribute "CDS_SEC" "1"
					( Origin gPackager )
				)
				( attribute "ATTRIBUTE" "300NH"
					( Origin gFrontEnd )
				)
				( attribute "PACK_SIZE" "DCR=0.17MOHM"
					( Origin gFrontEnd )
				)
				( attribute "RATED" "ISAT=33A@25C"
					( Origin gFrontEnd )
				)
				( attribute "TYPE" "IRMS=66A@DELTA_T<40C"
					( Origin gFrontEnd )
				)
				( objectStatus "L7A2" )
			)
			( gate "@baseboard_fab2_lib.baseboard_fab2(sch_1):page210_i12"
				( attribute "BOM_COST" "PROC_VRD_VCCIN_CPU0"
					( Origin gFrontEnd )
				)
				( attribute "CDS_LIB" "mstr_discrete"
					( Origin gPackager )
				)
				( attribute "CDS_LOCATION" "C9N11"
					( Origin gPackager )
				)
				( attribute "CDS_SEC" "1"
					( Origin gPackager )
				)
				( attribute "LOCATION" "C9N11"
					( Origin gFrontEnd )
				)
				( attribute "MATERIAL" "ALUM"
					( Origin gFrontEnd )
				)
				( attribute "PACK_TYPE" "3018"
					( Origin gFrontEnd )
				)
				( attribute "PART_NUMBER" "699013-049"
					( Origin gFrontEnd )
				)
				( attribute "PHYS_PAGE" "210"
					( Origin gFrontEnd )
				)
				( attribute "ROOM" "PVSA_CPU1_DECAP_VR"
					( Origin gFrontEnd )
				)
				( attribute "ROT" "0"
					( Origin gFrontEnd )
				)
				( attribute "SEC" "1"
					( Origin gFrontEnd )
				)
				( attribute "SEC_TYPE" "3018"
					( Origin gFrontEnd )
				)
				( attribute "TOLERANCE" "20%"
					( Origin gFrontEnd )
				)
				( attribute "VALUE" "470UF"
					( Origin gFrontEnd )
				)
				( attribute "VER" "1"
					( Origin gFrontEnd )
				)
				( attribute "VOLTAGE" "2.5V"
					( Units "uVoltage" "V" 1.000000)
					( Origin gFrontEnd )
				)
				( attribute "XY" "(-1350,1450)"
					( Origin gFrontEnd )
				)
				( attribute "CHIPS_PART_NAME" "CAPP"
					( Origin gPackager )
				)
				( attribute "CDS_PART_NAME" "CAPP_3018-470UF,2.5V,20%,ALUM,A"
					( Origin gPackager )
				)
				( attribute "GROUP" "PWR_BULK_CAP"
					( Origin gFrontEnd )
				)
				( objectStatus "C9N11" )
			)
			( gate "@baseboard_fab2_lib.baseboard_fab2(sch_1):page210_i14"
				( attribute "BOM_COST" "PROC_VRD_VCCIN_CPU0"
					( Origin gFrontEnd )
				)
				( attribute "CDS_LIB" "mstr_discrete"
					( Origin gPackager )
				)
				( attribute "CDS_LOCATION" "C9N20"
					( Origin gPackager )
				)
				( attribute "CDS_SEC" "1"
					( Origin gPackager )
				)
				( attribute "LOCATION" "C9N20"
					( Origin gFrontEnd )
				)
				( attribute "MATERIAL" "ALUM"
					( Origin gFrontEnd )
				)
				( attribute "PACK_TYPE" "3018"
					( Origin gFrontEnd )
				)
				( attribute "PART_NUMBER" "699013-049"
					( Origin gFrontEnd )
				)
				( attribute "PHYS_PAGE" "210"
					( Origin gFrontEnd )
				)
				( attribute "ROOM" "PVSA_CPU1_DECAP_VR"
					( Origin gFrontEnd )
				)
				( attribute "ROT" "2"
					( Origin gFrontEnd )
				)
				( attribute "SEC" "1"
					( Origin gFrontEnd )
				)
				( attribute "SEC_TYPE" "3018"
					( Origin gFrontEnd )
				)
				( attribute "TOLERANCE" "20%"
					( Origin gFrontEnd )
				)
				( attribute "VALUE" "470UF"
					( Origin gFrontEnd )
				)
				( attribute "VER" "1"
					( Origin gFrontEnd )
				)
				( attribute "VOLTAGE" "2.5V"
					( Units "uVoltage" "V" 1.000000)
					( Origin gFrontEnd )
				)
				( attribute "XY" "(-1900,1450)"
					( Origin gFrontEnd )
				)
				( attribute "CHIPS_PART_NAME" "CAPP"
					( Origin gPackager )
				)
				( attribute "CDS_PART_NAME" "CAPP_3018-470UF,2.5V,20%,ALUM,A"
					( Origin gPackager )
				)
				( attribute "GROUP" "PWR_BULK_CAP"
					( Origin gFrontEnd )
				)
				( objectStatus "C9N20" )
			)
			( gate "@baseboard_fab2_lib.baseboard_fab2(sch_1):page212_i140"
				( attribute "BOM_COST" "PROC_SIDEBAND"
					( Origin gFrontEnd )
				)
				( attribute "CDS_LIB" "mstr_discrete"
					( Origin gPackager )
				)
				( attribute "CDS_LOCATION" "R3N7"
					( Origin gPackager )
				)
				( attribute "CDS_SEC" "1"
					( Origin gPackager )
				)
				( attribute "LOCATION" "R3N7"
					( Origin gFrontEnd )
				)
				( attribute "MATERIAL" "CHIP"
					( Origin gFrontEnd )
				)
				( attribute "PACK_TYPE" "0402"
					( Origin gFrontEnd )
				)
				( attribute "PART_NUMBER" "G21497-005"
					( Origin gFrontEnd )
				)
				( attribute "PHYS_PAGE" "212"
					( Origin gFrontEnd )
				)
				( attribute "ROOM" "CPU0"
					( Origin gFrontEnd )
				)
				( attribute "ROT" "0"
					( Origin gFrontEnd )
				)
				( attribute "SEC" "1"
					( Origin gFrontEnd )
				)
				( attribute "SEC_TYPE" "0402"
					( Origin gFrontEnd )
				)
				( attribute "TOLERANCE" "5%"
					( Origin gFrontEnd )
				)
				( attribute "VALUE" "0.0"
					( Origin gFrontEnd )
				)
				( attribute "VER" "1"
					( Origin gFrontEnd )
				)
				( attribute "WATTAGE" "1/16W"
					( Origin gFrontEnd )
				)
				( attribute "XY" "(-1200,4750)"
					( Origin gFrontEnd )
				)
				( attribute "CHIPS_PART_NAME" "RES"
					( Origin gPackager )
				)
				( attribute "CDS_PART_NAME" "RES_0402-0.0,5%,1/16W,CHIP,G21A"
					( Origin gPackager )
				)
				( objectStatus "R3N7" )
			)
			( gate "@baseboard_fab2_lib.baseboard_fab2(sch_1):page210_i22"
				( attribute "CDS_LIB" "mstr_discrete"
					( Origin gPackager )
				)
				( attribute "CDS_LOCATION" "C1C4"
					( Origin gPackager )
				)
				( attribute "CDS_SEC" "1"
					( Origin gPackager )
				)
				( attribute "LOCATION" "C1C4"
					( Origin gFrontEnd )
				)
				( attribute "MATERIAL" "X7R"
					( Origin gFrontEnd )
				)
				( attribute "PACK_TYPE" "0402"
					( Origin gFrontEnd )
				)
				( attribute "PART_NUMBER" "A36096-155"
					( Origin gFrontEnd )
				)
				( attribute "PHYS_PAGE" "210"
					( Origin gFrontEnd )
				)
				( attribute "ROOM" "PVSA_CPU1_PWR_VR"
					( Origin gFrontEnd )
				)
				( attribute "ROT" "0"
					( Origin gFrontEnd )
				)
				( attribute "SEC" "1"
					( Origin gFrontEnd )
				)
				( attribute "SEC_TYPE" "0402"
					( Origin gFrontEnd )
				)
				( attribute "TOLERANCE" "10%"
					( Origin gFrontEnd )
				)
				( attribute "VALUE" "0.22UF"
					( Origin gFrontEnd )
				)
				( attribute "VER" "1"
					( Origin gFrontEnd )
				)
				( attribute "VOLTAGE" "16V"
					( Units "uVoltage" "V" 1.000000)
					( Origin gFrontEnd )
				)
				( attribute "XY" "(-5200,3850)"
					( Origin gFrontEnd )
				)
				( attribute "CHIPS_PART_NAME" "CAP"
					( Origin gPackager )
				)
				( attribute "CDS_PART_NAME" "CAP_0402-0.22UF,16V,10%,X7R,A3A"
					( Origin gPackager )
				)
				( objectStatus "C1C4" )
			)
			( gate "@baseboard_fab2_lib.baseboard_fab2(sch_1):page208_i118"
				( attribute "CDS_LIB" "w_hdl"
					( Origin gPackager )
				)
				( attribute "CDS_LMAN_SYM_OUTLINE" "-50,25,50,-25"
					( Origin gPackager )
				)
				( attribute "LOCATION" "C1D15"
					( Origin gFrontEnd )
				)
				( attribute "PACK_TYPE" "SMD-BCG6"
					( Origin gFrontEnd )
				)
				( attribute "PART_NUMBER" "78.10523.8FL"
					( Origin gFrontEnd )
				)
				( attribute "PHYS_PAGE" "208"
					( Origin gFrontEnd )
				)
				( attribute "ROT" "0"
					( Origin gFrontEnd )
				)
				( attribute "SEC" "1"
					( Origin gFrontEnd )
				)
				( attribute "SEC_TYPE" "SMD-BCG6"
					( Origin gFrontEnd )
				)
				( attribute "VALUE" "SC1U10V2KX-4-GP"
					( Origin gFrontEnd )
				)
				( attribute "VER" "1"
					( Origin gFrontEnd )
				)
				( attribute "XY" "(-5100,4200)"
					( Origin gFrontEnd )
				)
				( attribute "CHIPS_PART_NAME" "SC1U10V2KX-4-GP"
					( Origin gPackager )
				)
				( attribute "CDS_PART_NAME" "SC1U10V2KX-4-GP_SMD-BCG6-SC1U1A"
					( Origin gPackager )
				)
				( attribute "CDS_LOCATION" "C1D15"
					( Origin gPackager )
				)
				( attribute "CDS_SEC" "1"
					( Origin gPackager )
				)
				( attribute "ATTRIBUTE" "1UF"
					( Origin gFrontEnd )
				)
				( attribute "PACK_SIZE" "0402"
					( Origin gFrontEnd )
				)
				( attribute "RATED" "10V"
					( Origin gFrontEnd )
				)
				( attribute "TOLERANCE" "10%"
					( Origin gFrontEnd )
				)
				( objectStatus "C1D15" )
			)
			( gate "@baseboard_fab2_lib.baseboard_fab2(sch_1):page210_i24"
				( attribute "CDS_LIB" "mstr_discrete"
					( Origin gPackager )
				)
				( attribute "CDS_LOCATION" "C1C12"
					( Origin gPackager )
				)
				( attribute "CDS_SEC" "1"
					( Origin gPackager )
				)
				( attribute "LOCATION" "C1C12"
					( Origin gFrontEnd )
				)
				( attribute "MATERIAL" "X7R"
					( Origin gFrontEnd )
				)
				( attribute "PACK_TYPE" "0402"
					( Origin gFrontEnd )
				)
				( attribute "PART_NUMBER" "A36096-104"
					( Origin gFrontEnd )
				)
				( attribute "PHYS_PAGE" "210"
					( Origin gFrontEnd )
				)
				( attribute "ROOM" "PVSA_CPU1_PWR_VR"
					( Origin gFrontEnd )
				)
				( attribute "ROT" "2"
					( Origin gFrontEnd )
				)
				( attribute "SEC" "1"
					( Origin gFrontEnd )
				)
				( attribute "SEC_TYPE" "0402"
					( Origin gFrontEnd )
				)
				( attribute "SPOF" "TRUE"
					( Origin gFrontEnd )
				)
				( attribute "TOLERANCE" "10%"
					( Origin gFrontEnd )
				)
				( attribute "VALUE" "0.220UF"
					( Origin gFrontEnd )
				)
				( attribute "VER" "1"
					( Origin gFrontEnd )
				)
				( attribute "VOLTAGE" "16V"
					( Units "uVoltage" "V" 1.000000)
					( Origin gFrontEnd )
				)
				( attribute "XY" "(-6125,3250)"
					( Origin gFrontEnd )
				)
				( attribute "CHIPS_PART_NAME" "CAP"
					( Origin gPackager )
				)
				( attribute "CDS_PART_NAME" "CAP_0402-0.220UF,16V,10%,X7R,AA"
					( Origin gPackager )
				)
				( objectStatus "C1C12" )
			)
			( gate "@baseboard_fab2_lib.baseboard_fab2(sch_1):page210_i26"
				( attribute "CDS_LIB" "mstr_discrete"
					( Origin gPackager )
				)
				( attribute "CDS_LOCATION" "C1C5"
					( Origin gPackager )
				)
				( attribute "CDS_SEC" "1"
					( Origin gPackager )
				)
				( attribute "LOCATION" "C1C5"
					( Origin gFrontEnd )
				)
				( attribute "MATERIAL" "X6S"
					( Origin gFrontEnd )
				)
				( attribute "PACK_TYPE" "0402"
					( Origin gFrontEnd )
				)
				( attribute "PART_NUMBER" "D97712-011"
					( Origin gFrontEnd )
				)
				( attribute "PHYS_PAGE" "210"
					( Origin gFrontEnd )
				)
				( attribute "ROOM" "PVSA_CPU1_PWR_VR"
					( Origin gFrontEnd )
				)
				( attribute "ROT" "0"
					( Origin gFrontEnd )
				)
				( attribute "SEC" "1"
					( Origin gFrontEnd )
				)
				( attribute "SEC_TYPE" "0402"
					( Origin gFrontEnd )
				)
				( attribute "TOLERANCE" "10%"
					( Origin gFrontEnd )
				)
				( attribute "VALUE" "1.0UF"
					( Origin gFrontEnd )
				)
				( attribute "VER" "1"
					( Origin gFrontEnd )
				)
				( attribute "VOLTAGE" "16V"
					( Units "uVoltage" "V" 1.000000)
					( Origin gFrontEnd )
				)
				( attribute "XY" "(-5875,3825)"
					( Origin gFrontEnd )
				)
				( attribute "CHIPS_PART_NAME" "CAP"
					( Origin gPackager )
				)
				( attribute "CDS_PART_NAME" "CAP_0402-1.0UF,16V,10%,X6S,D97A"
					( Origin gPackager )
				)
				( objectStatus "C1C5" )
			)
			( gate "@baseboard_fab2_lib.baseboard_fab2(sch_1):page210_i27"
				( attribute "CDS_LIB" "dev_discrete"
					( Origin gPackager )
				)
				( attribute "CDS_LOCATION" "C1C17"
					( Origin gPackager )
				)
				( attribute "CDS_SEC" "1"
					( Origin gPackager )
				)
				( attribute "LOCATION" "C1C17"
					( Origin gFrontEnd )
				)
				( attribute "MATERIAL" "X7R"
					( Origin gFrontEnd )
				)
				( attribute "PACK_TYPE" "0402V"
					( Origin gFrontEnd )
				)
				( attribute "PART_NUMBER" "A36096-030"
					( Origin gFrontEnd )
				)
				( attribute "PHYS_PAGE" "210"
					( Origin gFrontEnd )
				)
				( attribute "ROOM" "PVSA_CPU1_PWR_VR"
					( Origin gFrontEnd )
				)
				( attribute "ROT" "0"
					( Origin gFrontEnd )
				)
				( attribute "SEC" "1"
					( Origin gFrontEnd )
				)
				( attribute "SEC_TYPE" "0402V"
					( Origin gFrontEnd )
				)
				( attribute "TOLERANCE" "10%"
					( Origin gFrontEnd )
				)
				( attribute "VALUE" "0.1UF"
					( Origin gFrontEnd )
				)
				( attribute "VER" "1"
					( Origin gFrontEnd )
				)
				( attribute "VOLTAGE" "16V"
					( Units "uVoltage" "V" 1.000000)
					( Origin gFrontEnd )
				)
				( attribute "XY" "(-6125,3850)"
					( Origin gFrontEnd )
				)
				( attribute "CHIPS_PART_NAME" "CAP_A"
					( Origin gPackager )
				)
				( attribute "CDS_PART_NAME" "CAP_A_0402V-0.1UF,16V,10%,X7R,A"
					( Origin gPackager )
				)
				( objectStatus "C1C17" )
			)
			( gate "@baseboard_fab2_lib.baseboard_fab2(sch_1):page210_i28"
				( attribute "CDS_LIB" "mstr_discrete"
					( Origin gPackager )
				)
				( attribute "CDS_LOCATION" "C1C15"
					( Origin gPackager )
				)
				( attribute "CDS_SEC" "1"
					( Origin gPackager )
				)
				( attribute "LOCATION" "C1C15"
					( Origin gFrontEnd )
				)
				( attribute "MATERIAL" "X6S"
					( Origin gFrontEnd )
				)
				( attribute "PACK_TYPE" "0402"
					( Origin gFrontEnd )
				)
				( attribute "PART_NUMBER" "D97712-011"
					( Origin gFrontEnd )
				)
				( attribute "PHYS_PAGE" "210"
					( Origin gFrontEnd )
				)
				( attribute "ROOM" "PVSA_CPU1_PWR_VR"
					( Origin gFrontEnd )
				)
				( attribute "ROT" "0"
					( Origin gFrontEnd )
				)
				( attribute "SEC" "1"
					( Origin gFrontEnd )
				)
				( attribute "SEC_TYPE" "0402"
					( Origin gFrontEnd )
				)
				( attribute "TOLERANCE" "10%"
					( Origin gFrontEnd )
				)
				( attribute "VALUE" "1.0UF"
					( Origin gFrontEnd )
				)
				( attribute "VER" "1"
					( Origin gFrontEnd )
				)
				( attribute "VOLTAGE" "16V"
					( Units "uVoltage" "V" 1.000000)
					( Origin gFrontEnd )
				)
				( attribute "XY" "(-6375,3825)"
					( Origin gFrontEnd )
				)
				( attribute "CHIPS_PART_NAME" "CAP"
					( Origin gPackager )
				)
				( attribute "CDS_PART_NAME" "CAP_0402-1.0UF,16V,10%,X6S,D97A"
					( Origin gPackager )
				)
				( objectStatus "C1C15" )
			)
			( gate "@baseboard_fab2_lib.baseboard_fab2(sch_1):page210_i29"
				( attribute "BOM_COST" "PROC_VRD_VCCIN_CPU0"
					( Origin gFrontEnd )
				)
				( attribute "CDS_LIB" "mstr_discrete"
					( Origin gPackager )
				)
				( attribute "CDS_LOCATION" "R1C12"
					( Origin gPackager )
				)
				( attribute "CDS_SEC" "1"
					( Origin gPackager )
				)
				( attribute "LOCATION" "R1C12"
					( Origin gFrontEnd )
				)
				( attribute "MATERIAL" "CHIP"
					( Origin gFrontEnd )
				)
				( attribute "PACK_TYPE" "0402"
					( Origin gFrontEnd )
				)
				( attribute "PART_NUMBER" "G21796-017"
					( Origin gFrontEnd )
				)
				( attribute "PHYS_PAGE" "210"
					( Origin gFrontEnd )
				)
				( attribute "ROOM" "PVSA_CPU1_VSENSE_VR"
					( Origin gFrontEnd )
				)
				( attribute "ROT" "0"
					( Origin gFrontEnd )
				)
				( attribute "SEC" "1"
					( Origin gFrontEnd )
				)
				( attribute "SEC_TYPE" "0402"
					( Origin gFrontEnd )
				)
				( attribute "TOLERANCE" "1%"
					( Origin gFrontEnd )
				)
				( attribute "VALUE" "100.0"
					( Origin gFrontEnd )
				)
				( attribute "VER" "1"
					( Origin gFrontEnd )
				)
				( attribute "WATTAGE" "1/16W"
					( Origin gFrontEnd )
				)
				( attribute "XY" "(-5300,2325)"
					( Origin gFrontEnd )
				)
				( attribute "CHIPS_PART_NAME" "RES"
					( Origin gPackager )
				)
				( attribute "CDS_PART_NAME" "RES_0402-100.0,1%,1/16W,CHIP,GA"
					( Origin gPackager )
				)
				( objectStatus "R1C12" )
			)
			( gate "@baseboard_fab2_lib.baseboard_fab2(sch_1):page210_i31"
				( attribute "BOM_COST" "PROC_VRD_VCCIN_CPU0"
					( Origin gFrontEnd )
				)
				( attribute "CDS_LIB" "mstr_discrete"
					( Origin gPackager )
				)
				( attribute "CDS_LOCATION" "R1C7"
					( Origin gPackager )
				)
				( attribute "CDS_SEC" "1"
					( Origin gPackager )
				)
				( attribute "LOCATION" "R1C7"
					( Origin gFrontEnd )
				)
				( attribute "MATERIAL" "CHIP"
					( Origin gFrontEnd )
				)
				( attribute "PACK_TYPE" "0402"
					( Origin gFrontEnd )
				)
				( attribute "PART_NUMBER" "G21497-005"
					( Origin gFrontEnd )
				)
				( attribute "PHYS_PAGE" "210"
					( Origin gFrontEnd )
				)
				( attribute "ROOM" "PVSA_CPU1_VSENSE_VR"
					( Origin gFrontEnd )
				)
				( attribute "ROT" "0"
					( Origin gFrontEnd )
				)
				( attribute "SEC" "1"
					( Origin gFrontEnd )
				)
				( attribute "SEC_TYPE" "0402"
					( Origin gFrontEnd )
				)
				( attribute "TOLERANCE" "5%"
					( Origin gFrontEnd )
				)
				( attribute "VALUE" "0.0"
					( Origin gFrontEnd )
				)
				( attribute "VER" "1"
					( Origin gFrontEnd )
				)
				( attribute "WATTAGE" "1/16W"
					( Origin gFrontEnd )
				)
				( attribute "XY" "(-5275,1925)"
					( Origin gFrontEnd )
				)
				( attribute "CHIPS_PART_NAME" "RES"
					( Origin gPackager )
				)
				( attribute "CDS_PART_NAME" "RES_0402-0.0,5%,1/16W,CHIP,G21A"
					( Origin gPackager )
				)
				( objectStatus "R1C7" )
			)
			( gate "@baseboard_fab2_lib.baseboard_fab2(sch_1):page210_i32"
				( attribute "BOM_COST" "PROC_VRD_VCCIN_CPU0"
					( Origin gFrontEnd )
				)
				( attribute "CDS_LIB" "mstr_discrete"
					( Origin gPackager )
				)
				( attribute "CDS_LOCATION" "R1C5"
					( Origin gPackager )
				)
				( attribute "CDS_SEC" "1"
					( Origin gPackager )
				)
				( attribute "LOCATION" "R1C5"
					( Origin gFrontEnd )
				)
				( attribute "MATERIAL" "CHIP"
					( Origin gFrontEnd )
				)
				( attribute "PACK_TYPE" "0402"
					( Origin gFrontEnd )
				)
				( attribute "PART_NUMBER" "G21497-005"
					( Origin gFrontEnd )
				)
				( attribute "PHYS_PAGE" "210"
					( Origin gFrontEnd )
				)
				( attribute "ROOM" "PVSA_CPU1_VSENSE_VR"
					( Origin gFrontEnd )
				)
				( attribute "ROT" "0"
					( Origin gFrontEnd )
				)
				( attribute "SEC" "1"
					( Origin gFrontEnd )
				)
				( attribute "SEC_TYPE" "0402"
					( Origin gFrontEnd )
				)
				( attribute "TOLERANCE" "5%"
					( Origin gFrontEnd )
				)
				( attribute "VALUE" "0.0"
					( Origin gFrontEnd )
				)
				( attribute "VER" "1"
					( Origin gFrontEnd )
				)
				( attribute "WATTAGE" "1/16W"
					( Origin gFrontEnd )
				)
				( attribute "XY" "(-5275,1475)"
					( Origin gFrontEnd )
				)
				( attribute "CHIPS_PART_NAME" "RES"
					( Origin gPackager )
				)
				( attribute "CDS_PART_NAME" "RES_0402-0.0,5%,1/16W,CHIP,G21A"
					( Origin gPackager )
				)
				( objectStatus "R1C5" )
			)
			( gate "@baseboard_fab2_lib.baseboard_fab2(sch_1):page210_i33"
				( attribute "BOM_COST" "PROC_VRD_VCCIN_CPU0"
					( Origin gFrontEnd )
				)
				( attribute "CDS_LIB" "mstr_discrete"
					( Origin gPackager )
				)
				( attribute "CDS_LOCATION" "R1C4"
					( Origin gPackager )
				)
				( attribute "CDS_SEC" "1"
					( Origin gPackager )
				)
				( attribute "LOCATION" "R1C4"
					( Origin gFrontEnd )
				)
				( attribute "MATERIAL" "CHIP"
					( Origin gFrontEnd )
				)
				( attribute "PACK_TYPE" "0402"
					( Origin gFrontEnd )
				)
				( attribute "PART_NUMBER" "G21796-017"
					( Origin gFrontEnd )
				)
				( attribute "PHYS_PAGE" "210"
					( Origin gFrontEnd )
				)
				( attribute "ROOM" "PVSA_CPU1_VSENSE_VR"
					( Origin gFrontEnd )
				)
				( attribute "ROT" "0"
					( Origin gFrontEnd )
				)
				( attribute "SEC" "1"
					( Origin gFrontEnd )
				)
				( attribute "SEC_TYPE" "0402"
					( Origin gFrontEnd )
				)
				( attribute "TOLERANCE" "1%"
					( Origin gFrontEnd )
				)
				( attribute "VALUE" "100.0"
					( Origin gFrontEnd )
				)
				( attribute "VER" "1"
					( Origin gFrontEnd )
				)
				( attribute "WATTAGE" "1/16W"
					( Origin gFrontEnd )
				)
				( attribute "XY" "(-5275,1100)"
					( Origin gFrontEnd )
				)
				( attribute "CHIPS_PART_NAME" "RES"
					( Origin gPackager )
				)
				( attribute "CDS_PART_NAME" "RES_0402-100.0,1%,1/16W,CHIP,GA"
					( Origin gPackager )
				)
				( objectStatus "R1C4" )
			)
			( gate "@baseboard_fab2_lib.baseboard_fab2(sch_1):page210_i34"
				( attribute "BOM_COST" "PROC_VRD_VCCIN_CPU0"
					( Origin gFrontEnd )
				)
				( attribute "CDS_LIB" "mstr_discrete"
					( Origin gPackager )
				)
				( attribute "CDS_LOCATION" "R1C6"
					( Origin gPackager )
				)
				( attribute "CDS_SEC" "1"
					( Origin gPackager )
				)
				( attribute "LOCATION" "R1C6"
					( Origin gFrontEnd )
				)
				( attribute "MATERIAL" "EMPTY"
					( Origin gFrontEnd )
				)
				( attribute "NO_XNET_CONNECTION" "1"
					( Origin gFrontEnd )
				)
				( attribute "PACK_TYPE" "0402"
					( Origin gFrontEnd )
				)
				( attribute "PART_NUMBER" "G21796-026"
					( Origin gFrontEnd )
				)
				( attribute "PHYS_PAGE" "210"
					( Origin gFrontEnd )
				)
				( attribute "ROOM" "PVSA_CPU1_VSENSE_VR"
					( Origin gFrontEnd )
				)
				( attribute "ROT" "0"
					( Origin gFrontEnd )
				)
				( attribute "SEC" "1"
					( Origin gFrontEnd )
				)
				( attribute "SEC_TYPE" "0402"
					( Origin gFrontEnd )
				)
				( attribute "TOLERANCE" "1%"
					( Origin gFrontEnd )
				)
				( attribute "VALUE" "1.00K"
					( Origin gFrontEnd )
				)
				( attribute "VER" "2"
					( Origin gFrontEnd )
				)
				( attribute "WATTAGE" "1/16W"
					( Origin gFrontEnd )
				)
				( attribute "XY" "(-5950,1725)"
					( Origin gFrontEnd )
				)
				( attribute "CHIPS_PART_NAME" "RES"
					( Origin gPackager )
				)
				( attribute "CDS_PART_NAME" "RES_0402-1.00K,1%,1/16W,EMPTY,A"
					( Origin gPackager )
				)
				( objectStatus "R1C6" )
			)
			( gate "@baseboard_fab2_lib.baseboard_fab2(sch_1):page210_i35"
				( attribute "CDS_LIB" "mstr_discrete"
					( Origin gPackager )
				)
				( attribute "CDS_LOCATION" "C9N13"
					( Origin gPackager )
				)
				( attribute "CDS_SEC" "1"
					( Origin gPackager )
				)
				( attribute "LOCATION" "C9N13"
					( Origin gFrontEnd )
				)
				( attribute "MATERIAL" "X6S"
					( Origin gFrontEnd )
				)
				( attribute "PACK_TYPE" "0805"
					( Origin gFrontEnd )
				)
				( attribute "PART_NUMBER" "C95333-007"
					( Origin gFrontEnd )
				)
				( attribute "PHYS_PAGE" "210"
					( Origin gFrontEnd )
				)
				( attribute "ROOM" "PVSA_CPU1_PWR_VR"
					( Origin gFrontEnd )
				)
				( attribute "ROT" "0"
					( Origin gFrontEnd )
				)
				( attribute "SEC" "1"
					( Origin gFrontEnd )
				)
				( attribute "SEC_TYPE" "0805"
					( Origin gFrontEnd )
				)
				( attribute "TOLERANCE" "10%"
					( Origin gFrontEnd )
				)
				( attribute "VALUE" "10UF"
					( Origin gFrontEnd )
				)
				( attribute "VER" "1"
					( Origin gFrontEnd )
				)
				( attribute "VOLTAGE" "16V"
					( Units "uVoltage" "V" 1.000000)
					( Origin gFrontEnd )
				)
				( attribute "XY" "(-6625,3825)"
					( Origin gFrontEnd )
				)
				( attribute "CHIPS_PART_NAME" "CAP"
					( Origin gPackager )
				)
				( attribute "CDS_PART_NAME" "CAP_0805-10UF,16V,10%,X6S,C953A"
					( Origin gPackager )
				)
				( objectStatus "C9N13" )
			)
			( gate "@baseboard_fab2_lib.baseboard_fab2(sch_1):page210_i36"
				( attribute "CDS_LIB" "mstr_discrete"
					( Origin gPackager )
				)
				( attribute "CDS_LOCATION" "C9N19"
					( Origin gPackager )
				)
				( attribute "CDS_SEC" "1"
					( Origin gPackager )
				)
				( attribute "LOCATION" "C9N19"
					( Origin gFrontEnd )
				)
				( attribute "MATERIAL" "X6S"
					( Origin gFrontEnd )
				)
				( attribute "PACK_TYPE" "0805"
					( Origin gFrontEnd )
				)
				( attribute "PART_NUMBER" "C95333-007"
					( Origin gFrontEnd )
				)
				( attribute "PHYS_PAGE" "210"
					( Origin gFrontEnd )
				)
				( attribute "ROOM" "PVSA_CPU1_PWR_VR"
					( Origin gFrontEnd )
				)
				( attribute "ROT" "0"
					( Origin gFrontEnd )
				)
				( attribute "SEC" "1"
					( Origin gFrontEnd )
				)
				( attribute "SEC_TYPE" "0805"
					( Origin gFrontEnd )
				)
				( attribute "TOLERANCE" "10%"
					( Origin gFrontEnd )
				)
				( attribute "VALUE" "10UF"
					( Origin gFrontEnd )
				)
				( attribute "VER" "1"
					( Origin gFrontEnd )
				)
				( attribute "VOLTAGE" "16V"
					( Units "uVoltage" "V" 1.000000)
					( Origin gFrontEnd )
				)
				( attribute "XY" "(-6900,3850)"
					( Origin gFrontEnd )
				)
				( attribute "CHIPS_PART_NAME" "CAP"
					( Origin gPackager )
				)
				( attribute "CDS_PART_NAME" "CAP_0805-10UF,16V,10%,X6S,C953A"
					( Origin gPackager )
				)
				( objectStatus "C9N19" )
			)
			( gate "@baseboard_fab2_lib.baseboard_fab2(sch_1):page210_i38"
				( attribute "CDS_LIB" "mstr_discrete"
					( Origin gPackager )
				)
				( attribute "CDS_LOCATION" "C9N21"
					( Origin gPackager )
				)
				( attribute "CDS_SEC" "1"
					( Origin gPackager )
				)
				( attribute "LOCATION" "C9N21"
					( Origin gFrontEnd )
				)
				( attribute "MATERIAL" "X6S"
					( Origin gFrontEnd )
				)
				( attribute "PACK_TYPE" "0805"
					( Origin gFrontEnd )
				)
				( attribute "PART_NUMBER" "C95333-007"
					( Origin gFrontEnd )
				)
				( attribute "PHYS_PAGE" "210"
					( Origin gFrontEnd )
				)
				( attribute "ROOM" "PVSA_CPU1_PWR_VR"
					( Origin gFrontEnd )
				)
				( attribute "ROT" "0"
					( Origin gFrontEnd )
				)
				( attribute "SEC" "1"
					( Origin gFrontEnd )
				)
				( attribute "SEC_TYPE" "0805"
					( Origin gFrontEnd )
				)
				( attribute "TOLERANCE" "10%"
					( Origin gFrontEnd )
				)
				( attribute "VALUE" "10UF"
					( Origin gFrontEnd )
				)
				( attribute "VER" "1"
					( Origin gFrontEnd )
				)
				( attribute "VOLTAGE" "16V"
					( Units "uVoltage" "V" 1.000000)
					( Origin gFrontEnd )
				)
				( attribute "XY" "(-7175,3850)"
					( Origin gFrontEnd )
				)
				( attribute "CHIPS_PART_NAME" "CAP"
					( Origin gPackager )
				)
				( attribute "CDS_PART_NAME" "CAP_0805-10UF,16V,10%,X6S,C953A"
					( Origin gPackager )
				)
				( objectStatus "C9N21" )
			)
			( gate "@baseboard_fab2_lib.baseboard_fab2(sch_1):page210_i44"
				( attribute "CDS_LIB" "dev_discrete"
					( Origin gPackager )
				)
				( attribute "CDS_LOCATION" "C9N22"
					( Origin gPackager )
				)
				( attribute "CDS_SEC" "1"
					( Origin gPackager )
				)
				( attribute "LOCATION" "C9N22"
					( Origin gFrontEnd )
				)
				( attribute "MATERIAL" "X6S"
					( Origin gFrontEnd )
				)
				( attribute "PACK_TYPE" "0603V"
					( Origin gFrontEnd )
				)
				( attribute "PART_NUMBER" "E15431-004"
					( Origin gFrontEnd )
				)
				( attribute "PHYS_PAGE" "210"
					( Origin gFrontEnd )
				)
				( attribute "ROT" "0"
					( Origin gFrontEnd )
				)
				( attribute "SEC" "1"
					( Origin gFrontEnd )
				)
				( attribute "SEC_TYPE" "0603V"
					( Origin gFrontEnd )
				)
				( attribute "TOLERANCE" "20%"
					( Origin gFrontEnd )
				)
				( attribute "VALUE" "22.0UF"
					( Origin gFrontEnd )
				)
				( attribute "VER" "1"
					( Origin gFrontEnd )
				)
				( attribute "VOLTAGE" "4V"
					( Units "uVoltage" "V" 1.000000)
					( Origin gFrontEnd )
				)
				( attribute "XY" "(-1000,3100)"
					( Origin gFrontEnd )
				)
				( attribute "CHIPS_PART_NAME" "CAP_A"
					( Origin gPackager )
				)
				( attribute "CDS_PART_NAME" "CAP_A_0603V-22.0UF,4V,20%,X6S,A"
					( Origin gPackager )
				)
				( attribute "GROUP" "PWR_MLCC_CAP"
					( Origin gFrontEnd )
				)
				( objectStatus "C9N22" )
			)
			( gate "@baseboard_fab2_lib.baseboard_fab2(sch_1):page210_i45"
				( attribute "CDS_LIB" "mstr_discrete"
					( Origin gPackager )
				)
				( attribute "CDS_LOCATION" "R9N4"
					( Origin gPackager )
				)
				( attribute "LOCATION" "R9N4"
					( Origin gFrontEnd )
				)
				( attribute "MATERIAL" "CHIP"
					( Origin gFrontEnd )
				)
				( attribute "PACK_TYPE" "0402"
					( Origin gFrontEnd )
				)
				( attribute "PART_NUMBER" "G21796-208"
					( Origin gFrontEnd )
				)
				( attribute "PHYS_PAGE" "210"
					( Origin gFrontEnd )
				)
				( attribute "ROT" "0"
					( Origin gFrontEnd )
				)
				( attribute "SEC" "1"
					( Origin gFrontEnd )
				)
				( attribute "TOLERANCE" "1.0%"
					( Origin gFrontEnd )
				)
				( attribute "VALUE" "51.1"
					( Origin gFrontEnd )
				)
				( attribute "VER" "2"
					( Origin gFrontEnd )
				)
				( attribute "WATTAGE" "1/16W"
					( Origin gFrontEnd )
				)
				( attribute "XY" "(-650,3100)"
					( Origin gFrontEnd )
				)
				( attribute "CHIPS_PART_NAME" "RES"
					( Origin gPackager )
				)
				( attribute "CDS_PART_NAME" "RES_0402-51.1,1.0%,1/16W,CHIP,A"
					( Origin gPackager )
				)
				( attribute "SEC_TYPE" "0402"
					( Origin gFrontEnd )
				)
				( attribute "CDS_SEC" "1"
					( Origin gPackager )
				)
				( objectStatus "R9N4" )
			)
			( gate "@baseboard_fab2_lib.baseboard_fab2(sch_1):page210_i51"
				( attribute "CDS_LIB" "mstr_discrete"
					( Origin gPackager )
				)
				( attribute "CDS_LOCATION" "EU1C1"
					( Origin gPackager )
				)
				( attribute "CDS_SEC" "1"
					( Origin gPackager )
				)
				( attribute "LOCATION" "EU1C1"
					( Origin gFrontEnd )
				)
				( attribute "MATERIAL" "IC"
					( Origin gFrontEnd )
				)
				( attribute "PACK_TYPE" "SM"
					( Origin gFrontEnd )
				)
				( attribute "PART_NUMBER" "H73684-001"
					( Origin gFrontEnd )
				)
				( attribute "PHYS_PAGE" "210"
					( Origin gFrontEnd )
				)
				( attribute "ROT" "0"
					( Origin gFrontEnd )
				)
				( attribute "SEC" "1"
					( Origin gFrontEnd )
				)
				( attribute "SEC_TYPE" "SM"
					( Origin gFrontEnd )
				)
				( attribute "VALUE" "IR35412"
					( Origin gFrontEnd )
				)
				( attribute "VER" "1"
					( Origin gFrontEnd )
				)
				( attribute "XY" "(-3725,3600)"
					( Origin gFrontEnd )
				)
				( attribute "CHIPS_PART_NAME" "IR354XX"
					( Origin gPackager )
				)
				( attribute "CDS_PART_NAME" "IR354XX_SM-IR35412,IC,H73684-0A"
					( Origin gPackager )
				)
				( objectStatus "EU1C1" )
			)
			( gate "@baseboard_fab2_lib.baseboard_fab2(sch_1):page210_i52"
				( attribute "CDS_LIB" "mstr_discrete"
					( Origin gPackager )
				)
				( attribute "CDS_LOCATION" "R1C37"
					( Origin gPackager )
				)
				( attribute "CDS_SEC" "1"
					( Origin gPackager )
				)
				( attribute "LOCATION" "R1C37"
					( Origin gFrontEnd )
				)
				( attribute "MATERIAL" "EMPTY"
					( Origin gFrontEnd )
				)
				( attribute "PACK_TYPE" "0402"
					( Origin gFrontEnd )
				)
				( attribute "PART_NUMBER" "G21796-187"
					( Origin gFrontEnd )
				)
				( attribute "PHYS_PAGE" "210"
					( Origin gFrontEnd )
				)
				( attribute "ROT" "0"
					( Origin gFrontEnd )
				)
				( attribute "SEC" "1"
					( Origin gPackager )
				)
				( attribute "TOLERANCE" "1%"
					( Origin gFrontEnd )
				)
				( attribute "VALUE" "68.1K"
					( Origin gFrontEnd )
				)
				( attribute "VER" "2"
					( Origin gFrontEnd )
				)
				( attribute "WATTAGE" "1/16W"
					( Origin gFrontEnd )
				)
				( attribute "XY" "(-1450,3775)"
					( Origin gFrontEnd )
				)
				( attribute "CHIPS_PART_NAME" "RES"
					( Origin gPackager )
				)
				( attribute "CDS_PART_NAME" "RES_0402-68.1K,1%,1/16W,EMPTY,A"
					( Origin gPackager )
				)
				( objectStatus "R1C37" )
			)
			( gate "@baseboard_fab2_lib.baseboard_fab2(sch_1):page211_i11"
				( attribute "CDS_LIB" "dev_discrete"
					( Origin gPackager )
				)
				( attribute "CDS_LOCATION" "C3P4"
					( Origin gPackager )
				)
				( attribute "CDS_SEC" "1"
					( Origin gPackager )
				)
				( attribute "LOCATION" "C3P4"
					( Origin gFrontEnd )
				)
				( attribute "MATERIAL" "X6S"
					( Origin gFrontEnd )
				)
				( attribute "PACK_TYPE" "0402V"
					( Origin gFrontEnd )
				)
				( attribute "PART_NUMBER" "D97712-004"
					( Origin gFrontEnd )
				)
				( attribute "PHYS_PAGE" "211"
					( Origin gFrontEnd )
				)
				( attribute "ROOM" "PVCCIO_CPU0"
					( Origin gFrontEnd )
				)
				( attribute "ROT" "0"
					( Origin gFrontEnd )
				)
				( attribute "SEC" "1"
					( Origin gFrontEnd )
				)
				( attribute "SEC_TYPE" "0402V"
					( Origin gFrontEnd )
				)
				( attribute "TOLERANCE" "10%"
					( Origin gFrontEnd )
				)
				( attribute "VALUE" "1.0UF"
					( Origin gFrontEnd )
				)
				( attribute "VER" "1"
					( Origin gFrontEnd )
				)
				( attribute "VOLTAGE" "6.3V"
					( Units "uVoltage" "V" 1.000000)
					( Origin gFrontEnd )
				)
				( attribute "XY" "(2475,1425)"
					( Origin gFrontEnd )
				)
				( attribute "CHIPS_PART_NAME" "CAP_A"
					( Origin gPackager )
				)
				( attribute "CDS_PART_NAME" "CAP_A_0402V-1.0UF,6.3V,10%,X6SA"
					( Origin gPackager )
				)
				( objectStatus "C3P4" )
			)
			( gate "@baseboard_fab2_lib.baseboard_fab2(sch_1):page211_i13"
				( attribute "CDS_LIB" "dev_discrete"
					( Origin gPackager )
				)
				( attribute "CDS_LOCATION" "C3P5"
					( Origin gPackager )
				)
				( attribute "CDS_SEC" "1"
					( Origin gPackager )
				)
				( attribute "LOCATION" "C3P5"
					( Origin gFrontEnd )
				)
				( attribute "MATERIAL" "X7R"
					( Origin gFrontEnd )
				)
				( attribute "PACK_TYPE" "0402V"
					( Origin gFrontEnd )
				)
				( attribute "PART_NUMBER" "A36096-030"
					( Origin gFrontEnd )
				)
				( attribute "PHYS_PAGE" "211"
					( Origin gFrontEnd )
				)
				( attribute "ROOM" "PVCCIO_CPU0"
					( Origin gFrontEnd )
				)
				( attribute "ROT" "0"
					( Origin gFrontEnd )
				)
				( attribute "SEC" "1"
					( Origin gFrontEnd )
				)
				( attribute "SEC_TYPE" "0402V"
					( Origin gFrontEnd )
				)
				( attribute "TOLERANCE" "10%"
					( Origin gFrontEnd )
				)
				( attribute "VALUE" "0.1UF"
					( Origin gFrontEnd )
				)
				( attribute "VER" "1"
					( Origin gFrontEnd )
				)
				( attribute "VOLTAGE" "16V"
					( Units "uVoltage" "V" 1.000000)
					( Origin gFrontEnd )
				)
				( attribute "XY" "(2075,1425)"
					( Origin gFrontEnd )
				)
				( attribute "CHIPS_PART_NAME" "CAP_A"
					( Origin gPackager )
				)
				( attribute "CDS_PART_NAME" "CAP_A_0402V-0.1UF,16V,10%,X7R,A"
					( Origin gPackager )
				)
				( objectStatus "C3P5" )
			)
			( gate "@baseboard_fab2_lib.baseboard_fab2(sch_1):page211_i16"
				( attribute "CDS_LIB" "mstr_discrete"
					( Origin gPackager )
				)
				( attribute "CDS_LOCATION" "R3P11"
					( Origin gPackager )
				)
				( attribute "CDS_SEC" "1"
					( Origin gPackager )
				)
				( attribute "LOCATION" "R3P11"
					( Origin gFrontEnd )
				)
				( attribute "MATERIAL" "CHIP"
					( Origin gFrontEnd )
				)
				( attribute "PACK_TYPE" "0402"
					( Origin gFrontEnd )
				)
				( attribute "PART_NUMBER" "G21497-005"
					( Origin gFrontEnd )
				)
				( attribute "PHYS_PAGE" "211"
					( Origin gFrontEnd )
				)
				( attribute "ROOM" "PVCCIO_CPU0"
					( Origin gFrontEnd )
				)
				( attribute "ROT" "0"
					( Origin gFrontEnd )
				)
				( attribute "SEC" "1"
					( Origin gFrontEnd )
				)
				( attribute "SEC_TYPE" "0402"
					( Origin gFrontEnd )
				)
				( attribute "TOLERANCE" "5%"
					( Origin gFrontEnd )
				)
				( attribute "VALUE" "0.0"
					( Origin gFrontEnd )
				)
				( attribute "VER" "1"
					( Origin gFrontEnd )
				)
				( attribute "WATTAGE" "1/16W"
					( Origin gFrontEnd )
				)
				( attribute "XY" "(-1250,2950)"
					( Origin gFrontEnd )
				)
				( attribute "CHIPS_PART_NAME" "RES"
					( Origin gPackager )
				)
				( attribute "CDS_PART_NAME" "RES_0402-0.0,5%,1/16W,CHIP,G21A"
					( Origin gPackager )
				)
				( objectStatus "R3P11" )
			)
			( gate "@baseboard_fab2_lib.baseboard_fab2(sch_1):page215_i70"
				( attribute "CDS_LIB" "mstr_discrete"
					( Origin gPackager )
				)
				( attribute "CDS_LOCATION" "R3T11"
					( Origin gPackager )
				)
				( attribute "CDS_SEC" "1"
					( Origin gPackager )
				)
				( attribute "LOCATION" "R3T11"
					( Origin gFrontEnd )
				)
				( attribute "MATERIAL" "CHIP"
					( Origin gFrontEnd )
				)
				( attribute "PACK_TYPE" "0402"
					( Origin gFrontEnd )
				)
				( attribute "PART_NUMBER" "G21796-047"
					( Origin gFrontEnd )
				)
				( attribute "PHYS_PAGE" "215"
					( Origin gFrontEnd )
				)
				( attribute "ROOM" "VDDQ_DEF_PWR_VR"
					( Origin gFrontEnd )
				)
				( attribute "ROT" "0"
					( Origin gFrontEnd )
				)
				( attribute "SEC" "1"
					( Origin gFrontEnd )
				)
				( attribute "SEC_TYPE" "0402"
					( Origin gFrontEnd )
				)
				( attribute "TOLERANCE" "1%"
					( Origin gFrontEnd )
				)
				( attribute "VALUE" "49.9"
					( Origin gFrontEnd )
				)
				( attribute "VER" "2"
					( Origin gFrontEnd )
				)
				( attribute "WATTAGE" "1/16W"
					( Origin gFrontEnd )
				)
				( attribute "XY" "(450,3325)"
					( Origin gFrontEnd )
				)
				( attribute "CHIPS_PART_NAME" "RES"
					( Origin gPackager )
				)
				( attribute "CDS_PART_NAME" "RES_0402-49.9,1%,1/16W,CHIP,G2A"
					( Origin gPackager )
				)
				( objectStatus "R3T11" )
			)
			( gate "@baseboard_fab2_lib.baseboard_fab2(sch_1):page211_i20"
				( attribute "CDS_LIB" "dev_discrete"
					( Origin gPackager )
				)
				( attribute "CDS_LOCATION" "C3P3"
					( Origin gPackager )
				)
				( attribute "LOCATION" "C3P3"
					( Origin gFrontEnd )
				)
				( attribute "MATERIAL" "X6S"
					( Origin gFrontEnd )
				)
				( attribute "PACK_TYPE" "0402V"
					( Origin gFrontEnd )
				)
				( attribute "PART_NUMBER" "D97712-004"
					( Origin gFrontEnd )
				)
				( attribute "PHYS_PAGE" "211"
					( Origin gFrontEnd )
				)
				( attribute "ROOM" "PVCCIO_CPU0"
					( Origin gFrontEnd )
				)
				( attribute "ROT" "0"
					( Origin gFrontEnd )
				)
				( attribute "SEC" "1"
					( Origin gFrontEnd )
				)
				( attribute "TOLERANCE" "10%"
					( Origin gFrontEnd )
				)
				( attribute "VALUE" "1.0UF"
					( Origin gFrontEnd )
				)
				( attribute "VER" "1"
					( Origin gFrontEnd )
				)
				( attribute "VOLTAGE" "6.3V"
					( Units "uVoltage" "V" 1.000000)
					( Origin gFrontEnd )
				)
				( attribute "XY" "(75,4175)"
					( Origin gFrontEnd )
				)
				( attribute "CHIPS_PART_NAME" "CAP_A"
					( Origin gPackager )
				)
				( attribute "CDS_PART_NAME" "CAP_A_0402V-1.0UF,6.3V,10%,X6SA"
					( Origin gPackager )
				)
				( attribute "SEC_TYPE" "0402V"
					( Origin gFrontEnd )
				)
				( attribute "CDS_SEC" "1"
					( Origin gPackager )
				)
				( objectStatus "C3P3" )
			)
			( gate "@baseboard_fab2_lib.baseboard_fab2(sch_1):page211_i22"
				( attribute "CDS_LIB" "dev_discrete"
					( Origin gPackager )
				)
				( attribute "CDS_LOCATION" "C3P7"
					( Origin gPackager )
				)
				( attribute "CDS_SEC" "1"
					( Origin gPackager )
				)
				( attribute "LOCATION" "C3P7"
					( Origin gFrontEnd )
				)
				( attribute "MATERIAL" "X7R"
					( Origin gFrontEnd )
				)
				( attribute "PACK_TYPE" "0402V"
					( Origin gFrontEnd )
				)
				( attribute "PART_NUMBER" "A36096-030"
					( Origin gFrontEnd )
				)
				( attribute "PHYS_PAGE" "211"
					( Origin gFrontEnd )
				)
				( attribute "ROOM" "PVCCIO_CPU0"
					( Origin gFrontEnd )
				)
				( attribute "ROT" "0"
					( Origin gFrontEnd )
				)
				( attribute "SEC" "1"
					( Origin gFrontEnd )
				)
				( attribute "SEC_TYPE" "0402V"
					( Origin gFrontEnd )
				)
				( attribute "TOLERANCE" "10%"
					( Origin gFrontEnd )
				)
				( attribute "VALUE" "0.1UF"
					( Origin gFrontEnd )
				)
				( attribute "VER" "1"
					( Origin gFrontEnd )
				)
				( attribute "VOLTAGE" "16V"
					( Units "uVoltage" "V" 1.000000)
					( Origin gFrontEnd )
				)
				( attribute "XY" "(-325,4175)"
					( Origin gFrontEnd )
				)
				( attribute "CHIPS_PART_NAME" "CAP_A"
					( Origin gPackager )
				)
				( attribute "CDS_PART_NAME" "CAP_A_0402V-0.1UF,16V,10%,X7R,A"
					( Origin gPackager )
				)
				( objectStatus "C3P7" )
			)
			( gate "@baseboard_fab2_lib.baseboard_fab2(sch_1):page211_i24"
				( attribute "CDS_LIB" "mstr_discrete"
					( Origin gPackager )
				)
				( attribute "CDS_LOCATION" "R3P22"
					( Origin gPackager )
				)
				( attribute "CDS_SEC" "1"
					( Origin gPackager )
				)
				( attribute "LOCATION" "R3P22"
					( Origin gFrontEnd )
				)
				( attribute "MATERIAL" "CHIP"
					( Origin gFrontEnd )
				)
				( attribute "PACK_TYPE" "0402"
					( Origin gFrontEnd )
				)
				( attribute "PART_NUMBER" "G21497-005"
					( Origin gFrontEnd )
				)
				( attribute "PHYS_PAGE" "211"
					( Origin gFrontEnd )
				)
				( attribute "ROOM" "PVCCIO_CPU0"
					( Origin gFrontEnd )
				)
				( attribute "ROT" "0"
					( Origin gFrontEnd )
				)
				( attribute "SEC" "1"
					( Origin gFrontEnd )
				)
				( attribute "SEC_TYPE" "0402"
					( Origin gFrontEnd )
				)
				( attribute "TOLERANCE" "5%"
					( Origin gFrontEnd )
				)
				( attribute "VALUE" "0.0"
					( Origin gFrontEnd )
				)
				( attribute "VER" "2"
					( Origin gFrontEnd )
				)
				( attribute "WATTAGE" "1/16W"
					( Origin gFrontEnd )
				)
				( attribute "XY" "(-625,4525)"
					( Origin gFrontEnd )
				)
				( attribute "CHIPS_PART_NAME" "RES"
					( Origin gPackager )
				)
				( attribute "CDS_PART_NAME" "RES_0402-0.0,5%,1/16W,CHIP,G21A"
					( Origin gPackager )
				)
				( objectStatus "R3P22" )
			)
			( gate "@baseboard_fab2_lib.baseboard_fab2(sch_1):page211_i100"
				( attribute "CDS_LIB" "mstr_discrete"
					( Origin gPackager )
				)
				( attribute "CDS_LOCATION" "R3P13"
					( Origin gPackager )
				)
				( attribute "CDS_SEC" "1"
					( Origin gPackager )
				)
				( attribute "LOCATION" "R3P13"
					( Origin gFrontEnd )
				)
				( attribute "MATERIAL" "CHIP"
					( Origin gFrontEnd )
				)
				( attribute "PACK_TYPE" "0402"
					( Origin gFrontEnd )
				)
				( attribute "PART_NUMBER" "G21796-017"
					( Origin gFrontEnd )
				)
				( attribute "PHYS_PAGE" "211"
					( Origin gFrontEnd )
				)
				( attribute "ROOM" "PVCCIN_CPU0_VR"
					( Origin gFrontEnd )
				)
				( attribute "ROT" "0"
					( Origin gFrontEnd )
				)
				( attribute "SEC" "1"
					( Origin gFrontEnd )
				)
				( attribute "SEC_TYPE" "0402"
					( Origin gFrontEnd )
				)
				( attribute "TOLERANCE" "1%"
					( Origin gFrontEnd )
				)
				( attribute "VALUE" "100.0"
					( Origin gFrontEnd )
				)
				( attribute "VER" "2"
					( Origin gFrontEnd )
				)
				( attribute "WATTAGE" "1/16W"
					( Origin gFrontEnd )
				)
				( attribute "XY" "(-1600,4500)"
					( Origin gFrontEnd )
				)
				( attribute "CHIPS_PART_NAME" "RES"
					( Origin gPackager )
				)
				( attribute "CDS_PART_NAME" "RES_0402-100.0,1%,1/16W,CHIP,GA"
					( Origin gPackager )
				)
				( objectStatus "R3P13" )
			)
			( gate "@baseboard_fab2_lib.baseboard_fab2(sch_1):page211_i29"
				( attribute "CDS_LIB" "mstr_discrete"
					( Origin gPackager )
				)
				( attribute "CDS_LOCATION" "R3P15"
					( Origin gPackager )
				)
				( attribute "CDS_SEC" "1"
					( Origin gPackager )
				)
				( attribute "LOCATION" "R3P15"
					( Origin gFrontEnd )
				)
				( attribute "MATERIAL" "CHIP"
					( Origin gFrontEnd )
				)
				( attribute "PACK_TYPE" "0402"
					( Origin gFrontEnd )
				)
				( attribute "PART_NUMBER" "G21796-009"
					( Origin gFrontEnd )
				)
				( attribute "PHYS_PAGE" "211"
					( Origin gFrontEnd )
				)
				( attribute "ROOM" "PVCCIO_CPU0"
					( Origin gFrontEnd )
				)
				( attribute "ROT" "0"
					( Origin gFrontEnd )
				)
				( attribute "SEC" "1"
					( Origin gFrontEnd )
				)
				( attribute "SEC_TYPE" "0402"
					( Origin gFrontEnd )
				)
				( attribute "TOLERANCE" "1%"
					( Origin gFrontEnd )
				)
				( attribute "VALUE" "150.0"
					( Origin gFrontEnd )
				)
				( attribute "VER" "1"
					( Origin gFrontEnd )
				)
				( attribute "WATTAGE" "1/16W"
					( Origin gFrontEnd )
				)
				( attribute "XY" "(-1975,3975)"
					( Origin gFrontEnd )
				)
				( attribute "CHIPS_PART_NAME" "RES"
					( Origin gPackager )
				)
				( attribute "CDS_PART_NAME" "RES_0402-150.0,1%,1/16W,CHIP,GA"
					( Origin gPackager )
				)
				( objectStatus "R3P15" )
			)
			( gate "@baseboard_fab2_lib.baseboard_fab2(sch_1):page211_i31"
				( attribute "CDS_LIB" "mstr_discrete"
					( Origin gPackager )
				)
				( attribute "CDS_LOCATION" "R3P12"
					( Origin gPackager )
				)
				( attribute "CDS_SEC" "1"
					( Origin gPackager )
				)
				( attribute "LOCATION" "R3P12"
					( Origin gFrontEnd )
				)
				( attribute "MATERIAL" "CHIP"
					( Origin gFrontEnd )
				)
				( attribute "NO_XNET_CONNECTION" "1"
					( Origin gFrontEnd )
				)
				( attribute "PACK_TYPE" "0402"
					( Origin gFrontEnd )
				)
				( attribute "PART_NUMBER" "G21796-160"
					( Origin gFrontEnd )
				)
				( attribute "PHYS_PAGE" "211"
					( Origin gFrontEnd )
				)
				( attribute "ROOM" "PVCCIO_CPU0"
					( Origin gFrontEnd )
				)
				( attribute "ROT" "0"
					( Origin gFrontEnd )
				)
				( attribute "SEC" "1"
					( Origin gFrontEnd )
				)
				( attribute "SEC_TYPE" "0402"
					( Origin gFrontEnd )
				)
				( attribute "TOLERANCE" "1%"
					( Origin gFrontEnd )
				)
				( attribute "VALUE" "100.0K"
					( Origin gFrontEnd )
				)
				( attribute "VER" "2"
					( Origin gFrontEnd )
				)
				( attribute "WATTAGE" "1/16W"
					( Origin gFrontEnd )
				)
				( attribute "XY" "(-2500,4650)"
					( Origin gFrontEnd )
				)
				( attribute "CHIPS_PART_NAME" "RES"
					( Origin gPackager )
				)
				( attribute "CDS_PART_NAME" "RES_0402-100.0K,1%,1/16W,CHIP,B"
					( Origin gPackager )
				)
				( objectStatus "R3P12" )
			)
			( gate "@baseboard_fab2_lib.baseboard_fab2(sch_1):page211_i32"
				( attribute "CDS_LIB" "mstr_discrete"
					( Origin gPackager )
				)
				( attribute "CDS_LOCATION" "R3P16"
					( Origin gPackager )
				)
				( attribute "CDS_SEC" "1"
					( Origin gPackager )
				)
				( attribute "LOCATION" "R3P16"
					( Origin gFrontEnd )
				)
				( attribute "MATERIAL" "CHIP"
					( Origin gFrontEnd )
				)
				( attribute "PACK_TYPE" "0402"
					( Origin gFrontEnd )
				)
				( attribute "PART_NUMBER" "G21796-003"
					( Origin gFrontEnd )
				)
				( attribute "PHYS_PAGE" "211"
					( Origin gFrontEnd )
				)
				( attribute "ROOM" "PVCCIO_CPU0"
					( Origin gFrontEnd )
				)
				( attribute "ROT" "0"
					( Origin gFrontEnd )
				)
				( attribute "SEC" "1"
					( Origin gFrontEnd )
				)
				( attribute "SEC_TYPE" "0402"
					( Origin gFrontEnd )
				)
				( attribute "TOLERANCE" "1%"
					( Origin gFrontEnd )
				)
				( attribute "VALUE" "1.5K"
					( Origin gFrontEnd )
				)
				( attribute "VER" "2"
					( Origin gFrontEnd )
				)
				( attribute "WATTAGE" "1/16W"
					( Origin gFrontEnd )
				)
				( attribute "XY" "(-2500,4300)"
					( Origin gFrontEnd )
				)
				( attribute "CHIPS_PART_NAME" "RES"
					( Origin gPackager )
				)
				( attribute "CDS_PART_NAME" "RES_0402-1.5K,1%,1/16W,CHIP,G2A"
					( Origin gPackager )
				)
				( objectStatus "R3P16" )
			)
			( gate "@baseboard_fab2_lib.baseboard_fab2(sch_1):page213_i105"
				( attribute "BOM_COST" "SM_THERM"
					( Origin gFrontEnd )
				)
				( attribute "CDS_LIB" "dev_discrete"
					( Origin gPackager )
				)
				( attribute "CDS_LOCATION" "C4D40"
					( Origin gPackager )
				)
				( attribute "CDS_SEC" "1"
					( Origin gPackager )
				)
				( attribute "LOCATION" "C4D40"
					( Origin gFrontEnd )
				)
				( attribute "MATERIAL" "X7R"
					( Origin gFrontEnd )
				)
				( attribute "PACK_TYPE" "0402V"
					( Origin gFrontEnd )
				)
				( attribute "PART_NUMBER" "A36096-030"
					( Origin gFrontEnd )
				)
				( attribute "PHYS_PAGE" "213"
					( Origin gFrontEnd )
				)
				( attribute "ROOM" "CPU_FANS"
					( Origin gFrontEnd )
				)
				( attribute "ROT" "0"
					( Origin gFrontEnd )
				)
				( attribute "SEC" "1"
					( Origin gFrontEnd )
				)
				( attribute "SEC_TYPE" "0402V"
					( Origin gFrontEnd )
				)
				( attribute "TOLERANCE" "10%"
					( Origin gFrontEnd )
				)
				( attribute "VALUE" "0.1UF"
					( Origin gFrontEnd )
				)
				( attribute "VER" "1"
					( Origin gFrontEnd )
				)
				( attribute "VOLTAGE" "16V"
					( Units "uVoltage" "V" 1.000000)
					( Origin gFrontEnd )
				)
				( attribute "XY" "(-2850,4250)"
					( Origin gFrontEnd )
				)
				( attribute "CHIPS_PART_NAME" "CAP_A"
					( Origin gPackager )
				)
				( attribute "CDS_PART_NAME" "CAP_A_0402V-0.1UF,16V,10%,X7R,A"
					( Origin gPackager )
				)
				( objectStatus "C4D40" )
			)
			( gate "@baseboard_fab2_lib.baseboard_fab2(sch_1):page211_i52"
				( attribute "CDS_LIB" "mstr_discrete"
					( Origin gPackager )
				)
				( attribute "CDS_LOCATION" "R3N31"
					( Origin gPackager )
				)
				( attribute "LOCATION" "R3N31"
					( Origin gFrontEnd )
				)
				( attribute "MATERIAL" "CHIP"
					( Origin gFrontEnd )
				)
				( attribute "PACK_TYPE" "0402"
					( Origin gFrontEnd )
				)
				( attribute "PART_NUMBER" "G21796-043"
					( Origin gFrontEnd )
				)
				( attribute "PHYS_PAGE" "211"
					( Origin gFrontEnd )
				)
				( attribute "ROOM" "PVCCIO_CPU0"
					( Origin gFrontEnd )
				)
				( attribute "ROT" "0"
					( Origin gFrontEnd )
				)
				( attribute "SEC" "1"
					( Origin gFrontEnd )
				)
				( attribute "TOLERANCE" "1%"
					( Origin gFrontEnd )
				)
				( attribute "VALUE" "3.16K"
					( Origin gFrontEnd )
				)
				( attribute "VER" "2"
					( Origin gFrontEnd )
				)
				( attribute "WATTAGE" "1/16W"
					( Origin gFrontEnd )
				)
				( attribute "XY" "(-925,1200)"
					( Origin gFrontEnd )
				)
				( attribute "CHIPS_PART_NAME" "RES"
					( Origin gPackager )
				)
				( attribute "CDS_PART_NAME" "RES_0402-3.16K,1%,1/16W,CHIP,GA"
					( Origin gPackager )
				)
				( attribute "SEC_TYPE" "0402"
					( Origin gFrontEnd )
				)
				( attribute "CDS_SEC" "1"
					( Origin gPackager )
				)
				( objectStatus "R3N31" )
			)
			( gate "@baseboard_fab2_lib.baseboard_fab2(sch_1):page211_i56"
				( attribute "CDS_LIB" "mstr_discrete"
					( Origin gPackager )
				)
				( attribute "CDS_LOCATION" "R3P25"
					( Origin gPackager )
				)
				( attribute "CDS_SEC" "1"
					( Origin gPackager )
				)
				( attribute "LOCATION" "R3P25"
					( Origin gFrontEnd )
				)
				( attribute "MATERIAL" "CHIP"
					( Origin gFrontEnd )
				)
				( attribute "PACK_TYPE" "0402"
					( Origin gFrontEnd )
				)
				( attribute "PART_NUMBER" "G21796-026"
					( Origin gFrontEnd )
				)
				( attribute "PHYS_PAGE" "211"
					( Origin gFrontEnd )
				)
				( attribute "ROOM" "PVCCIO_CPU0"
					( Origin gFrontEnd )
				)
				( attribute "ROT" "0"
					( Origin gFrontEnd )
				)
				( attribute "SEC" "1"
					( Origin gFrontEnd )
				)
				( attribute "SEC_TYPE" "0402"
					( Origin gFrontEnd )
				)
				( attribute "TOLERANCE" "1%"
					( Origin gFrontEnd )
				)
				( attribute "VALUE" "1.00K"
					( Origin gFrontEnd )
				)
				( attribute "VER" "2"
					( Origin gFrontEnd )
				)
				( attribute "WATTAGE" "1/16W"
					( Origin gFrontEnd )
				)
				( attribute "XY" "(775,4100)"
					( Origin gFrontEnd )
				)
				( attribute "CHIPS_PART_NAME" "RES"
					( Origin gPackager )
				)
				( attribute "CDS_PART_NAME" "RES_0402-1.00K,1%,1/16W,CHIP,GA"
					( Origin gPackager )
				)
				( objectStatus "R3P25" )
			)
			( gate "@baseboard_fab2_lib.baseboard_fab2(sch_1):page211_i58"
				( attribute "CDS_LIB" "mstr_discrete"
					( Origin gPackager )
				)
				( attribute "CDS_LOCATION" "R3P20"
					( Origin gPackager )
				)
				( attribute "CDS_SEC" "1"
					( Origin gPackager )
				)
				( attribute "LOCATION" "R3P20"
					( Origin gFrontEnd )
				)
				( attribute "MATERIAL" "CHIP"
					( Origin gFrontEnd )
				)
				( attribute "PACK_TYPE" "0402"
					( Origin gFrontEnd )
				)
				( attribute "PART_NUMBER" "G21796-250"
					( Origin gFrontEnd )
				)
				( attribute "PHYS_PAGE" "211"
					( Origin gFrontEnd )
				)
				( attribute "ROOM" "PVCCIO_CPU0"
					( Origin gFrontEnd )
				)
				( attribute "ROT" "0"
					( Origin gFrontEnd )
				)
				( attribute "SEC" "1"
					( Origin gFrontEnd )
				)
				( attribute "SEC_TYPE" "0402"
					( Origin gFrontEnd )
				)
				( attribute "TOLERANCE" "1.0%"
					( Origin gFrontEnd )
				)
				( attribute "VALUE" "22.1"
					( Origin gFrontEnd )
				)
				( attribute "VER" "1"
					( Origin gFrontEnd )
				)
				( attribute "WATTAGE" "1/16W"
					( Origin gFrontEnd )
				)
				( attribute "XY" "(1875,3600)"
					( Origin gFrontEnd )
				)
				( attribute "CHIPS_PART_NAME" "RES"
					( Origin gPackager )
				)
				( attribute "CDS_PART_NAME" "RES_0402-22.1,1.0%,1/16W,CHIP,A"
					( Origin gPackager )
				)
				( objectStatus "R3P20" )
			)
			( gate "@baseboard_fab2_lib.baseboard_fab2(sch_1):page211_i60"
				( attribute "CDS_LIB" "mstr_discrete"
					( Origin gPackager )
				)
				( attribute "CDS_LOCATION" "R3N23"
					( Origin gPackager )
				)
				( attribute "CDS_SEC" "1"
					( Origin gPackager )
				)
				( attribute "LOCATION" "R3N23"
					( Origin gFrontEnd )
				)
				( attribute "MATERIAL" "EMPTY"
					( Origin gFrontEnd )
				)
				( attribute "PACK_TYPE" "0402"
					( Origin gFrontEnd )
				)
				( attribute "PART_NUMBER" "G21796-311"
					( Origin gFrontEnd )
				)
				( attribute "PHYS_PAGE" "211"
					( Origin gFrontEnd )
				)
				( attribute "ROOM" "PVCCIO_CPU0"
					( Origin gFrontEnd )
				)
				( attribute "ROT" "0"
					( Origin gFrontEnd )
				)
				( attribute "SEC" "1"
					( Origin gFrontEnd )
				)
				( attribute "SEC_TYPE" "0402"
					( Origin gFrontEnd )
				)
				( attribute "TOLERANCE" "1.0%"
					( Origin gFrontEnd )
				)
				( attribute "VALUE" "2.26K"
					( Origin gFrontEnd )
				)
				( attribute "VER" "2"
					( Origin gFrontEnd )
				)
				( attribute "WATTAGE" "1/16W"
					( Origin gFrontEnd )
				)
				( attribute "XY" "(1525,4100)"
					( Origin gFrontEnd )
				)
				( attribute "CHIPS_PART_NAME" "RES"
					( Origin gPackager )
				)
				( attribute "CDS_PART_NAME" "RES_0402-2.26K,1.0%,1/16W,EMPTA"
					( Origin gPackager )
				)
				( objectStatus "R3N23" )
			)
			( gate "@baseboard_fab2_lib.baseboard_fab2(sch_1):page211_i61"
				( attribute "CDS_LIB" "mstr_discrete"
					( Origin gPackager )
				)
				( attribute "CDS_LOCATION" "R3P1"
					( Origin gPackager )
				)
				( attribute "CDS_SEC" "1"
					( Origin gPackager )
				)
				( attribute "LOCATION" "R3P1"
					( Origin gFrontEnd )
				)
				( attribute "MATERIAL" "CHIP"
					( Origin gFrontEnd )
				)
				( attribute "PACK_TYPE" "0402"
					( Origin gFrontEnd )
				)
				( attribute "PART_NUMBER" "G21497-005"
					( Origin gFrontEnd )
				)
				( attribute "PHYS_PAGE" "211"
					( Origin gFrontEnd )
				)
				( attribute "ROOM" "PVCCIO_CPU0"
					( Origin gFrontEnd )
				)
				( attribute "ROT" "0"
					( Origin gFrontEnd )
				)
				( attribute "SEC" "1"
					( Origin gFrontEnd )
				)
				( attribute "SEC_TYPE" "0402"
					( Origin gFrontEnd )
				)
				( attribute "TOLERANCE" "5%"
					( Origin gFrontEnd )
				)
				( attribute "VALUE" "0.0"
					( Origin gFrontEnd )
				)
				( attribute "VER" "1"
					( Origin gFrontEnd )
				)
				( attribute "WATTAGE" "1/16W"
					( Origin gFrontEnd )
				)
				( attribute "XY" "(1375,3150)"
					( Origin gFrontEnd )
				)
				( attribute "CHIPS_PART_NAME" "RES"
					( Origin gPackager )
				)
				( attribute "CDS_PART_NAME" "RES_0402-0.0,5%,1/16W,CHIP,G21A"
					( Origin gPackager )
				)
				( objectStatus "R3P1" )
			)
			( gate "@baseboard_fab2_lib.baseboard_fab2(sch_1):page211_i64"
				( attribute "CDS_LIB" "mstr_discrete"
					( Origin gPackager )
				)
				( attribute "CDS_LOCATION" "R3P18"
					( Origin gPackager )
				)
				( attribute "CDS_SEC" "1"
					( Origin gPackager )
				)
				( attribute "LOCATION" "R3P18"
					( Origin gFrontEnd )
				)
				( attribute "MATERIAL" "CHIP"
					( Origin gFrontEnd )
				)
				( attribute "PACK_TYPE" "0402"
					( Origin gFrontEnd )
				)
				( attribute "PART_NUMBER" "G21796-026"
					( Origin gFrontEnd )
				)
				( attribute "PHYS_PAGE" "211"
					( Origin gFrontEnd )
				)
				( attribute "ROT" "0"
					( Origin gFrontEnd )
				)
				( attribute "SEC" "1"
					( Origin gFrontEnd )
				)
				( attribute "SEC_TYPE" "0402"
					( Origin gFrontEnd )
				)
				( attribute "TOLERANCE" "1%"
					( Origin gFrontEnd )
				)
				( attribute "VALUE" "1.00K"
					( Origin gFrontEnd )
				)
				( attribute "VER" "2"
					( Origin gFrontEnd )
				)
				( attribute "WATTAGE" "1/16W"
					( Origin gFrontEnd )
				)
				( attribute "XY" "(2075,4050)"
					( Origin gFrontEnd )
				)
				( attribute "CHIPS_PART_NAME" "RES"
					( Origin gPackager )
				)
				( attribute "CDS_PART_NAME" "RES_0402-1.00K,1%,1/16W,CHIP,GA"
					( Origin gPackager )
				)
				( objectStatus "R3P18" )
			)
			( gate "@baseboard_fab2_lib.baseboard_fab2(sch_1):page215_i73"
				( attribute "BOM_COST" "SM_CONTROLLER"
					( Origin gFrontEnd )
				)
				( attribute "CDS_LIB" "mstr_discrete"
					( Origin gPackager )
				)
				( attribute "CDS_LOCATION" "R7G10"
					( Origin gPackager )
				)
				( attribute "CDS_SEC" "1"
					( Origin gPackager )
				)
				( attribute "LOCATION" "R7G10"
					( Origin gFrontEnd )
				)
				( attribute "MATERIAL" "CHIP"
					( Origin gFrontEnd )
				)
				( attribute "PACK_TYPE" "0402"
					( Origin gFrontEnd )
				)
				( attribute "PART_NUMBER" "G21796-311"
					( Origin gFrontEnd )
				)
				( attribute "PHYS_PAGE" "215"
					( Origin gFrontEnd )
				)
				( attribute "ROOM" "SMBUS"
					( Origin gFrontEnd )
				)
				( attribute "ROT" "0"
					( Origin gFrontEnd )
				)
				( attribute "SEC" "1"
					( Origin gFrontEnd )
				)
				( attribute "SEC_TYPE" "0402"
					( Origin gFrontEnd )
				)
				( attribute "SKU" "B"
					( Origin gFrontEnd )
				)
				( attribute "TOLERANCE" "1.0%"
					( Origin gFrontEnd )
				)
				( attribute "VALUE" "2.26K"
					( Origin gFrontEnd )
				)
				( attribute "VER" "2"
					( Origin gFrontEnd )
				)
				( attribute "WATTAGE" "1/16W"
					( Origin gFrontEnd )
				)
				( attribute "XY" "(1400,-50)"
					( Origin gFrontEnd )
				)
				( attribute "CHIPS_PART_NAME" "RES"
					( Origin gPackager )
				)
				( attribute "CDS_PART_NAME" "RES_0402-2.26K,1.0%,1/16W,CHIPA"
					( Origin gPackager )
				)
				( objectStatus "R7G10" )
			)
			( gate "@baseboard_fab2_lib.baseboard_fab2(sch_1):page211_i71"
				( attribute "CDS_LIB" "mstr_discrete"
					( Origin gPackager )
				)
				( attribute "CDS_LOCATION" "C3P6"
					( Origin gPackager )
				)
				( attribute "CDS_SEC" "1"
					( Origin gPackager )
				)
				( attribute "LOCATION" "C3P6"
					( Origin gFrontEnd )
				)
				( attribute "MATERIAL" "X7R"
					( Origin gFrontEnd )
				)
				( attribute "PACK_TYPE" "0402LF"
					( Origin gFrontEnd )
				)
				( attribute "PART_NUMBER" "A36096-046"
					( Origin gFrontEnd )
				)
				( attribute "PHYS_PAGE" "211"
					( Origin gFrontEnd )
				)
				( attribute "ROOM" "PVCCIO_CPU0_VR"
					( Origin gFrontEnd )
				)
				( attribute "ROT" "0"
					( Origin gFrontEnd )
				)
				( attribute "SEC" "1"
					( Origin gFrontEnd )
				)
				( attribute "SEC_TYPE" "0402LF"
					( Origin gFrontEnd )
				)
				( attribute "TOLERANCE" "10%"
					( Origin gFrontEnd )
				)
				( attribute "VALUE" "1000PF"
					( Origin gFrontEnd )
				)
				( attribute "VER" "1"
					( Origin gFrontEnd )
				)
				( attribute "VOLTAGE" "50V"
					( Units "uVoltage" "V" 1.000000)
					( Origin gFrontEnd )
				)
				( attribute "XY" "(1650,2750)"
					( Origin gFrontEnd )
				)
				( attribute "CHIPS_PART_NAME" "CAP"
					( Origin gPackager )
				)
				( attribute "CDS_PART_NAME" "CAP_0402LF-1000PF,50V,10%,X7R,A"
					( Origin gPackager )
				)
				( objectStatus "C3P6" )
			)
			( gate "@baseboard_fab2_lib.baseboard_fab2(sch_1):page211_i81"
				( attribute "CDS_LIB" "mstr_discrete"
					( Origin gPackager )
				)
				( attribute "CDS_LOCATION" "R3N19"
					( Origin gPackager )
				)
				( attribute "LOCATION" "R3N19"
					( Origin gFrontEnd )
				)
				( attribute "MATERIAL" "CHIP"
					( Origin gFrontEnd )
				)
				( attribute "PACK_TYPE" "0402"
					( Origin gFrontEnd )
				)
				( attribute "PART_NUMBER" "G21796-066"
					( Origin gFrontEnd )
				)
				( attribute "PHYS_PAGE" "211"
					( Origin gFrontEnd )
				)
				( attribute "ROOM" "PVCCIO_CPU0"
					( Origin gFrontEnd )
				)
				( attribute "ROT" "0"
					( Origin gFrontEnd )
				)
				( attribute "SEC" "1"
					( Origin gFrontEnd )
				)
				( attribute "TOLERANCE" "1%"
					( Origin gFrontEnd )
				)
				( attribute "VALUE" "10.0"
					( Origin gFrontEnd )
				)
				( attribute "VER" "1"
					( Origin gFrontEnd )
				)
				( attribute "WATTAGE" "1/16W"
					( Origin gFrontEnd )
				)
				( attribute "XY" "(-2600,2050)"
					( Origin gFrontEnd )
				)
				( attribute "CHIPS_PART_NAME" "RES"
					( Origin gPackager )
				)
				( attribute "CDS_PART_NAME" "RES_0402-10.0,1%,1/16W,CHIP,G2A"
					( Origin gPackager )
				)
				( attribute "SEC_TYPE" "0402"
					( Origin gFrontEnd )
				)
				( attribute "CDS_SEC" "1"
					( Origin gPackager )
				)
				( objectStatus "R3N19" )
			)
			( gate "@baseboard_fab2_lib.baseboard_fab2(sch_1):page211_i83"
				( attribute "CDS_LIB" "mstr_discrete"
					( Origin gPackager )
				)
				( attribute "CDS_LOCATION" "C3N39"
					( Origin gPackager )
				)
				( attribute "CDS_SEC" "1"
					( Origin gPackager )
				)
				( attribute "LOCATION" "C3N39"
					( Origin gFrontEnd )
				)
				( attribute "MATERIAL" "X7R"
					( Origin gFrontEnd )
				)
				( attribute "PACK_TYPE" "0402LF"
					( Origin gFrontEnd )
				)
				( attribute "PART_NUMBER" "A36096-050"
					( Origin gFrontEnd )
				)
				( attribute "PHYS_PAGE" "211"
					( Origin gFrontEnd )
				)
				( attribute "ROOM" "PVCCIO_CPU0"
					( Origin gFrontEnd )
				)
				( attribute "ROT" "0"
					( Origin gFrontEnd )
				)
				( attribute "SEC" "1"
					( Origin gFrontEnd )
				)
				( attribute "SEC_TYPE" "0402LF"
					( Origin gFrontEnd )
				)
				( attribute "TOLERANCE" "10%"
					( Origin gFrontEnd )
				)
				( attribute "VALUE" "220PF"
					( Origin gFrontEnd )
				)
				( attribute "VER" "1"
					( Origin gFrontEnd )
				)
				( attribute "VOLTAGE" "50V"
					( Units "uVoltage" "V" 1.000000)
					( Origin gFrontEnd )
				)
				( attribute "XY" "(-2400,1850)"
					( Origin gFrontEnd )
				)
				( attribute "CHIPS_PART_NAME" "CAP"
					( Origin gPackager )
				)
				( attribute "CDS_PART_NAME" "CAP_0402LF-220PF,50V,10%,X7R,AA"
					( Origin gPackager )
				)
				( objectStatus "C3N39" )
			)
			( gate "@baseboard_fab2_lib.baseboard_fab2(sch_1):page211_i87"
				( attribute "CDS_LIB" "mstr_discrete"
					( Origin gPackager )
				)
				( attribute "CDS_LOCATION" "R3P26"
					( Origin gPackager )
				)
				( attribute "LOCATION" "R3P26"
					( Origin gFrontEnd )
				)
				( attribute "MATERIAL" "CHIP"
					( Origin gFrontEnd )
				)
				( attribute "PACK_TYPE" "0402"
					( Origin gFrontEnd )
				)
				( attribute "PART_NUMBER" "G21497-005"
					( Origin gFrontEnd )
				)
				( attribute "PHYS_PAGE" "211"
					( Origin gFrontEnd )
				)
				( attribute "ROOM" "PVCCIN_CPU0_VR"
					( Origin gFrontEnd )
				)
				( attribute "ROT" "0"
					( Origin gFrontEnd )
				)
				( attribute "SEC" "1"
					( Origin gFrontEnd )
				)
				( attribute "TOLERANCE" "5%"
					( Origin gFrontEnd )
				)
				( attribute "VALUE" "0.0"
					( Origin gFrontEnd )
				)
				( attribute "VER" "1"
					( Origin gFrontEnd )
				)
				( attribute "WATTAGE" "1/16W"
					( Origin gFrontEnd )
				)
				( attribute "XY" "(-1950,3250)"
					( Origin gFrontEnd )
				)
				( attribute "CHIPS_PART_NAME" "RES"
					( Origin gPackager )
				)
				( attribute "CDS_PART_NAME" "RES_0402-0.0,5%,1/16W,CHIP,G21A"
					( Origin gPackager )
				)
				( attribute "SEC_TYPE" "0402"
					( Origin gFrontEnd )
				)
				( attribute "CDS_SEC" "1"
					( Origin gPackager )
				)
				( objectStatus "R3P26" )
			)
			( gate "@baseboard_fab2_lib.baseboard_fab2(sch_1):page211_i88"
				( attribute "BOM_COST" "SM_CONTROLLER"
					( Origin gFrontEnd )
				)
				( attribute "CDS_LIB" "mstr_discrete"
					( Origin gPackager )
				)
				( attribute "CDS_LOCATION" "R3P21"
					( Origin gPackager )
				)
				( attribute "CDS_SEC" "1"
					( Origin gPackager )
				)
				( attribute "LOCATION" "R3P21"
					( Origin gFrontEnd )
				)
				( attribute "MATERIAL" "EMPTY"
					( Origin gFrontEnd )
				)
				( attribute "PACK_TYPE" "0402"
					( Origin gFrontEnd )
				)
				( attribute "PART_NUMBER" "G21796-010"
					( Origin gFrontEnd )
				)
				( attribute "PHYS_PAGE" "211"
					( Origin gFrontEnd )
				)
				( attribute "ROOM" "BMC"
					( Origin gFrontEnd )
				)
				( attribute "ROT" "0"
					( Origin gFrontEnd )
				)
				( attribute "SEC" "1"
					( Origin gPackager )
				)
				( attribute "TOLERANCE" "1%"
					( Origin gFrontEnd )
				)
				( attribute "VALUE" "100.0K"
					( Origin gFrontEnd )
				)
				( attribute "VER" "2"
					( Origin gFrontEnd )
				)
				( attribute "WATTAGE" "1/16W"
					( Origin gFrontEnd )
				)
				( attribute "XY" "(-1125,4300)"
					( Origin gFrontEnd )
				)
				( attribute "CHIPS_PART_NAME" "RES"
					( Origin gPackager )
				)
				( attribute "CDS_PART_NAME" "RES_0402-100.0K,1%,1/16W,EMPTYA"
					( Origin gPackager )
				)
				( objectStatus "R3P21" )
			)
			( gate "@baseboard_fab2_lib.baseboard_fab2(sch_1):page211_i93"
				( attribute "CDS_LIB" "mstr_controller"
					( Origin gPackager )
				)
				( attribute "CDS_LMAN_SYM_OUTLINE" "-400,850,400,-850"
					( Origin gPackager )
				)
				( attribute "CDS_LOCATION" "EU3P1"
					( Origin gPackager )
				)
				( attribute "CDS_SEC" "1"
					( Origin gPackager )
				)
				( attribute "LOCATION" "EU3P1"
					( Origin gFrontEnd )
				)
				( attribute "MATERIAL" "IC"
					( Origin gFrontEnd )
				)
				( attribute "PACK_TYPE" "QFN"
					( Origin gFrontEnd )
				)
				( attribute "PART_NUMBER" "H89187-001"
					( Origin gFrontEnd )
				)
				( attribute "PHYS_PAGE" "211"
					( Origin gFrontEnd )
				)
				( attribute "ROT" "0"
					( Origin gFrontEnd )
				)
				( attribute "SEC" "1"
					( Origin gFrontEnd )
				)
				( attribute "SEC_TYPE" "QFN"
					( Origin gFrontEnd )
				)
				( attribute "VER" "1"
					( Origin gFrontEnd )
				)
				( attribute "XY" "(100,2850)"
					( Origin gFrontEnd )
				)
				( attribute "CHIPS_PART_NAME" "PXE1110B"
					( Origin gPackager )
				)
				( attribute "CDS_PART_NAME" "PXE1110B_QFN-IC,H89187-001"
					( Origin gPackager )
				)
				( objectStatus "EU3P1" )
			)
			( gate "@baseboard_fab2_lib.baseboard_fab2(sch_1):page214_i178"
				( attribute "BOM_COST" "PROC_VRD_PVCCIO_CPU1"
					( Origin gFrontEnd )
				)
				( attribute "CDS_LIB" "mstr_discrete"
					( Origin gPackager )
				)
				( attribute "CDS_LOCATION" "C4E7"
					( Origin gPackager )
				)
				( attribute "CDS_SEC" "1"
					( Origin gPackager )
				)
				( attribute "LOCATION" "C4E7"
					( Origin gFrontEnd )
				)
				( attribute "MATERIAL" "ALUM"
					( Origin gFrontEnd )
				)
				( attribute "PACK_TYPE" "3018"
					( Origin gFrontEnd )
				)
				( attribute "PART_NUMBER" "699013-049"
					( Origin gFrontEnd )
				)
				( attribute "PHYS_PAGE" "214"
					( Origin gFrontEnd )
				)
				( attribute "ROOM" "PVCCIO_CPU1"
					( Origin gFrontEnd )
				)
				( attribute "ROT" "2"
					( Origin gFrontEnd )
				)
				( attribute "SEC" "1"
					( Origin gFrontEnd )
				)
				( attribute "SEC_TYPE" "3018"
					( Origin gFrontEnd )
				)
				( attribute "TOLERANCE" "20%"
					( Origin gFrontEnd )
				)
				( attribute "VALUE" "470UF"
					( Origin gFrontEnd )
				)
				( attribute "VER" "1"
					( Origin gFrontEnd )
				)
				( attribute "VOLTAGE" "2.5V"
					( Units "uVoltage" "V" 1.000000)
					( Origin gFrontEnd )
				)
				( attribute "XY" "(3200,2300)"
					( Origin gFrontEnd )
				)
				( attribute "CHIPS_PART_NAME" "CAPP"
					( Origin gPackager )
				)
				( attribute "CDS_PART_NAME" "CAPP_3018-470UF,2.5V,20%,ALUM,A"
					( Origin gPackager )
				)
				( attribute "GROUP" "PWR_BULK_CAP"
					( Origin gFrontEnd )
				)
				( objectStatus "C4E7" )
			)
			( gate "@baseboard_fab2_lib.baseboard_fab2(sch_1):page214_i177"
				( attribute "BOM_COST" "PROC_VRD_PVCCIO_CPU1"
					( Origin gFrontEnd )
				)
				( attribute "CDS_LIB" "mstr_discrete"
					( Origin gPackager )
				)
				( attribute "CDS_LOCATION" "C6R12"
					( Origin gPackager )
				)
				( attribute "CDS_SEC" "1"
					( Origin gPackager )
				)
				( attribute "LOCATION" "C6R12"
					( Origin gFrontEnd )
				)
				( attribute "MATERIAL" "ALUM"
					( Origin gFrontEnd )
				)
				( attribute "PACK_TYPE" "3018"
					( Origin gFrontEnd )
				)
				( attribute "PART_NUMBER" "699013-049"
					( Origin gFrontEnd )
				)
				( attribute "PHYS_PAGE" "214"
					( Origin gFrontEnd )
				)
				( attribute "ROOM" "PVCCIO_CPU1"
					( Origin gFrontEnd )
				)
				( attribute "ROT" "2"
					( Origin gFrontEnd )
				)
				( attribute "SEC" "1"
					( Origin gFrontEnd )
				)
				( attribute "SEC_TYPE" "3018"
					( Origin gFrontEnd )
				)
				( attribute "TOLERANCE" "20%"
					( Origin gFrontEnd )
				)
				( attribute "VALUE" "470UF"
					( Origin gFrontEnd )
				)
				( attribute "VER" "1"
					( Origin gFrontEnd )
				)
				( attribute "VOLTAGE" "2.5V"
					( Units "uVoltage" "V" 1.000000)
					( Origin gFrontEnd )
				)
				( attribute "XY" "(2650,2300)"
					( Origin gFrontEnd )
				)
				( attribute "CHIPS_PART_NAME" "CAPP"
					( Origin gPackager )
				)
				( attribute "CDS_PART_NAME" "CAPP_3018-470UF,2.5V,20%,ALUM,A"
					( Origin gPackager )
				)
				( attribute "GROUP" "PWR_BULK_CAP"
					( Origin gFrontEnd )
				)
				( objectStatus "C6R12" )
			)
			( gate "@baseboard_fab2_lib.baseboard_fab2(sch_1):page212_i18"
				( attribute "BOM_COST" "PROC_VRD_PVCCIO_CPU0"
					( Origin gFrontEnd )
				)
				( attribute "CDS_LIB" "mstr_discrete"
					( Origin gPackager )
				)
				( attribute "CDS_LOCATION" "C3N35"
					( Origin gPackager )
				)
				( attribute "CDS_SEC" "1"
					( Origin gPackager )
				)
				( attribute "LOCATION" "C3N35"
					( Origin gFrontEnd )
				)
				( attribute "MATERIAL" "ALUM"
					( Origin gFrontEnd )
				)
				( attribute "PACK_TYPE" "3018"
					( Origin gFrontEnd )
				)
				( attribute "PART_NUMBER" "699013-049"
					( Origin gFrontEnd )
				)
				( attribute "PHYS_PAGE" "212"
					( Origin gFrontEnd )
				)
				( attribute "ROOM" "PVCCIO_CPU0"
					( Origin gFrontEnd )
				)
				( attribute "ROT" "2"
					( Origin gFrontEnd )
				)
				( attribute "SEC" "1"
					( Origin gPackager )
				)
				( attribute "TOLERANCE" "20%"
					( Origin gFrontEnd )
				)
				( attribute "VALUE" "470UF"
					( Origin gFrontEnd )
				)
				( attribute "VER" "1"
					( Origin gFrontEnd )
				)
				( attribute "VOLTAGE" "2.5V"
					( Units "uVoltage" "V" 1.000000)
					( Origin gFrontEnd )
				)
				( attribute "XY" "(850,1300)"
					( Origin gFrontEnd )
				)
				( attribute "CHIPS_PART_NAME" "CAPP"
					( Origin gPackager )
				)
				( attribute "CDS_PART_NAME" "CAPP_3018-470UF,2.5V,20%,ALUM,A"
					( Origin gPackager )
				)
				( attribute "GROUP" "PWR_BULK_CAP"
					( Origin gFrontEnd )
				)
				( objectStatus "C3N35" )
			)
			( gate "@baseboard_fab2_lib.baseboard_fab2(sch_1):page212_i23"
				( attribute "BOM_COST" "PROC_VRD_PVCCIO_CPU0"
					( Origin gFrontEnd )
				)
				( attribute "CDS_LIB" "dev_discrete"
					( Origin gPackager )
				)
				( attribute "CDS_LOCATION" "C7C6"
					( Origin gPackager )
				)
				( attribute "CDS_SEC" "1"
					( Origin gPackager )
				)
				( attribute "LOCATION" "C7C6"
					( Origin gFrontEnd )
				)
				( attribute "MATERIAL" "X6S"
					( Origin gFrontEnd )
				)
				( attribute "PACK_TYPE" "0603V"
					( Origin gFrontEnd )
				)
				( attribute "PART_NUMBER" "E15431-004"
					( Origin gFrontEnd )
				)
				( attribute "PHYS_PAGE" "212"
					( Origin gFrontEnd )
				)
				( attribute "ROOM" "PVCCIO_CPU0"
					( Origin gFrontEnd )
				)
				( attribute "ROT" "0"
					( Origin gFrontEnd )
				)
				( attribute "SEC" "1"
					( Origin gFrontEnd )
				)
				( attribute "SEC_TYPE" "0603V"
					( Origin gFrontEnd )
				)
				( attribute "TOLERANCE" "20%"
					( Origin gFrontEnd )
				)
				( attribute "VALUE" "22.0UF"
					( Origin gFrontEnd )
				)
				( attribute "VER" "1"
					( Origin gFrontEnd )
				)
				( attribute "VOLTAGE" "4V"
					( Units "uVoltage" "V" 1.000000)
					( Origin gFrontEnd )
				)
				( attribute "XY" "(3350,3450)"
					( Origin gFrontEnd )
				)
				( attribute "CHIPS_PART_NAME" "CAP_A"
					( Origin gPackager )
				)
				( attribute "CDS_PART_NAME" "CAP_A_0603V-22.0UF,4V,20%,X6S,A"
					( Origin gPackager )
				)
				( attribute "GROUP" "PWR_MLCC_CAP"
					( Origin gFrontEnd )
				)
				( objectStatus "C7C6" )
			)
			( gate "@baseboard_fab2_lib.baseboard_fab2(sch_1):page236_i179"
				( attribute "CDS_LIB" "w_hdl"
					( Origin gPackager )
				)
				( attribute "CDS_LMAN_SYM_OUTLINE" "-75,100,75,-100"
					( Origin gPackager )
				)
				( attribute "LOCATION" "L7A4"
					( Origin gFrontEnd )
				)
				( attribute "PACK_TYPE" "DISCRET-GB1"
					( Origin gFrontEnd )
				)
				( attribute "PART_NUMBER" "068.3012N.M001"
					( Origin gFrontEnd )
				)
				( attribute "PHYS_PAGE" "236"
					( Origin gFrontEnd )
				)
				( attribute "ROT" "1"
					( Origin gFrontEnd )
				)
				( attribute "SEC" "1"
					( Origin gFrontEnd )
				)
				( attribute "SEC_TYPE" "DISCRET-GB1"
					( Origin gFrontEnd )
				)
				( attribute "VALUE" "IND-300NH-20-GP"
					( Origin gFrontEnd )
				)
				( attribute "VER" "1"
					( Origin gFrontEnd )
				)
				( attribute "XY" "(11400,2300)"
					( Origin gFrontEnd )
				)
				( attribute "CHIPS_PART_NAME" "IND-300NH-20-GP"
					( Origin gPackager )
				)
				( attribute "CDS_PART_NAME" "IND-300NH-20-GP_DISCRET-GB1-INA"
					( Origin gPackager )
				)
				( attribute "CDS_LOCATION" "L7A4"
					( Origin gPackager )
				)
				( attribute "CDS_SEC" "1"
					( Origin gPackager )
				)
				( attribute "ATTRIBUTE" "300NH"
					( Origin gFrontEnd )
				)
				( attribute "PACK_SIZE" "DCR=0.17MOHM"
					( Origin gFrontEnd )
				)
				( attribute "RATED" "ISAT=33A@25C"
					( Origin gFrontEnd )
				)
				( attribute "TYPE" "IRMS=66A@DELTA_T<40C"
					( Origin gFrontEnd )
				)
				( objectStatus "L7A4" )
			)
			( gate "@baseboard_fab2_lib.baseboard_fab2(sch_1):page214_i173"
				( attribute "BOM_COST" "PROC_SIDEBAND"
					( Origin gFrontEnd )
				)
				( attribute "CDS_LIB" "mstr_discrete"
					( Origin gPackager )
				)
				( attribute "CDS_LOCATION" "R6R5"
					( Origin gPackager )
				)
				( attribute "CDS_SEC" "1"
					( Origin gPackager )
				)
				( attribute "LOCATION" "R6R5"
					( Origin gFrontEnd )
				)
				( attribute "MATERIAL" "CHIP"
					( Origin gFrontEnd )
				)
				( attribute "PACK_TYPE" "0402"
					( Origin gFrontEnd )
				)
				( attribute "PART_NUMBER" "G21497-005"
					( Origin gFrontEnd )
				)
				( attribute "PHYS_PAGE" "214"
					( Origin gFrontEnd )
				)
				( attribute "ROOM" "CPU0"
					( Origin gFrontEnd )
				)
				( attribute "ROT" "0"
					( Origin gFrontEnd )
				)
				( attribute "SEC" "1"
					( Origin gFrontEnd )
				)
				( attribute "SEC_TYPE" "0402"
					( Origin gFrontEnd )
				)
				( attribute "TOLERANCE" "5%"
					( Origin gFrontEnd )
				)
				( attribute "VALUE" "0.0"
					( Origin gFrontEnd )
				)
				( attribute "VER" "1"
					( Origin gFrontEnd )
				)
				( attribute "WATTAGE" "1/16W"
					( Origin gFrontEnd )
				)
				( attribute "XY" "(-1575,4750)"
					( Origin gFrontEnd )
				)
				( attribute "CHIPS_PART_NAME" "RES"
					( Origin gPackager )
				)
				( attribute "CDS_PART_NAME" "RES_0402-0.0,5%,1/16W,CHIP,G21A"
					( Origin gPackager )
				)
				( objectStatus "R6R5" )
			)
			( gate "@baseboard_fab2_lib.baseboard_fab2(sch_1):page212_i33"
				( attribute "CDS_LIB" "mstr_discrete"
					( Origin gPackager )
				)
				( attribute "CDS_LOCATION" "C7C18"
					( Origin gPackager )
				)
				( attribute "CDS_SEC" "1"
					( Origin gPackager )
				)
				( attribute "LOCATION" "C7C18"
					( Origin gFrontEnd )
				)
				( attribute "MATERIAL" "X7R"
					( Origin gFrontEnd )
				)
				( attribute "PACK_TYPE" "0402"
					( Origin gFrontEnd )
				)
				( attribute "PART_NUMBER" "A36096-155"
					( Origin gFrontEnd )
				)
				( attribute "PHYS_PAGE" "212"
					( Origin gFrontEnd )
				)
				( attribute "ROOM" "PVCCIO_CPU0"
					( Origin gFrontEnd )
				)
				( attribute "ROT" "0"
					( Origin gFrontEnd )
				)
				( attribute "SEC" "1"
					( Origin gFrontEnd )
				)
				( attribute "SEC_TYPE" "0402"
					( Origin gFrontEnd )
				)
				( attribute "TOLERANCE" "10%"
					( Origin gFrontEnd )
				)
				( attribute "VALUE" "0.22UF"
					( Origin gFrontEnd )
				)
				( attribute "VER" "1"
					( Origin gFrontEnd )
				)
				( attribute "VOLTAGE" "16V"
					( Units "uVoltage" "V" 1.000000)
					( Origin gFrontEnd )
				)
				( attribute "XY" "(-350,4225)"
					( Origin gFrontEnd )
				)
				( attribute "CHIPS_PART_NAME" "CAP"
					( Origin gPackager )
				)
				( attribute "CDS_PART_NAME" "CAP_0402-0.22UF,16V,10%,X7R,A3A"
					( Origin gPackager )
				)
				( objectStatus "C7C18" )
			)
			( gate "@baseboard_fab2_lib.baseboard_fab2(sch_1):page216_i149"
				( attribute "CDS_LIB" "w_hdl"
					( Origin gPackager )
				)
				( attribute "CDS_LMAN_SYM_OUTLINE" "-50,25,50,-25"
					( Origin gPackager )
				)
				( attribute "LOCATION" "C7G35"
					( Origin gFrontEnd )
				)
				( attribute "PACK_TYPE" "SMD-BCG6"
					( Origin gFrontEnd )
				)
				( attribute "PART_NUMBER" "78.10523.8FL"
					( Origin gFrontEnd )
				)
				( attribute "PHYS_PAGE" "216"
					( Origin gFrontEnd )
				)
				( attribute "ROT" "0"
					( Origin gFrontEnd )
				)
				( attribute "SEC" "1"
					( Origin gFrontEnd )
				)
				( attribute "SEC_TYPE" "SMD-BCG6"
					( Origin gFrontEnd )
				)
				( attribute "VALUE" "SC1U10V2KX-4-GP"
					( Origin gFrontEnd )
				)
				( attribute "VER" "1"
					( Origin gFrontEnd )
				)
				( attribute "XY" "(-250,2525)"
					( Origin gFrontEnd )
				)
				( attribute "CHIPS_PART_NAME" "SC1U10V2KX-4-GP"
					( Origin gPackager )
				)
				( attribute "CDS_PART_NAME" "SC1U10V2KX-4-GP_SMD-BCG6-SC1U1A"
					( Origin gPackager )
				)
				( attribute "CDS_LOCATION" "C7G35"
					( Origin gPackager )
				)
				( attribute "CDS_SEC" "1"
					( Origin gPackager )
				)
				( attribute "ATTRIBUTE" "1UF"
					( Origin gFrontEnd )
				)
				( attribute "PACK_SIZE" "0402"
					( Origin gFrontEnd )
				)
				( attribute "RATED" "10V"
					( Origin gFrontEnd )
				)
				( attribute "TOLERANCE" "10%"
					( Origin gFrontEnd )
				)
				( objectStatus "C7G35" )
			)
			( gate "@baseboard_fab2_lib.baseboard_fab2(sch_1):page212_i36"
				( attribute "CDS_LIB" "mstr_discrete"
					( Origin gPackager )
				)
				( attribute "CDS_LOCATION" "C7C17"
					( Origin gPackager )
				)
				( attribute "CDS_SEC" "1"
					( Origin gPackager )
				)
				( attribute "LOCATION" "C7C17"
					( Origin gFrontEnd )
				)
				( attribute "MATERIAL" "X6S"
					( Origin gFrontEnd )
				)
				( attribute "PACK_TYPE" "0402"
					( Origin gFrontEnd )
				)
				( attribute "PART_NUMBER" "D97712-011"
					( Origin gFrontEnd )
				)
				( attribute "PHYS_PAGE" "212"
					( Origin gFrontEnd )
				)
				( attribute "ROOM" "PVCCIO_CPU0"
					( Origin gFrontEnd )
				)
				( attribute "ROT" "0"
					( Origin gFrontEnd )
				)
				( attribute "SEC" "1"
					( Origin gFrontEnd )
				)
				( attribute "SEC_TYPE" "0402"
					( Origin gFrontEnd )
				)
				( attribute "TOLERANCE" "10%"
					( Origin gFrontEnd )
				)
				( attribute "VALUE" "1.0UF"
					( Origin gFrontEnd )
				)
				( attribute "VER" "1"
					( Origin gFrontEnd )
				)
				( attribute "VOLTAGE" "16V"
					( Units "uVoltage" "V" 1.000000)
					( Origin gFrontEnd )
				)
				( attribute "XY" "(-1350,4225)"
					( Origin gFrontEnd )
				)
				( attribute "CHIPS_PART_NAME" "CAP"
					( Origin gPackager )
				)
				( attribute "CDS_PART_NAME" "CAP_0402-1.0UF,16V,10%,X6S,D97A"
					( Origin gPackager )
				)
				( objectStatus "C7C17" )
			)
			( gate "@baseboard_fab2_lib.baseboard_fab2(sch_1):page212_i37"
				( attribute "CDS_LIB" "mstr_discrete"
					( Origin gPackager )
				)
				( attribute "CDS_LOCATION" "C7C14"
					( Origin gPackager )
				)
				( attribute "CDS_SEC" "1"
					( Origin gPackager )
				)
				( attribute "LOCATION" "C7C14"
					( Origin gFrontEnd )
				)
				( attribute "MATERIAL" "X7R"
					( Origin gFrontEnd )
				)
				( attribute "PACK_TYPE" "0402"
					( Origin gFrontEnd )
				)
				( attribute "PART_NUMBER" "A36096-104"
					( Origin gFrontEnd )
				)
				( attribute "PHYS_PAGE" "212"
					( Origin gFrontEnd )
				)
				( attribute "ROOM" "PVCCIO_CPU0"
					( Origin gFrontEnd )
				)
				( attribute "ROT" "2"
					( Origin gFrontEnd )
				)
				( attribute "SEC" "1"
					( Origin gFrontEnd )
				)
				( attribute "SEC_TYPE" "0402"
					( Origin gFrontEnd )
				)
				( attribute "SPOF" "TRUE"
					( Origin gFrontEnd )
				)
				( attribute "TOLERANCE" "10%"
					( Origin gFrontEnd )
				)
				( attribute "VALUE" "0.220UF"
					( Origin gFrontEnd )
				)
				( attribute "VER" "1"
					( Origin gFrontEnd )
				)
				( attribute "VOLTAGE" "16V"
					( Units "uVoltage" "V" 1.000000)
					( Origin gFrontEnd )
				)
				( attribute "XY" "(-1600,3600)"
					( Origin gFrontEnd )
				)
				( attribute "CHIPS_PART_NAME" "CAP"
					( Origin gPackager )
				)
				( attribute "CDS_PART_NAME" "CAP_0402-0.220UF,16V,10%,X7R,AA"
					( Origin gPackager )
				)
				( objectStatus "C7C14" )
			)
			( gate "@baseboard_fab2_lib.baseboard_fab2(sch_1):page212_i38"
				( attribute "CDS_LIB" "dev_discrete"
					( Origin gPackager )
				)
				( attribute "CDS_LOCATION" "C7C11"
					( Origin gPackager )
				)
				( attribute "CDS_SEC" "1"
					( Origin gPackager )
				)
				( attribute "LOCATION" "C7C11"
					( Origin gFrontEnd )
				)
				( attribute "MATERIAL" "X7R"
					( Origin gFrontEnd )
				)
				( attribute "PACK_TYPE" "0402V"
					( Origin gFrontEnd )
				)
				( attribute "PART_NUMBER" "A36096-030"
					( Origin gFrontEnd )
				)
				( attribute "PHYS_PAGE" "212"
					( Origin gFrontEnd )
				)
				( attribute "ROOM" "PVCCIO_CPU0"
					( Origin gFrontEnd )
				)
				( attribute "ROT" "0"
					( Origin gFrontEnd )
				)
				( attribute "SEC" "1"
					( Origin gFrontEnd )
				)
				( attribute "SEC_TYPE" "0402V"
					( Origin gFrontEnd )
				)
				( attribute "TOLERANCE" "10%"
					( Origin gFrontEnd )
				)
				( attribute "VALUE" "0.1UF"
					( Origin gFrontEnd )
				)
				( attribute "VER" "1"
					( Origin gFrontEnd )
				)
				( attribute "VOLTAGE" "16V"
					( Units "uVoltage" "V" 1.000000)
					( Origin gFrontEnd )
				)
				( attribute "XY" "(-1650,4225)"
					( Origin gFrontEnd )
				)
				( attribute "CHIPS_PART_NAME" "CAP_A"
					( Origin gPackager )
				)
				( attribute "CDS_PART_NAME" "CAP_A_0402V-0.1UF,16V,10%,X7R,A"
					( Origin gPackager )
				)
				( objectStatus "C7C11" )
			)
			( gate "@baseboard_fab2_lib.baseboard_fab2(sch_1):page212_i39"
				( attribute "CDS_LIB" "mstr_discrete"
					( Origin gPackager )
				)
				( attribute "CDS_LOCATION" "C7C12"
					( Origin gPackager )
				)
				( attribute "CDS_SEC" "1"
					( Origin gPackager )
				)
				( attribute "LOCATION" "C7C12"
					( Origin gFrontEnd )
				)
				( attribute "MATERIAL" "X6S"
					( Origin gFrontEnd )
				)
				( attribute "PACK_TYPE" "0402"
					( Origin gFrontEnd )
				)
				( attribute "PART_NUMBER" "D97712-011"
					( Origin gFrontEnd )
				)
				( attribute "PHYS_PAGE" "212"
					( Origin gFrontEnd )
				)
				( attribute "ROOM" "PVCCIO_CPU0"
					( Origin gFrontEnd )
				)
				( attribute "ROT" "0"
					( Origin gFrontEnd )
				)
				( attribute "SEC" "1"
					( Origin gFrontEnd )
				)
				( attribute "SEC_TYPE" "0402"
					( Origin gFrontEnd )
				)
				( attribute "TOLERANCE" "10%"
					( Origin gFrontEnd )
				)
				( attribute "VALUE" "1.0UF"
					( Origin gFrontEnd )
				)
				( attribute "VER" "1"
					( Origin gFrontEnd )
				)
				( attribute "VOLTAGE" "16V"
					( Units "uVoltage" "V" 1.000000)
					( Origin gFrontEnd )
				)
				( attribute "XY" "(-1950,4225)"
					( Origin gFrontEnd )
				)
				( attribute "CHIPS_PART_NAME" "CAP"
					( Origin gPackager )
				)
				( attribute "CDS_PART_NAME" "CAP_0402-1.0UF,16V,10%,X6S,D97A"
					( Origin gPackager )
				)
				( objectStatus "C7C12" )
			)
			( gate "@baseboard_fab2_lib.baseboard_fab2(sch_1):page212_i40"
				( attribute "CDS_LIB" "mstr_discrete"
					( Origin gPackager )
				)
				( attribute "CDS_LOCATION" "C3N36"
					( Origin gPackager )
				)
				( attribute "CDS_SEC" "1"
					( Origin gPackager )
				)
				( attribute "LOCATION" "C3N36"
					( Origin gFrontEnd )
				)
				( attribute "MATERIAL" "X6S"
					( Origin gFrontEnd )
				)
				( attribute "PACK_TYPE" "0805"
					( Origin gFrontEnd )
				)
				( attribute "PART_NUMBER" "C95333-007"
					( Origin gFrontEnd )
				)
				( attribute "PHYS_PAGE" "212"
					( Origin gFrontEnd )
				)
				( attribute "ROOM" "PVCCIO_CPU0"
					( Origin gFrontEnd )
				)
				( attribute "ROT" "0"
					( Origin gFrontEnd )
				)
				( attribute "SEC" "1"
					( Origin gFrontEnd )
				)
				( attribute "SEC_TYPE" "0805"
					( Origin gFrontEnd )
				)
				( attribute "TOLERANCE" "10%"
					( Origin gFrontEnd )
				)
				( attribute "VALUE" "10UF"
					( Origin gFrontEnd )
				)
				( attribute "VER" "1"
					( Origin gFrontEnd )
				)
				( attribute "VOLTAGE" "16V"
					( Units "uVoltage" "V" 1.000000)
					( Origin gFrontEnd )
				)
				( attribute "XY" "(-2250,4225)"
					( Origin gFrontEnd )
				)
				( attribute "CHIPS_PART_NAME" "CAP"
					( Origin gPackager )
				)
				( attribute "CDS_PART_NAME" "CAP_0805-10UF,16V,10%,X6S,C953A"
					( Origin gPackager )
				)
				( objectStatus "C3N36" )
			)
			( gate "@baseboard_fab2_lib.baseboard_fab2(sch_1):page212_i41"
				( attribute "CDS_LIB" "mstr_discrete"
					( Origin gPackager )
				)
				( attribute "CDS_LOCATION" "C3N33"
					( Origin gPackager )
				)
				( attribute "CDS_SEC" "1"
					( Origin gPackager )
				)
				( attribute "LOCATION" "C3N33"
					( Origin gFrontEnd )
				)
				( attribute "MATERIAL" "X6S"
					( Origin gFrontEnd )
				)
				( attribute "PACK_TYPE" "0805"
					( Origin gFrontEnd )
				)
				( attribute "PART_NUMBER" "C95333-007"
					( Origin gFrontEnd )
				)
				( attribute "PHYS_PAGE" "212"
					( Origin gFrontEnd )
				)
				( attribute "ROOM" "PVCCIO_CPU0"
					( Origin gFrontEnd )
				)
				( attribute "ROT" "0"
					( Origin gFrontEnd )
				)
				( attribute "SEC" "1"
					( Origin gFrontEnd )
				)
				( attribute "SEC_TYPE" "0805"
					( Origin gFrontEnd )
				)
				( attribute "TOLERANCE" "10%"
					( Origin gFrontEnd )
				)
				( attribute "VALUE" "10UF"
					( Origin gFrontEnd )
				)
				( attribute "VER" "1"
					( Origin gFrontEnd )
				)
				( attribute "VOLTAGE" "16V"
					( Units "uVoltage" "V" 1.000000)
					( Origin gFrontEnd )
				)
				( attribute "XY" "(-2475,4225)"
					( Origin gFrontEnd )
				)
				( attribute "CHIPS_PART_NAME" "CAP"
					( Origin gPackager )
				)
				( attribute "CDS_PART_NAME" "CAP_0805-10UF,16V,10%,X6S,C953A"
					( Origin gPackager )
				)
				( objectStatus "C3N33" )
			)
			( gate "@baseboard_fab2_lib.baseboard_fab2(sch_1):page212_i43"
				( attribute "CDS_LIB" "mstr_discrete"
					( Origin gPackager )
				)
				( attribute "CDS_LOCATION" "C3N34"
					( Origin gPackager )
				)
				( attribute "CDS_SEC" "1"
					( Origin gPackager )
				)
				( attribute "LOCATION" "C3N34"
					( Origin gFrontEnd )
				)
				( attribute "MATERIAL" "X6S"
					( Origin gFrontEnd )
				)
				( attribute "PACK_TYPE" "0805"
					( Origin gFrontEnd )
				)
				( attribute "PART_NUMBER" "C95333-007"
					( Origin gFrontEnd )
				)
				( attribute "PHYS_PAGE" "212"
					( Origin gFrontEnd )
				)
				( attribute "ROOM" "PVCCIO_CPU0"
					( Origin gFrontEnd )
				)
				( attribute "ROT" "0"
					( Origin gFrontEnd )
				)
				( attribute "SEC" "1"
					( Origin gFrontEnd )
				)
				( attribute "SEC_TYPE" "0805"
					( Origin gFrontEnd )
				)
				( attribute "TOLERANCE" "10%"
					( Origin gFrontEnd )
				)
				( attribute "VALUE" "10UF"
					( Origin gFrontEnd )
				)
				( attribute "VER" "1"
					( Origin gFrontEnd )
				)
				( attribute "VOLTAGE" "16V"
					( Units "uVoltage" "V" 1.000000)
					( Origin gFrontEnd )
				)
				( attribute "XY" "(-2725,4225)"
					( Origin gFrontEnd )
				)
				( attribute "CHIPS_PART_NAME" "CAP"
					( Origin gPackager )
				)
				( attribute "CDS_PART_NAME" "CAP_0805-10UF,16V,10%,X6S,C953A"
					( Origin gPackager )
				)
				( objectStatus "C3N34" )
			)
			( gate "@baseboard_fab2_lib.baseboard_fab2(sch_1):page203_i129"
				( attribute "BOM_COST" "PROC_SIDEBAND"
					( Origin gFrontEnd )
				)
				( attribute "CDS_LIB" "mstr_discrete"
					( Origin gPackager )
				)
				( attribute "CDS_LOCATION" "R6P10"
					( Origin gPackager )
				)
				( attribute "CDS_SEC" "1"
					( Origin gPackager )
				)
				( attribute "LOCATION" "R6P10"
					( Origin gFrontEnd )
				)
				( attribute "MATERIAL" "CHIP"
					( Origin gFrontEnd )
				)
				( attribute "PACK_TYPE" "0402"
					( Origin gFrontEnd )
				)
				( attribute "PART_NUMBER" "G21497-005"
					( Origin gFrontEnd )
				)
				( attribute "PHYS_PAGE" "203"
					( Origin gFrontEnd )
				)
				( attribute "ROOM" "CPU0"
					( Origin gFrontEnd )
				)
				( attribute "ROT" "0"
					( Origin gFrontEnd )
				)
				( attribute "SEC" "1"
					( Origin gFrontEnd )
				)
				( attribute "SEC_TYPE" "0402"
					( Origin gFrontEnd )
				)
				( attribute "TOLERANCE" "5%"
					( Origin gFrontEnd )
				)
				( attribute "VALUE" "0.0"
					( Origin gFrontEnd )
				)
				( attribute "VER" "1"
					( Origin gFrontEnd )
				)
				( attribute "WATTAGE" "1/16W"
					( Origin gFrontEnd )
				)
				( attribute "XY" "(-5425,2000)"
					( Origin gFrontEnd )
				)
				( attribute "CHIPS_PART_NAME" "RES"
					( Origin gPackager )
				)
				( attribute "CDS_PART_NAME" "RES_0402-0.0,5%,1/16W,CHIP,G21A"
					( Origin gPackager )
				)
				( objectStatus "R6P10" )
			)
			( gate "@baseboard_fab2_lib.baseboard_fab2(sch_1):page203_i128"
				( attribute "BOM_COST" "PROC_SIDEBAND"
					( Origin gFrontEnd )
				)
				( attribute "CDS_LIB" "mstr_discrete"
					( Origin gPackager )
				)
				( attribute "CDS_LOCATION" "R6P19"
					( Origin gPackager )
				)
				( attribute "CDS_SEC" "1"
					( Origin gPackager )
				)
				( attribute "LOCATION" "R6P19"
					( Origin gFrontEnd )
				)
				( attribute "MATERIAL" "CHIP"
					( Origin gFrontEnd )
				)
				( attribute "PACK_TYPE" "0402"
					( Origin gFrontEnd )
				)
				( attribute "PART_NUMBER" "G21497-005"
					( Origin gFrontEnd )
				)
				( attribute "PHYS_PAGE" "203"
					( Origin gFrontEnd )
				)
				( attribute "ROOM" "CPU0"
					( Origin gFrontEnd )
				)
				( attribute "ROT" "0"
					( Origin gFrontEnd )
				)
				( attribute "SEC" "1"
					( Origin gFrontEnd )
				)
				( attribute "SEC_TYPE" "0402"
					( Origin gFrontEnd )
				)
				( attribute "TOLERANCE" "5%"
					( Origin gFrontEnd )
				)
				( attribute "VALUE" "0.0"
					( Origin gFrontEnd )
				)
				( attribute "VER" "1"
					( Origin gFrontEnd )
				)
				( attribute "WATTAGE" "1/16W"
					( Origin gFrontEnd )
				)
				( attribute "XY" "(-5325,4750)"
					( Origin gFrontEnd )
				)
				( attribute "CHIPS_PART_NAME" "RES"
					( Origin gPackager )
				)
				( attribute "CDS_PART_NAME" "RES_0402-0.0,5%,1/16W,CHIP,G21A"
					( Origin gPackager )
				)
				( objectStatus "R6P19" )
			)
			( gate "@baseboard_fab2_lib.baseboard_fab2(sch_1):page214_i174"
				( attribute "CDS_LIB" "w_hdl"
					( Origin gPackager )
				)
				( attribute "CDS_LMAN_SYM_OUTLINE" "-75,100,75,-100"
					( Origin gPackager )
				)
				( attribute "LOCATION" "L4E2"
					( Origin gFrontEnd )
				)
				( attribute "PACK_TYPE" "DISCRET-GA1"
					( Origin gFrontEnd )
				)
				( attribute "PART_NUMBER" "068.1512N.M001"
					( Origin gFrontEnd )
				)
				( attribute "PHYS_PAGE" "214"
					( Origin gFrontEnd )
				)
				( attribute "ROT" "1"
					( Origin gFrontEnd )
				)
				( attribute "SEC" "1"
					( Origin gFrontEnd )
				)
				( attribute "SEC_TYPE" "DISCRET-GA1"
					( Origin gFrontEnd )
				)
				( attribute "VALUE" "IND-150NH-56-GP"
					( Origin gFrontEnd )
				)
				( attribute "VER" "1"
					( Origin gFrontEnd )
				)
				( attribute "XY" "(3000,3650)"
					( Origin gFrontEnd )
				)
				( attribute "CHIPS_PART_NAME" "IND-150NH-56-GP"
					( Origin gPackager )
				)
				( attribute "CDS_PART_NAME" "IND-150NH-56-GP_DISCRET-GA1-INA"
					( Origin gPackager )
				)
				( attribute "CDS_LOCATION" "L4E2"
					( Origin gPackager )
				)
				( attribute "CDS_SEC" "1"
					( Origin gPackager )
				)
				( attribute "ATTRIBUTE" "150NH"
					( Origin gFrontEnd )
				)
				( attribute "PACK_SIZE" "DCR=0.17MOHM"
					( Origin gFrontEnd )
				)
				( attribute "RATED" "ISAT=75A@25C"
					( Origin gFrontEnd )
				)
				( attribute "TYPE" "IRMS=66A@DELTA_T<40C"
					( Origin gFrontEnd )
				)
				( objectStatus "L4E2" )
			)
			( gate "@baseboard_fab2_lib.baseboard_fab2(sch_1):page212_i60"
				( attribute "BOM_COST" "PROC_VRD_PVCCIO_CPU0"
					( Origin gFrontEnd )
				)
				( attribute "CDS_LIB" "dev_discrete"
					( Origin gPackager )
				)
				( attribute "CDS_LOCATION" "C3P1"
					( Origin gPackager )
				)
				( attribute "LOCATION" "C3P1"
					( Origin gFrontEnd )
				)
				( attribute "MATERIAL" "EMPTY"
					( Origin gFrontEnd )
				)
				( attribute "PACK_TYPE" "0402V"
					( Origin gFrontEnd )
				)
				( attribute "PART_NUMBER" "A36096-030"
					( Origin gFrontEnd )
				)
				( attribute "PHYS_PAGE" "212"
					( Origin gFrontEnd )
				)
				( attribute "ROOM" "PVCCIO_CPU0"
					( Origin gFrontEnd )
				)
				( attribute "ROT" "0"
					( Origin gFrontEnd )
				)
				( attribute "SEC" "1"
					( Origin gFrontEnd )
				)
				( attribute "TOLERANCE" "10%"
					( Origin gFrontEnd )
				)
				( attribute "VALUE" "0.1UF"
					( Origin gFrontEnd )
				)
				( attribute "VER" "1"
					( Origin gFrontEnd )
				)
				( attribute "VOLTAGE" "16V"
					( Units "uVoltage" "V" 1.000000)
					( Origin gFrontEnd )
				)
				( attribute "XY" "(-1925,1675)"
					( Origin gFrontEnd )
				)
				( attribute "CHIPS_PART_NAME" "CAP_A"
					( Origin gPackager )
				)
				( attribute "CDS_PART_NAME" "CAP_A_0402V-0.1UF,16V,10%,EMPTA"
					( Origin gPackager )
				)
				( attribute "SEC_TYPE" "0402V"
					( Origin gFrontEnd )
				)
				( attribute "CDS_SEC" "1"
					( Origin gPackager )
				)
				( objectStatus "C3P1" )
			)
			( gate "@baseboard_fab2_lib.baseboard_fab2(sch_1):page212_i68"
				( attribute "BOM_COST" "PROC_VRD_PVCCIO_CPU0"
					( Origin gFrontEnd )
				)
				( attribute "CDS_LIB" "mstr_discrete"
					( Origin gPackager )
				)
				( attribute "CDS_LOCATION" "R3N20"
					( Origin gPackager )
				)
				( attribute "LOCATION" "R3N20"
					( Origin gFrontEnd )
				)
				( attribute "MATERIAL" "CHIP"
					( Origin gFrontEnd )
				)
				( attribute "PACK_TYPE" "0402"
					( Origin gFrontEnd )
				)
				( attribute "PART_NUMBER" "G21796-017"
					( Origin gFrontEnd )
				)
				( attribute "PHYS_PAGE" "212"
					( Origin gFrontEnd )
				)
				( attribute "ROOM" "PVCCIO_CPU0"
					( Origin gFrontEnd )
				)
				( attribute "ROT" "0"
					( Origin gFrontEnd )
				)
				( attribute "SEC" "1"
					( Origin gFrontEnd )
				)
				( attribute "TOLERANCE" "1%"
					( Origin gFrontEnd )
				)
				( attribute "VALUE" "100.0"
					( Origin gFrontEnd )
				)
				( attribute "VER" "1"
					( Origin gFrontEnd )
				)
				( attribute "WATTAGE" "1/16W"
					( Origin gFrontEnd )
				)
				( attribute "XY" "(-725,1150)"
					( Origin gFrontEnd )
				)
				( attribute "CHIPS_PART_NAME" "RES"
					( Origin gPackager )
				)
				( attribute "CDS_PART_NAME" "RES_0402-100.0,1%,1/16W,CHIP,GA"
					( Origin gPackager )
				)
				( attribute "SEC_TYPE" "0402"
					( Origin gFrontEnd )
				)
				( attribute "CDS_SEC" "1"
					( Origin gPackager )
				)
				( objectStatus "R3N20" )
			)
			( gate "@baseboard_fab2_lib.baseboard_fab2(sch_1):page212_i74"
				( attribute "BOM_COST" "PROC_VRD_PVCCIO_CPU0"
					( Origin gFrontEnd )
				)
				( attribute "CDS_LIB" "mstr_discrete"
					( Origin gPackager )
				)
				( attribute "CDS_LOCATION" "R3N21"
					( Origin gPackager )
				)
				( attribute "LOCATION" "R3N21"
					( Origin gFrontEnd )
				)
				( attribute "MATERIAL" "CHIP"
					( Origin gFrontEnd )
				)
				( attribute "PACK_TYPE" "0402"
					( Origin gFrontEnd )
				)
				( attribute "PART_NUMBER" "G21796-017"
					( Origin gFrontEnd )
				)
				( attribute "PHYS_PAGE" "212"
					( Origin gFrontEnd )
				)
				( attribute "ROOM" "PVCCIO_CPU0"
					( Origin gFrontEnd )
				)
				( attribute "ROT" "0"
					( Origin gFrontEnd )
				)
				( attribute "SEC" "1"
					( Origin gFrontEnd )
				)
				( attribute "TOLERANCE" "1%"
					( Origin gFrontEnd )
				)
				( attribute "VALUE" "100.0"
					( Origin gFrontEnd )
				)
				( attribute "VER" "1"
					( Origin gFrontEnd )
				)
				( attribute "WATTAGE" "1/16W"
					( Origin gFrontEnd )
				)
				( attribute "XY" "(-725,2325)"
					( Origin gFrontEnd )
				)
				( attribute "CHIPS_PART_NAME" "RES"
					( Origin gPackager )
				)
				( attribute "CDS_PART_NAME" "RES_0402-100.0,1%,1/16W,CHIP,GA"
					( Origin gPackager )
				)
				( attribute "SEC_TYPE" "0402"
					( Origin gFrontEnd )
				)
				( attribute "CDS_SEC" "1"
					( Origin gPackager )
				)
				( objectStatus "R3N21" )
			)
			( gate "@baseboard_fab2_lib.baseboard_fab2(sch_1):page212_i77"
				( attribute "CDS_LIB" "dev_discrete"
					( Origin gPackager )
				)
				( attribute "CDS_LOCATION" "C7C10"
					( Origin gPackager )
				)
				( attribute "CDS_SEC" "1"
					( Origin gPackager )
				)
				( attribute "LOCATION" "C7C10"
					( Origin gFrontEnd )
				)
				( attribute "MATERIAL" "X6S"
					( Origin gFrontEnd )
				)
				( attribute "PACK_TYPE" "0603V"
					( Origin gFrontEnd )
				)
				( attribute "PART_NUMBER" "E15431-004"
					( Origin gFrontEnd )
				)
				( attribute "PHYS_PAGE" "212"
					( Origin gFrontEnd )
				)
				( attribute "ROT" "0"
					( Origin gFrontEnd )
				)
				( attribute "SEC" "1"
					( Origin gFrontEnd )
				)
				( attribute "SEC_TYPE" "0603V"
					( Origin gFrontEnd )
				)
				( attribute "TOLERANCE" "20%"
					( Origin gFrontEnd )
				)
				( attribute "VALUE" "22.0UF"
					( Origin gFrontEnd )
				)
				( attribute "VER" "1"
					( Origin gFrontEnd )
				)
				( attribute "VOLTAGE" "4V"
					( Units "uVoltage" "V" 1.000000)
					( Origin gFrontEnd )
				)
				( attribute "XY" "(3650,3450)"
					( Origin gFrontEnd )
				)
				( attribute "CHIPS_PART_NAME" "CAP_A"
					( Origin gPackager )
				)
				( attribute "CDS_PART_NAME" "CAP_A_0603V-22.0UF,4V,20%,X6S,A"
					( Origin gPackager )
				)
				( attribute "GROUP" "PWR_MLCC_CAP"
					( Origin gFrontEnd )
				)
				( objectStatus "C7C10" )
			)
			( gate "@baseboard_fab2_lib.baseboard_fab2(sch_1):page212_i78"
				( attribute "CDS_LIB" "mstr_discrete"
					( Origin gPackager )
				)
				( attribute "CDS_LOCATION" "R7C3"
					( Origin gPackager )
				)
				( attribute "CDS_SEC" "1"
					( Origin gPackager )
				)
				( attribute "LOCATION" "R7C3"
					( Origin gFrontEnd )
				)
				( attribute "MATERIAL" "CHIP"
					( Origin gFrontEnd )
				)
				( attribute "PACK_TYPE" "0402"
					( Origin gFrontEnd )
				)
				( attribute "PART_NUMBER" "G21796-208"
					( Origin gFrontEnd )
				)
				( attribute "PHYS_PAGE" "212"
					( Origin gFrontEnd )
				)
				( attribute "ROT" "0"
					( Origin gFrontEnd )
				)
				( attribute "SEC" "1"
					( Origin gFrontEnd )
				)
				( attribute "SEC_TYPE" "0402"
					( Origin gFrontEnd )
				)
				( attribute "TOLERANCE" "1.0%"
					( Origin gFrontEnd )
				)
				( attribute "VALUE" "51.1"
					( Origin gFrontEnd )
				)
				( attribute "VER" "2"
					( Origin gFrontEnd )
				)
				( attribute "WATTAGE" "1/16W"
					( Origin gFrontEnd )
				)
				( attribute "XY" "(4025,3450)"
					( Origin gFrontEnd )
				)
				( attribute "CHIPS_PART_NAME" "RES"
					( Origin gPackager )
				)
				( attribute "CDS_PART_NAME" "RES_0402-51.1,1.0%,1/16W,CHIP,A"
					( Origin gPackager )
				)
				( objectStatus "R7C3" )
			)
			( gate "@baseboard_fab2_lib.baseboard_fab2(sch_1):page212_i101"
				( attribute "CDS_LIB" "mstr_discrete"
					( Origin gPackager )
				)
				( attribute "CDS_LOCATION" "EU7C1"
					( Origin gPackager )
				)
				( attribute "CDS_SEC" "1"
					( Origin gPackager )
				)
				( attribute "LOCATION" "EU7C1"
					( Origin gFrontEnd )
				)
				( attribute "MATERIAL" "IC"
					( Origin gFrontEnd )
				)
				( attribute "PACK_TYPE" "SM"
					( Origin gFrontEnd )
				)
				( attribute "PART_NUMBER" "H73684-001"
					( Origin gFrontEnd )
				)
				( attribute "PHYS_PAGE" "212"
					( Origin gFrontEnd )
				)
				( attribute "ROT" "0"
					( Origin gFrontEnd )
				)
				( attribute "SEC" "1"
					( Origin gPackager )
				)
				( attribute "VALUE" "IR35412"
					( Origin gFrontEnd )
				)
				( attribute "VER" "1"
					( Origin gFrontEnd )
				)
				( attribute "XY" "(1250,3950)"
					( Origin gFrontEnd )
				)
				( attribute "CHIPS_PART_NAME" "IR354XX"
					( Origin gPackager )
				)
				( attribute "CDS_PART_NAME" "IR354XX_SM-IR35412,IC,H73684-0A"
					( Origin gPackager )
				)
				( objectStatus "EU7C1" )
			)
			( gate "@baseboard_fab2_lib.baseboard_fab2(sch_1):page212_i103"
				( attribute "CDS_LIB" "mstr_discrete"
					( Origin gPackager )
				)
				( attribute "CDS_LOCATION" "R7C25"
					( Origin gPackager )
				)
				( attribute "CDS_SEC" "1"
					( Origin gPackager )
				)
				( attribute "LOCATION" "R7C25"
					( Origin gFrontEnd )
				)
				( attribute "MATERIAL" "EMPTY"
					( Origin gFrontEnd )
				)
				( attribute "PACK_TYPE" "0402"
					( Origin gFrontEnd )
				)
				( attribute "PART_NUMBER" "G21796-187"
					( Origin gFrontEnd )
				)
				( attribute "PHYS_PAGE" "212"
					( Origin gFrontEnd )
				)
				( attribute "ROT" "0"
					( Origin gFrontEnd )
				)
				( attribute "SEC" "1"
					( Origin gPackager )
				)
				( attribute "TOLERANCE" "1%"
					( Origin gFrontEnd )
				)
				( attribute "VALUE" "68.1K"
					( Origin gFrontEnd )
				)
				( attribute "VER" "2"
					( Origin gFrontEnd )
				)
				( attribute "WATTAGE" "1/16W"
					( Origin gFrontEnd )
				)
				( attribute "XY" "(3525,4125)"
					( Origin gFrontEnd )
				)
				( attribute "CHIPS_PART_NAME" "RES"
					( Origin gPackager )
				)
				( attribute "CDS_PART_NAME" "RES_0402-68.1K,1%,1/16W,EMPTY,A"
					( Origin gPackager )
				)
				( objectStatus "R7C25" )
			)
			( gate "@baseboard_fab2_lib.baseboard_fab2(sch_1):page212_i104"
				( attribute "CDS_LIB" "mstr_misc"
					( Origin gPackager )
				)
				( attribute "CDS_LOCATION" "SH3P1"
					( Origin gPackager )
				)
				( attribute "CDS_SEC" "1"
					( Origin gPackager )
				)
				( attribute "LOCATION" "SH3P1"
					( Origin gFrontEnd )
				)
				( attribute "MATERIAL" "EMPTY"
					( Origin gFrontEnd )
				)
				( attribute "PACK_TYPE" "SH0201"
					( Origin gFrontEnd )
				)
				( attribute "PART_NUMBER" "N_A"
					( Origin gFrontEnd )
				)
				( attribute "PHYS_PAGE" "212"
					( Origin gFrontEnd )
				)
				( attribute "PIN_SHORT" "A:B"
					( Origin gFrontEnd )
				)
				( attribute "ROT" "0"
					( Origin gFrontEnd )
				)
				( attribute "SEC" "1"
					( Origin gFrontEnd )
				)
				( attribute "SEC_TYPE" "SH0201"
					( Origin gFrontEnd )
				)
				( attribute "VER" "1"
					( Origin gFrontEnd )
				)
				( attribute "XY" "(-1300,1850)"
					( Origin gFrontEnd )
				)
				( attribute "CHIPS_PART_NAME" "SHUNT"
					( Origin gPackager )
				)
				( attribute "CDS_PART_NAME" "SHUNT_SH0201-EMPTY,N_A"
					( Origin gPackager )
				)
				( objectStatus "SH3P1" )
			)
			( gate "@baseboard_fab2_lib.baseboard_fab2(sch_1):page212_i105"
				( attribute "CDS_LIB" "mstr_misc"
					( Origin gPackager )
				)
				( attribute "CDS_LOCATION" "SH3P2"
					( Origin gPackager )
				)
				( attribute "CDS_SEC" "1"
					( Origin gPackager )
				)
				( attribute "LOCATION" "SH3P2"
					( Origin gFrontEnd )
				)
				( attribute "MATERIAL" "EMPTY"
					( Origin gFrontEnd )
				)
				( attribute "PACK_TYPE" "SH0201"
					( Origin gFrontEnd )
				)
				( attribute "PART_NUMBER" "N_A"
					( Origin gFrontEnd )
				)
				( attribute "PHYS_PAGE" "212"
					( Origin gFrontEnd )
				)
				( attribute "PIN_SHORT" "A:B"
					( Origin gFrontEnd )
				)
				( attribute "ROT" "0"
					( Origin gFrontEnd )
				)
				( attribute "SEC" "1"
					( Origin gFrontEnd )
				)
				( attribute "SEC_TYPE" "SH0201"
					( Origin gFrontEnd )
				)
				( attribute "VER" "1"
					( Origin gFrontEnd )
				)
				( attribute "XY" "(-1300,1400)"
					( Origin gFrontEnd )
				)
				( attribute "CHIPS_PART_NAME" "SHUNT"
					( Origin gPackager )
				)
				( attribute "CDS_PART_NAME" "SHUNT_SH0201-EMPTY,N_A"
					( Origin gPackager )
				)
				( objectStatus "SH3P2" )
			)
			( gate "@baseboard_fab2_lib.baseboard_fab2(sch_1):page213_i9"
				( attribute "CDS_LIB" "dev_discrete"
					( Origin gPackager )
				)
				( attribute "CDS_LOCATION" "C4D31"
					( Origin gPackager )
				)
				( attribute "CDS_SEC" "1"
					( Origin gPackager )
				)
				( attribute "LOCATION" "C4D31"
					( Origin gFrontEnd )
				)
				( attribute "MATERIAL" "X6S"
					( Origin gFrontEnd )
				)
				( attribute "PACK_TYPE" "0402V"
					( Origin gFrontEnd )
				)
				( attribute "PART_NUMBER" "D97712-004"
					( Origin gFrontEnd )
				)
				( attribute "PHYS_PAGE" "213"
					( Origin gFrontEnd )
				)
				( attribute "ROOM" "PVCCIO_CPU1"
					( Origin gFrontEnd )
				)
				( attribute "ROT" "0"
					( Origin gFrontEnd )
				)
				( attribute "SEC" "1"
					( Origin gFrontEnd )
				)
				( attribute "SEC_TYPE" "0402V"
					( Origin gFrontEnd )
				)
				( attribute "TOLERANCE" "10%"
					( Origin gFrontEnd )
				)
				( attribute "VALUE" "1.0UF"
					( Origin gFrontEnd )
				)
				( attribute "VER" "1"
					( Origin gFrontEnd )
				)
				( attribute "VOLTAGE" "6.3V"
					( Units "uVoltage" "V" 1.000000)
					( Origin gFrontEnd )
				)
				( attribute "XY" "(2425,1575)"
					( Origin gFrontEnd )
				)
				( attribute "CHIPS_PART_NAME" "CAP_A"
					( Origin gPackager )
				)
				( attribute "CDS_PART_NAME" "CAP_A_0402V-1.0UF,6.3V,10%,X6SA"
					( Origin gPackager )
				)
				( objectStatus "C4D31" )
			)
			( gate "@baseboard_fab2_lib.baseboard_fab2(sch_1):page213_i11"
				( attribute "CDS_LIB" "dev_discrete"
					( Origin gPackager )
				)
				( attribute "CDS_LOCATION" "C4D32"
					( Origin gPackager )
				)
				( attribute "CDS_SEC" "1"
					( Origin gPackager )
				)
				( attribute "LOCATION" "C4D32"
					( Origin gFrontEnd )
				)
				( attribute "MATERIAL" "X7R"
					( Origin gFrontEnd )
				)
				( attribute "PACK_TYPE" "0402V"
					( Origin gFrontEnd )
				)
				( attribute "PART_NUMBER" "A36096-030"
					( Origin gFrontEnd )
				)
				( attribute "PHYS_PAGE" "213"
					( Origin gFrontEnd )
				)
				( attribute "ROOM" "PVCCIO_CPU1"
					( Origin gFrontEnd )
				)
				( attribute "ROT" "0"
					( Origin gFrontEnd )
				)
				( attribute "SEC" "1"
					( Origin gFrontEnd )
				)
				( attribute "SEC_TYPE" "0402V"
					( Origin gFrontEnd )
				)
				( attribute "TOLERANCE" "10%"
					( Origin gFrontEnd )
				)
				( attribute "VALUE" "0.1UF"
					( Origin gFrontEnd )
				)
				( attribute "VER" "1"
					( Origin gFrontEnd )
				)
				( attribute "VOLTAGE" "16V"
					( Units "uVoltage" "V" 1.000000)
					( Origin gFrontEnd )
				)
				( attribute "XY" "(2025,1575)"
					( Origin gFrontEnd )
				)
				( attribute "CHIPS_PART_NAME" "CAP_A"
					( Origin gPackager )
				)
				( attribute "CDS_PART_NAME" "CAP_A_0402V-0.1UF,16V,10%,X7R,A"
					( Origin gPackager )
				)
				( objectStatus "C4D32" )
			)
			( gate "@baseboard_fab2_lib.baseboard_fab2(sch_1):page213_i13"
				( attribute "CDS_LIB" "mstr_discrete"
					( Origin gPackager )
				)
				( attribute "CDS_LOCATION" "R4D46"
					( Origin gPackager )
				)
				( attribute "CDS_SEC" "1"
					( Origin gPackager )
				)
				( attribute "LOCATION" "R4D46"
					( Origin gFrontEnd )
				)
				( attribute "MATERIAL" "CHIP"
					( Origin gFrontEnd )
				)
				( attribute "PACK_TYPE" "0402"
					( Origin gFrontEnd )
				)
				( attribute "PART_NUMBER" "G21796-250"
					( Origin gFrontEnd )
				)
				( attribute "PHYS_PAGE" "213"
					( Origin gFrontEnd )
				)
				( attribute "ROOM" "PVCCIO_CPU1"
					( Origin gFrontEnd )
				)
				( attribute "ROT" "0"
					( Origin gFrontEnd )
				)
				( attribute "SEC" "1"
					( Origin gFrontEnd )
				)
				( attribute "SEC_TYPE" "0402"
					( Origin gFrontEnd )
				)
				( attribute "TOLERANCE" "1.0%"
					( Origin gFrontEnd )
				)
				( attribute "VALUE" "22.1"
					( Origin gFrontEnd )
				)
				( attribute "VER" "1"
					( Origin gFrontEnd )
				)
				( attribute "WATTAGE" "1/16W"
					( Origin gFrontEnd )
				)
				( attribute "XY" "(1950,3575)"
					( Origin gFrontEnd )
				)
				( attribute "CHIPS_PART_NAME" "RES"
					( Origin gPackager )
				)
				( attribute "CDS_PART_NAME" "RES_0402-22.1,1.0%,1/16W,CHIP,A"
					( Origin gPackager )
				)
				( objectStatus "R4D46" )
			)
			( gate "@baseboard_fab2_lib.baseboard_fab2(sch_1):page213_i14"
				( attribute "CDS_LIB" "mstr_discrete"
					( Origin gPackager )
				)
				( attribute "CDS_LOCATION" "R6P49"
					( Origin gPackager )
				)
				( attribute "CDS_SEC" "1"
					( Origin gPackager )
				)
				( attribute "LOCATION" "R6P49"
					( Origin gFrontEnd )
				)
				( attribute "MATERIAL" "EMPTY"
					( Origin gFrontEnd )
				)
				( attribute "PACK_TYPE" "0402"
					( Origin gFrontEnd )
				)
				( attribute "PART_NUMBER" "G21796-311"
					( Origin gFrontEnd )
				)
				( attribute "PHYS_PAGE" "213"
					( Origin gFrontEnd )
				)
				( attribute "ROOM" "PVCCIO_CPU1"
					( Origin gFrontEnd )
				)
				( attribute "ROT" "0"
					( Origin gFrontEnd )
				)
				( attribute "SEC" "1"
					( Origin gFrontEnd )
				)
				( attribute "SEC_TYPE" "0402"
					( Origin gFrontEnd )
				)
				( attribute "TOLERANCE" "1.0%"
					( Origin gFrontEnd )
				)
				( attribute "VALUE" "2.26K"
					( Origin gFrontEnd )
				)
				( attribute "VER" "2"
					( Origin gFrontEnd )
				)
				( attribute "WATTAGE" "1/16W"
					( Origin gFrontEnd )
				)
				( attribute "XY" "(1600,4075)"
					( Origin gFrontEnd )
				)
				( attribute "CHIPS_PART_NAME" "RES"
					( Origin gPackager )
				)
				( attribute "CDS_PART_NAME" "RES_0402-2.26K,1.0%,1/16W,EMPTA"
					( Origin gPackager )
				)
				( objectStatus "R6P49" )
			)
			( gate "@baseboard_fab2_lib.baseboard_fab2(sch_1):page213_i15"
				( attribute "CDS_LIB" "mstr_discrete"
					( Origin gPackager )
				)
				( attribute "CDS_LOCATION" "R4D42"
					( Origin gPackager )
				)
				( attribute "LOCATION" "R4D42"
					( Origin gFrontEnd )
				)
				( attribute "MATERIAL" "CHIP"
					( Origin gFrontEnd )
				)
				( attribute "PACK_TYPE" "0402"
					( Origin gFrontEnd )
				)
				( attribute "PART_NUMBER" "G21796-026"
					( Origin gFrontEnd )
				)
				( attribute "PHYS_PAGE" "213"
					( Origin gFrontEnd )
				)
				( attribute "ROOM" "PVCCIO_CPU1"
					( Origin gFrontEnd )
				)
				( attribute "ROT" "0"
					( Origin gFrontEnd )
				)
				( attribute "SEC" "1"
					( Origin gFrontEnd )
				)
				( attribute "TOLERANCE" "1%"
					( Origin gFrontEnd )
				)
				( attribute "VALUE" "1.00K"
					( Origin gFrontEnd )
				)
				( attribute "VER" "2"
					( Origin gFrontEnd )
				)
				( attribute "WATTAGE" "1/16W"
					( Origin gFrontEnd )
				)
				( attribute "XY" "(950,4050)"
					( Origin gFrontEnd )
				)
				( attribute "CHIPS_PART_NAME" "RES"
					( Origin gPackager )
				)
				( attribute "CDS_PART_NAME" "RES_0402-1.00K,1%,1/16W,CHIP,GA"
					( Origin gPackager )
				)
				( attribute "SEC_TYPE" "0402"
					( Origin gFrontEnd )
				)
				( attribute "CDS_SEC" "1"
					( Origin gPackager )
				)
				( objectStatus "R4D42" )
			)
			( gate "@baseboard_fab2_lib.baseboard_fab2(sch_1):page213_i16"
				( attribute "CDS_LIB" "mstr_discrete"
					( Origin gPackager )
				)
				( attribute "CDS_LOCATION" "R4D56"
					( Origin gPackager )
				)
				( attribute "CDS_SEC" "1"
					( Origin gPackager )
				)
				( attribute "LOCATION" "R4D56"
					( Origin gFrontEnd )
				)
				( attribute "MATERIAL" "CHIP"
					( Origin gFrontEnd )
				)
				( attribute "PACK_TYPE" "0402"
					( Origin gFrontEnd )
				)
				( attribute "PART_NUMBER" "G21497-005"
					( Origin gFrontEnd )
				)
				( attribute "PHYS_PAGE" "213"
					( Origin gFrontEnd )
				)
				( attribute "ROOM" "PVCCIO_CPU1"
					( Origin gFrontEnd )
				)
				( attribute "ROT" "0"
					( Origin gFrontEnd )
				)
				( attribute "SEC" "1"
					( Origin gFrontEnd )
				)
				( attribute "SEC_TYPE" "0402"
					( Origin gFrontEnd )
				)
				( attribute "TOLERANCE" "5%"
					( Origin gFrontEnd )
				)
				( attribute "VALUE" "0.0"
					( Origin gFrontEnd )
				)
				( attribute "VER" "1"
					( Origin gFrontEnd )
				)
				( attribute "WATTAGE" "1/16W"
					( Origin gFrontEnd )
				)
				( attribute "XY" "(1450,3125)"
					( Origin gFrontEnd )
				)
				( attribute "CHIPS_PART_NAME" "RES"
					( Origin gPackager )
				)
				( attribute "CDS_PART_NAME" "RES_0402-0.0,5%,1/16W,CHIP,G21A"
					( Origin gPackager )
				)
				( objectStatus "R4D56" )
			)
			( gate "@baseboard_fab2_lib.baseboard_fab2(sch_1):page213_i17"
				( attribute "CDS_LIB" "dev_discrete"
					( Origin gPackager )
				)
				( attribute "CDS_LOCATION" "C4D36"
					( Origin gPackager )
				)
				( attribute "LOCATION" "C4D36"
					( Origin gFrontEnd )
				)
				( attribute "MATERIAL" "X6S"
					( Origin gFrontEnd )
				)
				( attribute "PACK_TYPE" "0402V"
					( Origin gFrontEnd )
				)
				( attribute "PART_NUMBER" "D97712-004"
					( Origin gFrontEnd )
				)
				( attribute "PHYS_PAGE" "213"
					( Origin gFrontEnd )
				)
				( attribute "ROOM" "PVCCIO_CPU1"
					( Origin gFrontEnd )
				)
				( attribute "ROT" "0"
					( Origin gFrontEnd )
				)
				( attribute "SEC" "1"
					( Origin gFrontEnd )
				)
				( attribute "TOLERANCE" "10%"
					( Origin gFrontEnd )
				)
				( attribute "VALUE" "1.0UF"
					( Origin gFrontEnd )
				)
				( attribute "VER" "1"
					( Origin gFrontEnd )
				)
				( attribute "VOLTAGE" "6.3V"
					( Units "uVoltage" "V" 1.000000)
					( Origin gFrontEnd )
				)
				( attribute "XY" "(150,4150)"
					( Origin gFrontEnd )
				)
				( attribute "CHIPS_PART_NAME" "CAP_A"
					( Origin gPackager )
				)
				( attribute "CDS_PART_NAME" "CAP_A_0402V-1.0UF,6.3V,10%,X6SA"
					( Origin gPackager )
				)
				( attribute "SEC_TYPE" "0402V"
					( Origin gFrontEnd )
				)
				( attribute "CDS_SEC" "1"
					( Origin gPackager )
				)
				( objectStatus "C4D36" )
			)
			( gate "@baseboard_fab2_lib.baseboard_fab2(sch_1):page213_i25"
				( attribute "CDS_LIB" "mstr_discrete"
					( Origin gPackager )
				)
				( attribute "CDS_LOCATION" "R4D47"
					( Origin gPackager )
				)
				( attribute "LOCATION" "R4D47"
					( Origin gFrontEnd )
				)
				( attribute "MATERIAL" "CHIP"
					( Origin gFrontEnd )
				)
				( attribute "PACK_TYPE" "0402"
					( Origin gFrontEnd )
				)
				( attribute "PART_NUMBER" "G21497-005"
					( Origin gFrontEnd )
				)
				( attribute "PHYS_PAGE" "213"
					( Origin gFrontEnd )
				)
				( attribute "ROOM" "PVCCIO_CPU1"
					( Origin gFrontEnd )
				)
				( attribute "ROT" "0"
					( Origin gFrontEnd )
				)
				( attribute "SEC" "1"
					( Origin gFrontEnd )
				)
				( attribute "TOLERANCE" "5%"
					( Origin gFrontEnd )
				)
				( attribute "VALUE" "0.0"
					( Origin gFrontEnd )
				)
				( attribute "VER" "2"
					( Origin gFrontEnd )
				)
				( attribute "WATTAGE" "1/16W"
					( Origin gFrontEnd )
				)
				( attribute "XY" "(-550,4500)"
					( Origin gFrontEnd )
				)
				( attribute "CHIPS_PART_NAME" "RES"
					( Origin gPackager )
				)
				( attribute "CDS_PART_NAME" "RES_0402-0.0,5%,1/16W,CHIP,G21A"
					( Origin gPackager )
				)
				( attribute "SEC_TYPE" "0402"
					( Origin gFrontEnd )
				)
				( attribute "CDS_SEC" "1"
					( Origin gPackager )
				)
				( objectStatus "R4D47" )
			)
			( gate "@baseboard_fab2_lib.baseboard_fab2(sch_1):page213_i27"
				( attribute "CDS_LIB" "mstr_discrete"
					( Origin gPackager )
				)
				( attribute "CDS_LOCATION" "R6P35"
					( Origin gPackager )
				)
				( attribute "LOCATION" "R6P35"
					( Origin gFrontEnd )
				)
				( attribute "MATERIAL" "EMPTY"
					( Origin gFrontEnd )
				)
				( attribute "PACK_TYPE" "0402"
					( Origin gFrontEnd )
				)
				( attribute "PART_NUMBER" "G21796-017"
					( Origin gFrontEnd )
				)
				( attribute "PHYS_PAGE" "213"
					( Origin gFrontEnd )
				)
				( attribute "ROOM" "PVCCIO_CPU1"
					( Origin gFrontEnd )
				)
				( attribute "ROT" "0"
					( Origin gFrontEnd )
				)
				( attribute "SEC" "1"
					( Origin gFrontEnd )
				)
				( attribute "TOLERANCE" "1%"
					( Origin gFrontEnd )
				)
				( attribute "VALUE" "100.0"
					( Origin gFrontEnd )
				)
				( attribute "VER" "2"
					( Origin gFrontEnd )
				)
				( attribute "WATTAGE" "1/16W"
					( Origin gFrontEnd )
				)
				( attribute "XY" "(-1450,4475)"
					( Origin gFrontEnd )
				)
				( attribute "CHIPS_PART_NAME" "RES"
					( Origin gPackager )
				)
				( attribute "CDS_PART_NAME" "RES_0402-100.0,1%,1/16W,EMPTY,A"
					( Origin gPackager )
				)
				( attribute "SEC_TYPE" "0402"
					( Origin gFrontEnd )
				)
				( attribute "CDS_SEC" "1"
					( Origin gPackager )
				)
				( objectStatus "R6P35" )
			)
			( gate "@baseboard_fab2_lib.baseboard_fab2(sch_1):page213_i30"
				( attribute "CDS_LIB" "mstr_discrete"
					( Origin gPackager )
				)
				( attribute "CDS_LOCATION" "R6P33"
					( Origin gPackager )
				)
				( attribute "CDS_SEC" "1"
					( Origin gPackager )
				)
				( attribute "LOCATION" "R6P33"
					( Origin gFrontEnd )
				)
				( attribute "MATERIAL" "EMPTY"
					( Origin gFrontEnd )
				)
				( attribute "PACK_TYPE" "0402"
					( Origin gFrontEnd )
				)
				( attribute "PART_NUMBER" "G21796-203"
					( Origin gFrontEnd )
				)
				( attribute "PHYS_PAGE" "213"
					( Origin gFrontEnd )
				)
				( attribute "ROOM" "PVCCIO_CPU1"
					( Origin gFrontEnd )
				)
				( attribute "ROT" "0"
					( Origin gFrontEnd )
				)
				( attribute "SEC" "1"
					( Origin gFrontEnd )
				)
				( attribute "SEC_TYPE" "0402"
					( Origin gFrontEnd )
				)
				( attribute "TOLERANCE" "1%"
					( Origin gFrontEnd )
				)
				( attribute "VALUE" "110"
					( Origin gFrontEnd )
				)
				( attribute "VER" "2"
					( Origin gFrontEnd )
				)
				( attribute "WATTAGE" "1/16W"
					( Origin gFrontEnd )
				)
				( attribute "XY" "(-2050,4425)"
					( Origin gFrontEnd )
				)
				( attribute "CHIPS_PART_NAME" "RES"
					( Origin gPackager )
				)
				( attribute "CDS_PART_NAME" "RES_0402-110,1%,1/16W,EMPTY,G2A"
					( Origin gPackager )
				)
				( objectStatus "R6P33" )
			)
			( gate "@baseboard_fab2_lib.baseboard_fab2(sch_1):page213_i31"
				( attribute "CDS_LIB" "mstr_discrete"
					( Origin gPackager )
				)
				( attribute "CDS_LOCATION" "R4D60"
					( Origin gPackager )
				)
				( attribute "CDS_SEC" "1"
					( Origin gPackager )
				)
				( attribute "LOCATION" "R4D60"
					( Origin gFrontEnd )
				)
				( attribute "MATERIAL" "CHIP"
					( Origin gFrontEnd )
				)
				( attribute "PACK_TYPE" "0402"
					( Origin gFrontEnd )
				)
				( attribute "PART_NUMBER" "G21796-160"
					( Origin gFrontEnd )
				)
				( attribute "PHYS_PAGE" "213"
					( Origin gFrontEnd )
				)
				( attribute "ROOM" "PVCCIO_CPU1"
					( Origin gFrontEnd )
				)
				( attribute "ROT" "0"
					( Origin gFrontEnd )
				)
				( attribute "SEC" "1"
					( Origin gFrontEnd )
				)
				( attribute "SEC_TYPE" "0402"
					( Origin gFrontEnd )
				)
				( attribute "TOLERANCE" "1%"
					( Origin gFrontEnd )
				)
				( attribute "VALUE" "100.0K"
					( Origin gFrontEnd )
				)
				( attribute "VER" "2"
					( Origin gFrontEnd )
				)
				( attribute "WATTAGE" "1/16W"
					( Origin gFrontEnd )
				)
				( attribute "XY" "(-2425,4700)"
					( Origin gFrontEnd )
				)
				( attribute "CHIPS_PART_NAME" "RES"
					( Origin gPackager )
				)
				( attribute "CDS_PART_NAME" "RES_0402-100.0K,1%,1/16W,CHIP,B"
					( Origin gPackager )
				)
				( objectStatus "R4D60" )
			)
			( gate "@baseboard_fab2_lib.baseboard_fab2(sch_1):page213_i32"
				( attribute "CDS_LIB" "mstr_discrete"
					( Origin gPackager )
				)
				( attribute "CDS_LOCATION" "R4D57"
					( Origin gPackager )
				)
				( attribute "CDS_SEC" "1"
					( Origin gPackager )
				)
				( attribute "LOCATION" "R4D57"
					( Origin gFrontEnd )
				)
				( attribute "MATERIAL" "CHIP"
					( Origin gFrontEnd )
				)
				( attribute "PACK_TYPE" "0402"
					( Origin gFrontEnd )
				)
				( attribute "PART_NUMBER" "G21796-003"
					( Origin gFrontEnd )
				)
				( attribute "PHYS_PAGE" "213"
					( Origin gFrontEnd )
				)
				( attribute "ROOM" "PVCCIO_CPU1"
					( Origin gFrontEnd )
				)
				( attribute "ROT" "0"
					( Origin gFrontEnd )
				)
				( attribute "SEC" "1"
					( Origin gFrontEnd )
				)
				( attribute "SEC_TYPE" "0402"
					( Origin gFrontEnd )
				)
				( attribute "TOLERANCE" "1%"
					( Origin gFrontEnd )
				)
				( attribute "VALUE" "1.5K"
					( Origin gFrontEnd )
				)
				( attribute "VER" "2"
					( Origin gFrontEnd )
				)
				( attribute "WATTAGE" "1/16W"
					( Origin gFrontEnd )
				)
				( attribute "XY" "(-2425,4250)"
					( Origin gFrontEnd )
				)
				( attribute "CHIPS_PART_NAME" "RES"
					( Origin gPackager )
				)
				( attribute "CDS_PART_NAME" "RES_0402-1.5K,1%,1/16W,CHIP,G2A"
					( Origin gPackager )
				)
				( objectStatus "R4D57" )
			)
			( gate "@baseboard_fab2_lib.baseboard_fab2(sch_1):page235_i255"
				( attribute "BOM_COST" "SM_THERM"
					( Origin gFrontEnd )
				)
				( attribute "CDS_LIB" "dev_discrete"
					( Origin gPackager )
				)
				( attribute "CDS_LOCATION" "C8A3"
					( Origin gPackager )
				)
				( attribute "CDS_SEC" "1"
					( Origin gPackager )
				)
				( attribute "LOCATION" "C8A3"
					( Origin gFrontEnd )
				)
				( attribute "MATERIAL" "X7R"
					( Origin gFrontEnd )
				)
				( attribute "PACK_TYPE" "0402V"
					( Origin gFrontEnd )
				)
				( attribute "PART_NUMBER" "A36096-030"
					( Origin gFrontEnd )
				)
				( attribute "PHYS_PAGE" "235"
					( Origin gFrontEnd )
				)
				( attribute "ROOM" "CPU_FANS"
					( Origin gFrontEnd )
				)
				( attribute "ROT" "0"
					( Origin gFrontEnd )
				)
				( attribute "SEC" "1"
					( Origin gFrontEnd )
				)
				( attribute "SEC_TYPE" "0402V"
					( Origin gFrontEnd )
				)
				( attribute "TOLERANCE" "10%"
					( Origin gFrontEnd )
				)
				( attribute "VALUE" "0.1UF"
					( Origin gFrontEnd )
				)
				( attribute "VER" "1"
					( Origin gFrontEnd )
				)
				( attribute "VOLTAGE" "16V"
					( Units "uVoltage" "V" 1.000000)
					( Origin gFrontEnd )
				)
				( attribute "XY" "(-12750,5150)"
					( Origin gFrontEnd )
				)
				( attribute "CHIPS_PART_NAME" "CAP_A"
					( Origin gPackager )
				)
				( attribute "CDS_PART_NAME" "CAP_A_0402V-0.1UF,16V,10%,X7R,A"
					( Origin gPackager )
				)
				( objectStatus "C8A3" )
			)
			( gate "@baseboard_fab2_lib.baseboard_fab2(sch_1):page213_i35"
				( attribute "CDS_LIB" "dev_discrete"
					( Origin gPackager )
				)
				( attribute "CDS_LOCATION" "C4D38"
					( Origin gPackager )
				)
				( attribute "LOCATION" "C4D38"
					( Origin gFrontEnd )
				)
				( attribute "MATERIAL" "X7R"
					( Origin gFrontEnd )
				)
				( attribute "PACK_TYPE" "0402V"
					( Origin gFrontEnd )
				)
				( attribute "PART_NUMBER" "A36096-030"
					( Origin gFrontEnd )
				)
				( attribute "PHYS_PAGE" "213"
					( Origin gFrontEnd )
				)
				( attribute "ROOM" "PVCCIO_CPU1"
					( Origin gFrontEnd )
				)
				( attribute "ROT" "0"
					( Origin gFrontEnd )
				)
				( attribute "SEC" "1"
					( Origin gFrontEnd )
				)
				( attribute "TOLERANCE" "10%"
					( Origin gFrontEnd )
				)
				( attribute "VALUE" "0.1UF"
					( Origin gFrontEnd )
				)
				( attribute "VER" "1"
					( Origin gFrontEnd )
				)
				( attribute "VOLTAGE" "16V"
					( Units "uVoltage" "V" 1.000000)
					( Origin gFrontEnd )
				)
				( attribute "XY" "(-250,4150)"
					( Origin gFrontEnd )
				)
				( attribute "CHIPS_PART_NAME" "CAP_A"
					( Origin gPackager )
				)
				( attribute "CDS_PART_NAME" "CAP_A_0402V-0.1UF,16V,10%,X7R,A"
					( Origin gPackager )
				)
				( attribute "SEC_TYPE" "0402V"
					( Origin gFrontEnd )
				)
				( attribute "CDS_SEC" "1"
					( Origin gPackager )
				)
				( objectStatus "C4D38" )
			)
			( gate "@baseboard_fab2_lib.baseboard_fab2(sch_1):page213_i37"
				( attribute "CDS_LIB" "mstr_discrete"
					( Origin gPackager )
				)
				( attribute "CDS_LOCATION" "R4D54"
					( Origin gPackager )
				)
				( attribute "LOCATION" "R4D54"
					( Origin gFrontEnd )
				)
				( attribute "MATERIAL" "CHIP"
					( Origin gFrontEnd )
				)
				( attribute "PACK_TYPE" "0402"
					( Origin gFrontEnd )
				)
				( attribute "PART_NUMBER" "G21497-005"
					( Origin gFrontEnd )
				)
				( attribute "PHYS_PAGE" "213"
					( Origin gFrontEnd )
				)
				( attribute "ROOM" "PVCCIO_CPU1"
					( Origin gFrontEnd )
				)
				( attribute "ROT" "0"
					( Origin gFrontEnd )
				)
				( attribute "SEC" "1"
					( Origin gFrontEnd )
				)
				( attribute "TOLERANCE" "5%"
					( Origin gFrontEnd )
				)
				( attribute "VALUE" "0.0"
					( Origin gFrontEnd )
				)
				( attribute "VER" "1"
					( Origin gFrontEnd )
				)
				( attribute "WATTAGE" "1/16W"
					( Origin gFrontEnd )
				)
				( attribute "XY" "(-1175,2925)"
					( Origin gFrontEnd )
				)
				( attribute "CHIPS_PART_NAME" "RES"
					( Origin gPackager )
				)
				( attribute "CDS_PART_NAME" "RES_0402-0.0,5%,1/16W,CHIP,G21A"
					( Origin gPackager )
				)
				( attribute "SEC_TYPE" "0402"
					( Origin gFrontEnd )
				)
				( attribute "CDS_SEC" "1"
					( Origin gPackager )
				)
				( objectStatus "R4D54" )
			)
			( gate "@baseboard_fab2_lib.baseboard_fab2(sch_1):page223_i73"
				( attribute "CDS_LIB" "mstr_discrete"
					( Origin gPackager )
				)
				( attribute "CDS_LOCATION" "R1G23"
					( Origin gPackager )
				)
				( attribute "CDS_SEC" "1"
					( Origin gPackager )
				)
				( attribute "LOCATION" "R1G23"
					( Origin gFrontEnd )
				)
				( attribute "MATERIAL" "CHIP"
					( Origin gFrontEnd )
				)
				( attribute "PACK_TYPE" "0402"
					( Origin gFrontEnd )
				)
				( attribute "PART_NUMBER" "G21796-297"
					( Origin gFrontEnd )
				)
				( attribute "PHYS_PAGE" "223"
					( Origin gFrontEnd )
				)
				( attribute "POP" "NOPOP"
					( Origin gFrontEnd )
				)
				( attribute "ROOM" "VDDQ_GHJ_PWR_VR"
					( Origin gFrontEnd )
				)
				( attribute "ROT" "0"
					( Origin gFrontEnd )
				)
				( attribute "SEC" "1"
					( Origin gFrontEnd )
				)
				( attribute "SEC_TYPE" "0402"
					( Origin gFrontEnd )
				)
				( attribute "TOLERANCE" "1.0%"
					( Origin gFrontEnd )
				)
				( attribute "VALUE" "5.36K"
					( Origin gFrontEnd )
				)
				( attribute "VER" "2"
					( Origin gFrontEnd )
				)
				( attribute "WATTAGE" "1/16W"
					( Origin gFrontEnd )
				)
				( attribute "XY" "(275,-250)"
					( Origin gFrontEnd )
				)
				( attribute "CHIPS_PART_NAME" "RES"
					( Origin gPackager )
				)
				( attribute "CDS_PART_NAME" "RES_0402-5.36K,1.0%,1/16W,CHIPA"
					( Origin gPackager )
				)
				( objectStatus "R1G23" )
			)
			( gate "@baseboard_fab2_lib.baseboard_fab2(sch_1):page213_i46"
				( attribute "CDS_LIB" "mstr_discrete"
					( Origin gPackager )
				)
				( attribute "CDS_LOCATION" "R4D51"
					( Origin gPackager )
				)
				( attribute "CDS_SEC" "1"
					( Origin gPackager )
				)
				( attribute "LOCATION" "R4D51"
					( Origin gFrontEnd )
				)
				( attribute "MATERIAL" "CHIP"
					( Origin gFrontEnd )
				)
				( attribute "PACK_TYPE" "0402"
					( Origin gFrontEnd )
				)
				( attribute "PART_NUMBER" "G21796-009"
					( Origin gFrontEnd )
				)
				( attribute "PHYS_PAGE" "213"
					( Origin gFrontEnd )
				)
				( attribute "ROOM" "PVCCIO_CPU1"
					( Origin gFrontEnd )
				)
				( attribute "ROT" "0"
					( Origin gFrontEnd )
				)
				( attribute "SEC" "1"
					( Origin gFrontEnd )
				)
				( attribute "SEC_TYPE" "0402"
					( Origin gFrontEnd )
				)
				( attribute "TOLERANCE" "1%"
					( Origin gFrontEnd )
				)
				( attribute "VALUE" "150.0"
					( Origin gFrontEnd )
				)
				( attribute "VER" "1"
					( Origin gFrontEnd )
				)
				( attribute "WATTAGE" "1/16W"
					( Origin gFrontEnd )
				)
				( attribute "XY" "(-1825,3925)"
					( Origin gFrontEnd )
				)
				( attribute "CHIPS_PART_NAME" "RES"
					( Origin gPackager )
				)
				( attribute "CDS_PART_NAME" "RES_0402-150.0,1%,1/16W,CHIP,GA"
					( Origin gPackager )
				)
				( objectStatus "R4D51" )
			)
			( gate "@baseboard_fab2_lib.baseboard_fab2(sch_1):page213_i63"
				( attribute "CDS_LIB" "mstr_discrete"
					( Origin gPackager )
				)
				( attribute "CDS_LOCATION" "R4D49"
					( Origin gPackager )
				)
				( attribute "LOCATION" "R4D49"
					( Origin gFrontEnd )
				)
				( attribute "MATERIAL" "CHIP"
					( Origin gFrontEnd )
				)
				( attribute "PACK_TYPE" "0402"
					( Origin gFrontEnd )
				)
				( attribute "PART_NUMBER" "G21796-026"
					( Origin gFrontEnd )
				)
				( attribute "PHYS_PAGE" "213"
					( Origin gFrontEnd )
				)
				( attribute "ROT" "0"
					( Origin gFrontEnd )
				)
				( attribute "SEC" "1"
					( Origin gFrontEnd )
				)
				( attribute "TOLERANCE" "1%"
					( Origin gFrontEnd )
				)
				( attribute "VALUE" "1.00K"
					( Origin gFrontEnd )
				)
				( attribute "VER" "2"
					( Origin gFrontEnd )
				)
				( attribute "WATTAGE" "1/16W"
					( Origin gFrontEnd )
				)
				( attribute "XY" "(2175,4050)"
					( Origin gFrontEnd )
				)
				( attribute "CHIPS_PART_NAME" "RES"
					( Origin gPackager )
				)
				( attribute "CDS_PART_NAME" "RES_0402-1.00K,1%,1/16W,CHIP,GA"
					( Origin gPackager )
				)
				( attribute "SEC_TYPE" "0402"
					( Origin gFrontEnd )
				)
				( attribute "CDS_SEC" "1"
					( Origin gPackager )
				)
				( objectStatus "R4D49" )
			)
			( gate "@baseboard_fab2_lib.baseboard_fab2(sch_1):page218_i74"
				( attribute "BOM_COST" "SM_CONTROLLER"
					( Origin gFrontEnd )
				)
				( attribute "CDS_LIB" "mstr_discrete"
					( Origin gPackager )
				)
				( attribute "CDS_LOCATION" "R7A8"
					( Origin gPackager )
				)
				( attribute "CDS_SEC" "1"
					( Origin gPackager )
				)
				( attribute "LOCATION" "R7A8"
					( Origin gFrontEnd )
				)
				( attribute "MATERIAL" "CHIP"
					( Origin gFrontEnd )
				)
				( attribute "PACK_TYPE" "0402"
					( Origin gFrontEnd )
				)
				( attribute "PART_NUMBER" "G21796-311"
					( Origin gFrontEnd )
				)
				( attribute "PHYS_PAGE" "218"
					( Origin gFrontEnd )
				)
				( attribute "ROOM" "SMBUS"
					( Origin gFrontEnd )
				)
				( attribute "ROT" "0"
					( Origin gFrontEnd )
				)
				( attribute "SEC" "1"
					( Origin gFrontEnd )
				)
				( attribute "SEC_TYPE" "0402"
					( Origin gFrontEnd )
				)
				( attribute "SKU" "B"
					( Origin gFrontEnd )
				)
				( attribute "TOLERANCE" "1.0%"
					( Origin gFrontEnd )
				)
				( attribute "VALUE" "2.26K"
					( Origin gFrontEnd )
				)
				( attribute "VER" "2"
					( Origin gFrontEnd )
				)
				( attribute "WATTAGE" "1/16W"
					( Origin gFrontEnd )
				)
				( attribute "XY" "(-775,-150)"
					( Origin gFrontEnd )
				)
				( attribute "CHIPS_PART_NAME" "RES"
					( Origin gPackager )
				)
				( attribute "CDS_PART_NAME" "RES_0402-2.26K,1.0%,1/16W,CHIPA"
					( Origin gPackager )
				)
				( objectStatus "R7A8" )
			)
			( gate "@baseboard_fab2_lib.baseboard_fab2(sch_1):page213_i73"
				( attribute "CDS_LIB" "mstr_discrete"
					( Origin gPackager )
				)
				( attribute "CDS_LOCATION" "C4D33"
					( Origin gPackager )
				)
				( attribute "CDS_SEC" "1"
					( Origin gPackager )
				)
				( attribute "LOCATION" "C4D33"
					( Origin gFrontEnd )
				)
				( attribute "MATERIAL" "X7R"
					( Origin gFrontEnd )
				)
				( attribute "PACK_TYPE" "0402LF"
					( Origin gFrontEnd )
				)
				( attribute "PART_NUMBER" "A36096-046"
					( Origin gFrontEnd )
				)
				( attribute "PHYS_PAGE" "213"
					( Origin gFrontEnd )
				)
				( attribute "ROOM" "PVCCIO_CPU1_VR"
					( Origin gFrontEnd )
				)
				( attribute "ROT" "0"
					( Origin gFrontEnd )
				)
				( attribute "SEC" "1"
					( Origin gFrontEnd )
				)
				( attribute "SEC_TYPE" "0402LF"
					( Origin gFrontEnd )
				)
				( attribute "TOLERANCE" "10%"
					( Origin gFrontEnd )
				)
				( attribute "VALUE" "1000PF"
					( Origin gFrontEnd )
				)
				( attribute "VER" "1"
					( Origin gFrontEnd )
				)
				( attribute "VOLTAGE" "50V"
					( Units "uVoltage" "V" 1.000000)
					( Origin gFrontEnd )
				)
				( attribute "XY" "(1750,2700)"
					( Origin gFrontEnd )
				)
				( attribute "CHIPS_PART_NAME" "CAP"
					( Origin gPackager )
				)
				( attribute "CDS_PART_NAME" "CAP_0402LF-1000PF,50V,10%,X7R,A"
					( Origin gPackager )
				)
				( objectStatus "C4D33" )
			)
			( gate "@baseboard_fab2_lib.baseboard_fab2(sch_1):page213_i83"
				( attribute "CDS_LIB" "mstr_discrete"
					( Origin gPackager )
				)
				( attribute "CDS_LOCATION" "C4D44"
					( Origin gPackager )
				)
				( attribute "CDS_SEC" "1"
					( Origin gPackager )
				)
				( attribute "LOCATION" "C4D44"
					( Origin gFrontEnd )
				)
				( attribute "MATERIAL" "X7R"
					( Origin gFrontEnd )
				)
				( attribute "PACK_TYPE" "0402LF"
					( Origin gFrontEnd )
				)
				( attribute "PART_NUMBER" "A36096-050"
					( Origin gFrontEnd )
				)
				( attribute "PHYS_PAGE" "213"
					( Origin gFrontEnd )
				)
				( attribute "ROOM" "PVCCIO_CPU1"
					( Origin gFrontEnd )
				)
				( attribute "ROT" "0"
					( Origin gFrontEnd )
				)
				( attribute "SEC" "1"
					( Origin gFrontEnd )
				)
				( attribute "SEC_TYPE" "0402LF"
					( Origin gFrontEnd )
				)
				( attribute "TOLERANCE" "10%"
					( Origin gFrontEnd )
				)
				( attribute "VALUE" "220PF"
					( Origin gFrontEnd )
				)
				( attribute "VER" "1"
					( Origin gFrontEnd )
				)
				( attribute "VOLTAGE" "50V"
					( Units "uVoltage" "V" 1.000000)
					( Origin gFrontEnd )
				)
				( attribute "XY" "(-2075,1725)"
					( Origin gFrontEnd )
				)
				( attribute "CHIPS_PART_NAME" "CAP"
					( Origin gPackager )
				)
				( attribute "CDS_PART_NAME" "CAP_0402LF-220PF,50V,10%,X7R,AA"
					( Origin gPackager )
				)
				( objectStatus "C4D44" )
			)
			( gate "@baseboard_fab2_lib.baseboard_fab2(sch_1):page213_i84"
				( attribute "CDS_LIB" "mstr_discrete"
					( Origin gPackager )
				)
				( attribute "CDS_LOCATION" "R4E7"
					( Origin gPackager )
				)
				( attribute "CDS_SEC" "1"
					( Origin gPackager )
				)
				( attribute "LOCATION" "R4E7"
					( Origin gFrontEnd )
				)
				( attribute "MATERIAL" "CHIP"
					( Origin gFrontEnd )
				)
				( attribute "PACK_TYPE" "0402"
					( Origin gFrontEnd )
				)
				( attribute "PART_NUMBER" "G21796-066"
					( Origin gFrontEnd )
				)
				( attribute "PHYS_PAGE" "213"
					( Origin gFrontEnd )
				)
				( attribute "ROOM" "PVCCIO_CPU1"
					( Origin gFrontEnd )
				)
				( attribute "ROT" "0"
					( Origin gFrontEnd )
				)
				( attribute "SEC" "1"
					( Origin gFrontEnd )
				)
				( attribute "SEC_TYPE" "0402"
					( Origin gFrontEnd )
				)
				( attribute "TOLERANCE" "1%"
					( Origin gFrontEnd )
				)
				( attribute "VALUE" "10.0"
					( Origin gFrontEnd )
				)
				( attribute "VER" "1"
					( Origin gFrontEnd )
				)
				( attribute "WATTAGE" "1/16W"
					( Origin gFrontEnd )
				)
				( attribute "XY" "(-2325,1925)"
					( Origin gFrontEnd )
				)
				( attribute "CHIPS_PART_NAME" "RES"
					( Origin gPackager )
				)
				( attribute "CDS_PART_NAME" "RES_0402-10.0,1%,1/16W,CHIP,G2A"
					( Origin gPackager )
				)
				( objectStatus "R4E7" )
			)
			( gate "@baseboard_fab2_lib.baseboard_fab2(sch_1):page213_i90"
				( attribute "CDS_LIB" "mstr_discrete"
					( Origin gPackager )
				)
				( attribute "CDS_LOCATION" "R6P41"
					( Origin gPackager )
				)
				( attribute "LOCATION" "R6P41"
					( Origin gFrontEnd )
				)
				( attribute "MATERIAL" "CHIP"
					( Origin gFrontEnd )
				)
				( attribute "PACK_TYPE" "0402"
					( Origin gFrontEnd )
				)
				( attribute "PART_NUMBER" "G21497-005"
					( Origin gFrontEnd )
				)
				( attribute "PHYS_PAGE" "213"
					( Origin gFrontEnd )
				)
				( attribute "ROOM" "PVCCIN_CPU0_VR"
					( Origin gFrontEnd )
				)
				( attribute "ROT" "0"
					( Origin gFrontEnd )
				)
				( attribute "SEC" "1"
					( Origin gFrontEnd )
				)
				( attribute "TOLERANCE" "5%"
					( Origin gFrontEnd )
				)
				( attribute "VALUE" "0.0"
					( Origin gFrontEnd )
				)
				( attribute "VER" "1"
					( Origin gFrontEnd )
				)
				( attribute "WATTAGE" "1/16W"
					( Origin gFrontEnd )
				)
				( attribute "XY" "(-1925,3225)"
					( Origin gFrontEnd )
				)
				( attribute "CHIPS_PART_NAME" "RES"
					( Origin gPackager )
				)
				( attribute "CDS_PART_NAME" "RES_0402-0.0,5%,1/16W,CHIP,G21A"
					( Origin gPackager )
				)
				( attribute "SEC_TYPE" "0402"
					( Origin gFrontEnd )
				)
				( attribute "CDS_SEC" "1"
					( Origin gPackager )
				)
				( objectStatus "R6P41" )
			)
			( gate "@baseboard_fab2_lib.baseboard_fab2(sch_1):page213_i91"
				( attribute "BOM_COST" "SM_CONTROLLER"
					( Origin gFrontEnd )
				)
				( attribute "CDS_LIB" "mstr_discrete"
					( Origin gPackager )
				)
				( attribute "CDS_LOCATION" "R6P40"
					( Origin gPackager )
				)
				( attribute "LOCATION" "R6P40"
					( Origin gFrontEnd )
				)
				( attribute "MATERIAL" "EMPTY"
					( Origin gFrontEnd )
				)
				( attribute "PACK_TYPE" "0402"
					( Origin gFrontEnd )
				)
				( attribute "PART_NUMBER" "G21796-010"
					( Origin gFrontEnd )
				)
				( attribute "PHYS_PAGE" "213"
					( Origin gFrontEnd )
				)
				( attribute "ROOM" "BMC"
					( Origin gFrontEnd )
				)
				( attribute "ROT" "0"
					( Origin gFrontEnd )
				)
				( attribute "SEC" "1"
					( Origin gFrontEnd )
				)
				( attribute "TOLERANCE" "1%"
					( Origin gFrontEnd )
				)
				( attribute "VALUE" "100.0K"
					( Origin gFrontEnd )
				)
				( attribute "VER" "2"
					( Origin gFrontEnd )
				)
				( attribute "WATTAGE" "1/16W"
					( Origin gFrontEnd )
				)
				( attribute "XY" "(-1025,4275)"
					( Origin gFrontEnd )
				)
				( attribute "CHIPS_PART_NAME" "RES"
					( Origin gPackager )
				)
				( attribute "CDS_PART_NAME" "RES_0402-100.0K,1%,1/16W,EMPTYA"
					( Origin gPackager )
				)
				( attribute "SEC_TYPE" "0402"
					( Origin gFrontEnd )
				)
				( attribute "CDS_SEC" "1"
					( Origin gPackager )
				)
				( objectStatus "R6P40" )
			)
			( gate "@baseboard_fab2_lib.baseboard_fab2(sch_1):page213_i96"
				( attribute "CDS_LIB" "mstr_controller"
					( Origin gPackager )
				)
				( attribute "CDS_LMAN_SYM_OUTLINE" "-400,850,400,-850"
					( Origin gPackager )
				)
				( attribute "CDS_LOCATION" "EU4D5"
					( Origin gPackager )
				)
				( attribute "CDS_SEC" "1"
					( Origin gPackager )
				)
				( attribute "LOCATION" "EU4D5"
					( Origin gFrontEnd )
				)
				( attribute "MATERIAL" "IC"
					( Origin gFrontEnd )
				)
				( attribute "PACK_TYPE" "QFN"
					( Origin gFrontEnd )
				)
				( attribute "PART_NUMBER" "H89187-001"
					( Origin gFrontEnd )
				)
				( attribute "PHYS_PAGE" "213"
					( Origin gFrontEnd )
				)
				( attribute "ROT" "0"
					( Origin gFrontEnd )
				)
				( attribute "SEC" "1"
					( Origin gFrontEnd )
				)
				( attribute "SEC_TYPE" "QFN"
					( Origin gFrontEnd )
				)
				( attribute "VER" "1"
					( Origin gFrontEnd )
				)
				( attribute "XY" "(175,2825)"
					( Origin gFrontEnd )
				)
				( attribute "CHIPS_PART_NAME" "PXE1110B"
					( Origin gPackager )
				)
				( attribute "CDS_PART_NAME" "PXE1110B_QFN-IC,H89187-001"
					( Origin gPackager )
				)
				( objectStatus "EU4D5" )
			)
			( gate "@baseboard_fab2_lib.baseboard_fab2(sch_1):page236_i161"
				( attribute "CDS_LIB" "w_hdl"
					( Origin gPackager )
				)
				( attribute "CDS_LMAN_SYM_OUTLINE" "-50,25,50,-25"
					( Origin gPackager )
				)
				( attribute "LOCATION" "C7A13"
					( Origin gFrontEnd )
				)
				( attribute "PACK_TYPE" "SMD-BCG5"
					( Origin gFrontEnd )
				)
				( attribute "PART_NUMBER" "078.22611.0811"
					( Origin gFrontEnd )
				)
				( attribute "PHYS_PAGE" "236"
					( Origin gFrontEnd )
				)
				( attribute "ROT" "0"
					( Origin gFrontEnd )
				)
				( attribute "SEC" "1"
					( Origin gFrontEnd )
				)
				( attribute "SEC_TYPE" "SMD-BCG5"
					( Origin gFrontEnd )
				)
				( attribute "VALUE" "SC22U16V5MX-4-GP"
					( Origin gFrontEnd )
				)
				( attribute "VER" "1"
					( Origin gFrontEnd )
				)
				( attribute "XY" "(11800,975)"
					( Origin gFrontEnd )
				)
				( attribute "CHIPS_PART_NAME" "SC22U16V5MX-4-GP"
					( Origin gPackager )
				)
				( attribute "CDS_PART_NAME" "SC22U16V5MX-4-GP_SMD-BCG5-SC22A"
					( Origin gPackager )
				)
				( attribute "ATTRIBUTE" "22UF"
					( Origin gFrontEnd )
				)
				( attribute "PACK_SIZE" "0805"
					( Origin gFrontEnd )
				)
				( attribute "RATED" "16V"
					( Origin gFrontEnd )
				)
				( attribute "TOLERANCE" "20%"
					( Origin gFrontEnd )
				)
				( attribute "TYPE" "X6S"
					( Origin gFrontEnd )
				)
				( attribute "CDS_LOCATION" "C7A13"
					( Origin gPackager )
				)
				( attribute "CDS_SEC" "1"
					( Origin gPackager )
				)
				( objectStatus "C7A13" )
			)
			( gate "@baseboard_fab2_lib.baseboard_fab2(sch_1):page214_i24"
				( attribute "BOM_COST" "PROC_VRD_PVCCIO_CPU1"
					( Origin gFrontEnd )
				)
				( attribute "CDS_LIB" "mstr_discrete"
					( Origin gPackager )
				)
				( attribute "CDS_LOCATION" "C6R5"
					( Origin gPackager )
				)
				( attribute "CDS_SEC" "1"
					( Origin gPackager )
				)
				( attribute "LOCATION" "C6R5"
					( Origin gFrontEnd )
				)
				( attribute "MATERIAL" "ALUM"
					( Origin gFrontEnd )
				)
				( attribute "PACK_TYPE" "3018"
					( Origin gFrontEnd )
				)
				( attribute "PART_NUMBER" "699013-049"
					( Origin gFrontEnd )
				)
				( attribute "PHYS_PAGE" "214"
					( Origin gFrontEnd )
				)
				( attribute "ROOM" "PVCCIO_CPU1"
					( Origin gFrontEnd )
				)
				( attribute "ROT" "2"
					( Origin gFrontEnd )
				)
				( attribute "SEC" "1"
					( Origin gFrontEnd )
				)
				( attribute "SEC_TYPE" "3018"
					( Origin gFrontEnd )
				)
				( attribute "TOLERANCE" "20%"
					( Origin gFrontEnd )
				)
				( attribute "VALUE" "470UF"
					( Origin gFrontEnd )
				)
				( attribute "VER" "1"
					( Origin gFrontEnd )
				)
				( attribute "VOLTAGE" "2.5V"
					( Units "uVoltage" "V" 1.000000)
					( Origin gFrontEnd )
				)
				( attribute "XY" "(2100,2300)"
					( Origin gFrontEnd )
				)
				( attribute "CHIPS_PART_NAME" "CAPP"
					( Origin gPackager )
				)
				( attribute "CDS_PART_NAME" "CAPP_3018-470UF,2.5V,20%,ALUM,A"
					( Origin gPackager )
				)
				( attribute "GROUP" "PWR_BULK_CAP"
					( Origin gFrontEnd )
				)
				( objectStatus "C6R5" )
			)
			( gate "@baseboard_fab2_lib.baseboard_fab2(sch_1):page236_i160"
				( attribute "CDS_LIB" "w_hdl"
					( Origin gPackager )
				)
				( attribute "CDS_LMAN_SYM_OUTLINE" "-50,25,50,-25"
					( Origin gPackager )
				)
				( attribute "LOCATION" "C22W24"
					( Origin gFrontEnd )
				)
				( attribute "PACK_TYPE" "SMD-BCG5"
					( Origin gFrontEnd )
				)
				( attribute "PART_NUMBER" "078.22611.0811"
					( Origin gFrontEnd )
				)
				( attribute "PHYS_PAGE" "236"
					( Origin gFrontEnd )
				)
				( attribute "ROT" "0"
					( Origin gFrontEnd )
				)
				( attribute "SEC" "1"
					( Origin gFrontEnd )
				)
				( attribute "SEC_TYPE" "SMD-BCG5"
					( Origin gFrontEnd )
				)
				( attribute "VALUE" "SC22U16V5MX-4-GP"
					( Origin gFrontEnd )
				)
				( attribute "VER" "1"
					( Origin gFrontEnd )
				)
				( attribute "XY" "(11450,975)"
					( Origin gFrontEnd )
				)
				( attribute "CHIPS_PART_NAME" "SC22U16V5MX-4-GP"
					( Origin gPackager )
				)
				( attribute "CDS_PART_NAME" "SC22U16V5MX-4-GP_SMD-BCG5-SC22A"
					( Origin gPackager )
				)
				( attribute "CDS_LOCATION" "C22W24"
					( Origin gPackager )
				)
				( attribute "CDS_SEC" "1"
					( Origin gPackager )
				)
				( attribute "ATTRIBUTE" "22UF"
					( Origin gFrontEnd )
				)
				( attribute "PACK_SIZE" "0805"
					( Origin gFrontEnd )
				)
				( attribute "RATED" "16V"
					( Origin gFrontEnd )
				)
				( attribute "TOLERANCE" "20%"
					( Origin gFrontEnd )
				)
				( attribute "TYPE" "X6S"
					( Origin gFrontEnd )
				)
				( objectStatus "C22W24" )
			)
			( gate "@baseboard_fab2_lib.baseboard_fab2(sch_1):page236_i159"
				( attribute "CDS_LIB" "w_hdl"
					( Origin gPackager )
				)
				( attribute "CDS_LMAN_SYM_OUTLINE" "-50,25,50,-25"
					( Origin gPackager )
				)
				( attribute "LOCATION" "C22W23"
					( Origin gFrontEnd )
				)
				( attribute "PACK_TYPE" "SMD-BCG5"
					( Origin gFrontEnd )
				)
				( attribute "PART_NUMBER" "078.22611.0811"
					( Origin gFrontEnd )
				)
				( attribute "PHYS_PAGE" "236"
					( Origin gFrontEnd )
				)
				( attribute "ROT" "0"
					( Origin gFrontEnd )
				)
				( attribute "SEC" "1"
					( Origin gFrontEnd )
				)
				( attribute "SEC_TYPE" "SMD-BCG5"
					( Origin gFrontEnd )
				)
				( attribute "VALUE" "SC22U16V5MX-4-GP"
					( Origin gFrontEnd )
				)
				( attribute "VER" "1"
					( Origin gFrontEnd )
				)
				( attribute "XY" "(11150,975)"
					( Origin gFrontEnd )
				)
				( attribute "CHIPS_PART_NAME" "SC22U16V5MX-4-GP"
					( Origin gPackager )
				)
				( attribute "CDS_PART_NAME" "SC22U16V5MX-4-GP_SMD-BCG5-SC22A"
					( Origin gPackager )
				)
				( attribute "CDS_LOCATION" "C22W23"
					( Origin gPackager )
				)
				( attribute "CDS_SEC" "1"
					( Origin gPackager )
				)
				( attribute "ATTRIBUTE" "22UF"
					( Origin gFrontEnd )
				)
				( attribute "PACK_SIZE" "0805"
					( Origin gFrontEnd )
				)
				( attribute "RATED" "16V"
					( Origin gFrontEnd )
				)
				( attribute "TOLERANCE" "20%"
					( Origin gFrontEnd )
				)
				( attribute "TYPE" "X6S"
					( Origin gFrontEnd )
				)
				( objectStatus "C22W23" )
			)
			( gate "@baseboard_fab2_lib.baseboard_fab2(sch_1):page214_i65"
				( attribute "BOM_COST" "PROC_VRD_PVCCIO_CPU1"
					( Origin gFrontEnd )
				)
				( attribute "CDS_LIB" "dev_discrete"
					( Origin gPackager )
				)
				( attribute "CDS_LOCATION" "C7R1"
					( Origin gPackager )
				)
				( attribute "CDS_SEC" "1"
					( Origin gPackager )
				)
				( attribute "LOCATION" "C7R1"
					( Origin gFrontEnd )
				)
				( attribute "MATERIAL" "X6S"
					( Origin gFrontEnd )
				)
				( attribute "PACK_TYPE" "0603V"
					( Origin gFrontEnd )
				)
				( attribute "PART_NUMBER" "E15431-004"
					( Origin gFrontEnd )
				)
				( attribute "PHYS_PAGE" "214"
					( Origin gFrontEnd )
				)
				( attribute "ROOM" "PVCCIO_CPU1"
					( Origin gFrontEnd )
				)
				( attribute "ROT" "0"
					( Origin gFrontEnd )
				)
				( attribute "SEC" "1"
					( Origin gFrontEnd )
				)
				( attribute "SEC_TYPE" "0603V"
					( Origin gFrontEnd )
				)
				( attribute "TOLERANCE" "20%"
					( Origin gFrontEnd )
				)
				( attribute "VALUE" "22.0UF"
					( Origin gFrontEnd )
				)
				( attribute "VER" "1"
					( Origin gFrontEnd )
				)
				( attribute "VOLTAGE" "4V"
					( Units "uVoltage" "V" 1.000000)
					( Origin gFrontEnd )
				)
				( attribute "XY" "(3350,3425)"
					( Origin gFrontEnd )
				)
				( attribute "CHIPS_PART_NAME" "CAP_A"
					( Origin gPackager )
				)
				( attribute "CDS_PART_NAME" "CAP_A_0603V-22.0UF,4V,20%,X6S,A"
					( Origin gPackager )
				)
				( attribute "GROUP" "PWR_MLCC_CAP"
					( Origin gFrontEnd )
				)
				( objectStatus "C7R1" )
			)
			( gate "@baseboard_fab2_lib.baseboard_fab2(sch_1):page205_i82"
				( attribute "CDS_LIB" "w_hdl"
					( Origin gPackager )
				)
				( attribute "CDS_LMAN_SYM_OUTLINE" "-75,100,75,-100"
					( Origin gPackager )
				)
				( attribute "LOCATION" "L4C2"
					( Origin gFrontEnd )
				)
				( attribute "PACK_TYPE" "DISCRET-GB1"
					( Origin gFrontEnd )
				)
				( attribute "PART_NUMBER" "068.3012N.M001"
					( Origin gFrontEnd )
				)
				( attribute "PHYS_PAGE" "205"
					( Origin gFrontEnd )
				)
				( attribute "ROT" "1"
					( Origin gFrontEnd )
				)
				( attribute "SEC" "1"
					( Origin gFrontEnd )
				)
				( attribute "SEC_TYPE" "DISCRET-GB1"
					( Origin gFrontEnd )
				)
				( attribute "VALUE" "IND-300NH-20-GP"
					( Origin gFrontEnd )
				)
				( attribute "VER" "1"
					( Origin gFrontEnd )
				)
				( attribute "XY" "(-1325,3650)"
					( Origin gFrontEnd )
				)
				( attribute "CHIPS_PART_NAME" "IND-300NH-20-GP"
					( Origin gPackager )
				)
				( attribute "CDS_PART_NAME" "IND-300NH-20-GP_DISCRET-GB1-INA"
					( Origin gPackager )
				)
				( attribute "CDS_LOCATION" "L4C2"
					( Origin gPackager )
				)
				( attribute "CDS_SEC" "1"
					( Origin gPackager )
				)
				( attribute "ATTRIBUTE" "300NH"
					( Origin gFrontEnd )
				)
				( attribute "PACK_SIZE" "DCR=0.17MOHM"
					( Origin gFrontEnd )
				)
				( attribute "RATED" "ISAT=33A@25C"
					( Origin gFrontEnd )
				)
				( attribute "TYPE" "IRMS=66A@DELTA_T<40C"
					( Origin gFrontEnd )
				)
				( objectStatus "L4C2" )
			)
			( gate "@baseboard_fab2_lib.baseboard_fab2(sch_1):page216_i145"
				( attribute "BOM_COST" "PROC_SIDEBAND"
					( Origin gFrontEnd )
				)
				( attribute "CDS_LIB" "mstr_discrete"
					( Origin gPackager )
				)
				( attribute "CDS_LOCATION" "R3U6"
					( Origin gPackager )
				)
				( attribute "CDS_SEC" "1"
					( Origin gPackager )
				)
				( attribute "LOCATION" "R3U6"
					( Origin gFrontEnd )
				)
				( attribute "MATERIAL" "CHIP"
					( Origin gFrontEnd )
				)
				( attribute "PACK_TYPE" "0402"
					( Origin gFrontEnd )
				)
				( attribute "PART_NUMBER" "G21497-005"
					( Origin gFrontEnd )
				)
				( attribute "PHYS_PAGE" "216"
					( Origin gFrontEnd )
				)
				( attribute "ROOM" "CPU0"
					( Origin gFrontEnd )
				)
				( attribute "ROT" "0"
					( Origin gFrontEnd )
				)
				( attribute "SEC" "1"
					( Origin gFrontEnd )
				)
				( attribute "SEC_TYPE" "0402"
					( Origin gFrontEnd )
				)
				( attribute "TOLERANCE" "5%"
					( Origin gFrontEnd )
				)
				( attribute "VALUE" "0.0"
					( Origin gFrontEnd )
				)
				( attribute "VER" "1"
					( Origin gFrontEnd )
				)
				( attribute "WATTAGE" "1/16W"
					( Origin gFrontEnd )
				)
				( attribute "XY" "(-575,3100)"
					( Origin gFrontEnd )
				)
				( attribute "CHIPS_PART_NAME" "RES"
					( Origin gPackager )
				)
				( attribute "CDS_PART_NAME" "RES_0402-0.0,5%,1/16W,CHIP,G21A"
					( Origin gPackager )
				)
				( objectStatus "R3U6" )
			)
			( gate "@baseboard_fab2_lib.baseboard_fab2(sch_1):page214_i73"
				( attribute "CDS_LIB" "mstr_discrete"
					( Origin gPackager )
				)
				( attribute "CDS_LOCATION" "C4E23"
					( Origin gPackager )
				)
				( attribute "CDS_SEC" "1"
					( Origin gPackager )
				)
				( attribute "LOCATION" "C4E23"
					( Origin gFrontEnd )
				)
				( attribute "MATERIAL" "X7R"
					( Origin gFrontEnd )
				)
				( attribute "PACK_TYPE" "0402"
					( Origin gFrontEnd )
				)
				( attribute "PART_NUMBER" "A36096-155"
					( Origin gFrontEnd )
				)
				( attribute "PHYS_PAGE" "214"
					( Origin gFrontEnd )
				)
				( attribute "ROOM" "PVCCIO_CPU1"
					( Origin gFrontEnd )
				)
				( attribute "ROT" "0"
					( Origin gFrontEnd )
				)
				( attribute "SEC" "1"
					( Origin gFrontEnd )
				)
				( attribute "SEC_TYPE" "0402"
					( Origin gFrontEnd )
				)
				( attribute "TOLERANCE" "10%"
					( Origin gFrontEnd )
				)
				( attribute "VALUE" "0.22UF"
					( Origin gFrontEnd )
				)
				( attribute "VER" "1"
					( Origin gFrontEnd )
				)
				( attribute "VOLTAGE" "16V"
					( Units "uVoltage" "V" 1.000000)
					( Origin gFrontEnd )
				)
				( attribute "XY" "(-950,4200)"
					( Origin gFrontEnd )
				)
				( attribute "CHIPS_PART_NAME" "CAP"
					( Origin gPackager )
				)
				( attribute "CDS_PART_NAME" "CAP_0402-0.22UF,16V,10%,X7R,A3A"
					( Origin gPackager )
				)
				( objectStatus "C4E23" )
			)
			( gate "@baseboard_fab2_lib.baseboard_fab2(sch_1):page219_i151"
				( attribute "CDS_LIB" "w_hdl"
					( Origin gPackager )
				)
				( attribute "CDS_LMAN_SYM_OUTLINE" "-50,25,50,-25"
					( Origin gPackager )
				)
				( attribute "LOCATION" "C7A18"
					( Origin gFrontEnd )
				)
				( attribute "PACK_TYPE" "SMD-BCG6"
					( Origin gFrontEnd )
				)
				( attribute "PART_NUMBER" "78.10523.8FL"
					( Origin gFrontEnd )
				)
				( attribute "PHYS_PAGE" "219"
					( Origin gFrontEnd )
				)
				( attribute "ROT" "0"
					( Origin gFrontEnd )
				)
				( attribute "SEC" "1"
					( Origin gFrontEnd )
				)
				( attribute "SEC_TYPE" "SMD-BCG6"
					( Origin gFrontEnd )
				)
				( attribute "VALUE" "SC1U10V2KX-4-GP"
					( Origin gFrontEnd )
				)
				( attribute "VER" "1"
					( Origin gFrontEnd )
				)
				( attribute "XY" "(-450,2350)"
					( Origin gFrontEnd )
				)
				( attribute "CHIPS_PART_NAME" "SC1U10V2KX-4-GP"
					( Origin gPackager )
				)
				( attribute "CDS_PART_NAME" "SC1U10V2KX-4-GP_SMD-BCG6-SC1U1A"
					( Origin gPackager )
				)
				( attribute "CDS_LOCATION" "C7A18"
					( Origin gPackager )
				)
				( attribute "CDS_SEC" "1"
					( Origin gPackager )
				)
				( attribute "ATTRIBUTE" "1UF"
					( Origin gFrontEnd )
				)
				( attribute "PACK_SIZE" "0402"
					( Origin gFrontEnd )
				)
				( attribute "RATED" "10V"
					( Origin gFrontEnd )
				)
				( attribute "TOLERANCE" "10%"
					( Origin gFrontEnd )
				)
				( objectStatus "C7A18" )
			)
			( gate "@baseboard_fab2_lib.baseboard_fab2(sch_1):page214_i76"
				( attribute "CDS_LIB" "mstr_discrete"
					( Origin gPackager )
				)
				( attribute "CDS_LOCATION" "C4E22"
					( Origin gPackager )
				)
				( attribute "CDS_SEC" "1"
					( Origin gPackager )
				)
				( attribute "LOCATION" "C4E22"
					( Origin gFrontEnd )
				)
				( attribute "MATERIAL" "X6S"
					( Origin gFrontEnd )
				)
				( attribute "PACK_TYPE" "0402"
					( Origin gFrontEnd )
				)
				( attribute "PART_NUMBER" "D97712-011"
					( Origin gFrontEnd )
				)
				( attribute "PHYS_PAGE" "214"
					( Origin gFrontEnd )
				)
				( attribute "ROOM" "PVCCIO_CPU1"
					( Origin gFrontEnd )
				)
				( attribute "ROT" "0"
					( Origin gFrontEnd )
				)
				( attribute "SEC" "1"
					( Origin gFrontEnd )
				)
				( attribute "SEC_TYPE" "0402"
					( Origin gFrontEnd )
				)
				( attribute "TOLERANCE" "10%"
					( Origin gFrontEnd )
				)
				( attribute "VALUE" "1.0UF"
					( Origin gFrontEnd )
				)
				( attribute "VER" "1"
					( Origin gFrontEnd )
				)
				( attribute "VOLTAGE" "16V"
					( Units "uVoltage" "V" 1.000000)
					( Origin gFrontEnd )
				)
				( attribute "XY" "(-1700,4150)"
					( Origin gFrontEnd )
				)
				( attribute "CHIPS_PART_NAME" "CAP"
					( Origin gPackager )
				)
				( attribute "CDS_PART_NAME" "CAP_0402-1.0UF,16V,10%,X6S,D97A"
					( Origin gPackager )
				)
				( objectStatus "C4E22" )
			)
			( gate "@baseboard_fab2_lib.baseboard_fab2(sch_1):page214_i77"
				( attribute "CDS_LIB" "dev_discrete"
					( Origin gPackager )
				)
				( attribute "CDS_LOCATION" "C4E13"
					( Origin gPackager )
				)
				( attribute "CDS_SEC" "1"
					( Origin gPackager )
				)
				( attribute "LOCATION" "C4E13"
					( Origin gFrontEnd )
				)
				( attribute "MATERIAL" "X7R"
					( Origin gFrontEnd )
				)
				( attribute "PACK_TYPE" "0402V"
					( Origin gFrontEnd )
				)
				( attribute "PART_NUMBER" "A36096-030"
					( Origin gFrontEnd )
				)
				( attribute "PHYS_PAGE" "214"
					( Origin gFrontEnd )
				)
				( attribute "ROOM" "PVCCIO_CPU1"
					( Origin gFrontEnd )
				)
				( attribute "ROT" "0"
					( Origin gFrontEnd )
				)
				( attribute "SEC" "1"
					( Origin gFrontEnd )
				)
				( attribute "SEC_TYPE" "0402V"
					( Origin gFrontEnd )
				)
				( attribute "TOLERANCE" "10%"
					( Origin gFrontEnd )
				)
				( attribute "VALUE" "0.1UF"
					( Origin gFrontEnd )
				)
				( attribute "VER" "1"
					( Origin gFrontEnd )
				)
				( attribute "VOLTAGE" "16V"
					( Units "uVoltage" "V" 1.000000)
					( Origin gFrontEnd )
				)
				( attribute "XY" "(-1975,4150)"
					( Origin gFrontEnd )
				)
				( attribute "CHIPS_PART_NAME" "CAP_A"
					( Origin gPackager )
				)
				( attribute "CDS_PART_NAME" "CAP_A_0402V-0.1UF,16V,10%,X7R,A"
					( Origin gPackager )
				)
				( objectStatus "C4E13" )
			)
			( gate "@baseboard_fab2_lib.baseboard_fab2(sch_1):page214_i78"
				( attribute "CDS_LIB" "mstr_discrete"
					( Origin gPackager )
				)
				( attribute "CDS_LOCATION" "C4E18"
					( Origin gPackager )
				)
				( attribute "CDS_SEC" "1"
					( Origin gPackager )
				)
				( attribute "LOCATION" "C4E18"
					( Origin gFrontEnd )
				)
				( attribute "MATERIAL" "X7R"
					( Origin gFrontEnd )
				)
				( attribute "PACK_TYPE" "0402"
					( Origin gFrontEnd )
				)
				( attribute "PART_NUMBER" "A36096-104"
					( Origin gFrontEnd )
				)
				( attribute "PHYS_PAGE" "214"
					( Origin gFrontEnd )
				)
				( attribute "ROOM" "PVCCIO_CPU1"
					( Origin gFrontEnd )
				)
				( attribute "ROT" "2"
					( Origin gFrontEnd )
				)
				( attribute "SEC" "1"
					( Origin gFrontEnd )
				)
				( attribute "SEC_TYPE" "0402"
					( Origin gFrontEnd )
				)
				( attribute "SPOF" "TRUE"
					( Origin gFrontEnd )
				)
				( attribute "TOLERANCE" "10%"
					( Origin gFrontEnd )
				)
				( attribute "VALUE" "0.220UF"
					( Origin gFrontEnd )
				)
				( attribute "VER" "1"
					( Origin gFrontEnd )
				)
				( attribute "VOLTAGE" "16V"
					( Units "uVoltage" "V" 1.000000)
					( Origin gFrontEnd )
				)
				( attribute "XY" "(-1625,3575)"
					( Origin gFrontEnd )
				)
				( attribute "CHIPS_PART_NAME" "CAP"
					( Origin gPackager )
				)
				( attribute "CDS_PART_NAME" "CAP_0402-0.220UF,16V,10%,X7R,AA"
					( Origin gPackager )
				)
				( objectStatus "C4E18" )
			)
			( gate "@baseboard_fab2_lib.baseboard_fab2(sch_1):page214_i79"
				( attribute "CDS_LIB" "mstr_discrete"
					( Origin gPackager )
				)
				( attribute "CDS_LOCATION" "C4E15"
					( Origin gPackager )
				)
				( attribute "CDS_SEC" "1"
					( Origin gPackager )
				)
				( attribute "LOCATION" "C4E15"
					( Origin gFrontEnd )
				)
				( attribute "MATERIAL" "X6S"
					( Origin gFrontEnd )
				)
				( attribute "PACK_TYPE" "0402"
					( Origin gFrontEnd )
				)
				( attribute "PART_NUMBER" "D97712-011"
					( Origin gFrontEnd )
				)
				( attribute "PHYS_PAGE" "214"
					( Origin gFrontEnd )
				)
				( attribute "ROOM" "PVCCIO_CPU1"
					( Origin gFrontEnd )
				)
				( attribute "ROT" "0"
					( Origin gFrontEnd )
				)
				( attribute "SEC" "1"
					( Origin gFrontEnd )
				)
				( attribute "SEC_TYPE" "0402"
					( Origin gFrontEnd )
				)
				( attribute "TOLERANCE" "10%"
					( Origin gFrontEnd )
				)
				( attribute "VALUE" "1.0UF"
					( Origin gFrontEnd )
				)
				( attribute "VER" "1"
					( Origin gFrontEnd )
				)
				( attribute "VOLTAGE" "16V"
					( Units "uVoltage" "V" 1.000000)
					( Origin gFrontEnd )
				)
				( attribute "XY" "(-2250,4150)"
					( Origin gFrontEnd )
				)
				( attribute "CHIPS_PART_NAME" "CAP"
					( Origin gPackager )
				)
				( attribute "CDS_PART_NAME" "CAP_0402-1.0UF,16V,10%,X6S,D97A"
					( Origin gPackager )
				)
				( objectStatus "C4E15" )
			)
			( gate "@baseboard_fab2_lib.baseboard_fab2(sch_1):page214_i80"
				( attribute "CDS_LIB" "mstr_discrete"
					( Origin gPackager )
				)
				( attribute "CDS_LOCATION" "C6R14"
					( Origin gPackager )
				)
				( attribute "CDS_SEC" "1"
					( Origin gPackager )
				)
				( attribute "LOCATION" "C6R14"
					( Origin gFrontEnd )
				)
				( attribute "MATERIAL" "X6S"
					( Origin gFrontEnd )
				)
				( attribute "PACK_TYPE" "0805"
					( Origin gFrontEnd )
				)
				( attribute "PART_NUMBER" "C95333-007"
					( Origin gFrontEnd )
				)
				( attribute "PHYS_PAGE" "214"
					( Origin gFrontEnd )
				)
				( attribute "ROOM" "PVCCIO_CPU1"
					( Origin gFrontEnd )
				)
				( attribute "ROT" "0"
					( Origin gFrontEnd )
				)
				( attribute "SEC" "1"
					( Origin gFrontEnd )
				)
				( attribute "SEC_TYPE" "0805"
					( Origin gFrontEnd )
				)
				( attribute "TOLERANCE" "10%"
					( Origin gFrontEnd )
				)
				( attribute "VALUE" "10UF"
					( Origin gFrontEnd )
				)
				( attribute "VER" "1"
					( Origin gFrontEnd )
				)
				( attribute "VOLTAGE" "16V"
					( Units "uVoltage" "V" 1.000000)
					( Origin gFrontEnd )
				)
				( attribute "XY" "(-2525,4150)"
					( Origin gFrontEnd )
				)
				( attribute "CHIPS_PART_NAME" "CAP"
					( Origin gPackager )
				)
				( attribute "CDS_PART_NAME" "CAP_0805-10UF,16V,10%,X6S,C953A"
					( Origin gPackager )
				)
				( objectStatus "C6R14" )
			)
			( gate "@baseboard_fab2_lib.baseboard_fab2(sch_1):page214_i81"
				( attribute "CDS_LIB" "mstr_discrete"
					( Origin gPackager )
				)
				( attribute "CDS_LOCATION" "C6R10"
					( Origin gPackager )
				)
				( attribute "CDS_SEC" "1"
					( Origin gPackager )
				)
				( attribute "LOCATION" "C6R10"
					( Origin gFrontEnd )
				)
				( attribute "MATERIAL" "X6S"
					( Origin gFrontEnd )
				)
				( attribute "PACK_TYPE" "0805"
					( Origin gFrontEnd )
				)
				( attribute "PART_NUMBER" "C95333-007"
					( Origin gFrontEnd )
				)
				( attribute "PHYS_PAGE" "214"
					( Origin gFrontEnd )
				)
				( attribute "ROOM" "PVCCIO_CPU1"
					( Origin gFrontEnd )
				)
				( attribute "ROT" "0"
					( Origin gFrontEnd )
				)
				( attribute "SEC" "1"
					( Origin gFrontEnd )
				)
				( attribute "SEC_TYPE" "0805"
					( Origin gFrontEnd )
				)
				( attribute "TOLERANCE" "10%"
					( Origin gFrontEnd )
				)
				( attribute "VALUE" "10UF"
					( Origin gFrontEnd )
				)
				( attribute "VER" "1"
					( Origin gFrontEnd )
				)
				( attribute "VOLTAGE" "16V"
					( Units "uVoltage" "V" 1.000000)
					( Origin gFrontEnd )
				)
				( attribute "XY" "(-2800,4150)"
					( Origin gFrontEnd )
				)
				( attribute "CHIPS_PART_NAME" "CAP"
					( Origin gPackager )
				)
				( attribute "CDS_PART_NAME" "CAP_0805-10UF,16V,10%,X6S,C953A"
					( Origin gPackager )
				)
				( objectStatus "C6R10" )
			)
			( gate "@baseboard_fab2_lib.baseboard_fab2(sch_1):page214_i83"
				( attribute "CDS_LIB" "mstr_discrete"
					( Origin gPackager )
				)
				( attribute "CDS_LOCATION" "C6R8"
					( Origin gPackager )
				)
				( attribute "CDS_SEC" "1"
					( Origin gPackager )
				)
				( attribute "LOCATION" "C6R8"
					( Origin gFrontEnd )
				)
				( attribute "MATERIAL" "X6S"
					( Origin gFrontEnd )
				)
				( attribute "PACK_TYPE" "0805"
					( Origin gFrontEnd )
				)
				( attribute "PART_NUMBER" "C95333-007"
					( Origin gFrontEnd )
				)
				( attribute "PHYS_PAGE" "214"
					( Origin gFrontEnd )
				)
				( attribute "ROOM" "PVCCIO_CPU1"
					( Origin gFrontEnd )
				)
				( attribute "ROT" "0"
					( Origin gFrontEnd )
				)
				( attribute "SEC" "1"
					( Origin gFrontEnd )
				)
				( attribute "SEC_TYPE" "0805"
					( Origin gFrontEnd )
				)
				( attribute "TOLERANCE" "10%"
					( Origin gFrontEnd )
				)
				( attribute "VALUE" "10UF"
					( Origin gFrontEnd )
				)
				( attribute "VER" "1"
					( Origin gFrontEnd )
				)
				( attribute "VOLTAGE" "16V"
					( Units "uVoltage" "V" 1.000000)
					( Origin gFrontEnd )
				)
				( attribute "XY" "(-3100,4150)"
					( Origin gFrontEnd )
				)
				( attribute "CHIPS_PART_NAME" "CAP"
					( Origin gPackager )
				)
				( attribute "CDS_PART_NAME" "CAP_0805-10UF,16V,10%,X6S,C953A"
					( Origin gPackager )
				)
				( objectStatus "C6R8" )
			)
			( gate "@baseboard_fab2_lib.baseboard_fab2(sch_1):page214_i96"
				( attribute "BOM_COST" "PROC_VRD_VCCIO_CPU1"
					( Origin gFrontEnd )
				)
				( attribute "CDS_LIB" "dev_discrete"
					( Origin gPackager )
				)
				( attribute "CDS_LOCATION" "C3D27"
					( Origin gPackager )
				)
				( attribute "CDS_SEC" "1"
					( Origin gPackager )
				)
				( attribute "LOCATION" "C3D27"
					( Origin gFrontEnd )
				)
				( attribute "MATERIAL" "EMPTY"
					( Origin gFrontEnd )
				)
				( attribute "PACK_TYPE" "0402V"
					( Origin gFrontEnd )
				)
				( attribute "PART_NUMBER" "A36096-030"
					( Origin gFrontEnd )
				)
				( attribute "PHYS_PAGE" "214"
					( Origin gFrontEnd )
				)
				( attribute "ROOM" "PVCCIO_CPU1"
					( Origin gFrontEnd )
				)
				( attribute "ROT" "0"
					( Origin gFrontEnd )
				)
				( attribute "SEC" "1"
					( Origin gFrontEnd )
				)
				( attribute "SEC_TYPE" "0402V"
					( Origin gFrontEnd )
				)
				( attribute "TOLERANCE" "10%"
					( Origin gFrontEnd )
				)
				( attribute "VALUE" "0.1UF"
					( Origin gFrontEnd )
				)
				( attribute "VER" "1"
					( Origin gFrontEnd )
				)
				( attribute "VOLTAGE" "16V"
					( Units "uVoltage" "V" 1.000000)
					( Origin gFrontEnd )
				)
				( attribute "XY" "(-1725,1575)"
					( Origin gFrontEnd )
				)
				( attribute "CHIPS_PART_NAME" "CAP_A"
					( Origin gPackager )
				)
				( attribute "CDS_PART_NAME" "CAP_A_0402V-0.1UF,16V,10%,EMPTA"
					( Origin gPackager )
				)
				( objectStatus "C3D27" )
			)
			( gate "@baseboard_fab2_lib.baseboard_fab2(sch_1):page214_i101"
				( attribute "BOM_COST" "PROC_VRD_VCCIO_CPU1"
					( Origin gFrontEnd )
				)
				( attribute "CDS_LIB" "mstr_discrete"
					( Origin gPackager )
				)
				( attribute "CDS_LOCATION" "R3D28"
					( Origin gPackager )
				)
				( attribute "CDS_SEC" "1"
					( Origin gPackager )
				)
				( attribute "LOCATION" "R3D28"
					( Origin gFrontEnd )
				)
				( attribute "MATERIAL" "CHIP"
					( Origin gFrontEnd )
				)
				( attribute "PACK_TYPE" "0402"
					( Origin gFrontEnd )
				)
				( attribute "PART_NUMBER" "G21796-017"
					( Origin gFrontEnd )
				)
				( attribute "PHYS_PAGE" "214"
					( Origin gFrontEnd )
				)
				( attribute "ROOM" "PVCCIO_CPU1"
					( Origin gFrontEnd )
				)
				( attribute "ROT" "0"
					( Origin gFrontEnd )
				)
				( attribute "SEC" "1"
					( Origin gFrontEnd )
				)
				( attribute "SEC_TYPE" "0402"
					( Origin gFrontEnd )
				)
				( attribute "TOLERANCE" "1%"
					( Origin gFrontEnd )
				)
				( attribute "VALUE" "100.0"
					( Origin gFrontEnd )
				)
				( attribute "VER" "1"
					( Origin gFrontEnd )
				)
				( attribute "WATTAGE" "1/16W"
					( Origin gFrontEnd )
				)
				( attribute "XY" "(-750,1050)"
					( Origin gFrontEnd )
				)
				( attribute "CHIPS_PART_NAME" "RES"
					( Origin gPackager )
				)
				( attribute "CDS_PART_NAME" "RES_0402-100.0,1%,1/16W,CHIP,GA"
					( Origin gPackager )
				)
				( objectStatus "R3D28" )
			)
			( gate "@baseboard_fab2_lib.baseboard_fab2(sch_1):page214_i105"
				( attribute "BOM_COST" "PROC_VRD_VCCIO_CPU1"
					( Origin gFrontEnd )
				)
				( attribute "CDS_LIB" "mstr_discrete"
					( Origin gPackager )
				)
				( attribute "CDS_LOCATION" "R3E1"
					( Origin gPackager )
				)
				( attribute "CDS_SEC" "1"
					( Origin gPackager )
				)
				( attribute "LOCATION" "R3E1"
					( Origin gFrontEnd )
				)
				( attribute "MATERIAL" "CHIP"
					( Origin gFrontEnd )
				)
				( attribute "PACK_TYPE" "0402"
					( Origin gFrontEnd )
				)
				( attribute "PART_NUMBER" "G21796-017"
					( Origin gFrontEnd )
				)
				( attribute "PHYS_PAGE" "214"
					( Origin gFrontEnd )
				)
				( attribute "ROOM" "PVCCIO_CPU1"
					( Origin gFrontEnd )
				)
				( attribute "ROT" "0"
					( Origin gFrontEnd )
				)
				( attribute "SEC" "1"
					( Origin gFrontEnd )
				)
				( attribute "SEC_TYPE" "0402"
					( Origin gFrontEnd )
				)
				( attribute "TOLERANCE" "1%"
					( Origin gFrontEnd )
				)
				( attribute "VALUE" "100.0"
					( Origin gFrontEnd )
				)
				( attribute "VER" "1"
					( Origin gFrontEnd )
				)
				( attribute "WATTAGE" "1/16W"
					( Origin gFrontEnd )
				)
				( attribute "XY" "(-750,2250)"
					( Origin gFrontEnd )
				)
				( attribute "CHIPS_PART_NAME" "RES"
					( Origin gPackager )
				)
				( attribute "CDS_PART_NAME" "RES_0402-100.0,1%,1/16W,CHIP,GA"
					( Origin gPackager )
				)
				( objectStatus "R3E1" )
			)
			( gate "@baseboard_fab2_lib.baseboard_fab2(sch_1):page214_i108"
				( attribute "BOM_COST" "PROC_VRD_PVCCIO_CPU1"
					( Origin gFrontEnd )
				)
				( attribute "CDS_LIB" "dev_discrete"
					( Origin gPackager )
				)
				( attribute "CDS_LOCATION" "C3E1"
					( Origin gPackager )
				)
				( attribute "LOCATION" "C3E1"
					( Origin gFrontEnd )
				)
				( attribute "MATERIAL" "X6S"
					( Origin gFrontEnd )
				)
				( attribute "PACK_TYPE" "0603V"
					( Origin gFrontEnd )
				)
				( attribute "PART_NUMBER" "E15431-004"
					( Origin gFrontEnd )
				)
				( attribute "PHYS_PAGE" "214"
					( Origin gFrontEnd )
				)
				( attribute "REUSE_ID" "281"
					( Origin gFrontEnd )
				)
				( attribute "ROOM" "PVCCIO_CPU1"
					( Origin gFrontEnd )
				)
				( attribute "ROT" "0"
					( Origin gFrontEnd )
				)
				( attribute "SEC" "1"
					( Origin gFrontEnd )
				)
				( attribute "TOLERANCE" "20%"
					( Origin gFrontEnd )
				)
				( attribute "VALUE" "22.0UF"
					( Origin gFrontEnd )
				)
				( attribute "VER" "1"
					( Origin gFrontEnd )
				)
				( attribute "VOLTAGE" "4V"
					( Units "uVoltage" "V" 1.000000)
					( Origin gFrontEnd )
				)
				( attribute "XY" "(3650,3450)"
					( Origin gFrontEnd )
				)
				( attribute "CHIPS_PART_NAME" "CAP_A"
					( Origin gPackager )
				)
				( attribute "CDS_PART_NAME" "CAP_A_0603V-22.0UF,4V,20%,X6S,A"
					( Origin gPackager )
				)
				( attribute "SEC_TYPE" "0603V"
					( Origin gFrontEnd )
				)
				( attribute "CDS_SEC" "1"
					( Origin gPackager )
				)
				( attribute "GROUP" "PWR_MLCC_CAP"
					( Origin gFrontEnd )
				)
				( objectStatus "C3E1" )
			)
			( gate "@baseboard_fab2_lib.baseboard_fab2(sch_1):page214_i109"
				( attribute "CDS_LIB" "mstr_discrete"
					( Origin gPackager )
				)
				( attribute "CDS_LOCATION" "R7R1"
					( Origin gPackager )
				)
				( attribute "LOCATION" "R7R1"
					( Origin gFrontEnd )
				)
				( attribute "MATERIAL" "CHIP"
					( Origin gFrontEnd )
				)
				( attribute "PACK_TYPE" "0402"
					( Origin gFrontEnd )
				)
				( attribute "PART_NUMBER" "G21796-208"
					( Origin gFrontEnd )
				)
				( attribute "PHYS_PAGE" "214"
					( Origin gFrontEnd )
				)
				( attribute "ROT" "0"
					( Origin gFrontEnd )
				)
				( attribute "SEC" "1"
					( Origin gFrontEnd )
				)
				( attribute "TOLERANCE" "1.0%"
					( Origin gFrontEnd )
				)
				( attribute "VALUE" "51.1"
					( Origin gFrontEnd )
				)
				( attribute "VER" "2"
					( Origin gFrontEnd )
				)
				( attribute "WATTAGE" "1/16W"
					( Origin gFrontEnd )
				)
				( attribute "XY" "(3975,3425)"
					( Origin gFrontEnd )
				)
				( attribute "CHIPS_PART_NAME" "RES"
					( Origin gPackager )
				)
				( attribute "CDS_PART_NAME" "RES_0402-51.1,1.0%,1/16W,CHIP,A"
					( Origin gPackager )
				)
				( attribute "SEC_TYPE" "0402"
					( Origin gFrontEnd )
				)
				( attribute "CDS_SEC" "1"
					( Origin gPackager )
				)
				( objectStatus "R7R1" )
			)
			( gate "@baseboard_fab2_lib.baseboard_fab2(sch_1):page214_i126"
				( attribute "CDS_LIB" "mstr_discrete"
					( Origin gPackager )
				)
				( attribute "CDS_LOCATION" "EU4E2"
					( Origin gPackager )
				)
				( attribute "CDS_SEC" "1"
					( Origin gPackager )
				)
				( attribute "LOCATION" "EU4E2"
					( Origin gFrontEnd )
				)
				( attribute "MATERIAL" "IC"
					( Origin gFrontEnd )
				)
				( attribute "NO_XNET_CONNECTION" "1"
					( Origin gFrontEnd )
				)
				( attribute "PACK_TYPE" "SM"
					( Origin gFrontEnd )
				)
				( attribute "PART_NUMBER" "H73684-001"
					( Origin gFrontEnd )
				)
				( attribute "PHYS_PAGE" "214"
					( Origin gFrontEnd )
				)
				( attribute "ROT" "0"
					( Origin gFrontEnd )
				)
				( attribute "SEC" "1"
					( Origin gFrontEnd )
				)
				( attribute "SEC_TYPE" "SM"
					( Origin gFrontEnd )
				)
				( attribute "VALUE" "IR35412"
					( Origin gFrontEnd )
				)
				( attribute "VER" "1"
					( Origin gFrontEnd )
				)
				( attribute "XY" "(1075,3925)"
					( Origin gFrontEnd )
				)
				( attribute "CHIPS_PART_NAME" "IR354XX"
					( Origin gPackager )
				)
				( attribute "CDS_PART_NAME" "IR354XX_SM-IR35412,IC,H73684-0A"
					( Origin gPackager )
				)
				( objectStatus "EU4E2" )
			)
			( gate "@baseboard_fab2_lib.baseboard_fab2(sch_1):page214_i127"
				( attribute "CDS_LIB" "mstr_discrete"
					( Origin gPackager )
				)
				( attribute "CDS_LOCATION" "R4E21"
					( Origin gPackager )
				)
				( attribute "CDS_SEC" "1"
					( Origin gPackager )
				)
				( attribute "LOCATION" "R4E21"
					( Origin gFrontEnd )
				)
				( attribute "MATERIAL" "EMPTY"
					( Origin gFrontEnd )
				)
				( attribute "PACK_TYPE" "0402"
					( Origin gFrontEnd )
				)
				( attribute "PART_NUMBER" "G21796-187"
					( Origin gFrontEnd )
				)
				( attribute "PHYS_PAGE" "214"
					( Origin gFrontEnd )
				)
				( attribute "ROT" "0"
					( Origin gFrontEnd )
				)
				( attribute "SEC" "1"
					( Origin gPackager )
				)
				( attribute "TOLERANCE" "1%"
					( Origin gFrontEnd )
				)
				( attribute "VALUE" "68.1K"
					( Origin gFrontEnd )
				)
				( attribute "VER" "2"
					( Origin gFrontEnd )
				)
				( attribute "WATTAGE" "1/16W"
					( Origin gFrontEnd )
				)
				( attribute "XY" "(3400,4075)"
					( Origin gFrontEnd )
				)
				( attribute "CHIPS_PART_NAME" "RES"
					( Origin gPackager )
				)
				( attribute "CDS_PART_NAME" "RES_0402-68.1K,1%,1/16W,EMPTY,A"
					( Origin gPackager )
				)
				( objectStatus "R4E21" )
			)
			( gate "@baseboard_fab2_lib.baseboard_fab2(sch_1):page214_i129"
				( attribute "CDS_LIB" "mstr_misc"
					( Origin gPackager )
				)
				( attribute "CDS_LOCATION" "SH3D2"
					( Origin gPackager )
				)
				( attribute "CDS_SEC" "1"
					( Origin gPackager )
				)
				( attribute "LOCATION" "SH3D2"
					( Origin gFrontEnd )
				)
				( attribute "MATERIAL" "EMPTY"
					( Origin gFrontEnd )
				)
				( attribute "PACK_TYPE" "SH0201"
					( Origin gFrontEnd )
				)
				( attribute "PART_NUMBER" "N_A"
					( Origin gFrontEnd )
				)
				( attribute "PHYS_PAGE" "214"
					( Origin gFrontEnd )
				)
				( attribute "PIN_SHORT" "A:B"
					( Origin gFrontEnd )
				)
				( attribute "ROT" "0"
					( Origin gFrontEnd )
				)
				( attribute "SEC" "1"
					( Origin gFrontEnd )
				)
				( attribute "SEC_TYPE" "SH0201"
					( Origin gFrontEnd )
				)
				( attribute "VER" "1"
					( Origin gFrontEnd )
				)
				( attribute "XY" "(-1250,1750)"
					( Origin gFrontEnd )
				)
				( attribute "CHIPS_PART_NAME" "SHUNT"
					( Origin gPackager )
				)
				( attribute "CDS_PART_NAME" "SHUNT_SH0201-EMPTY,N_A"
					( Origin gPackager )
				)
				( objectStatus "SH3D2" )
			)
			( gate "@baseboard_fab2_lib.baseboard_fab2(sch_1):page214_i130"
				( attribute "CDS_LIB" "mstr_misc"
					( Origin gPackager )
				)
				( attribute "CDS_LOCATION" "SH3D1"
					( Origin gPackager )
				)
				( attribute "CDS_SEC" "1"
					( Origin gPackager )
				)
				( attribute "LOCATION" "SH3D1"
					( Origin gFrontEnd )
				)
				( attribute "MATERIAL" "EMPTY"
					( Origin gFrontEnd )
				)
				( attribute "PACK_TYPE" "SH0201"
					( Origin gFrontEnd )
				)
				( attribute "PART_NUMBER" "N_A"
					( Origin gFrontEnd )
				)
				( attribute "PHYS_PAGE" "214"
					( Origin gFrontEnd )
				)
				( attribute "PIN_SHORT" "A:B"
					( Origin gFrontEnd )
				)
				( attribute "ROT" "0"
					( Origin gFrontEnd )
				)
				( attribute "SEC" "1"
					( Origin gFrontEnd )
				)
				( attribute "SEC_TYPE" "SH0201"
					( Origin gFrontEnd )
				)
				( attribute "VER" "1"
					( Origin gFrontEnd )
				)
				( attribute "XY" "(-1250,1300)"
					( Origin gFrontEnd )
				)
				( attribute "CHIPS_PART_NAME" "SHUNT"
					( Origin gPackager )
				)
				( attribute "CDS_PART_NAME" "SHUNT_SH0201-EMPTY,N_A"
					( Origin gPackager )
				)
				( objectStatus "SH3D1" )
			)
			( gate "@baseboard_fab2_lib.baseboard_fab2(sch_1):page197_i35"
				( attribute "CDS_LIB" "w_hdl"
					( Origin gPackager )
				)
				( attribute "CDS_LMAN_SYM_OUTLINE" "-125,250,125,-250"
					( Origin gPackager )
				)
				( attribute "CDS_LOCATION" "Q12W4"
					( Origin gPackager )
				)
				( attribute "CDS_SEC" "1"
					( Origin gPackager )
				)
				( attribute "LOCATION" "Q12W4"
					( Origin gFrontEnd )
				)
				( attribute "PACK_TYPE" "DISCRET-GB1"
					( Origin gFrontEnd )
				)
				( attribute "PART_NUMBER" "075.00308.007C"
					( Origin gFrontEnd )
				)
				( attribute "PHYS_PAGE" "197"
					( Origin gFrontEnd )
				)
				( attribute "ROT" "0"
					( Origin gFrontEnd )
				)
				( attribute "SEC" "1"
					( Origin gFrontEnd )
				)
				( attribute "SEC_TYPE" "DISCRET-GB1"
					( Origin gFrontEnd )
				)
				( attribute "VALUE" "BSL308C-H6327-GP"
					( Origin gFrontEnd )
				)
				( attribute "VER" "1"
					( Origin gFrontEnd )
				)
				( attribute "XY" "(-700,2000)"
					( Origin gFrontEnd )
				)
				( attribute "CHIPS_PART_NAME" "BSL308C-H6327-GP"
					( Origin gPackager )
				)
				( attribute "CDS_PART_NAME" "BSL308C-H6327-GP_DISCRET-GB1-BA"
					( Origin gPackager )
				)
				( objectStatus "Q12W4" )
			)
			( gate "@baseboard_fab2_lib.baseboard_fab2(sch_1):page197_i29"
				( attribute "BOM_COST" "PVDDQ_ABC_VR"
					( Origin gFrontEnd )
				)
				( attribute "CDS_LIB" "mstr_discrete"
					( Origin gPackager )
				)
				( attribute "CDS_LOCATION" "R9M4"
					( Origin gPackager )
				)
				( attribute "CDS_SEC" "1"
					( Origin gPackager )
				)
				( attribute "LOCATION" "R9M4"
					( Origin gFrontEnd )
				)
				( attribute "MATERIAL" "CHIP"
					( Origin gFrontEnd )
				)
				( attribute "PACK_TYPE" "1206"
					( Origin gFrontEnd )
				)
				( attribute "PART_NUMBER" "G52199-004"
					( Origin gFrontEnd )
				)
				( attribute "PHYS_PAGE" "197"
					( Origin gFrontEnd )
				)
				( attribute "ROOM" "PVDDQ_ABC_PWR_VR"
					( Origin gFrontEnd )
				)
				( attribute "ROT" "0"
					( Origin gFrontEnd )
				)
				( attribute "SEC" "1"
					( Origin gFrontEnd )
				)
				( attribute "SEC_TYPE" "1206"
					( Origin gFrontEnd )
				)
				( attribute "TOLERANCE" "1%"
					( Origin gFrontEnd )
				)
				( attribute "VALUE" "0.002"
					( Origin gFrontEnd )
				)
				( attribute "VER" "1"
					( Origin gFrontEnd )
				)
				( attribute "WATTAGE" "1W"
					( Origin gFrontEnd )
				)
				( attribute "XY" "(-1725,2700)"
					( Origin gFrontEnd )
				)
				( attribute "CHIPS_PART_NAME" "RES"
					( Origin gPackager )
				)
				( attribute "CDS_PART_NAME" "RES_1206-0.002,1%,1W,CHIP,G521A"
					( Origin gPackager )
				)
				( attribute "CONFIG" "064.R0045.0711"
					( Origin gFrontEnd )
				)
				( attribute "NEW_VALUE" "0.004 OHM"
					( Origin gFrontEnd )
				)
				( objectStatus "R9M4" )
			)
			( gate "@baseboard_fab2_lib.baseboard_fab2(sch_1):page101_i146"
				( attribute "BOM_COST" "SYS_CLOCK"
					( Origin gFrontEnd )
				)
				( attribute "CDS_LIB" "mstr_discrete"
					( Origin gPackager )
				)
				( attribute "CDS_LOCATION" "C8F19"
					( Origin gPackager )
				)
				( attribute "CDS_SEC" "1"
					( Origin gPackager )
				)
				( attribute "LOCATION" "C8F19"
					( Origin gFrontEnd )
				)
				( attribute "MATERIAL" "COG"
					( Origin gFrontEnd )
				)
				( attribute "PACK_TYPE" "0402LF"
					( Origin gFrontEnd )
				)
				( attribute "PART_NUMBER" "A36095-047"
					( Origin gFrontEnd )
				)
				( attribute "PHYS_PAGE" "101"
					( Origin gFrontEnd )
				)
				( attribute "ROOM" "SB"
					( Origin gFrontEnd )
				)
				( attribute "ROT" "0"
					( Origin gFrontEnd )
				)
				( attribute "SEC" "1"
					( Origin gFrontEnd )
				)
				( attribute "SEC_TYPE" "0402LF"
					( Origin gFrontEnd )
				)
				( attribute "TOLERANCE" "5%"
					( Origin gFrontEnd )
				)
				( attribute "VALUE" "15.0PF"
					( Origin gFrontEnd )
				)
				( attribute "VER" "1"
					( Origin gFrontEnd )
				)
				( attribute "VOLTAGE" "50V"
					( Units "uVoltage" "V" 1.000000)
					( Origin gFrontEnd )
				)
				( attribute "XY" "(-7600,800)"
					( Origin gFrontEnd )
				)
				( attribute "CHIPS_PART_NAME" "CAP"
					( Origin gPackager )
				)
				( attribute "CDS_PART_NAME" "CAP_0402LF-15.0PF,50V,5%,COG,AA"
					( Origin gPackager )
				)
				( objectStatus "C8F19" )
			)
			( gate "@baseboard_fab2_lib.baseboard_fab2(sch_1):page226_i69"
				( attribute "CDS_LIB" "mstr_controller"
					( Origin gPackager )
				)
				( attribute "CDS_LMAN_SYM_OUTLINE" "-400,900,400,-900"
					( Origin gPackager )
				)
				( attribute "CDS_LOCATION" "EU1B1"
					( Origin gPackager )
				)
				( attribute "CDS_SEC" "1"
					( Origin gPackager )
				)
				( attribute "LOCATION" "EU1B1"
					( Origin gFrontEnd )
				)
				( attribute "MATERIAL" "IC"
					( Origin gFrontEnd )
				)
				( attribute "PACK_TYPE" "QFN"
					( Origin gFrontEnd )
				)
				( attribute "PART_NUMBER" "H89186-001"
					( Origin gFrontEnd )
				)
				( attribute "PHYS_PAGE" "226"
					( Origin gFrontEnd )
				)
				( attribute "ROT" "0"
					( Origin gFrontEnd )
				)
				( attribute "SEC" "1"
					( Origin gFrontEnd )
				)
				( attribute "SEC_TYPE" "QFN"
					( Origin gFrontEnd )
				)
				( attribute "VER" "2"
					( Origin gFrontEnd )
				)
				( attribute "XY" "(1175,1075)"
					( Origin gFrontEnd )
				)
				( attribute "CHIPS_PART_NAME" "PXM1310B"
					( Origin gPackager )
				)
				( attribute "CDS_PART_NAME" "PXM1310B_QFN-IC,H89186-001"
					( Origin gPackager )
				)
				( objectStatus "EU1B1" )
			)
			( gate "@baseboard_fab2_lib.baseboard_fab2(sch_1):page226_i57"
				( attribute "CDS_LIB" "mstr_discrete"
					( Origin gPackager )
				)
				( attribute "CDS_LOCATION" "R9M7"
					( Origin gPackager )
				)
				( attribute "CDS_SEC" "1"
					( Origin gPackager )
				)
				( attribute "LOCATION" "R9M7"
					( Origin gFrontEnd )
				)
				( attribute "MATERIAL" "EMPTY"
					( Origin gFrontEnd )
				)
				( attribute "PACK_TYPE" "0402"
					( Origin gFrontEnd )
				)
				( attribute "PART_NUMBER" "G21796-017"
					( Origin gFrontEnd )
				)
				( attribute "PHYS_PAGE" "226"
					( Origin gFrontEnd )
				)
				( attribute "ROOM" "VDDQ_KLM_PWR_VR"
					( Origin gFrontEnd )
				)
				( attribute "ROT" "0"
					( Origin gFrontEnd )
				)
				( attribute "SEC" "1"
					( Origin gFrontEnd )
				)
				( attribute "SEC_TYPE" "0402"
					( Origin gFrontEnd )
				)
				( attribute "TOLERANCE" "1%"
					( Origin gFrontEnd )
				)
				( attribute "VALUE" "100.0"
					( Origin gFrontEnd )
				)
				( attribute "VER" "2"
					( Origin gFrontEnd )
				)
				( attribute "WATTAGE" "1/16W"
					( Origin gFrontEnd )
				)
				( attribute "XY" "(3750,2075)"
					( Origin gFrontEnd )
				)
				( attribute "CHIPS_PART_NAME" "RES"
					( Origin gPackager )
				)
				( attribute "CDS_PART_NAME" "RES_0402-100.0,1%,1/16W,EMPTY,A"
					( Origin gPackager )
				)
				( objectStatus "R9M7" )
			)
			( gate "@baseboard_fab2_lib.baseboard_fab2(sch_1):page223_i69"
				( attribute "CDS_LIB" "mstr_controller"
					( Origin gPackager )
				)
				( attribute "CDS_LMAN_SYM_OUTLINE" "-400,900,400,-900"
					( Origin gPackager )
				)
				( attribute "CDS_LOCATION" "EU1G2"
					( Origin gPackager )
				)
				( attribute "CDS_SEC" "1"
					( Origin gPackager )
				)
				( attribute "LOCATION" "EU1G2"
					( Origin gFrontEnd )
				)
				( attribute "MATERIAL" "IC"
					( Origin gFrontEnd )
				)
				( attribute "PACK_TYPE" "QFN"
					( Origin gFrontEnd )
				)
				( attribute "PART_NUMBER" "H89186-001"
					( Origin gFrontEnd )
				)
				( attribute "PHYS_PAGE" "223"
					( Origin gFrontEnd )
				)
				( attribute "ROT" "0"
					( Origin gFrontEnd )
				)
				( attribute "SEC" "1"
					( Origin gFrontEnd )
				)
				( attribute "SEC_TYPE" "QFN"
					( Origin gFrontEnd )
				)
				( attribute "VER" "2"
					( Origin gFrontEnd )
				)
				( attribute "XY" "(1500,1450)"
					( Origin gFrontEnd )
				)
				( attribute "CHIPS_PART_NAME" "PXM1310B"
					( Origin gPackager )
				)
				( attribute "CDS_PART_NAME" "PXM1310B_QFN-IC,H89186-001"
					( Origin gPackager )
				)
				( objectStatus "EU1G2" )
			)
			( gate "@baseboard_fab2_lib.baseboard_fab2(sch_1):page223_i57"
				( attribute "CDS_LIB" "mstr_discrete"
					( Origin gPackager )
				)
				( attribute "CDS_LOCATION" "R9U3"
					( Origin gPackager )
				)
				( attribute "CDS_SEC" "1"
					( Origin gPackager )
				)
				( attribute "LOCATION" "R9U3"
					( Origin gFrontEnd )
				)
				( attribute "MATERIAL" "CHIP"
					( Origin gFrontEnd )
				)
				( attribute "PACK_TYPE" "0402"
					( Origin gFrontEnd )
				)
				( attribute "PART_NUMBER" "G21796-017"
					( Origin gFrontEnd )
				)
				( attribute "PHYS_PAGE" "223"
					( Origin gFrontEnd )
				)
				( attribute "ROOM" "VDDQ_GHJ_PWR_VR"
					( Origin gFrontEnd )
				)
				( attribute "ROT" "0"
					( Origin gFrontEnd )
				)
				( attribute "SEC" "1"
					( Origin gFrontEnd )
				)
				( attribute "SEC_TYPE" "0402"
					( Origin gFrontEnd )
				)
				( attribute "TOLERANCE" "1%"
					( Origin gFrontEnd )
				)
				( attribute "VALUE" "100.0"
					( Origin gFrontEnd )
				)
				( attribute "VER" "2"
					( Origin gFrontEnd )
				)
				( attribute "WATTAGE" "1/16W"
					( Origin gFrontEnd )
				)
				( attribute "XY" "(4100,2425)"
					( Origin gFrontEnd )
				)
				( attribute "CHIPS_PART_NAME" "RES"
					( Origin gPackager )
				)
				( attribute "CDS_PART_NAME" "RES_0402-100.0,1%,1/16W,CHIP,GA"
					( Origin gPackager )
				)
				( objectStatus "R9U3" )
			)
			( gate "@baseboard_fab2_lib.baseboard_fab2(sch_1):page226_i75"
				( attribute "BOM_COST" "SM_CONTROLLER"
					( Origin gFrontEnd )
				)
				( attribute "CDS_LIB" "mstr_discrete"
					( Origin gPackager )
				)
				( attribute "LOCATION" "R1B13"
					( Origin gFrontEnd )
				)
				( attribute "MATERIAL" "CHIP"
					( Origin gFrontEnd )
				)
				( attribute "PACK_TYPE" "0402"
					( Origin gFrontEnd )
				)
				( attribute "PART_NUMBER" "G21796-311"
					( Origin gFrontEnd )
				)
				( attribute "PHYS_PAGE" "226"
					( Origin gFrontEnd )
				)
				( attribute "ROOM" "SMBUS"
					( Origin gFrontEnd )
				)
				( attribute "ROT" "0"
					( Origin gFrontEnd )
				)
				( attribute "SKU" "B"
					( Origin gFrontEnd )
				)
				( attribute "TOLERANCE" "1.0%"
					( Origin gFrontEnd )
				)
				( attribute "VALUE" "2.26K"
					( Origin gFrontEnd )
				)
				( attribute "VER" "2"
					( Origin gFrontEnd )
				)
				( attribute "WATTAGE" "1/16W"
					( Origin gFrontEnd )
				)
				( attribute "XY" "(3250,2350)"
					( Origin gFrontEnd )
				)
				( attribute "CHIPS_PART_NAME" "RES"
					( Origin gPackager )
				)
				( attribute "CDS_PART_NAME" "RES_0402-2.26K,1.0%,1/16W,CHIPA"
					( Origin gPackager )
				)
				( attribute "CDS_LOCATION" "R1B13"
					( Origin gPackager )
				)
				( attribute "CDS_SEC" "1"
					( Origin gPackager )
				)
				( attribute "SEC" "1"
					( Origin gPackager )
				)
				( objectStatus "R1B13" )
			)
			( gate "@baseboard_fab2_lib.baseboard_fab2(sch_1):page223_i55"
				( attribute "CDS_LIB" "mstr_discrete"
					( Origin gPackager )
				)
				( attribute "CDS_LOCATION" "R1G8"
					( Origin gPackager )
				)
				( attribute "CDS_SEC" "1"
					( Origin gPackager )
				)
				( attribute "LOCATION" "R1G8"
					( Origin gFrontEnd )
				)
				( attribute "MATERIAL" "CHIP"
					( Origin gFrontEnd )
				)
				( attribute "PACK_TYPE" "0402"
					( Origin gFrontEnd )
				)
				( attribute "PART_NUMBER" "G21796-074"
					( Origin gFrontEnd )
				)
				( attribute "PHYS_PAGE" "223"
					( Origin gFrontEnd )
				)
				( attribute "ROT" "0"
					( Origin gFrontEnd )
				)
				( attribute "SEC" "1"
					( Origin gFrontEnd )
				)
				( attribute "SEC_TYPE" "0402"
					( Origin gFrontEnd )
				)
				( attribute "TOLERANCE" "1%"
					( Origin gFrontEnd )
				)
				( attribute "VALUE" "33.2"
					( Origin gFrontEnd )
				)
				( attribute "VER" "1"
					( Origin gFrontEnd )
				)
				( attribute "WATTAGE" "1/16W"
					( Origin gFrontEnd )
				)
				( attribute "XY" "(3175,2100)"
					( Origin gFrontEnd )
				)
				( attribute "CHIPS_PART_NAME" "RES"
					( Origin gPackager )
				)
				( attribute "CDS_PART_NAME" "RES_0402-33.2,1%,1/16W,CHIP,G2A"
					( Origin gPackager )
				)
				( objectStatus "R1G8" )
			)
			( gate "@baseboard_fab2_lib.baseboard_fab2(sch_1):page218_i69"
				( attribute "CDS_LIB" "mstr_controller"
					( Origin gPackager )
				)
				( attribute "CDS_LMAN_SYM_OUTLINE" "-400,900,400,-900"
					( Origin gPackager )
				)
				( attribute "CDS_LOCATION" "EU7A5"
					( Origin gPackager )
				)
				( attribute "CDS_SEC" "1"
					( Origin gPackager )
				)
				( attribute "LOCATION" "EU7A5"
					( Origin gFrontEnd )
				)
				( attribute "MATERIAL" "IC"
					( Origin gFrontEnd )
				)
				( attribute "PACK_TYPE" "QFN"
					( Origin gFrontEnd )
				)
				( attribute "PART_NUMBER" "H89186-001"
					( Origin gFrontEnd )
				)
				( attribute "PHYS_PAGE" "218"
					( Origin gFrontEnd )
				)
				( attribute "ROT" "0"
					( Origin gFrontEnd )
				)
				( attribute "SEC" "1"
					( Origin gFrontEnd )
				)
				( attribute "SEC_TYPE" "QFN"
					( Origin gFrontEnd )
				)
				( attribute "VER" "2"
					( Origin gFrontEnd )
				)
				( attribute "XY" "(150,1500)"
					( Origin gFrontEnd )
				)
				( attribute "CHIPS_PART_NAME" "PXM1310B"
					( Origin gPackager )
				)
				( attribute "CDS_PART_NAME" "PXM1310B_QFN-IC,H89186-001"
					( Origin gPackager )
				)
				( objectStatus "EU7A5" )
			)
			( gate "@baseboard_fab2_lib.baseboard_fab2(sch_1):page218_i67"
				( attribute "CDS_LIB" "mstr_discrete"
					( Origin gPackager )
				)
				( attribute "CDS_LOCATION" "R3L11"
					( Origin gPackager )
				)
				( attribute "CDS_SEC" "1"
					( Origin gPackager )
				)
				( attribute "LOCATION" "R3L11"
					( Origin gFrontEnd )
				)
				( attribute "MATERIAL" "EMPTY"
					( Origin gFrontEnd )
				)
				( attribute "PACK_TYPE" "0402"
					( Origin gFrontEnd )
				)
				( attribute "PART_NUMBER" "G21796-017"
					( Origin gFrontEnd )
				)
				( attribute "PHYS_PAGE" "218"
					( Origin gFrontEnd )
				)
				( attribute "ROOM" "VDDQ_DEF_PWR_VR"
					( Origin gFrontEnd )
				)
				( attribute "ROT" "0"
					( Origin gFrontEnd )
				)
				( attribute "SEC" "1"
					( Origin gFrontEnd )
				)
				( attribute "SEC_TYPE" "0402"
					( Origin gFrontEnd )
				)
				( attribute "TOLERANCE" "1%"
					( Origin gFrontEnd )
				)
				( attribute "VALUE" "100.0"
					( Origin gFrontEnd )
				)
				( attribute "VER" "2"
					( Origin gFrontEnd )
				)
				( attribute "WATTAGE" "1/16W"
					( Origin gFrontEnd )
				)
				( attribute "XY" "(2700,2625)"
					( Origin gFrontEnd )
				)
				( attribute "CHIPS_PART_NAME" "RES"
					( Origin gPackager )
				)
				( attribute "CDS_PART_NAME" "RES_0402-100.0,1%,1/16W,EMPTY,A"
					( Origin gPackager )
				)
				( objectStatus "R3L11" )
			)
			( gate "@baseboard_fab2_lib.baseboard_fab2(sch_1):page223_i76"
				( attribute "BOM_COST" "SM_CONTROLLER"
					( Origin gFrontEnd )
				)
				( attribute "CDS_LIB" "mstr_discrete"
					( Origin gPackager )
				)
				( attribute "LOCATION" "R1G6"
					( Origin gFrontEnd )
				)
				( attribute "MATERIAL" "CHIP"
					( Origin gFrontEnd )
				)
				( attribute "PACK_TYPE" "0402"
					( Origin gFrontEnd )
				)
				( attribute "PART_NUMBER" "G21796-311"
					( Origin gFrontEnd )
				)
				( attribute "PHYS_PAGE" "223"
					( Origin gFrontEnd )
				)
				( attribute "ROOM" "SMBUS"
					( Origin gFrontEnd )
				)
				( attribute "ROT" "0"
					( Origin gFrontEnd )
				)
				( attribute "SEC" "1"
					( Origin gFrontEnd )
				)
				( attribute "SEC_TYPE" "0402"
					( Origin gFrontEnd )
				)
				( attribute "SKU" "B"
					( Origin gFrontEnd )
				)
				( attribute "TOLERANCE" "1.0%"
					( Origin gFrontEnd )
				)
				( attribute "VALUE" "2.26K"
					( Origin gFrontEnd )
				)
				( attribute "VER" "2"
					( Origin gFrontEnd )
				)
				( attribute "WATTAGE" "1/16W"
					( Origin gFrontEnd )
				)
				( attribute "XY" "(3550,2750)"
					( Origin gFrontEnd )
				)
				( attribute "CHIPS_PART_NAME" "RES"
					( Origin gPackager )
				)
				( attribute "CDS_PART_NAME" "RES_0402-2.26K,1.0%,1/16W,CHIPA"
					( Origin gPackager )
				)
				( attribute "CDS_LOCATION" "R1G6"
					( Origin gPackager )
				)
				( attribute "CDS_SEC" "1"
					( Origin gPackager )
				)
				( objectStatus "R1G6" )
			)
			( gate "@baseboard_fab2_lib.baseboard_fab2(sch_1):page218_i58"
				( attribute "CDS_LIB" "mstr_discrete"
					( Origin gPackager )
				)
				( attribute "CDS_LOCATION" "R7B5"
					( Origin gPackager )
				)
				( attribute "CDS_SEC" "1"
					( Origin gPackager )
				)
				( attribute "LOCATION" "R7B5"
					( Origin gFrontEnd )
				)
				( attribute "MATERIAL" "CHIP"
					( Origin gFrontEnd )
				)
				( attribute "PACK_TYPE" "0402"
					( Origin gFrontEnd )
				)
				( attribute "PART_NUMBER" "G21796-026"
					( Origin gFrontEnd )
				)
				( attribute "PHYS_PAGE" "218"
					( Origin gFrontEnd )
				)
				( attribute "ROOM" "VDDQ_DEF_PWR_VR"
					( Origin gFrontEnd )
				)
				( attribute "ROT" "0"
					( Origin gFrontEnd )
				)
				( attribute "SEC" "1"
					( Origin gFrontEnd )
				)
				( attribute "SEC_TYPE" "0402"
					( Origin gFrontEnd )
				)
				( attribute "TOLERANCE" "1%"
					( Origin gFrontEnd )
				)
				( attribute "VALUE" "1.00K"
					( Origin gFrontEnd )
				)
				( attribute "VER" "2"
					( Origin gFrontEnd )
				)
				( attribute "WATTAGE" "1/16W"
					( Origin gFrontEnd )
				)
				( attribute "XY" "(1175,2800)"
					( Origin gFrontEnd )
				)
				( attribute "CHIPS_PART_NAME" "RES"
					( Origin gPackager )
				)
				( attribute "CDS_PART_NAME" "RES_0402-1.00K,1%,1/16W,CHIP,GA"
					( Origin gPackager )
				)
				( objectStatus "R7B5" )
			)
			( gate "@baseboard_fab2_lib.baseboard_fab2(sch_1):page221_i33"
				( attribute "CDS_LIB" "mstr_discrete"
					( Origin gPackager )
				)
				( attribute "CDS_LOCATION" "R4G19"
					( Origin gPackager )
				)
				( attribute "CDS_SEC" "1"
					( Origin gPackager )
				)
				( attribute "LOCATION" "R4G19"
					( Origin gFrontEnd )
				)
				( attribute "MATERIAL" "CHIP"
					( Origin gFrontEnd )
				)
				( attribute "PACK_TYPE" "0402"
					( Origin gFrontEnd )
				)
				( attribute "PART_NUMBER" "G21796-074"
					( Origin gFrontEnd )
				)
				( attribute "PHYS_PAGE" "221"
					( Origin gFrontEnd )
				)
				( attribute "ROT" "0"
					( Origin gFrontEnd )
				)
				( attribute "SEC" "1"
					( Origin gFrontEnd )
				)
				( attribute "SEC_TYPE" "0402"
					( Origin gFrontEnd )
				)
				( attribute "TOLERANCE" "1%"
					( Origin gFrontEnd )
				)
				( attribute "VALUE" "33.2"
					( Origin gFrontEnd )
				)
				( attribute "VER" "1"
					( Origin gFrontEnd )
				)
				( attribute "WATTAGE" "1/16W"
					( Origin gFrontEnd )
				)
				( attribute "XY" "(4350,1725)"
					( Origin gFrontEnd )
				)
				( attribute "CHIPS_PART_NAME" "RES"
					( Origin gPackager )
				)
				( attribute "CDS_PART_NAME" "RES_0402-33.2,1%,1/16W,CHIP,G2A"
					( Origin gPackager )
				)
				( objectStatus "R4G19" )
			)
			( gate "@baseboard_fab2_lib.baseboard_fab2(sch_1):page221_i30"
				( attribute "BOM_COST" "MEM_VRD_VTT_ABC"
					( Origin gFrontEnd )
				)
				( attribute "CDS_LIB" "mstr_discrete"
					( Origin gPackager )
				)
				( attribute "CDS_LOCATION" "C4G14"
					( Origin gPackager )
				)
				( attribute "CDS_SEC" "1"
					( Origin gPackager )
				)
				( attribute "LOCATION" "C4G14"
					( Origin gFrontEnd )
				)
				( attribute "MATERIAL" "X7R"
					( Origin gFrontEnd )
				)
				( attribute "PACK_TYPE" "0402LF"
					( Origin gFrontEnd )
				)
				( attribute "PART_NUMBER" "A36096-046"
					( Origin gFrontEnd )
				)
				( attribute "PHYS_PAGE" "221"
					( Origin gFrontEnd )
				)
				( attribute "ROOM" "VTT_ABC_PWR_VR"
					( Origin gFrontEnd )
				)
				( attribute "ROT" "0"
					( Origin gFrontEnd )
				)
				( attribute "SEC" "1"
					( Origin gFrontEnd )
				)
				( attribute "SEC_TYPE" "0402LF"
					( Origin gFrontEnd )
				)
				( attribute "TOLERANCE" "10%"
					( Origin gFrontEnd )
				)
				( attribute "VALUE" "1000PF"
					( Origin gFrontEnd )
				)
				( attribute "VER" "1"
					( Origin gFrontEnd )
				)
				( attribute "VOLTAGE" "50V"
					( Units "uVoltage" "V" 1.000000)
					( Origin gFrontEnd )
				)
				( attribute "XY" "(3850,1525)"
					( Origin gFrontEnd )
				)
				( attribute "CHIPS_PART_NAME" "CAP"
					( Origin gPackager )
				)
				( attribute "CDS_PART_NAME" "CAP_0402LF-1000PF,50V,10%,X7R,A"
					( Origin gPackager )
				)
				( objectStatus "C4G14" )
			)
			( gate "@baseboard_fab2_lib.baseboard_fab2(sch_1):page222_i46"
				( attribute "BOM_COST" "MEM_VRD_PVDDQ_CD"
					( Origin gFrontEnd )
				)
				( attribute "CDS_LIB" "mstr_discrete"
					( Origin gPackager )
				)
				( attribute "CDS_LOCATION" "C4W5"
					( Origin gPackager )
				)
				( attribute "CDS_SEC" "1"
					( Origin gPackager )
				)
				( attribute "LOCATION" "C4W5"
					( Origin gFrontEnd )
				)
				( attribute "MATERIAL" "X5R"
					( Origin gFrontEnd )
				)
				( attribute "NEW_MATERIAL" "X6S"
					( Origin gFrontEnd )
				)
				( attribute "PACK_TYPE" "0805"
					( Origin gFrontEnd )
				)
				( attribute "PART_NUMBER" "602433-112"
					( Origin gFrontEnd )
				)
				( attribute "PHYS_PAGE" "222"
					( Origin gFrontEnd )
				)
				( attribute "ROOM" "VDDQ_ABC_PWR_VR"
					( Origin gFrontEnd )
				)
				( attribute "ROT" "0"
					( Origin gFrontEnd )
				)
				( attribute "SEC" "1"
					( Origin gFrontEnd )
				)
				( attribute "SEC_TYPE" "0805"
					( Origin gFrontEnd )
				)
				( attribute "TOLERANCE" "20%"
					( Origin gFrontEnd )
				)
				( attribute "VALUE" "100UF"
					( Origin gFrontEnd )
				)
				( attribute "VER" "1"
					( Origin gFrontEnd )
				)
				( attribute "VOLTAGE" "4V"
					( Units "uVoltage" "V" 1.000000)
					( Origin gFrontEnd )
				)
				( attribute "XY" "(4100,575)"
					( Origin gFrontEnd )
				)
				( attribute "CHIPS_PART_NAME" "CAP"
					( Origin gPackager )
				)
				( attribute "CDS_PART_NAME" "CAP_0805-100UF,4V,20%,X5R,6024A"
					( Origin gPackager )
				)
				( attribute "GROUP" "PWR_MLCC_CAP"
					( Origin gFrontEnd )
				)
				( attribute "NEW_PN" "078.1071T.M002"
					( Origin gFrontEnd )
				)
				( objectStatus "C4W5" )
			)
			( gate "@baseboard_fab2_lib.baseboard_fab2(sch_1):page221_i25"
				( attribute "BOM_COST" "MEM_VRD_VTT_ABC"
					( Origin gFrontEnd )
				)
				( attribute "CDS_LIB" "mstr_discrete"
					( Origin gPackager )
				)
				( attribute "CDS_LOCATION" "R4G18"
					( Origin gPackager )
				)
				( attribute "CDS_SEC" "1"
					( Origin gPackager )
				)
				( attribute "LOCATION" "R4G18"
					( Origin gFrontEnd )
				)
				( attribute "MATERIAL" "CHIP"
					( Origin gFrontEnd )
				)
				( attribute "PACK_TYPE" "0402"
					( Origin gFrontEnd )
				)
				( attribute "PART_NUMBER" "G21796-016"
					( Origin gFrontEnd )
				)
				( attribute "PHYS_PAGE" "221"
					( Origin gFrontEnd )
				)
				( attribute "ROOM" "VTT_ABC_PWR_VR"
					( Origin gFrontEnd )
				)
				( attribute "ROT" "0"
					( Origin gFrontEnd )
				)
				( attribute "SEC" "1"
					( Origin gFrontEnd )
				)
				( attribute "SEC_TYPE" "0402"
					( Origin gFrontEnd )
				)
				( attribute "TOLERANCE" "1%"
					( Origin gFrontEnd )
				)
				( attribute "VALUE" "10.0K"
					( Origin gFrontEnd )
				)
				( attribute "VER" "2"
					( Origin gFrontEnd )
				)
				( attribute "WATTAGE" "1/16W"
					( Origin gFrontEnd )
				)
				( attribute "XY" "(3225,2000)"
					( Origin gFrontEnd )
				)
				( attribute "CHIPS_PART_NAME" "RES"
					( Origin gPackager )
				)
				( attribute "CDS_PART_NAME" "RES_0402-10.0K,1%,1/16W,CHIP,GA"
					( Origin gPackager )
				)
				( objectStatus "R4G18" )
			)
			( gate "@baseboard_fab2_lib.baseboard_fab2(sch_1):page221_i19"
				( attribute "BOM_COST" "MEM_VRD_VTT_ABC"
					( Origin gFrontEnd )
				)
				( attribute "CDS_LIB" "mstr_discrete"
					( Origin gPackager )
				)
				( attribute "CDS_LOCATION" "C6U16"
					( Origin gPackager )
				)
				( attribute "CDS_SEC" "1"
					( Origin gPackager )
				)
				( attribute "LOCATION" "C6U16"
					( Origin gFrontEnd )
				)
				( attribute "MATERIAL" "X6S"
					( Origin gFrontEnd )
				)
				( attribute "PACK_TYPE" "0603LF"
					( Origin gFrontEnd )
				)
				( attribute "PART_NUMBER" "E15431-001"
					( Origin gFrontEnd )
				)
				( attribute "PHYS_PAGE" "221"
					( Origin gFrontEnd )
				)
				( attribute "ROOM" "VTT_ABC_PWR_VR"
					( Origin gFrontEnd )
				)
				( attribute "ROT" "0"
					( Origin gFrontEnd )
				)
				( attribute "SEC" "1"
					( Origin gFrontEnd )
				)
				( attribute "SEC_TYPE" "0603LF"
					( Origin gFrontEnd )
				)
				( attribute "TOLERANCE" "20%"
					( Origin gFrontEnd )
				)
				( attribute "VALUE" "10UF"
					( Origin gFrontEnd )
				)
				( attribute "VER" "1"
					( Origin gFrontEnd )
				)
				( attribute "VOLTAGE" "4V"
					( Units "uVoltage" "V" 1.000000)
					( Origin gFrontEnd )
				)
				( attribute "XY" "(200,2275)"
					( Origin gFrontEnd )
				)
				( attribute "CHIPS_PART_NAME" "CAP"
					( Origin gPackager )
				)
				( attribute "CDS_PART_NAME" "CAP_0603LF-10UF,4V,20%,X6S,E15A"
					( Origin gPackager )
				)
				( objectStatus "C6U16" )
			)
			( gate "@baseboard_fab2_lib.baseboard_fab2(sch_1):page221_i18"
				( attribute "BOM_COST" "MEM_VRD_VTT_ABC"
					( Origin gFrontEnd )
				)
				( attribute "CDS_LIB" "mstr_discrete"
					( Origin gPackager )
				)
				( attribute "CDS_LOCATION" "C6U15"
					( Origin gPackager )
				)
				( attribute "CDS_SEC" "1"
					( Origin gPackager )
				)
				( attribute "LOCATION" "C6U15"
					( Origin gFrontEnd )
				)
				( attribute "MATERIAL" "X6S"
					( Origin gFrontEnd )
				)
				( attribute "PACK_TYPE" "0603LF"
					( Origin gFrontEnd )
				)
				( attribute "PART_NUMBER" "E15431-001"
					( Origin gFrontEnd )
				)
				( attribute "PHYS_PAGE" "221"
					( Origin gFrontEnd )
				)
				( attribute "ROOM" "VTT_ABC_PWR_VR"
					( Origin gFrontEnd )
				)
				( attribute "ROT" "0"
					( Origin gFrontEnd )
				)
				( attribute "SEC" "1"
					( Origin gFrontEnd )
				)
				( attribute "SEC_TYPE" "0603LF"
					( Origin gFrontEnd )
				)
				( attribute "TOLERANCE" "20%"
					( Origin gFrontEnd )
				)
				( attribute "VALUE" "10UF"
					( Origin gFrontEnd )
				)
				( attribute "VER" "1"
					( Origin gFrontEnd )
				)
				( attribute "VOLTAGE" "4V"
					( Units "uVoltage" "V" 1.000000)
					( Origin gFrontEnd )
				)
				( attribute "XY" "(-225,2250)"
					( Origin gFrontEnd )
				)
				( attribute "CHIPS_PART_NAME" "CAP"
					( Origin gPackager )
				)
				( attribute "CDS_PART_NAME" "CAP_0603LF-10UF,4V,20%,X6S,E15A"
					( Origin gPackager )
				)
				( objectStatus "C6U15" )
			)
			( gate "@baseboard_fab2_lib.baseboard_fab2(sch_1):page221_i14"
				( attribute "BOM_COST" "MEM_VRD_VTT_ABC"
					( Origin gFrontEnd )
				)
				( attribute "CDS_LIB" "mstr_discrete"
					( Origin gPackager )
				)
				( attribute "CDS_LOCATION" "R6U4"
					( Origin gPackager )
				)
				( attribute "CDS_SEC" "1"
					( Origin gPackager )
				)
				( attribute "LOCATION" "R6U4"
					( Origin gFrontEnd )
				)
				( attribute "MATERIAL" "CHIP"
					( Origin gFrontEnd )
				)
				( attribute "PACK_TYPE" "0402"
					( Origin gFrontEnd )
				)
				( attribute "PART_NUMBER" "G21497-005"
					( Origin gFrontEnd )
				)
				( attribute "PHYS_PAGE" "221"
					( Origin gFrontEnd )
				)
				( attribute "ROOM" "VTT_ABC_PWR_VR"
					( Origin gFrontEnd )
				)
				( attribute "ROT" "0"
					( Origin gFrontEnd )
				)
				( attribute "SEC" "1"
					( Origin gFrontEnd )
				)
				( attribute "SEC_TYPE" "0402"
					( Origin gFrontEnd )
				)
				( attribute "TOLERANCE" "5%"
					( Origin gFrontEnd )
				)
				( attribute "VALUE" "0.0"
					( Origin gFrontEnd )
				)
				( attribute "VER" "1"
					( Origin gFrontEnd )
				)
				( attribute "WATTAGE" "1/16W"
					( Origin gFrontEnd )
				)
				( attribute "XY" "(-150,1675)"
					( Origin gFrontEnd )
				)
				( attribute "CHIPS_PART_NAME" "RES"
					( Origin gPackager )
				)
				( attribute "CDS_PART_NAME" "RES_0402-0.0,5%,1/16W,CHIP,G21A"
					( Origin gPackager )
				)
				( objectStatus "R6U4" )
			)
			( gate "@baseboard_fab2_lib.baseboard_fab2(sch_1):page221_i13"
				( attribute "BOM_COST" "MEM_VRD_VTT_ABC"
					( Origin gFrontEnd )
				)
				( attribute "CDS_LIB" "mstr_discrete"
					( Origin gPackager )
				)
				( attribute "CDS_LOCATION" "C4G15"
					( Origin gPackager )
				)
				( attribute "CDS_SEC" "1"
					( Origin gPackager )
				)
				( attribute "LOCATION" "C4G15"
					( Origin gFrontEnd )
				)
				( attribute "MATERIAL" "X6S"
					( Origin gFrontEnd )
				)
				( attribute "PACK_TYPE" "0402"
					( Origin gFrontEnd )
				)
				( attribute "PART_NUMBER" "D97712-011"
					( Origin gFrontEnd )
				)
				( attribute "PHYS_PAGE" "221"
					( Origin gFrontEnd )
				)
				( attribute "ROOM" "VTT_ABC_PWR_VR"
					( Origin gFrontEnd )
				)
				( attribute "ROT" "0"
					( Origin gFrontEnd )
				)
				( attribute "SEC" "1"
					( Origin gPackager )
				)
				( attribute "TOLERANCE" "10%"
					( Origin gFrontEnd )
				)
				( attribute "VALUE" "1.0UF"
					( Origin gFrontEnd )
				)
				( attribute "VER" "1"
					( Origin gFrontEnd )
				)
				( attribute "VOLTAGE" "16V"
					( Units "uVoltage" "V" 1.000000)
					( Origin gFrontEnd )
				)
				( attribute "XY" "(200,1400)"
					( Origin gFrontEnd )
				)
				( attribute "CHIPS_PART_NAME" "CAP"
					( Origin gPackager )
				)
				( attribute "CDS_PART_NAME" "CAP_0402-1.0UF,16V,10%,X6S,D97A"
					( Origin gPackager )
				)
				( objectStatus "C4G15" )
			)
			( gate "@baseboard_fab2_lib.baseboard_fab2(sch_1):page221_i11"
				( attribute "CDS_LIB" "mstr_discrete"
					( Origin gPackager )
				)
				( attribute "CDS_LOCATION" "C6U12"
					( Origin gPackager )
				)
				( attribute "CDS_SEC" "1"
					( Origin gPackager )
				)
				( attribute "LOCATION" "C6U12"
					( Origin gFrontEnd )
				)
				( attribute "MATERIAL" "X6S"
					( Origin gFrontEnd )
				)
				( attribute "PACK_TYPE" "0603"
					( Origin gFrontEnd )
				)
				( attribute "PART_NUMBER" "E15431-003"
					( Origin gFrontEnd )
				)
				( attribute "PHYS_PAGE" "221"
					( Origin gFrontEnd )
				)
				( attribute "ROOM" "VTT_ABC_PWR_VR"
					( Origin gFrontEnd )
				)
				( attribute "ROT" "0"
					( Origin gFrontEnd )
				)
				( attribute "SEC" "1"
					( Origin gFrontEnd )
				)
				( attribute "SEC_TYPE" "0603"
					( Origin gFrontEnd )
				)
				( attribute "TOLERANCE" "10%"
					( Origin gFrontEnd )
				)
				( attribute "VALUE" "4.7UF"
					( Origin gFrontEnd )
				)
				( attribute "VER" "1"
					( Origin gFrontEnd )
				)
				( attribute "VOLTAGE" "6.3V"
					( Units "uVoltage" "V" 1.000000)
					( Origin gFrontEnd )
				)
				( attribute "XY" "(50,925)"
					( Origin gFrontEnd )
				)
				( attribute "CHIPS_PART_NAME" "CAP"
					( Origin gPackager )
				)
				( attribute "CDS_PART_NAME" "CAP_0603-4.7UF,6.3V,10%,X6S,E1A"
					( Origin gPackager )
				)
				( objectStatus "C6U12" )
			)
			( gate "@baseboard_fab2_lib.baseboard_fab2(sch_1):page221_i9"
				( attribute "CDS_LIB" "mstr_misc"
					( Origin gPackager )
				)
				( attribute "CDS_LOCATION" "SH5U1"
					( Origin gPackager )
				)
				( attribute "CDS_SEC" "1"
					( Origin gPackager )
				)
				( attribute "LOCATION" "SH5U1"
					( Origin gFrontEnd )
				)
				( attribute "MATERIAL" "EMPTY"
					( Origin gFrontEnd )
				)
				( attribute "PACK_TYPE" "SH0201"
					( Origin gFrontEnd )
				)
				( attribute "PART_NUMBER" "N_A"
					( Origin gFrontEnd )
				)
				( attribute "PHYS_PAGE" "221"
					( Origin gFrontEnd )
				)
				( attribute "PIN_SHORT" "A:B"
					( Origin gFrontEnd )
				)
				( attribute "ROT" "0"
					( Origin gFrontEnd )
				)
				( attribute "SEC" "1"
					( Origin gFrontEnd )
				)
				( attribute "SEC_TYPE" "SH0201"
					( Origin gFrontEnd )
				)
				( attribute "VER" "1"
					( Origin gFrontEnd )
				)
				( attribute "XY" "(4700,-75)"
					( Origin gFrontEnd )
				)
				( attribute "CHIPS_PART_NAME" "SHUNT"
					( Origin gPackager )
				)
				( attribute "CDS_PART_NAME" "SHUNT_SH0201-EMPTY,N_A"
					( Origin gPackager )
				)
				( objectStatus "SH5U1" )
			)
			( gate "@baseboard_fab2_lib.baseboard_fab2(sch_1):page235_i244"
				( attribute "CDS_LIB" "mstr_discrete"
					( Origin gPackager )
				)
				( attribute "CDS_LOCATION" "C4W3"
					( Origin gPackager )
				)
				( attribute "CDS_SEC" "1"
					( Origin gPackager )
				)
				( attribute "LOCATION" "C4W3"
					( Origin gFrontEnd )
				)
				( attribute "MATERIAL" "X7R"
					( Origin gFrontEnd )
				)
				( attribute "PACK_TYPE" "0402LF"
					( Origin gFrontEnd )
				)
				( attribute "PART_NUMBER" "A36096-050"
					( Origin gFrontEnd )
				)
				( attribute "PHYS_PAGE" "235"
					( Origin gFrontEnd )
				)
				( attribute "ROOM" "PVCCIN_CPU0_VR"
					( Origin gFrontEnd )
				)
				( attribute "ROT" "0"
					( Origin gFrontEnd )
				)
				( attribute "SEC" "1"
					( Origin gFrontEnd )
				)
				( attribute "SEC_TYPE" "0402LF"
					( Origin gFrontEnd )
				)
				( attribute "TOLERANCE" "10%"
					( Origin gFrontEnd )
				)
				( attribute "VALUE" "220PF"
					( Origin gFrontEnd )
				)
				( attribute "VER" "1"
					( Origin gFrontEnd )
				)
				( attribute "VOLTAGE" "50V"
					( Units "uVoltage" "V" 1.000000)
					( Origin gFrontEnd )
				)
				( attribute "XY" "(-12200,3700)"
					( Origin gFrontEnd )
				)
				( attribute "CHIPS_PART_NAME" "CAP"
					( Origin gPackager )
				)
				( attribute "CDS_PART_NAME" "CAP_0402LF-220PF,50V,10%,X7R,AA"
					( Origin gPackager )
				)
				( objectStatus "C4W3" )
			)
			( gate "@baseboard_fab2_lib.baseboard_fab2(sch_1):page216_i6"
				( attribute "BOM_COST" "PROC_VRD_VCCIN_CPU0"
					( Origin gFrontEnd )
				)
				( attribute "CDS_LIB" "mstr_discrete"
					( Origin gPackager )
				)
				( attribute "CDS_LOCATION" "C6G3"
					( Origin gPackager )
				)
				( attribute "LOCATION" "C6G3"
					( Origin gFrontEnd )
				)
				( attribute "MATERIAL" "X6S"
					( Origin gFrontEnd )
				)
				( attribute "PACK_TYPE" "0805LF"
					( Origin gFrontEnd )
				)
				( attribute "PART_NUMBER" "C95333-002"
					( Origin gFrontEnd )
				)
				( attribute "PHYS_PAGE" "216"
					( Origin gFrontEnd )
				)
				( attribute "ROOM" "VDDQ_ABC_PWR_VR"
					( Origin gFrontEnd )
				)
				( attribute "ROT" "0"
					( Origin gFrontEnd )
				)
				( attribute "SEC" "1"
					( Origin gFrontEnd )
				)
				( attribute "SEC_TYPE" "0805LF"
					( Origin gFrontEnd )
				)
				( attribute "TOLERANCE" "20%"
					( Origin gFrontEnd )
				)
				( attribute "VALUE" "22UF"
					( Origin gFrontEnd )
				)
				( attribute "VER" "1"
					( Origin gFrontEnd )
				)
				( attribute "VOLTAGE" "4V"
					( Units "uVoltage" "V" 1.000000)
					( Origin gFrontEnd )
				)
				( attribute "XY" "(4350,1850)"
					( Origin gFrontEnd )
				)
				( attribute "CHIPS_PART_NAME" "CAP"
					( Origin gPackager )
				)
				( attribute "CDS_PART_NAME" "CAP_0805LF-22UF,4V,20%,X6S,C95A"
					( Origin gPackager )
				)
				( attribute "CDS_SEC" "1"
					( Origin gPackager )
				)
				( attribute "GROUP" "PWR_MLCC_CAP"
					( Origin gFrontEnd )
				)
				( objectStatus "C6G3" )
			)
			( gate "@baseboard_fab2_lib.baseboard_fab2(sch_1):page216_i44"
				( attribute "CDS_LIB" "mstr_discrete"
					( Origin gPackager )
				)
				( attribute "CDS_LOCATION" "C7G31"
					( Origin gPackager )
				)
				( attribute "LOCATION" "C7G31"
					( Origin gFrontEnd )
				)
				( attribute "MATERIAL" "X7R"
					( Origin gFrontEnd )
				)
				( attribute "PACK_TYPE" "0402"
					( Origin gFrontEnd )
				)
				( attribute "PART_NUMBER" "A36096-104"
					( Origin gFrontEnd )
				)
				( attribute "PHYS_PAGE" "216"
					( Origin gFrontEnd )
				)
				( attribute "ROOM" "VDDQ_ABC_PWR_VR"
					( Origin gFrontEnd )
				)
				( attribute "ROT" "2"
					( Origin gFrontEnd )
				)
				( attribute "SEC" "1"
					( Origin gFrontEnd )
				)
				( attribute "SEC_TYPE" "0402"
					( Origin gFrontEnd )
				)
				( attribute "SPOF" "TRUE"
					( Origin gFrontEnd )
				)
				( attribute "TOLERANCE" "10%"
					( Origin gFrontEnd )
				)
				( attribute "VALUE" "0.220UF"
					( Origin gFrontEnd )
				)
				( attribute "VER" "1"
					( Origin gFrontEnd )
				)
				( attribute "VOLTAGE" "16V"
					( Units "uVoltage" "V" 1.000000)
					( Origin gFrontEnd )
				)
				( attribute "XY" "(-675,1925)"
					( Origin gFrontEnd )
				)
				( attribute "CHIPS_PART_NAME" "CAP"
					( Origin gPackager )
				)
				( attribute "CDS_PART_NAME" "CAP_0402-0.220UF,16V,10%,X7R,AA"
					( Origin gPackager )
				)
				( attribute "CDS_SEC" "1"
					( Origin gPackager )
				)
				( objectStatus "C7G31" )
			)
			( gate "@baseboard_fab2_lib.baseboard_fab2(sch_1):page216_i45"
				( attribute "CDS_LIB" "mstr_discrete"
					( Origin gPackager )
				)
				( attribute "CDS_LOCATION" "C3U2"
					( Origin gPackager )
				)
				( attribute "LOCATION" "C3U2"
					( Origin gFrontEnd )
				)
				( attribute "MATERIAL" "X6S"
					( Origin gFrontEnd )
				)
				( attribute "PACK_TYPE" "0805"
					( Origin gFrontEnd )
				)
				( attribute "PART_NUMBER" "C95333-007"
					( Origin gFrontEnd )
				)
				( attribute "PHYS_PAGE" "216"
					( Origin gFrontEnd )
				)
				( attribute "ROOM" "VDDQ_ABC_PWR_VR"
					( Origin gFrontEnd )
				)
				( attribute "ROT" "0"
					( Origin gFrontEnd )
				)
				( attribute "SEC" "1"
					( Origin gFrontEnd )
				)
				( attribute "SEC_TYPE" "0805"
					( Origin gFrontEnd )
				)
				( attribute "TOLERANCE" "10%"
					( Origin gFrontEnd )
				)
				( attribute "VALUE" "10UF"
					( Origin gFrontEnd )
				)
				( attribute "VER" "1"
					( Origin gFrontEnd )
				)
				( attribute "VOLTAGE" "16V"
					( Units "uVoltage" "V" 1.000000)
					( Origin gFrontEnd )
				)
				( attribute "XY" "(-2050,2525)"
					( Origin gFrontEnd )
				)
				( attribute "CHIPS_PART_NAME" "CAP"
					( Origin gPackager )
				)
				( attribute "CDS_PART_NAME" "CAP_0805-10UF,16V,10%,X6S,C953A"
					( Origin gPackager )
				)
				( attribute "CDS_SEC" "1"
					( Origin gPackager )
				)
				( objectStatus "C3U2" )
			)
			( gate "@baseboard_fab2_lib.baseboard_fab2(sch_1):page216_i46"
				( attribute "CDS_LIB" "mstr_discrete"
					( Origin gPackager )
				)
				( attribute "CDS_LOCATION" "C3U3"
					( Origin gPackager )
				)
				( attribute "LOCATION" "C3U3"
					( Origin gFrontEnd )
				)
				( attribute "MATERIAL" "X6S"
					( Origin gFrontEnd )
				)
				( attribute "PACK_TYPE" "0805"
					( Origin gFrontEnd )
				)
				( attribute "PART_NUMBER" "C95333-007"
					( Origin gFrontEnd )
				)
				( attribute "PHYS_PAGE" "216"
					( Origin gFrontEnd )
				)
				( attribute "ROOM" "VDDQ_ABC_PWR_VR"
					( Origin gFrontEnd )
				)
				( attribute "ROT" "0"
					( Origin gFrontEnd )
				)
				( attribute "SEC" "1"
					( Origin gFrontEnd )
				)
				( attribute "SEC_TYPE" "0805"
					( Origin gFrontEnd )
				)
				( attribute "TOLERANCE" "10%"
					( Origin gFrontEnd )
				)
				( attribute "VALUE" "10UF"
					( Origin gFrontEnd )
				)
				( attribute "VER" "1"
					( Origin gFrontEnd )
				)
				( attribute "VOLTAGE" "16V"
					( Units "uVoltage" "V" 1.000000)
					( Origin gFrontEnd )
				)
				( attribute "XY" "(-1775,2525)"
					( Origin gFrontEnd )
				)
				( attribute "CHIPS_PART_NAME" "CAP"
					( Origin gPackager )
				)
				( attribute "CDS_PART_NAME" "CAP_0805-10UF,16V,10%,X6S,C953A"
					( Origin gPackager )
				)
				( attribute "CDS_SEC" "1"
					( Origin gPackager )
				)
				( objectStatus "C3U3" )
			)
			( gate "@baseboard_fab2_lib.baseboard_fab2(sch_1):page216_i47"
				( attribute "CDS_LIB" "mstr_discrete"
					( Origin gPackager )
				)
				( attribute "CDS_LOCATION" "C3U4"
					( Origin gPackager )
				)
				( attribute "LOCATION" "C3U4"
					( Origin gFrontEnd )
				)
				( attribute "MATERIAL" "X6S"
					( Origin gFrontEnd )
				)
				( attribute "PACK_TYPE" "0805"
					( Origin gFrontEnd )
				)
				( attribute "PART_NUMBER" "C95333-007"
					( Origin gFrontEnd )
				)
				( attribute "PHYS_PAGE" "216"
					( Origin gFrontEnd )
				)
				( attribute "ROOM" "VDDQ_ABC_PWR_VR"
					( Origin gFrontEnd )
				)
				( attribute "ROT" "0"
					( Origin gFrontEnd )
				)
				( attribute "SEC" "1"
					( Origin gFrontEnd )
				)
				( attribute "SEC_TYPE" "0805"
					( Origin gFrontEnd )
				)
				( attribute "TOLERANCE" "10%"
					( Origin gFrontEnd )
				)
				( attribute "VALUE" "10UF"
					( Origin gFrontEnd )
				)
				( attribute "VER" "1"
					( Origin gFrontEnd )
				)
				( attribute "VOLTAGE" "16V"
					( Units "uVoltage" "V" 1.000000)
					( Origin gFrontEnd )
				)
				( attribute "XY" "(-1525,2525)"
					( Origin gFrontEnd )
				)
				( attribute "CHIPS_PART_NAME" "CAP"
					( Origin gPackager )
				)
				( attribute "CDS_PART_NAME" "CAP_0805-10UF,16V,10%,X6S,C953A"
					( Origin gPackager )
				)
				( attribute "CDS_SEC" "1"
					( Origin gPackager )
				)
				( objectStatus "C3U4" )
			)
			( gate "@baseboard_fab2_lib.baseboard_fab2(sch_1):page216_i48"
				( attribute "CDS_LIB" "mstr_discrete"
					( Origin gPackager )
				)
				( attribute "CDS_LOCATION" "C7G37"
					( Origin gPackager )
				)
				( attribute "LOCATION" "C7G37"
					( Origin gFrontEnd )
				)
				( attribute "MATERIAL" "X6S"
					( Origin gFrontEnd )
				)
				( attribute "PACK_TYPE" "0402"
					( Origin gFrontEnd )
				)
				( attribute "PART_NUMBER" "D97712-011"
					( Origin gFrontEnd )
				)
				( attribute "PHYS_PAGE" "216"
					( Origin gFrontEnd )
				)
				( attribute "ROOM" "VDDQ_ABC_PWR_VR"
					( Origin gFrontEnd )
				)
				( attribute "ROT" "0"
					( Origin gFrontEnd )
				)
				( attribute "SEC" "1"
					( Origin gFrontEnd )
				)
				( attribute "SEC_TYPE" "0402"
					( Origin gFrontEnd )
				)
				( attribute "TOLERANCE" "10%"
					( Origin gFrontEnd )
				)
				( attribute "VALUE" "1.0UF"
					( Origin gFrontEnd )
				)
				( attribute "VER" "1"
					( Origin gFrontEnd )
				)
				( attribute "VOLTAGE" "16V"
					( Units "uVoltage" "V" 1.000000)
					( Origin gFrontEnd )
				)
				( attribute "XY" "(-1275,2525)"
					( Origin gFrontEnd )
				)
				( attribute "CHIPS_PART_NAME" "CAP"
					( Origin gPackager )
				)
				( attribute "CDS_PART_NAME" "CAP_0402-1.0UF,16V,10%,X6S,D97A"
					( Origin gPackager )
				)
				( attribute "CDS_SEC" "1"
					( Origin gPackager )
				)
				( objectStatus "C7G37" )
			)
			( gate "@baseboard_fab2_lib.baseboard_fab2(sch_1):page216_i50"
				( attribute "CDS_LIB" "mstr_discrete"
					( Origin gPackager )
				)
				( attribute "CDS_LOCATION" "C7G33"
					( Origin gPackager )
				)
				( attribute "LOCATION" "C7G33"
					( Origin gFrontEnd )
				)
				( attribute "MATERIAL" "X6S"
					( Origin gFrontEnd )
				)
				( attribute "PACK_TYPE" "0402"
					( Origin gFrontEnd )
				)
				( attribute "PART_NUMBER" "D97712-011"
					( Origin gFrontEnd )
				)
				( attribute "PHYS_PAGE" "216"
					( Origin gFrontEnd )
				)
				( attribute "ROOM" "VDDQ_ABC_PWR_VR"
					( Origin gFrontEnd )
				)
				( attribute "ROT" "0"
					( Origin gFrontEnd )
				)
				( attribute "SEC" "1"
					( Origin gFrontEnd )
				)
				( attribute "SEC_TYPE" "0402"
					( Origin gFrontEnd )
				)
				( attribute "TOLERANCE" "10%"
					( Origin gFrontEnd )
				)
				( attribute "VALUE" "1.0UF"
					( Origin gFrontEnd )
				)
				( attribute "VER" "1"
					( Origin gFrontEnd )
				)
				( attribute "VOLTAGE" "16V"
					( Units "uVoltage" "V" 1.000000)
					( Origin gFrontEnd )
				)
				( attribute "XY" "(-725,2525)"
					( Origin gFrontEnd )
				)
				( attribute "CHIPS_PART_NAME" "CAP"
					( Origin gPackager )
				)
				( attribute "CDS_PART_NAME" "CAP_0402-1.0UF,16V,10%,X6S,D97A"
					( Origin gPackager )
				)
				( attribute "CDS_SEC" "1"
					( Origin gPackager )
				)
				( objectStatus "C7G33" )
			)
			( gate "@baseboard_fab2_lib.baseboard_fab2(sch_1):page216_i51"
				( attribute "CDS_LIB" "dev_discrete"
					( Origin gPackager )
				)
				( attribute "CDS_LOCATION" "C7G29"
					( Origin gPackager )
				)
				( attribute "CDS_SEC" "1"
					( Origin gPackager )
				)
				( attribute "LOCATION" "C7G29"
					( Origin gFrontEnd )
				)
				( attribute "MATERIAL" "X7R"
					( Origin gFrontEnd )
				)
				( attribute "PACK_TYPE" "0402V"
					( Origin gFrontEnd )
				)
				( attribute "PART_NUMBER" "A36096-030"
					( Origin gFrontEnd )
				)
				( attribute "PHYS_PAGE" "216"
					( Origin gFrontEnd )
				)
				( attribute "ROOM" "VDDQ_ABC_PWR_VR"
					( Origin gFrontEnd )
				)
				( attribute "ROT" "0"
					( Origin gFrontEnd )
				)
				( attribute "SEC" "1"
					( Origin gFrontEnd )
				)
				( attribute "SEC_TYPE" "0402V"
					( Origin gFrontEnd )
				)
				( attribute "TOLERANCE" "10%"
					( Origin gFrontEnd )
				)
				( attribute "VALUE" "0.1UF"
					( Origin gFrontEnd )
				)
				( attribute "VER" "1"
					( Origin gFrontEnd )
				)
				( attribute "VOLTAGE" "16V"
					( Units "uVoltage" "V" 1.000000)
					( Origin gFrontEnd )
				)
				( attribute "XY" "(-1000,2525)"
					( Origin gFrontEnd )
				)
				( attribute "CHIPS_PART_NAME" "CAP_A"
					( Origin gPackager )
				)
				( attribute "CDS_PART_NAME" "CAP_A_0402V-0.1UF,16V,10%,X7R,A"
					( Origin gPackager )
				)
				( objectStatus "C7G29" )
			)
			( gate "@baseboard_fab2_lib.baseboard_fab2(sch_1):page219_i148"
				( attribute "BOM_COST" "PROC_SIDEBAND"
					( Origin gFrontEnd )
				)
				( attribute "CDS_LIB" "mstr_discrete"
					( Origin gPackager )
				)
				( attribute "CDS_LOCATION" "R3L8"
					( Origin gPackager )
				)
				( attribute "CDS_SEC" "1"
					( Origin gPackager )
				)
				( attribute "LOCATION" "R3L8"
					( Origin gFrontEnd )
				)
				( attribute "MATERIAL" "CHIP"
					( Origin gFrontEnd )
				)
				( attribute "PACK_TYPE" "0402"
					( Origin gFrontEnd )
				)
				( attribute "PART_NUMBER" "G21497-005"
					( Origin gFrontEnd )
				)
				( attribute "PHYS_PAGE" "219"
					( Origin gFrontEnd )
				)
				( attribute "ROOM" "CPU0"
					( Origin gFrontEnd )
				)
				( attribute "ROT" "0"
					( Origin gFrontEnd )
				)
				( attribute "SEC" "1"
					( Origin gFrontEnd )
				)
				( attribute "SEC_TYPE" "0402"
					( Origin gFrontEnd )
				)
				( attribute "TOLERANCE" "5%"
					( Origin gFrontEnd )
				)
				( attribute "VALUE" "0.0"
					( Origin gFrontEnd )
				)
				( attribute "VER" "1"
					( Origin gFrontEnd )
				)
				( attribute "WATTAGE" "1/16W"
					( Origin gFrontEnd )
				)
				( attribute "XY" "(-775,700)"
					( Origin gFrontEnd )
				)
				( attribute "CHIPS_PART_NAME" "RES"
					( Origin gPackager )
				)
				( attribute "CDS_PART_NAME" "RES_0402-0.0,5%,1/16W,CHIP,G21A"
					( Origin gPackager )
				)
				( attribute "BOM_SS" "NOPOP"
					( Origin gFrontEnd )
				)
				( objectStatus "R3L8" )
			)
			( gate "@baseboard_fab2_lib.baseboard_fab2(sch_1):page216_i54"
				( attribute "CDS_LIB" "mstr_discrete"
					( Origin gPackager )
				)
				( attribute "CDS_LOCATION" "C7G34"
					( Origin gPackager )
				)
				( attribute "LOCATION" "C7G34"
					( Origin gFrontEnd )
				)
				( attribute "MATERIAL" "X7R"
					( Origin gFrontEnd )
				)
				( attribute "PACK_TYPE" "0402"
					( Origin gFrontEnd )
				)
				( attribute "PART_NUMBER" "A36096-155"
					( Origin gFrontEnd )
				)
				( attribute "PHYS_PAGE" "216"
					( Origin gFrontEnd )
				)
				( attribute "ROOM" "VDDQ_ABC_PWR_VR"
					( Origin gFrontEnd )
				)
				( attribute "ROT" "0"
					( Origin gFrontEnd )
				)
				( attribute "SEC" "1"
					( Origin gFrontEnd )
				)
				( attribute "SEC_TYPE" "0402"
					( Origin gFrontEnd )
				)
				( attribute "TOLERANCE" "10%"
					( Origin gFrontEnd )
				)
				( attribute "VALUE" "0.22UF"
					( Origin gFrontEnd )
				)
				( attribute "VER" "1"
					( Origin gFrontEnd )
				)
				( attribute "VOLTAGE" "16V"
					( Units "uVoltage" "V" 1.000000)
					( Origin gFrontEnd )
				)
				( attribute "XY" "(100,2550)"
					( Origin gFrontEnd )
				)
				( attribute "CHIPS_PART_NAME" "CAP"
					( Origin gPackager )
				)
				( attribute "CDS_PART_NAME" "CAP_0402-0.22UF,16V,10%,X7R,A3A"
					( Origin gPackager )
				)
				( attribute "CDS_SEC" "1"
					( Origin gPackager )
				)
				( objectStatus "C7G34" )
			)
			( gate "@baseboard_fab2_lib.baseboard_fab2(sch_1):page210_i55"
				( attribute "CDS_LIB" "dev_discrete"
					( Origin gPackager )
				)
				( attribute "LOCATION" "CT57"
					( Origin gFrontEnd )
				)
				( attribute "MATERIAL" "X7R"
					( Origin gFrontEnd )
				)
				( attribute "PACK_TYPE" "0402V"
					( Origin gFrontEnd )
				)
				( attribute "PART_NUMBER" "A36096-030"
					( Origin gFrontEnd )
				)
				( attribute "PHYS_PAGE" "210"
					( Origin gFrontEnd )
				)
				( attribute "ROOM" "PVCCIN_CPU0_PWR_VR"
					( Origin gFrontEnd )
				)
				( attribute "ROT" "0"
					( Origin gFrontEnd )
				)
				( attribute "TOLERANCE" "10%"
					( Origin gFrontEnd )
				)
				( attribute "VALUE" "0.1UF"
					( Origin gFrontEnd )
				)
				( attribute "VER" "1"
					( Origin gFrontEnd )
				)
				( attribute "VOLTAGE" "16V"
					( Units "uVoltage" "V" 1.000000)
					( Origin gFrontEnd )
				)
				( attribute "XY" "(-4450,3100)"
					( Origin gFrontEnd )
				)
				( attribute "CHIPS_PART_NAME" "CAP_A"
					( Origin gPackager )
				)
				( attribute "CDS_PART_NAME" "CAP_A_0402V-0.1UF,16V,10%,X7R,A"
					( Origin gPackager )
				)
				( attribute "CDS_LOCATION" "CT57"
					( Origin gPackager )
				)
				( attribute "SEC" "1"
					( Origin gFrontEnd )
				)
				( attribute "POP" "NOPOP"
					( Origin gFrontEnd )
				)
				( attribute "SEC_TYPE" "0402V"
					( Origin gFrontEnd )
				)
				( attribute "CDS_SEC" "1"
					( Origin gPackager )
				)
				( objectStatus "CT57" )
			)
			( gate "@baseboard_fab2_lib.baseboard_fab2(sch_1):page224_i161"
				( attribute "ATTRIBUTE" "120NH"
					( Origin gFrontEnd )
				)
				( attribute "BOM_DS" "068.9002N.1021"
					( Origin gFrontEnd )
				)
				( attribute "BOM_SS" "NOPOP"
					( Origin gFrontEnd )
				)
				( attribute "CDS_LIB" "w_hdl"
					( Origin gPackager )
				)
				( attribute "CDS_LMAN_SYM_OUTLINE" "-75,100,75,-100"
					( Origin gPackager )
				)
				( attribute "CDS_LOCATION" "L1F2"
					( Origin gPackager )
				)
				( attribute "CDS_SEC" "1"
					( Origin gPackager )
				)
				( attribute "DS_VALUE" "90NH"
					( Origin gFrontEnd )
				)
				( attribute "LOCATION" "L1F2"
					( Origin gFrontEnd )
				)
				( attribute "NEW_PACK_SIZE" "DCR=0.17MOHM"
					( Origin gFrontEnd )
				)
				( attribute "NEW_RATED" "DS_ISAT=134A@25C"
					( Origin gFrontEnd )
				)
				( attribute "NEW_TYPE" "IRMS=66A@DELTA_T<40C"
					( Origin gFrontEnd )
				)
				( attribute "PACK_SIZE" "DCR=0.17MOHM"
					( Origin gFrontEnd )
				)
				( attribute "PACK_TYPE" "DISCRET-GB2"
					( Origin gFrontEnd )
				)
				( attribute "PART_NUMBER" "068.1202N.M001"
					( Origin gFrontEnd )
				)
				( attribute "PHYS_PAGE" "224"
					( Origin gFrontEnd )
				)
				( attribute "RATED" "ISAT=94A@25C"
					( Origin gFrontEnd )
				)
				( attribute "ROT" "1"
					( Origin gFrontEnd )
				)
				( attribute "SEC" "1"
					( Origin gFrontEnd )
				)
				( attribute "SEC_TYPE" "DISCRET-GB2"
					( Origin gFrontEnd )
				)
				( attribute "TYPE" "IRMS=66A@DELTA_T<40C"
					( Origin gFrontEnd )
				)
				( attribute "VALUE" "IND-120NH-30-GP"
					( Origin gFrontEnd )
				)
				( attribute "VER" "1"
					( Origin gFrontEnd )
				)
				( attribute "XY" "(3900,-400)"
					( Origin gFrontEnd )
				)
				( attribute "CHIPS_PART_NAME" "IND-120NH-30-GP"
					( Origin gPackager )
				)
				( attribute "CDS_PART_NAME" "IND-120NH-30-GP_DISCRET-GB2-INA"
					( Origin gPackager )
				)
				( objectStatus "L1F2" )
			)
			( gate "@baseboard_fab2_lib.baseboard_fab2(sch_1):page216_i68"
				( attribute "BOM_COST" "PROC_VRD_VCCIN_CPU0"
					( Origin gFrontEnd )
				)
				( attribute "CDS_LIB" "mstr_discrete"
					( Origin gPackager )
				)
				( attribute "CDS_LOCATION" "C7G27"
					( Origin gPackager )
				)
				( attribute "LOCATION" "C7G27"
					( Origin gFrontEnd )
				)
				( attribute "MATERIAL" "X6S"
					( Origin gFrontEnd )
				)
				( attribute "PACK_TYPE" "0805LF"
					( Origin gFrontEnd )
				)
				( attribute "PART_NUMBER" "C95333-002"
					( Origin gFrontEnd )
				)
				( attribute "PHYS_PAGE" "216"
					( Origin gFrontEnd )
				)
				( attribute "ROOM" "VDDQ_ABC_PWR_VR"
					( Origin gFrontEnd )
				)
				( attribute "ROT" "0"
					( Origin gFrontEnd )
				)
				( attribute "SEC" "1"
					( Origin gFrontEnd )
				)
				( attribute "SEC_TYPE" "0805LF"
					( Origin gFrontEnd )
				)
				( attribute "TOLERANCE" "20%"
					( Origin gFrontEnd )
				)
				( attribute "VALUE" "22UF"
					( Origin gFrontEnd )
				)
				( attribute "VER" "1"
					( Origin gFrontEnd )
				)
				( attribute "VOLTAGE" "4V"
					( Units "uVoltage" "V" 1.000000)
					( Origin gFrontEnd )
				)
				( attribute "XY" "(4400,-550)"
					( Origin gFrontEnd )
				)
				( attribute "CHIPS_PART_NAME" "CAP"
					( Origin gPackager )
				)
				( attribute "CDS_PART_NAME" "CAP_0805LF-22UF,4V,20%,X6S,C95A"
					( Origin gPackager )
				)
				( attribute "CDS_SEC" "1"
					( Origin gPackager )
				)
				( attribute "GROUP" "PWR_MLCC_CAP"
					( Origin gFrontEnd )
				)
				( attribute "BOM_SS" "NOPOP"
					( Origin gFrontEnd )
				)
				( objectStatus "C7G27" )
			)
			( gate "@baseboard_fab2_lib.baseboard_fab2(sch_1):page216_i72"
				( attribute "CDS_LIB" "mstr_discrete"
					( Origin gPackager )
				)
				( attribute "CDS_LOCATION" "C7G41"
					( Origin gPackager )
				)
				( attribute "LOCATION" "C7G41"
					( Origin gFrontEnd )
				)
				( attribute "MATERIAL" "X7R"
					( Origin gFrontEnd )
				)
				( attribute "PACK_TYPE" "0402"
					( Origin gFrontEnd )
				)
				( attribute "PART_NUMBER" "A36096-155"
					( Origin gFrontEnd )
				)
				( attribute "PHYS_PAGE" "216"
					( Origin gFrontEnd )
				)
				( attribute "ROOM" "VDDQ_ABC_PWR_VR"
					( Origin gFrontEnd )
				)
				( attribute "ROT" "0"
					( Origin gFrontEnd )
				)
				( attribute "SEC" "1"
					( Origin gFrontEnd )
				)
				( attribute "SEC_TYPE" "0402"
					( Origin gFrontEnd )
				)
				( attribute "TOLERANCE" "10%"
					( Origin gFrontEnd )
				)
				( attribute "VALUE" "0.22UF"
					( Origin gFrontEnd )
				)
				( attribute "VER" "1"
					( Origin gFrontEnd )
				)
				( attribute "VOLTAGE" "16V"
					( Units "uVoltage" "V" 1.000000)
					( Origin gFrontEnd )
				)
				( attribute "XY" "(50,200)"
					( Origin gFrontEnd )
				)
				( attribute "CHIPS_PART_NAME" "CAP"
					( Origin gPackager )
				)
				( attribute "CDS_PART_NAME" "CAP_0402-0.22UF,16V,10%,X7R,A3A"
					( Origin gPackager )
				)
				( attribute "CDS_SEC" "1"
					( Origin gPackager )
				)
				( attribute "BOM_SS" "NOPOP"
					( Origin gFrontEnd )
				)
				( objectStatus "C7G41" )
			)
			( gate "@baseboard_fab2_lib.baseboard_fab2(sch_1):page209_i73"
				( attribute "CDS_LIB" "mstr_discrete"
					( Origin gPackager )
				)
				( attribute "LOCATION" "CT14"
					( Origin gFrontEnd )
				)
				( attribute "MATERIAL" "X7R"
					( Origin gFrontEnd )
				)
				( attribute "PACK_TYPE" "0402LF"
					( Origin gFrontEnd )
				)
				( attribute "PART_NUMBER" "A36096-046"
					( Origin gFrontEnd )
				)
				( attribute "PHYS_PAGE" "209"
					( Origin gFrontEnd )
				)
				( attribute "POP" "NOPOP"
					( Origin gFrontEnd )
				)
				( attribute "ROOM" "VDDQ_KLM_PWR_VR"
					( Origin gFrontEnd )
				)
				( attribute "ROT" "0"
					( Origin gFrontEnd )
				)
				( attribute "TOLERANCE" "10%"
					( Origin gFrontEnd )
				)
				( attribute "VALUE" "1000PF"
					( Origin gFrontEnd )
				)
				( attribute "VER" "1"
					( Origin gFrontEnd )
				)
				( attribute "VOLTAGE" "50V"
					( Units "uVoltage" "V" 1.000000)
					( Origin gFrontEnd )
				)
				( attribute "XY" "(-2400,3300)"
					( Origin gFrontEnd )
				)
				( attribute "CHIPS_PART_NAME" "CAP"
					( Origin gPackager )
				)
				( attribute "CDS_PART_NAME" "CAP_0402LF-1000PF,50V,10%,X7R,A"
					( Origin gPackager )
				)
				( attribute "CDS_LOCATION" "CT14"
					( Origin gPackager )
				)
				( attribute "SEC" "1"
					( Origin gFrontEnd )
				)
				( attribute "SEC_TYPE" "0402LF"
					( Origin gFrontEnd )
				)
				( attribute "CDS_SEC" "1"
					( Origin gPackager )
				)
				( objectStatus "CT14" )
			)
			( gate "@baseboard_fab2_lib.baseboard_fab2(sch_1):page219_i147"
				( attribute "BOM_COST" "PROC_SIDEBAND"
					( Origin gFrontEnd )
				)
				( attribute "CDS_LIB" "mstr_discrete"
					( Origin gPackager )
				)
				( attribute "CDS_LOCATION" "R3L6"
					( Origin gPackager )
				)
				( attribute "CDS_SEC" "1"
					( Origin gPackager )
				)
				( attribute "LOCATION" "R3L6"
					( Origin gFrontEnd )
				)
				( attribute "MATERIAL" "CHIP"
					( Origin gFrontEnd )
				)
				( attribute "PACK_TYPE" "0402"
					( Origin gFrontEnd )
				)
				( attribute "PART_NUMBER" "G21497-005"
					( Origin gFrontEnd )
				)
				( attribute "PHYS_PAGE" "219"
					( Origin gFrontEnd )
				)
				( attribute "ROOM" "CPU0"
					( Origin gFrontEnd )
				)
				( attribute "ROT" "0"
					( Origin gFrontEnd )
				)
				( attribute "SEC" "1"
					( Origin gFrontEnd )
				)
				( attribute "SEC_TYPE" "0402"
					( Origin gFrontEnd )
				)
				( attribute "TOLERANCE" "5%"
					( Origin gFrontEnd )
				)
				( attribute "VALUE" "0.0"
					( Origin gFrontEnd )
				)
				( attribute "VER" "1"
					( Origin gFrontEnd )
				)
				( attribute "WATTAGE" "1/16W"
					( Origin gFrontEnd )
				)
				( attribute "XY" "(-725,3000)"
					( Origin gFrontEnd )
				)
				( attribute "CHIPS_PART_NAME" "RES"
					( Origin gPackager )
				)
				( attribute "CDS_PART_NAME" "RES_0402-0.0,5%,1/16W,CHIP,G21A"
					( Origin gPackager )
				)
				( objectStatus "R3L6" )
			)
			( gate "@baseboard_fab2_lib.baseboard_fab2(sch_1):page216_i77"
				( attribute "CDS_LIB" "mstr_discrete"
					( Origin gPackager )
				)
				( attribute "CDS_LOCATION" "C7G40"
					( Origin gPackager )
				)
				( attribute "LOCATION" "C7G40"
					( Origin gFrontEnd )
				)
				( attribute "MATERIAL" "X6S"
					( Origin gFrontEnd )
				)
				( attribute "PACK_TYPE" "0402"
					( Origin gFrontEnd )
				)
				( attribute "PART_NUMBER" "D97712-011"
					( Origin gFrontEnd )
				)
				( attribute "PHYS_PAGE" "216"
					( Origin gFrontEnd )
				)
				( attribute "ROOM" "VDDQ_ABC_PWR_VR"
					( Origin gFrontEnd )
				)
				( attribute "ROT" "0"
					( Origin gFrontEnd )
				)
				( attribute "SEC" "1"
					( Origin gFrontEnd )
				)
				( attribute "SEC_TYPE" "0402"
					( Origin gFrontEnd )
				)
				( attribute "TOLERANCE" "10%"
					( Origin gFrontEnd )
				)
				( attribute "VALUE" "1.0UF"
					( Origin gFrontEnd )
				)
				( attribute "VER" "1"
					( Origin gFrontEnd )
				)
				( attribute "VOLTAGE" "16V"
					( Units "uVoltage" "V" 1.000000)
					( Origin gFrontEnd )
				)
				( attribute "XY" "(-825,175)"
					( Origin gFrontEnd )
				)
				( attribute "CHIPS_PART_NAME" "CAP"
					( Origin gPackager )
				)
				( attribute "CDS_PART_NAME" "CAP_0402-1.0UF,16V,10%,X6S,D97A"
					( Origin gPackager )
				)
				( attribute "CDS_SEC" "1"
					( Origin gPackager )
				)
				( attribute "BOM_SS" "NOPOP"
					( Origin gFrontEnd )
				)
				( objectStatus "C7G40" )
			)
			( gate "@baseboard_fab2_lib.baseboard_fab2(sch_1):page216_i78"
				( attribute "CDS_LIB" "dev_discrete"
					( Origin gPackager )
				)
				( attribute "CDS_LOCATION" "C7G36"
					( Origin gPackager )
				)
				( attribute "CDS_SEC" "1"
					( Origin gPackager )
				)
				( attribute "LOCATION" "C7G36"
					( Origin gFrontEnd )
				)
				( attribute "MATERIAL" "X7R"
					( Origin gFrontEnd )
				)
				( attribute "PACK_TYPE" "0402V"
					( Origin gFrontEnd )
				)
				( attribute "PART_NUMBER" "A36096-030"
					( Origin gFrontEnd )
				)
				( attribute "PHYS_PAGE" "216"
					( Origin gFrontEnd )
				)
				( attribute "ROOM" "VDDQ_ABC_PWR_VR"
					( Origin gFrontEnd )
				)
				( attribute "ROT" "0"
					( Origin gFrontEnd )
				)
				( attribute "SEC" "1"
					( Origin gFrontEnd )
				)
				( attribute "SEC_TYPE" "0402V"
					( Origin gFrontEnd )
				)
				( attribute "TOLERANCE" "10%"
					( Origin gFrontEnd )
				)
				( attribute "VALUE" "0.1UF"
					( Origin gFrontEnd )
				)
				( attribute "VER" "1"
					( Origin gFrontEnd )
				)
				( attribute "VOLTAGE" "16V"
					( Units "uVoltage" "V" 1.000000)
					( Origin gFrontEnd )
				)
				( attribute "XY" "(-1075,175)"
					( Origin gFrontEnd )
				)
				( attribute "CHIPS_PART_NAME" "CAP_A"
					( Origin gPackager )
				)
				( attribute "CDS_PART_NAME" "CAP_A_0402V-0.1UF,16V,10%,X7R,A"
					( Origin gPackager )
				)
				( objectStatus "C7G36" )
			)
			( gate "@baseboard_fab2_lib.baseboard_fab2(sch_1):page216_i79"
				( attribute "CDS_LIB" "mstr_discrete"
					( Origin gPackager )
				)
				( attribute "CDS_LOCATION" "C7G30"
					( Origin gPackager )
				)
				( attribute "LOCATION" "C7G30"
					( Origin gFrontEnd )
				)
				( attribute "MATERIAL" "X6S"
					( Origin gFrontEnd )
				)
				( attribute "PACK_TYPE" "0402"
					( Origin gFrontEnd )
				)
				( attribute "PART_NUMBER" "D97712-011"
					( Origin gFrontEnd )
				)
				( attribute "PHYS_PAGE" "216"
					( Origin gFrontEnd )
				)
				( attribute "ROOM" "VDDQ_ABC_PWR_VR"
					( Origin gFrontEnd )
				)
				( attribute "ROT" "0"
					( Origin gFrontEnd )
				)
				( attribute "SEC" "1"
					( Origin gFrontEnd )
				)
				( attribute "SEC_TYPE" "0402"
					( Origin gFrontEnd )
				)
				( attribute "TOLERANCE" "10%"
					( Origin gFrontEnd )
				)
				( attribute "VALUE" "1.0UF"
					( Origin gFrontEnd )
				)
				( attribute "VER" "1"
					( Origin gFrontEnd )
				)
				( attribute "VOLTAGE" "16V"
					( Units "uVoltage" "V" 1.000000)
					( Origin gFrontEnd )
				)
				( attribute "XY" "(-1325,175)"
					( Origin gFrontEnd )
				)
				( attribute "CHIPS_PART_NAME" "CAP"
					( Origin gPackager )
				)
				( attribute "CDS_PART_NAME" "CAP_0402-1.0UF,16V,10%,X6S,D97A"
					( Origin gPackager )
				)
				( attribute "CDS_SEC" "1"
					( Origin gPackager )
				)
				( objectStatus "C7G30" )
			)
			( gate "@baseboard_fab2_lib.baseboard_fab2(sch_1):page216_i80"
				( attribute "CDS_LIB" "mstr_discrete"
					( Origin gPackager )
				)
				( attribute "CDS_LOCATION" "C3U9"
					( Origin gPackager )
				)
				( attribute "LOCATION" "C3U9"
					( Origin gFrontEnd )
				)
				( attribute "MATERIAL" "X6S"
					( Origin gFrontEnd )
				)
				( attribute "PACK_TYPE" "0805"
					( Origin gFrontEnd )
				)
				( attribute "PART_NUMBER" "C95333-007"
					( Origin gFrontEnd )
				)
				( attribute "PHYS_PAGE" "216"
					( Origin gFrontEnd )
				)
				( attribute "ROOM" "VDDQ_ABC_PWR_VR"
					( Origin gFrontEnd )
				)
				( attribute "ROT" "0"
					( Origin gFrontEnd )
				)
				( attribute "SEC" "1"
					( Origin gFrontEnd )
				)
				( attribute "SEC_TYPE" "0805"
					( Origin gFrontEnd )
				)
				( attribute "TOLERANCE" "10%"
					( Origin gFrontEnd )
				)
				( attribute "VALUE" "10UF"
					( Origin gFrontEnd )
				)
				( attribute "VER" "1"
					( Origin gFrontEnd )
				)
				( attribute "VOLTAGE" "16V"
					( Units "uVoltage" "V" 1.000000)
					( Origin gFrontEnd )
				)
				( attribute "XY" "(-1550,175)"
					( Origin gFrontEnd )
				)
				( attribute "CHIPS_PART_NAME" "CAP"
					( Origin gPackager )
				)
				( attribute "CDS_PART_NAME" "CAP_0805-10UF,16V,10%,X6S,C953A"
					( Origin gPackager )
				)
				( attribute "CDS_SEC" "1"
					( Origin gPackager )
				)
				( objectStatus "C3U9" )
			)
			( gate "@baseboard_fab2_lib.baseboard_fab2(sch_1):page216_i81"
				( attribute "CDS_LIB" "mstr_discrete"
					( Origin gPackager )
				)
				( attribute "CDS_LOCATION" "C3U7"
					( Origin gPackager )
				)
				( attribute "LOCATION" "C3U7"
					( Origin gFrontEnd )
				)
				( attribute "MATERIAL" "X6S"
					( Origin gFrontEnd )
				)
				( attribute "PACK_TYPE" "0805"
					( Origin gFrontEnd )
				)
				( attribute "PART_NUMBER" "C95333-007"
					( Origin gFrontEnd )
				)
				( attribute "PHYS_PAGE" "216"
					( Origin gFrontEnd )
				)
				( attribute "ROOM" "VDDQ_ABC_PWR_VR"
					( Origin gFrontEnd )
				)
				( attribute "ROT" "0"
					( Origin gFrontEnd )
				)
				( attribute "SEC" "1"
					( Origin gFrontEnd )
				)
				( attribute "SEC_TYPE" "0805"
					( Origin gFrontEnd )
				)
				( attribute "TOLERANCE" "10%"
					( Origin gFrontEnd )
				)
				( attribute "VALUE" "10UF"
					( Origin gFrontEnd )
				)
				( attribute "VER" "1"
					( Origin gFrontEnd )
				)
				( attribute "VOLTAGE" "16V"
					( Units "uVoltage" "V" 1.000000)
					( Origin gFrontEnd )
				)
				( attribute "XY" "(-1800,175)"
					( Origin gFrontEnd )
				)
				( attribute "CHIPS_PART_NAME" "CAP"
					( Origin gPackager )
				)
				( attribute "CDS_PART_NAME" "CAP_0805-10UF,16V,10%,X6S,C953A"
					( Origin gPackager )
				)
				( attribute "CDS_SEC" "1"
					( Origin gPackager )
				)
				( objectStatus "C3U7" )
			)
			( gate "@baseboard_fab2_lib.baseboard_fab2(sch_1):page216_i84"
				( attribute "CDS_LIB" "mstr_discrete"
					( Origin gPackager )
				)
				( attribute "CDS_LOCATION" "C3U6"
					( Origin gPackager )
				)
				( attribute "LOCATION" "C3U6"
					( Origin gFrontEnd )
				)
				( attribute "MATERIAL" "X6S"
					( Origin gFrontEnd )
				)
				( attribute "PACK_TYPE" "0805"
					( Origin gFrontEnd )
				)
				( attribute "PART_NUMBER" "C95333-007"
					( Origin gFrontEnd )
				)
				( attribute "PHYS_PAGE" "216"
					( Origin gFrontEnd )
				)
				( attribute "ROOM" "VDDQ_ABC_PWR_VR"
					( Origin gFrontEnd )
				)
				( attribute "ROT" "0"
					( Origin gFrontEnd )
				)
				( attribute "SEC" "1"
					( Origin gFrontEnd )
				)
				( attribute "SEC_TYPE" "0805"
					( Origin gFrontEnd )
				)
				( attribute "TOLERANCE" "10%"
					( Origin gFrontEnd )
				)
				( attribute "VALUE" "10UF"
					( Origin gFrontEnd )
				)
				( attribute "VER" "1"
					( Origin gFrontEnd )
				)
				( attribute "VOLTAGE" "16V"
					( Units "uVoltage" "V" 1.000000)
					( Origin gFrontEnd )
				)
				( attribute "XY" "(-2050,175)"
					( Origin gFrontEnd )
				)
				( attribute "CHIPS_PART_NAME" "CAP"
					( Origin gPackager )
				)
				( attribute "CDS_PART_NAME" "CAP_0805-10UF,16V,10%,X6S,C953A"
					( Origin gPackager )
				)
				( attribute "CDS_SEC" "1"
					( Origin gPackager )
				)
				( objectStatus "C3U6" )
			)
			( gate "@baseboard_fab2_lib.baseboard_fab2(sch_1):page216_i102"
				( attribute "CDS_LIB" "mstr_discrete"
					( Origin gPackager )
				)
				( attribute "CDS_LOCATION" "EU7G2"
					( Origin gPackager )
				)
				( attribute "LOCATION" "EU7G2"
					( Origin gFrontEnd )
				)
				( attribute "MATERIAL" "IC"
					( Origin gFrontEnd )
				)
				( attribute "NO_XNET_CONNECTION" "1"
					( Origin gFrontEnd )
				)
				( attribute "PACK_TYPE" "SM"
					( Origin gFrontEnd )
				)
				( attribute "PART_NUMBER" "H73688-001"
					( Origin gFrontEnd )
				)
				( attribute "PHYS_PAGE" "216"
					( Origin gFrontEnd )
				)
				( attribute "ROT" "0"
					( Origin gFrontEnd )
				)
				( attribute "SEC" "1"
					( Origin gFrontEnd )
				)
				( attribute "SEC_TYPE" "SM"
					( Origin gFrontEnd )
				)
				( attribute "VALUE" "IR35411"
					( Origin gFrontEnd )
				)
				( attribute "VER" "1"
					( Origin gFrontEnd )
				)
				( attribute "XY" "(1775,2300)"
					( Origin gFrontEnd )
				)
				( attribute "CHIPS_PART_NAME" "IR354XX"
					( Origin gPackager )
				)
				( attribute "CDS_PART_NAME" "IR354XX_SM-IR35411,IC,H73688-0A"
					( Origin gPackager )
				)
				( attribute "CDS_SEC" "1"
					( Origin gPackager )
				)
				( objectStatus "EU7G2" )
			)
			( gate "@baseboard_fab2_lib.baseboard_fab2(sch_1):page216_i103"
				( attribute "CDS_LIB" "mstr_discrete"
					( Origin gPackager )
				)
				( attribute "CDS_LOCATION" "EU7G3"
					( Origin gPackager )
				)
				( attribute "LOCATION" "EU7G3"
					( Origin gFrontEnd )
				)
				( attribute "MATERIAL" "IC"
					( Origin gFrontEnd )
				)
				( attribute "NO_XNET_CONNECTION" "1"
					( Origin gFrontEnd )
				)
				( attribute "PACK_TYPE" "SM"
					( Origin gFrontEnd )
				)
				( attribute "PART_NUMBER" "H73688-001"
					( Origin gFrontEnd )
				)
				( attribute "PHYS_PAGE" "216"
					( Origin gFrontEnd )
				)
				( attribute "ROT" "0"
					( Origin gFrontEnd )
				)
				( attribute "SEC" "1"
					( Origin gFrontEnd )
				)
				( attribute "SEC_TYPE" "SM"
					( Origin gFrontEnd )
				)
				( attribute "VALUE" "IR35411"
					( Origin gFrontEnd )
				)
				( attribute "VER" "1"
					( Origin gFrontEnd )
				)
				( attribute "XY" "(1775,-75)"
					( Origin gFrontEnd )
				)
				( attribute "CHIPS_PART_NAME" "IR354XX"
					( Origin gPackager )
				)
				( attribute "CDS_PART_NAME" "IR354XX_SM-IR35411,IC,H73688-0A"
					( Origin gPackager )
				)
				( attribute "CDS_SEC" "1"
					( Origin gPackager )
				)
				( attribute "BOM_SS" "NOPOP"
					( Origin gFrontEnd )
				)
				( objectStatus "EU7G3" )
			)
			( gate "@baseboard_fab2_lib.baseboard_fab2(sch_1):page216_i104"
				( attribute "CDS_LIB" "mstr_discrete"
					( Origin gPackager )
				)
				( attribute "LOCATION" "R7G25"
					( Origin gFrontEnd )
				)
				( attribute "MATERIAL" "EMPTY"
					( Origin gFrontEnd )
				)
				( attribute "PACK_TYPE" "0402"
					( Origin gFrontEnd )
				)
				( attribute "PART_NUMBER" "G21796-187"
					( Origin gFrontEnd )
				)
				( attribute "PHYS_PAGE" "216"
					( Origin gFrontEnd )
				)
				( attribute "ROT" "0"
					( Origin gFrontEnd )
				)
				( attribute "SEC" "1"
					( Origin gFrontEnd )
				)
				( attribute "SEC_TYPE" "0402"
					( Origin gFrontEnd )
				)
				( attribute "TOLERANCE" "1%"
					( Origin gFrontEnd )
				)
				( attribute "VALUE" "68.1K"
					( Origin gFrontEnd )
				)
				( attribute "VER" "2"
					( Origin gFrontEnd )
				)
				( attribute "WATTAGE" "1/16W"
					( Origin gFrontEnd )
				)
				( attribute "XY" "(4575,2450)"
					( Origin gFrontEnd )
				)
				( attribute "CHIPS_PART_NAME" "RES"
					( Origin gPackager )
				)
				( attribute "CDS_PART_NAME" "RES_0402-68.1K,1%,1/16W,EMPTY,A"
					( Origin gPackager )
				)
				( attribute "CDS_LOCATION" "R7G25"
					( Origin gPackager )
				)
				( attribute "CDS_SEC" "1"
					( Origin gPackager )
				)
				( objectStatus "R7G25" )
			)
			( gate "@baseboard_fab2_lib.baseboard_fab2(sch_1):page216_i106"
				( attribute "CDS_LIB" "mstr_discrete"
					( Origin gPackager )
				)
				( attribute "LOCATION" "R7G30"
					( Origin gFrontEnd )
				)
				( attribute "MATERIAL" "EMPTY"
					( Origin gFrontEnd )
				)
				( attribute "PACK_TYPE" "0402"
					( Origin gFrontEnd )
				)
				( attribute "PART_NUMBER" "G21796-187"
					( Origin gFrontEnd )
				)
				( attribute "PHYS_PAGE" "216"
					( Origin gFrontEnd )
				)
				( attribute "ROT" "0"
					( Origin gFrontEnd )
				)
				( attribute "SEC" "1"
					( Origin gFrontEnd )
				)
				( attribute "SEC_TYPE" "0402"
					( Origin gFrontEnd )
				)
				( attribute "TOLERANCE" "1%"
					( Origin gFrontEnd )
				)
				( attribute "VALUE" "68.1K"
					( Origin gFrontEnd )
				)
				( attribute "VER" "2"
					( Origin gFrontEnd )
				)
				( attribute "WATTAGE" "1/16W"
					( Origin gFrontEnd )
				)
				( attribute "XY" "(4675,50)"
					( Origin gFrontEnd )
				)
				( attribute "CHIPS_PART_NAME" "RES"
					( Origin gPackager )
				)
				( attribute "CDS_PART_NAME" "RES_0402-68.1K,1%,1/16W,EMPTY,A"
					( Origin gPackager )
				)
				( attribute "CDS_LOCATION" "R7G30"
					( Origin gPackager )
				)
				( attribute "CDS_SEC" "1"
					( Origin gPackager )
				)
				( attribute "BOM_SS" "NOPOP"
					( Origin gFrontEnd )
				)
				( objectStatus "R7G30" )
			)
			( gate "@baseboard_fab2_lib.baseboard_fab2(sch_1):page217_i58"
				( attribute "BOM_COST" "MEM_VRD_PVPP_AB"
					( Origin gFrontEnd )
				)
				( attribute "CDS_LIB" "mstr_discrete"
					( Origin gPackager )
				)
				( attribute "CDS_LOCATION" "R3U4"
					( Origin gPackager )
				)
				( attribute "CDS_SEC" "1"
					( Origin gPackager )
				)
				( attribute "LOCATION" "R3U4"
					( Origin gFrontEnd )
				)
				( attribute "MATERIAL" "CHIP"
					( Origin gFrontEnd )
				)
				( attribute "PACK_TYPE" "0603"
					( Origin gFrontEnd )
				)
				( attribute "PART_NUMBER" "G22026-003"
					( Origin gFrontEnd )
				)
				( attribute "PHYS_PAGE" "217"
					( Origin gFrontEnd )
				)
				( attribute "ROOM" "VDDQ_ABC_PWR_VR"
					( Origin gFrontEnd )
				)
				( attribute "ROT" "0"
					( Origin gFrontEnd )
				)
				( attribute "SEC" "1"
					( Origin gPackager )
				)
				( attribute "TOLERANCE" "1%"
					( Origin gFrontEnd )
				)
				( attribute "VALUE" "120.0"
					( Origin gFrontEnd )
				)
				( attribute "VER" "2"
					( Origin gFrontEnd )
				)
				( attribute "WATTAGE" "1/10W"
					( Origin gFrontEnd )
				)
				( attribute "XY" "(4550,-400)"
					( Origin gFrontEnd )
				)
				( attribute "CHIPS_PART_NAME" "RES"
					( Origin gPackager )
				)
				( attribute "CDS_PART_NAME" "RES_0603-120.0,1%,1/10W,CHIP,GA"
					( Origin gPackager )
				)
				( objectStatus "R3U4" )
			)
			( gate "@baseboard_fab2_lib.baseboard_fab2(sch_1):page217_i74"
				( attribute "CDS_LIB" "mstr_discrete"
					( Origin gPackager )
				)
				( attribute "CDS_LOCATION" "R4U6"
					( Origin gPackager )
				)
				( attribute "CDS_SEC" "1"
					( Origin gPackager )
				)
				( attribute "LOCATION" "R4U6"
					( Origin gFrontEnd )
				)
				( attribute "MATERIAL" "EMPTY"
					( Origin gFrontEnd )
				)
				( attribute "PACK_TYPE" "0402"
					( Origin gFrontEnd )
				)
				( attribute "PART_NUMBER" "G21796-017"
					( Origin gFrontEnd )
				)
				( attribute "PHYS_PAGE" "217"
					( Origin gFrontEnd )
				)
				( attribute "ROOM" "VDDQ_ABC_PWR_VR"
					( Origin gFrontEnd )
				)
				( attribute "ROT" "0"
					( Origin gFrontEnd )
				)
				( attribute "SEC" "1"
					( Origin gFrontEnd )
				)
				( attribute "SEC_TYPE" "0402"
					( Origin gFrontEnd )
				)
				( attribute "TOLERANCE" "1%"
					( Origin gFrontEnd )
				)
				( attribute "VALUE" "100.0"
					( Origin gFrontEnd )
				)
				( attribute "VER" "2"
					( Origin gFrontEnd )
				)
				( attribute "WATTAGE" "1/16W"
					( Origin gFrontEnd )
				)
				( attribute "XY" "(-250,1700)"
					( Origin gFrontEnd )
				)
				( attribute "CHIPS_PART_NAME" "RES"
					( Origin gPackager )
				)
				( attribute "CDS_PART_NAME" "RES_0402-100.0,1%,1/16W,EMPTY,A"
					( Origin gPackager )
				)
				( objectStatus "R4U6" )
			)
			( gate "@baseboard_fab2_lib.baseboard_fab2(sch_1):page217_i75"
				( attribute "CDS_LIB" "mstr_discrete"
					( Origin gPackager )
				)
				( attribute "CDS_LOCATION" "C7G28"
					( Origin gPackager )
				)
				( attribute "CDS_SEC" "1"
					( Origin gPackager )
				)
				( attribute "LOCATION" "C7G28"
					( Origin gFrontEnd )
				)
				( attribute "MATERIAL" "ALUM"
					( Origin gFrontEnd )
				)
				( attribute "PACK_TYPE" "3018"
					( Origin gFrontEnd )
				)
				( attribute "PART_NUMBER" "699013-049"
					( Origin gFrontEnd )
				)
				( attribute "PHYS_PAGE" "217"
					( Origin gFrontEnd )
				)
				( attribute "ROOM" "VDDQ_ABC_PWR_VR"
					( Origin gFrontEnd )
				)
				( attribute "ROT" "0"
					( Origin gFrontEnd )
				)
				( attribute "SEC" "1"
					( Origin gFrontEnd )
				)
				( attribute "SEC_TYPE" "3018"
					( Origin gFrontEnd )
				)
				( attribute "TOLERANCE" "20%"
					( Origin gFrontEnd )
				)
				( attribute "VALUE" "470UF"
					( Origin gFrontEnd )
				)
				( attribute "VER" "1"
					( Origin gFrontEnd )
				)
				( attribute "VOLTAGE" "2.5V"
					( Units "uVoltage" "V" 1.000000)
					( Origin gFrontEnd )
				)
				( attribute "XY" "(3350,-400)"
					( Origin gFrontEnd )
				)
				( attribute "CHIPS_PART_NAME" "CAPP"
					( Origin gPackager )
				)
				( attribute "CDS_PART_NAME" "CAPP_3018-470UF,2.5V,20%,ALUM,A"
					( Origin gPackager )
				)
				( attribute "GROUP" "PWR_BULK_CAP"
					( Origin gFrontEnd )
				)
				( objectStatus "C7G28" )
			)
			( gate "@baseboard_fab2_lib.baseboard_fab2(sch_1):page217_i76"
				( attribute "CDS_LIB" "mstr_discrete"
					( Origin gPackager )
				)
				( attribute "CDS_LOCATION" "C3U1"
					( Origin gPackager )
				)
				( attribute "CDS_SEC" "1"
					( Origin gPackager )
				)
				( attribute "LOCATION" "C3U1"
					( Origin gFrontEnd )
				)
				( attribute "MATERIAL" "ALUM"
					( Origin gFrontEnd )
				)
				( attribute "PACK_TYPE" "3018"
					( Origin gFrontEnd )
				)
				( attribute "PART_NUMBER" "699013-049"
					( Origin gFrontEnd )
				)
				( attribute "PHYS_PAGE" "217"
					( Origin gFrontEnd )
				)
				( attribute "ROOM" "VDDQ_ABC_PWR_VR"
					( Origin gFrontEnd )
				)
				( attribute "ROT" "0"
					( Origin gFrontEnd )
				)
				( attribute "SEC" "1"
					( Origin gFrontEnd )
				)
				( attribute "SEC_TYPE" "3018"
					( Origin gFrontEnd )
				)
				( attribute "TOLERANCE" "20%"
					( Origin gFrontEnd )
				)
				( attribute "VALUE" "470UF"
					( Origin gFrontEnd )
				)
				( attribute "VER" "1"
					( Origin gFrontEnd )
				)
				( attribute "VOLTAGE" "2.5V"
					( Units "uVoltage" "V" 1.000000)
					( Origin gFrontEnd )
				)
				( attribute "XY" "(3650,-400)"
					( Origin gFrontEnd )
				)
				( attribute "CHIPS_PART_NAME" "CAPP"
					( Origin gPackager )
				)
				( attribute "CDS_PART_NAME" "CAPP_3018-470UF,2.5V,20%,ALUM,A"
					( Origin gPackager )
				)
				( attribute "GROUP" "PWR_BULK_CAP"
					( Origin gFrontEnd )
				)
				( objectStatus "C3U1" )
			)
			( gate "@baseboard_fab2_lib.baseboard_fab2(sch_1):page217_i77"
				( attribute "CDS_LIB" "mstr_discrete"
					( Origin gPackager )
				)
				( attribute "CDS_LOCATION" "C3U5"
					( Origin gPackager )
				)
				( attribute "CDS_SEC" "1"
					( Origin gPackager )
				)
				( attribute "LOCATION" "C3U5"
					( Origin gFrontEnd )
				)
				( attribute "MATERIAL" "ALUM"
					( Origin gFrontEnd )
				)
				( attribute "PACK_TYPE" "3018"
					( Origin gFrontEnd )
				)
				( attribute "PART_NUMBER" "699013-049"
					( Origin gFrontEnd )
				)
				( attribute "PHYS_PAGE" "217"
					( Origin gFrontEnd )
				)
				( attribute "ROOM" "VDDQ_ABC_PWR_VR"
					( Origin gFrontEnd )
				)
				( attribute "ROT" "0"
					( Origin gFrontEnd )
				)
				( attribute "SEC" "1"
					( Origin gFrontEnd )
				)
				( attribute "SEC_TYPE" "3018"
					( Origin gFrontEnd )
				)
				( attribute "TOLERANCE" "20%"
					( Origin gFrontEnd )
				)
				( attribute "VALUE" "470UF"
					( Origin gFrontEnd )
				)
				( attribute "VER" "1"
					( Origin gFrontEnd )
				)
				( attribute "VOLTAGE" "2.5V"
					( Units "uVoltage" "V" 1.000000)
					( Origin gFrontEnd )
				)
				( attribute "XY" "(3950,-400)"
					( Origin gFrontEnd )
				)
				( attribute "CHIPS_PART_NAME" "CAPP"
					( Origin gPackager )
				)
				( attribute "CDS_PART_NAME" "CAPP_3018-470UF,2.5V,20%,ALUM,A"
					( Origin gPackager )
				)
				( attribute "GROUP" "PWR_BULK_CAP"
					( Origin gFrontEnd )
				)
				( objectStatus "C3U5" )
			)
			( gate "@baseboard_fab2_lib.baseboard_fab2(sch_1):page217_i78"
				( attribute "CDS_LIB" "mstr_discrete"
					( Origin gPackager )
				)
				( attribute "CDS_LOCATION" "C3U8"
					( Origin gPackager )
				)
				( attribute "CDS_SEC" "1"
					( Origin gPackager )
				)
				( attribute "LOCATION" "C3U8"
					( Origin gFrontEnd )
				)
				( attribute "MATERIAL" "ALUM"
					( Origin gFrontEnd )
				)
				( attribute "PACK_TYPE" "3018"
					( Origin gFrontEnd )
				)
				( attribute "PART_NUMBER" "699013-049"
					( Origin gFrontEnd )
				)
				( attribute "PHYS_PAGE" "217"
					( Origin gFrontEnd )
				)
				( attribute "ROOM" "VDDQ_ABC_PWR_VR"
					( Origin gFrontEnd )
				)
				( attribute "ROT" "0"
					( Origin gFrontEnd )
				)
				( attribute "SEC" "1"
					( Origin gFrontEnd )
				)
				( attribute "SEC_TYPE" "3018"
					( Origin gFrontEnd )
				)
				( attribute "TOLERANCE" "20%"
					( Origin gFrontEnd )
				)
				( attribute "VALUE" "470UF"
					( Origin gFrontEnd )
				)
				( attribute "VER" "1"
					( Origin gFrontEnd )
				)
				( attribute "VOLTAGE" "2.5V"
					( Units "uVoltage" "V" 1.000000)
					( Origin gFrontEnd )
				)
				( attribute "XY" "(4250,-400)"
					( Origin gFrontEnd )
				)
				( attribute "CHIPS_PART_NAME" "CAPP"
					( Origin gPackager )
				)
				( attribute "CDS_PART_NAME" "CAPP_3018-470UF,2.5V,20%,ALUM,A"
					( Origin gPackager )
				)
				( attribute "GROUP" "PWR_BULK_CAP"
					( Origin gFrontEnd )
				)
				( objectStatus "C3U8" )
			)
			( gate "@baseboard_fab2_lib.baseboard_fab2(sch_1):page217_i322"
				( attribute "BOM_COST" "MEM_VRD_PVDDQ_CD"
					( Origin gFrontEnd )
				)
				( attribute "CDS_LIB" "mstr_discrete"
					( Origin gPackager )
				)
				( attribute "CDS_LOCATION" "C5U14"
					( Origin gPackager )
				)
				( attribute "CDS_SEC" "1"
					( Origin gPackager )
				)
				( attribute "LOCATION" "C5U14"
					( Origin gFrontEnd )
				)
				( attribute "MATERIAL" "X5R"
					( Origin gFrontEnd )
				)
				( attribute "NEW_MATERIAL" "X6S"
					( Origin gFrontEnd )
				)
				( attribute "PACK_TYPE" "0805"
					( Origin gFrontEnd )
				)
				( attribute "PART_NUMBER" "602433-112"
					( Origin gFrontEnd )
				)
				( attribute "PHYS_PAGE" "217"
					( Origin gFrontEnd )
				)
				( attribute "ROOM" "VDDQ_ABC_PWR_VR"
					( Origin gFrontEnd )
				)
				( attribute "ROT" "0"
					( Origin gFrontEnd )
				)
				( attribute "SEC" "1"
					( Origin gFrontEnd )
				)
				( attribute "SEC_TYPE" "0805"
					( Origin gFrontEnd )
				)
				( attribute "TOLERANCE" "20%"
					( Origin gFrontEnd )
				)
				( attribute "VALUE" "100UF"
					( Origin gFrontEnd )
				)
				( attribute "VER" "1"
					( Origin gFrontEnd )
				)
				( attribute "VOLTAGE" "4V"
					( Units "uVoltage" "V" 1.000000)
					( Origin gFrontEnd )
				)
				( attribute "XY" "(4325,2850)"
					( Origin gFrontEnd )
				)
				( attribute "CHIPS_PART_NAME" "CAP"
					( Origin gPackager )
				)
				( attribute "CDS_PART_NAME" "CAP_0805-100UF,4V,20%,X5R,6024A"
					( Origin gPackager )
				)
				( attribute "GROUP" "PWR_MLCC_CAP"
					( Origin gFrontEnd )
				)
				( attribute "NEW_PN" "078.1071T.M002"
					( Origin gFrontEnd )
				)
				( attribute "BOM_SS" "NOPOP"
					( Origin gFrontEnd )
				)
				( objectStatus "C5U14" )
			)
			( gate "@baseboard_fab2_lib.baseboard_fab2(sch_1):page217_i319"
				( attribute "BOM_COST" "MEM_VRD_PVDDQ_CD"
					( Origin gFrontEnd )
				)
				( attribute "CDS_LIB" "mstr_discrete"
					( Origin gPackager )
				)
				( attribute "CDS_LOCATION" "C4T4"
					( Origin gPackager )
				)
				( attribute "CDS_SEC" "1"
					( Origin gPackager )
				)
				( attribute "LOCATION" "C4T4"
					( Origin gFrontEnd )
				)
				( attribute "MATERIAL" "X5R"
					( Origin gFrontEnd )
				)
				( attribute "NEW_MATERIAL" "X6S"
					( Origin gFrontEnd )
				)
				( attribute "PACK_TYPE" "0805"
					( Origin gFrontEnd )
				)
				( attribute "PART_NUMBER" "602433-112"
					( Origin gFrontEnd )
				)
				( attribute "PHYS_PAGE" "217"
					( Origin gFrontEnd )
				)
				( attribute "ROOM" "VDDQ_ABC_PWR_VR"
					( Origin gFrontEnd )
				)
				( attribute "ROT" "0"
					( Origin gFrontEnd )
				)
				( attribute "SEC" "1"
					( Origin gFrontEnd )
				)
				( attribute "SEC_TYPE" "0805"
					( Origin gFrontEnd )
				)
				( attribute "TOLERANCE" "20%"
					( Origin gFrontEnd )
				)
				( attribute "VALUE" "100UF"
					( Origin gFrontEnd )
				)
				( attribute "VER" "1"
					( Origin gFrontEnd )
				)
				( attribute "VOLTAGE" "4V"
					( Units "uVoltage" "V" 1.000000)
					( Origin gFrontEnd )
				)
				( attribute "XY" "(3625,2850)"
					( Origin gFrontEnd )
				)
				( attribute "CHIPS_PART_NAME" "CAP"
					( Origin gPackager )
				)
				( attribute "CDS_PART_NAME" "CAP_0805-100UF,4V,20%,X5R,6024A"
					( Origin gPackager )
				)
				( attribute "GROUP" "PWR_MLCC_CAP"
					( Origin gFrontEnd )
				)
				( attribute "NEW_PN" "078.1071T.M002"
					( Origin gFrontEnd )
				)
				( attribute "BOM_SS" "NOPOP"
					( Origin gFrontEnd )
				)
				( objectStatus "C4T4" )
			)
			( gate "@baseboard_fab2_lib.baseboard_fab2(sch_1):page217_i318"
				( attribute "BOM_COST" "MEM_VRD_PVDDQ_CD"
					( Origin gFrontEnd )
				)
				( attribute "CDS_LIB" "mstr_discrete"
					( Origin gPackager )
				)
				( attribute "CDS_LOCATION" "C5G9"
					( Origin gPackager )
				)
				( attribute "CDS_SEC" "1"
					( Origin gPackager )
				)
				( attribute "LOCATION" "C5G9"
					( Origin gFrontEnd )
				)
				( attribute "MATERIAL" "X5R"
					( Origin gFrontEnd )
				)
				( attribute "NEW_MATERIAL" "X6S"
					( Origin gFrontEnd )
				)
				( attribute "PACK_TYPE" "0805"
					( Origin gFrontEnd )
				)
				( attribute "PART_NUMBER" "602433-112"
					( Origin gFrontEnd )
				)
				( attribute "PHYS_PAGE" "217"
					( Origin gFrontEnd )
				)
				( attribute "ROOM" "VDDQ_ABC_PWR_VR"
					( Origin gFrontEnd )
				)
				( attribute "ROT" "0"
					( Origin gFrontEnd )
				)
				( attribute "SEC" "1"
					( Origin gFrontEnd )
				)
				( attribute "SEC_TYPE" "0805"
					( Origin gFrontEnd )
				)
				( attribute "TOLERANCE" "20%"
					( Origin gFrontEnd )
				)
				( attribute "VALUE" "100UF"
					( Origin gFrontEnd )
				)
				( attribute "VER" "1"
					( Origin gFrontEnd )
				)
				( attribute "VOLTAGE" "4V"
					( Units "uVoltage" "V" 1.000000)
					( Origin gFrontEnd )
				)
				( attribute "XY" "(3225,2850)"
					( Origin gFrontEnd )
				)
				( attribute "CHIPS_PART_NAME" "CAP"
					( Origin gPackager )
				)
				( attribute "CDS_PART_NAME" "CAP_0805-100UF,4V,20%,X5R,6024A"
					( Origin gPackager )
				)
				( attribute "GROUP" "PWR_MLCC_CAP"
					( Origin gFrontEnd )
				)
				( attribute "NEW_PN" "078.1071T.M002"
					( Origin gFrontEnd )
				)
				( attribute "BOM_SS" "NOPOP"
					( Origin gFrontEnd )
				)
				( objectStatus "C5G9" )
			)
			( gate "@baseboard_fab2_lib.baseboard_fab2(sch_1):page217_i323"
				( attribute "BOM_COST" "MEM_VRD_PVDDQ_CD"
					( Origin gFrontEnd )
				)
				( attribute "CDS_LIB" "mstr_discrete"
					( Origin gPackager )
				)
				( attribute "CDS_LOCATION" "C5P41"
					( Origin gPackager )
				)
				( attribute "CDS_SEC" "1"
					( Origin gPackager )
				)
				( attribute "LOCATION" "C5P41"
					( Origin gFrontEnd )
				)
				( attribute "MATERIAL" "X5R"
					( Origin gFrontEnd )
				)
				( attribute "NEW_MATERIAL" "X6S"
					( Origin gFrontEnd )
				)
				( attribute "PACK_TYPE" "0805"
					( Origin gFrontEnd )
				)
				( attribute "PART_NUMBER" "602433-112"
					( Origin gFrontEnd )
				)
				( attribute "PHYS_PAGE" "217"
					( Origin gFrontEnd )
				)
				( attribute "ROOM" "VDDQ_ABC_PWR_VR"
					( Origin gFrontEnd )
				)
				( attribute "ROT" "0"
					( Origin gFrontEnd )
				)
				( attribute "SEC" "1"
					( Origin gFrontEnd )
				)
				( attribute "SEC_TYPE" "0805"
					( Origin gFrontEnd )
				)
				( attribute "TOLERANCE" "20%"
					( Origin gFrontEnd )
				)
				( attribute "VALUE" "100UF"
					( Origin gFrontEnd )
				)
				( attribute "VER" "1"
					( Origin gFrontEnd )
				)
				( attribute "VOLTAGE" "4V"
					( Units "uVoltage" "V" 1.000000)
					( Origin gFrontEnd )
				)
				( attribute "XY" "(2000,2875)"
					( Origin gFrontEnd )
				)
				( attribute "CHIPS_PART_NAME" "CAP"
					( Origin gPackager )
				)
				( attribute "CDS_PART_NAME" "CAP_0805-100UF,4V,20%,X5R,6024A"
					( Origin gPackager )
				)
				( attribute "GROUP" "PWR_MLCC_CAP"
					( Origin gFrontEnd )
				)
				( attribute "NEW_PN" "078.1071T.M002"
					( Origin gFrontEnd )
				)
				( attribute "BOM_SS" "NOPOP"
					( Origin gFrontEnd )
				)
				( objectStatus "C5P41" )
			)
			( gate "@baseboard_fab2_lib.baseboard_fab2(sch_1):page217_i326"
				( attribute "BOM_COST" "MEM_VRD_PVDDQ_CD"
					( Origin gFrontEnd )
				)
				( attribute "CDS_LIB" "mstr_discrete"
					( Origin gPackager )
				)
				( attribute "LOCATION" "C5P43"
					( Origin gFrontEnd )
				)
				( attribute "MATERIAL" "X5R"
					( Origin gFrontEnd )
				)
				( attribute "NEW_MATERIAL" "X6S"
					( Origin gFrontEnd )
				)
				( attribute "PACK_TYPE" "0805"
					( Origin gFrontEnd )
				)
				( attribute "PART_NUMBER" "602433-112"
					( Origin gFrontEnd )
				)
				( attribute "PHYS_PAGE" "217"
					( Origin gFrontEnd )
				)
				( attribute "ROOM" "VDDQ_ABC_PWR_VR"
					( Origin gFrontEnd )
				)
				( attribute "ROT" "0"
					( Origin gFrontEnd )
				)
				( attribute "TOLERANCE" "20%"
					( Origin gFrontEnd )
				)
				( attribute "VALUE" "100UF"
					( Origin gFrontEnd )
				)
				( attribute "VER" "1"
					( Origin gFrontEnd )
				)
				( attribute "VOLTAGE" "4V"
					( Units "uVoltage" "V" 1.000000)
					( Origin gFrontEnd )
				)
				( attribute "XY" "(1025,2850)"
					( Origin gFrontEnd )
				)
				( attribute "CHIPS_PART_NAME" "CAP"
					( Origin gPackager )
				)
				( attribute "CDS_PART_NAME" "CAP_0805-100UF,4V,20%,X5R,6024A"
					( Origin gPackager )
				)
				( attribute "CDS_LOCATION" "C5P43"
					( Origin gPackager )
				)
				( attribute "CDS_SEC" "1"
					( Origin gPackager )
				)
				( attribute "SEC" "1"
					( Origin gPackager )
				)
				( attribute "GROUP" "PWR_MLCC_CAP"
					( Origin gFrontEnd )
				)
				( attribute "NEW_PN" "078.1071T.M002"
					( Origin gFrontEnd )
				)
				( attribute "BOM_SS" "NOPOP"
					( Origin gFrontEnd )
				)
				( objectStatus "C5P43" )
			)
			( gate "@baseboard_fab2_lib.baseboard_fab2(sch_1):page217_i325"
				( attribute "BOM_COST" "MEM_VRD_PVDDQ_CD"
					( Origin gFrontEnd )
				)
				( attribute "CDS_LIB" "mstr_discrete"
					( Origin gPackager )
				)
				( attribute "LOCATION" "C5P42"
					( Origin gFrontEnd )
				)
				( attribute "MATERIAL" "X5R"
					( Origin gFrontEnd )
				)
				( attribute "NEW_MATERIAL" "X6S"
					( Origin gFrontEnd )
				)
				( attribute "PACK_TYPE" "0805"
					( Origin gFrontEnd )
				)
				( attribute "PART_NUMBER" "602433-112"
					( Origin gFrontEnd )
				)
				( attribute "PHYS_PAGE" "217"
					( Origin gFrontEnd )
				)
				( attribute "ROOM" "VDDQ_ABC_PWR_VR"
					( Origin gFrontEnd )
				)
				( attribute "ROT" "0"
					( Origin gFrontEnd )
				)
				( attribute "TOLERANCE" "20%"
					( Origin gFrontEnd )
				)
				( attribute "VALUE" "100UF"
					( Origin gFrontEnd )
				)
				( attribute "VER" "1"
					( Origin gFrontEnd )
				)
				( attribute "VOLTAGE" "4V"
					( Units "uVoltage" "V" 1.000000)
					( Origin gFrontEnd )
				)
				( attribute "XY" "(1375,2850)"
					( Origin gFrontEnd )
				)
				( attribute "CHIPS_PART_NAME" "CAP"
					( Origin gPackager )
				)
				( attribute "CDS_PART_NAME" "CAP_0805-100UF,4V,20%,X5R,6024A"
					( Origin gPackager )
				)
				( attribute "CDS_LOCATION" "C5P42"
					( Origin gPackager )
				)
				( attribute "CDS_SEC" "1"
					( Origin gPackager )
				)
				( attribute "SEC" "1"
					( Origin gPackager )
				)
				( attribute "GROUP" "PWR_MLCC_CAP"
					( Origin gFrontEnd )
				)
				( attribute "NEW_PN" "078.1071T.M002"
					( Origin gFrontEnd )
				)
				( attribute "BOM_SS" "NOPOP"
					( Origin gFrontEnd )
				)
				( objectStatus "C5P42" )
			)
			( gate "@baseboard_fab2_lib.baseboard_fab2(sch_1):page217_i321"
				( attribute "BOM_COST" "MEM_VRD_PVDDQ_CD"
					( Origin gFrontEnd )
				)
				( attribute "CDS_LIB" "mstr_discrete"
					( Origin gPackager )
				)
				( attribute "CDS_LOCATION" "C5U13"
					( Origin gPackager )
				)
				( attribute "CDS_SEC" "1"
					( Origin gPackager )
				)
				( attribute "LOCATION" "C5U13"
					( Origin gFrontEnd )
				)
				( attribute "MATERIAL" "X5R"
					( Origin gFrontEnd )
				)
				( attribute "NEW_MATERIAL" "X6S"
					( Origin gFrontEnd )
				)
				( attribute "PACK_TYPE" "0805"
					( Origin gFrontEnd )
				)
				( attribute "PART_NUMBER" "602433-112"
					( Origin gFrontEnd )
				)
				( attribute "PHYS_PAGE" "217"
					( Origin gFrontEnd )
				)
				( attribute "ROOM" "VDDQ_ABC_PWR_VR"
					( Origin gFrontEnd )
				)
				( attribute "ROT" "0"
					( Origin gFrontEnd )
				)
				( attribute "SEC" "1"
					( Origin gFrontEnd )
				)
				( attribute "SEC_TYPE" "0805"
					( Origin gFrontEnd )
				)
				( attribute "TOLERANCE" "20%"
					( Origin gFrontEnd )
				)
				( attribute "VALUE" "100UF"
					( Origin gFrontEnd )
				)
				( attribute "VER" "1"
					( Origin gFrontEnd )
				)
				( attribute "VOLTAGE" "4V"
					( Units "uVoltage" "V" 1.000000)
					( Origin gFrontEnd )
				)
				( attribute "XY" "(5475,2850)"
					( Origin gFrontEnd )
				)
				( attribute "CHIPS_PART_NAME" "CAP"
					( Origin gPackager )
				)
				( attribute "CDS_PART_NAME" "CAP_0805-100UF,4V,20%,X5R,6024A"
					( Origin gPackager )
				)
				( attribute "GROUP" "PWR_MLCC_CAP"
					( Origin gFrontEnd )
				)
				( attribute "NEW_PN" "078.1071T.M002"
					( Origin gFrontEnd )
				)
				( attribute "BOM_SS" "NOPOP"
					( Origin gFrontEnd )
				)
				( objectStatus "C5U13" )
			)
			( gate "@baseboard_fab2_lib.baseboard_fab2(sch_1):page220_i308"
				( attribute "BOM_COST" "MEM_VRD_PVDDQ_CD"
					( Origin gFrontEnd )
				)
				( attribute "CDS_LIB" "mstr_discrete"
					( Origin gPackager )
				)
				( attribute "CDS_LOCATION" "C5A20"
					( Origin gPackager )
				)
				( attribute "CDS_SEC" "1"
					( Origin gPackager )
				)
				( attribute "LOCATION" "C5A20"
					( Origin gFrontEnd )
				)
				( attribute "MATERIAL" "X5R"
					( Origin gFrontEnd )
				)
				( attribute "NEW_MATERIAL" "X6S"
					( Origin gFrontEnd )
				)
				( attribute "PACK_TYPE" "0805"
					( Origin gFrontEnd )
				)
				( attribute "PART_NUMBER" "602433-112"
					( Origin gFrontEnd )
				)
				( attribute "PHYS_PAGE" "220"
					( Origin gFrontEnd )
				)
				( attribute "ROOM" "VDDQ_ABC_PWR_VR"
					( Origin gFrontEnd )
				)
				( attribute "ROT" "0"
					( Origin gFrontEnd )
				)
				( attribute "SEC" "1"
					( Origin gFrontEnd )
				)
				( attribute "SEC_TYPE" "0805"
					( Origin gFrontEnd )
				)
				( attribute "TOLERANCE" "20%"
					( Origin gFrontEnd )
				)
				( attribute "VALUE" "100UF"
					( Origin gFrontEnd )
				)
				( attribute "VER" "1"
					( Origin gFrontEnd )
				)
				( attribute "VOLTAGE" "4V"
					( Units "uVoltage" "V" 1.000000)
					( Origin gFrontEnd )
				)
				( attribute "XY" "(2750,2825)"
					( Origin gFrontEnd )
				)
				( attribute "CHIPS_PART_NAME" "CAP"
					( Origin gPackager )
				)
				( attribute "CDS_PART_NAME" "CAP_0805-100UF,4V,20%,X5R,6024A"
					( Origin gPackager )
				)
				( attribute "GROUP" "PWR_MLCC_CAP"
					( Origin gFrontEnd )
				)
				( attribute "NEW_PN" "078.1071T.M002"
					( Origin gFrontEnd )
				)
				( attribute "BOM_SS" "NOPOP"
					( Origin gFrontEnd )
				)
				( objectStatus "C5A20" )
			)
			( gate "@baseboard_fab2_lib.baseboard_fab2(sch_1):page220_i241"
				( attribute "CDS_LIB" "w_hdl"
					( Origin gPackager )
				)
				( attribute "CDS_LMAN_SYM_OUTLINE" "-75,100,75,-100"
					( Origin gPackager )
				)
				( attribute "LOCATION" "L7A5"
					( Origin gFrontEnd )
				)
				( attribute "PACK_TYPE" "DISCRET-G8"
					( Origin gFrontEnd )
				)
				( attribute "PART_NUMBER" "068.1011N.M001"
					( Origin gFrontEnd )
				)
				( attribute "PHYS_PAGE" "220"
					( Origin gFrontEnd )
				)
				( attribute "ROT" "1"
					( Origin gFrontEnd )
				)
				( attribute "SEC" "1"
					( Origin gFrontEnd )
				)
				( attribute "SEC_TYPE" "DISCRET-G8"
					( Origin gFrontEnd )
				)
				( attribute "VALUE" "IND-100NH-35-GP"
					( Origin gFrontEnd )
				)
				( attribute "VER" "1"
					( Origin gFrontEnd )
				)
				( attribute "XY" "(-1950,1325)"
					( Origin gFrontEnd )
				)
				( attribute "CHIPS_PART_NAME" "IND-100NH-35-GP"
					( Origin gPackager )
				)
				( attribute "CDS_PART_NAME" "IND-100NH-35-GP_DISCRET-G8-INDA"
					( Origin gPackager )
				)
				( attribute "CDS_LOCATION" "L7A5"
					( Origin gPackager )
				)
				( attribute "CDS_SEC" "1"
					( Origin gPackager )
				)
				( attribute "ATTRIBUTE" "100NH"
					( Origin gFrontEnd )
				)
				( attribute "PACK_SIZE" "DCR=0.16MOHM"
					( Origin gFrontEnd )
				)
				( attribute "RATED" "ISAT=16A@25C"
					( Origin gFrontEnd )
				)
				( attribute "TYPE" "IRMS=29A@DELTA_T<45C"
					( Origin gFrontEnd )
				)
				( objectStatus "L7A5" )
			)
			( gate "@baseboard_fab2_lib.baseboard_fab2(sch_1):page217_i175"
				( attribute "CDS_LIB" "mstr_discrete"
					( Origin gPackager )
				)
				( attribute "CDS_LOCATION" "C7G2"
					( Origin gPackager )
				)
				( attribute "CDS_SEC" "1"
					( Origin gPackager )
				)
				( attribute "LOCATION" "C7G2"
					( Origin gFrontEnd )
				)
				( attribute "MATERIAL" "OSCON"
					( Origin gFrontEnd )
				)
				( attribute "PACK_TYPE" "2626"
					( Origin gFrontEnd )
				)
				( attribute "PART_NUMBER" "A31228-047"
					( Origin gFrontEnd )
				)
				( attribute "PHYS_PAGE" "217"
					( Origin gFrontEnd )
				)
				( attribute "ROOM" "VDDQ_ABC_PWR_VR"
					( Origin gFrontEnd )
				)
				( attribute "ROT" "0"
					( Origin gFrontEnd )
				)
				( attribute "SEC" "1"
					( Origin gFrontEnd )
				)
				( attribute "SEC_TYPE" "2626"
					( Origin gFrontEnd )
				)
				( attribute "TOLERANCE" "20%"
					( Origin gFrontEnd )
				)
				( attribute "VALUE" "270UF"
					( Origin gFrontEnd )
				)
				( attribute "VER" "1"
					( Origin gFrontEnd )
				)
				( attribute "VOLTAGE" "16V"
					( Units "uVoltage" "V" 1.000000)
					( Origin gFrontEnd )
				)
				( attribute "XY" "(200,700)"
					( Origin gFrontEnd )
				)
				( attribute "CHIPS_PART_NAME" "CAPP"
					( Origin gPackager )
				)
				( attribute "CDS_PART_NAME" "CAPP_2626-270UF,16V,20%,OSCON,A"
					( Origin gPackager )
				)
				( objectStatus "C7G2" )
			)
			( gate "@baseboard_fab2_lib.baseboard_fab2(sch_1):page220_i321"
				( attribute "BOM_COST" "MEM_VRD_PVDDQ_CD"
					( Origin gFrontEnd )
				)
				( attribute "CDS_LIB" "mstr_discrete"
					( Origin gPackager )
				)
				( attribute "CDS_LOCATION" "C5A10"
					( Origin gPackager )
				)
				( attribute "CDS_SEC" "1"
					( Origin gPackager )
				)
				( attribute "LOCATION" "C5A10"
					( Origin gFrontEnd )
				)
				( attribute "MATERIAL" "X5R"
					( Origin gFrontEnd )
				)
				( attribute "NEW_MATERIAL" "X6S"
					( Origin gFrontEnd )
				)
				( attribute "PACK_TYPE" "0805"
					( Origin gFrontEnd )
				)
				( attribute "PART_NUMBER" "602433-112"
					( Origin gFrontEnd )
				)
				( attribute "PHYS_PAGE" "220"
					( Origin gFrontEnd )
				)
				( attribute "ROOM" "VDDQ_ABC_PWR_VR"
					( Origin gFrontEnd )
				)
				( attribute "ROT" "0"
					( Origin gFrontEnd )
				)
				( attribute "SEC" "1"
					( Origin gFrontEnd )
				)
				( attribute "SEC_TYPE" "0805"
					( Origin gFrontEnd )
				)
				( attribute "TOLERANCE" "20%"
					( Origin gFrontEnd )
				)
				( attribute "VALUE" "100UF"
					( Origin gFrontEnd )
				)
				( attribute "VER" "1"
					( Origin gFrontEnd )
				)
				( attribute "VOLTAGE" "4V"
					( Units "uVoltage" "V" 1.000000)
					( Origin gFrontEnd )
				)
				( attribute "XY" "(2400,2825)"
					( Origin gFrontEnd )
				)
				( attribute "CHIPS_PART_NAME" "CAP"
					( Origin gPackager )
				)
				( attribute "CDS_PART_NAME" "CAP_0805-100UF,4V,20%,X5R,6024A"
					( Origin gPackager )
				)
				( attribute "GROUP" "PWR_MLCC_CAP"
					( Origin gFrontEnd )
				)
				( attribute "NEW_PN" "078.1071T.M002"
					( Origin gFrontEnd )
				)
				( attribute "BOM_SS" "NOPOP"
					( Origin gFrontEnd )
				)
				( objectStatus "C5A10" )
			)
			( gate "@baseboard_fab2_lib.baseboard_fab2(sch_1):page217_i286"
				( attribute "CDS_LIB" "dev_discrete"
					( Origin gPackager )
				)
				( attribute "CDS_LOCATION" "C5U5"
					( Origin gPackager )
				)
				( attribute "CDS_SEC" "1"
					( Origin gPackager )
				)
				( attribute "LOCATION" "C5U5"
					( Origin gFrontEnd )
				)
				( attribute "MATERIAL" "X5R"
					( Origin gFrontEnd )
				)
				( attribute "PACK_TYPE" "0603V"
					( Origin gFrontEnd )
				)
				( attribute "PART_NUMBER" "602433-106"
					( Origin gFrontEnd )
				)
				( attribute "PHYS_PAGE" "217"
					( Origin gFrontEnd )
				)
				( attribute "ROT" "0"
					( Origin gFrontEnd )
				)
				( attribute "SEC" "1"
					( Origin gFrontEnd )
				)
				( attribute "SEC_TYPE" "0603V"
					( Origin gFrontEnd )
				)
				( attribute "TOLERANCE" "20%"
					( Origin gFrontEnd )
				)
				( attribute "VALUE" "47UF"
					( Origin gFrontEnd )
				)
				( attribute "VER" "1"
					( Origin gFrontEnd )
				)
				( attribute "VOLTAGE" "4V"
					( Units "uVoltage" "V" 1.000000)
					( Origin gFrontEnd )
				)
				( attribute "XY" "(-950,50)"
					( Origin gFrontEnd )
				)
				( attribute "CHIPS_PART_NAME" "CAP_A"
					( Origin gPackager )
				)
				( attribute "CDS_PART_NAME" "CAP_A_0603V-47UF,4V,20%,X5R,60A"
					( Origin gPackager )
				)
				( attribute "GROUP" "PWR_MLCC_CAP"
					( Origin gFrontEnd )
				)
				( attribute "BOM_SS" "E15431-004"
					( Origin gFrontEnd )
				)
				( objectStatus "C5U5" )
			)
			( gate "@baseboard_fab2_lib.baseboard_fab2(sch_1):page217_i285"
				( attribute "CDS_LIB" "dev_discrete"
					( Origin gPackager )
				)
				( attribute "CDS_LOCATION" "C5U4"
					( Origin gPackager )
				)
				( attribute "CDS_SEC" "1"
					( Origin gPackager )
				)
				( attribute "LOCATION" "C5U4"
					( Origin gFrontEnd )
				)
				( attribute "MATERIAL" "X5R"
					( Origin gFrontEnd )
				)
				( attribute "PACK_TYPE" "0603V"
					( Origin gFrontEnd )
				)
				( attribute "PART_NUMBER" "602433-106"
					( Origin gFrontEnd )
				)
				( attribute "PHYS_PAGE" "217"
					( Origin gFrontEnd )
				)
				( attribute "ROT" "0"
					( Origin gFrontEnd )
				)
				( attribute "SEC" "1"
					( Origin gFrontEnd )
				)
				( attribute "SEC_TYPE" "0603V"
					( Origin gFrontEnd )
				)
				( attribute "TOLERANCE" "20%"
					( Origin gFrontEnd )
				)
				( attribute "VALUE" "47UF"
					( Origin gFrontEnd )
				)
				( attribute "VER" "1"
					( Origin gFrontEnd )
				)
				( attribute "VOLTAGE" "4V"
					( Units "uVoltage" "V" 1.000000)
					( Origin gFrontEnd )
				)
				( attribute "XY" "(-1225,50)"
					( Origin gFrontEnd )
				)
				( attribute "CHIPS_PART_NAME" "CAP_A"
					( Origin gPackager )
				)
				( attribute "CDS_PART_NAME" "CAP_A_0603V-47UF,4V,20%,X5R,60A"
					( Origin gPackager )
				)
				( attribute "GROUP" "PWR_MLCC_CAP"
					( Origin gFrontEnd )
				)
				( attribute "BOM_SS" "E15431-004"
					( Origin gFrontEnd )
				)
				( objectStatus "C5U4" )
			)
			( gate "@baseboard_fab2_lib.baseboard_fab2(sch_1):page217_i284"
				( attribute "CDS_LIB" "dev_discrete"
					( Origin gPackager )
				)
				( attribute "CDS_LOCATION" "C5U3"
					( Origin gPackager )
				)
				( attribute "CDS_SEC" "1"
					( Origin gPackager )
				)
				( attribute "LOCATION" "C5U3"
					( Origin gFrontEnd )
				)
				( attribute "MATERIAL" "X5R"
					( Origin gFrontEnd )
				)
				( attribute "PACK_TYPE" "0603V"
					( Origin gFrontEnd )
				)
				( attribute "PART_NUMBER" "602433-106"
					( Origin gFrontEnd )
				)
				( attribute "PHYS_PAGE" "217"
					( Origin gFrontEnd )
				)
				( attribute "ROT" "0"
					( Origin gFrontEnd )
				)
				( attribute "SEC" "1"
					( Origin gFrontEnd )
				)
				( attribute "SEC_TYPE" "0603V"
					( Origin gFrontEnd )
				)
				( attribute "TOLERANCE" "20%"
					( Origin gFrontEnd )
				)
				( attribute "VALUE" "47UF"
					( Origin gFrontEnd )
				)
				( attribute "VER" "1"
					( Origin gFrontEnd )
				)
				( attribute "VOLTAGE" "4V"
					( Units "uVoltage" "V" 1.000000)
					( Origin gFrontEnd )
				)
				( attribute "XY" "(-1525,50)"
					( Origin gFrontEnd )
				)
				( attribute "CHIPS_PART_NAME" "CAP_A"
					( Origin gPackager )
				)
				( attribute "CDS_PART_NAME" "CAP_A_0603V-47UF,4V,20%,X5R,60A"
					( Origin gPackager )
				)
				( attribute "GROUP" "PWR_MLCC_CAP"
					( Origin gFrontEnd )
				)
				( attribute "BOM_SS" "E15431-004"
					( Origin gFrontEnd )
				)
				( objectStatus "C5U3" )
			)
			( gate "@baseboard_fab2_lib.baseboard_fab2(sch_1):page217_i283"
				( attribute "CDS_LIB" "dev_discrete"
					( Origin gPackager )
				)
				( attribute "CDS_LOCATION" "C5U2"
					( Origin gPackager )
				)
				( attribute "CDS_SEC" "1"
					( Origin gPackager )
				)
				( attribute "LOCATION" "C5U2"
					( Origin gFrontEnd )
				)
				( attribute "MATERIAL" "X5R"
					( Origin gFrontEnd )
				)
				( attribute "PACK_TYPE" "0603V"
					( Origin gFrontEnd )
				)
				( attribute "PART_NUMBER" "602433-106"
					( Origin gFrontEnd )
				)
				( attribute "PHYS_PAGE" "217"
					( Origin gFrontEnd )
				)
				( attribute "ROT" "0"
					( Origin gFrontEnd )
				)
				( attribute "SEC" "1"
					( Origin gFrontEnd )
				)
				( attribute "SEC_TYPE" "0603V"
					( Origin gFrontEnd )
				)
				( attribute "TOLERANCE" "20%"
					( Origin gFrontEnd )
				)
				( attribute "VALUE" "47UF"
					( Origin gFrontEnd )
				)
				( attribute "VER" "1"
					( Origin gFrontEnd )
				)
				( attribute "VOLTAGE" "4V"
					( Units "uVoltage" "V" 1.000000)
					( Origin gFrontEnd )
				)
				( attribute "XY" "(-1825,50)"
					( Origin gFrontEnd )
				)
				( attribute "CHIPS_PART_NAME" "CAP_A"
					( Origin gPackager )
				)
				( attribute "CDS_PART_NAME" "CAP_A_0603V-47UF,4V,20%,X5R,60A"
					( Origin gPackager )
				)
				( attribute "GROUP" "PWR_MLCC_CAP"
					( Origin gFrontEnd )
				)
				( attribute "BOM_SS" "E15431-004"
					( Origin gFrontEnd )
				)
				( objectStatus "C5U2" )
			)
			( gate "@baseboard_fab2_lib.baseboard_fab2(sch_1):page221_i46"
				( attribute "BOM_COST" "MEM_VRD_PVDDQ_CD"
					( Origin gFrontEnd )
				)
				( attribute "CDS_LIB" "mstr_discrete"
					( Origin gPackager )
				)
				( attribute "CDS_LOCATION" "C5U16"
					( Origin gPackager )
				)
				( attribute "CDS_SEC" "1"
					( Origin gPackager )
				)
				( attribute "LOCATION" "C5U16"
					( Origin gFrontEnd )
				)
				( attribute "MATERIAL" "X5R"
					( Origin gFrontEnd )
				)
				( attribute "NEW_MATERIAL" "X6S"
					( Origin gFrontEnd )
				)
				( attribute "PACK_TYPE" "0805"
					( Origin gFrontEnd )
				)
				( attribute "PART_NUMBER" "602433-112"
					( Origin gFrontEnd )
				)
				( attribute "PHYS_PAGE" "221"
					( Origin gFrontEnd )
				)
				( attribute "ROOM" "VDDQ_ABC_PWR_VR"
					( Origin gFrontEnd )
				)
				( attribute "ROT" "0"
					( Origin gFrontEnd )
				)
				( attribute "SEC" "1"
					( Origin gFrontEnd )
				)
				( attribute "SEC_TYPE" "0805"
					( Origin gFrontEnd )
				)
				( attribute "TOLERANCE" "20%"
					( Origin gFrontEnd )
				)
				( attribute "VALUE" "100UF"
					( Origin gFrontEnd )
				)
				( attribute "VER" "1"
					( Origin gFrontEnd )
				)
				( attribute "VOLTAGE" "4V"
					( Units "uVoltage" "V" 1.000000)
					( Origin gFrontEnd )
				)
				( attribute "XY" "(3675,3300)"
					( Origin gFrontEnd )
				)
				( attribute "CHIPS_PART_NAME" "CAP"
					( Origin gPackager )
				)
				( attribute "CDS_PART_NAME" "CAP_0805-100UF,4V,20%,X5R,6024A"
					( Origin gPackager )
				)
				( attribute "GROUP" "PWR_MLCC_CAP"
					( Origin gFrontEnd )
				)
				( attribute "NEW_PN" "078.1071T.M002"
					( Origin gFrontEnd )
				)
				( objectStatus "C5U16" )
			)
			( gate "@baseboard_fab2_lib.baseboard_fab2(sch_1):page217_i205"
				( attribute "CDS_LIB" "dev_discrete"
					( Origin gPackager )
				)
				( attribute "CDS_LOCATION" "C5F2"
					( Origin gPackager )
				)
				( attribute "CDS_SEC" "1"
					( Origin gPackager )
				)
				( attribute "LOCATION" "C5F2"
					( Origin gFrontEnd )
				)
				( attribute "MATERIAL" "X5R"
					( Origin gFrontEnd )
				)
				( attribute "PACK_TYPE" "0603V"
					( Origin gFrontEnd )
				)
				( attribute "PART_NUMBER" "602433-106"
					( Origin gFrontEnd )
				)
				( attribute "PHYS_PAGE" "217"
					( Origin gFrontEnd )
				)
				( attribute "ROT" "0"
					( Origin gFrontEnd )
				)
				( attribute "SEC" "1"
					( Origin gFrontEnd )
				)
				( attribute "SEC_TYPE" "0603V"
					( Origin gFrontEnd )
				)
				( attribute "TOLERANCE" "20%"
					( Origin gFrontEnd )
				)
				( attribute "VALUE" "47UF"
					( Origin gFrontEnd )
				)
				( attribute "VER" "1"
					( Origin gFrontEnd )
				)
				( attribute "VOLTAGE" "4V"
					( Units "uVoltage" "V" 1.000000)
					( Origin gFrontEnd )
				)
				( attribute "XY" "(2925,1000)"
					( Origin gFrontEnd )
				)
				( attribute "CHIPS_PART_NAME" "CAP_A"
					( Origin gPackager )
				)
				( attribute "CDS_PART_NAME" "CAP_A_0603V-47UF,4V,20%,X5R,60A"
					( Origin gPackager )
				)
				( attribute "GROUP" "PWR_MLCC_CAP"
					( Origin gFrontEnd )
				)
				( attribute "BOM_SS" "NOPOP"
					( Origin gFrontEnd )
				)
				( objectStatus "C5F2" )
			)
			( gate "@baseboard_fab2_lib.baseboard_fab2(sch_1):page217_i206"
				( attribute "CDS_LIB" "dev_discrete"
					( Origin gPackager )
				)
				( attribute "CDS_LOCATION" "C5F1"
					( Origin gPackager )
				)
				( attribute "CDS_SEC" "1"
					( Origin gPackager )
				)
				( attribute "LOCATION" "C5F1"
					( Origin gFrontEnd )
				)
				( attribute "MATERIAL" "X5R"
					( Origin gFrontEnd )
				)
				( attribute "PACK_TYPE" "0603V"
					( Origin gFrontEnd )
				)
				( attribute "PART_NUMBER" "602433-106"
					( Origin gFrontEnd )
				)
				( attribute "PHYS_PAGE" "217"
					( Origin gFrontEnd )
				)
				( attribute "ROT" "0"
					( Origin gFrontEnd )
				)
				( attribute "SEC" "1"
					( Origin gFrontEnd )
				)
				( attribute "SEC_TYPE" "0603V"
					( Origin gFrontEnd )
				)
				( attribute "TOLERANCE" "20%"
					( Origin gFrontEnd )
				)
				( attribute "VALUE" "47UF"
					( Origin gFrontEnd )
				)
				( attribute "VER" "1"
					( Origin gFrontEnd )
				)
				( attribute "VOLTAGE" "4V"
					( Units "uVoltage" "V" 1.000000)
					( Origin gFrontEnd )
				)
				( attribute "XY" "(3275,1000)"
					( Origin gFrontEnd )
				)
				( attribute "CHIPS_PART_NAME" "CAP_A"
					( Origin gPackager )
				)
				( attribute "CDS_PART_NAME" "CAP_A_0603V-47UF,4V,20%,X5R,60A"
					( Origin gPackager )
				)
				( attribute "GROUP" "PWR_MLCC_CAP"
					( Origin gFrontEnd )
				)
				( attribute "BOM_SS" "NOPOP"
					( Origin gFrontEnd )
				)
				( objectStatus "C5F1" )
			)
			( gate "@baseboard_fab2_lib.baseboard_fab2(sch_1):page217_i207"
				( attribute "CDS_LIB" "dev_discrete"
					( Origin gPackager )
				)
				( attribute "CDS_LOCATION" "C5G10"
					( Origin gPackager )
				)
				( attribute "CDS_SEC" "1"
					( Origin gPackager )
				)
				( attribute "LOCATION" "C5G10"
					( Origin gFrontEnd )
				)
				( attribute "MATERIAL" "X5R"
					( Origin gFrontEnd )
				)
				( attribute "PACK_TYPE" "0603V"
					( Origin gFrontEnd )
				)
				( attribute "PART_NUMBER" "602433-106"
					( Origin gFrontEnd )
				)
				( attribute "PHYS_PAGE" "217"
					( Origin gFrontEnd )
				)
				( attribute "ROT" "0"
					( Origin gFrontEnd )
				)
				( attribute "SEC" "1"
					( Origin gFrontEnd )
				)
				( attribute "SEC_TYPE" "0603V"
					( Origin gFrontEnd )
				)
				( attribute "TOLERANCE" "20%"
					( Origin gFrontEnd )
				)
				( attribute "VALUE" "47UF"
					( Origin gFrontEnd )
				)
				( attribute "VER" "1"
					( Origin gFrontEnd )
				)
				( attribute "VOLTAGE" "4V"
					( Units "uVoltage" "V" 1.000000)
					( Origin gFrontEnd )
				)
				( attribute "XY" "(3675,1000)"
					( Origin gFrontEnd )
				)
				( attribute "CHIPS_PART_NAME" "CAP_A"
					( Origin gPackager )
				)
				( attribute "CDS_PART_NAME" "CAP_A_0603V-47UF,4V,20%,X5R,60A"
					( Origin gPackager )
				)
				( attribute "GROUP" "PWR_MLCC_CAP"
					( Origin gFrontEnd )
				)
				( attribute "BOM_SS" "NOPOP"
					( Origin gFrontEnd )
				)
				( objectStatus "C5G10" )
			)
			( gate "@baseboard_fab2_lib.baseboard_fab2(sch_1):page217_i208"
				( attribute "CDS_LIB" "dev_discrete"
					( Origin gPackager )
				)
				( attribute "CDS_LOCATION" "C5T2"
					( Origin gPackager )
				)
				( attribute "CDS_SEC" "1"
					( Origin gPackager )
				)
				( attribute "LOCATION" "C5T2"
					( Origin gFrontEnd )
				)
				( attribute "MATERIAL" "X5R"
					( Origin gFrontEnd )
				)
				( attribute "PACK_TYPE" "0603V"
					( Origin gFrontEnd )
				)
				( attribute "PART_NUMBER" "602433-106"
					( Origin gFrontEnd )
				)
				( attribute "PHYS_PAGE" "217"
					( Origin gFrontEnd )
				)
				( attribute "ROT" "0"
					( Origin gFrontEnd )
				)
				( attribute "SEC" "1"
					( Origin gFrontEnd )
				)
				( attribute "SEC_TYPE" "0603V"
					( Origin gFrontEnd )
				)
				( attribute "TOLERANCE" "20%"
					( Origin gFrontEnd )
				)
				( attribute "VALUE" "47UF"
					( Origin gFrontEnd )
				)
				( attribute "VER" "1"
					( Origin gFrontEnd )
				)
				( attribute "VOLTAGE" "4V"
					( Units "uVoltage" "V" 1.000000)
					( Origin gFrontEnd )
				)
				( attribute "XY" "(4000,1725)"
					( Origin gFrontEnd )
				)
				( attribute "CHIPS_PART_NAME" "CAP_A"
					( Origin gPackager )
				)
				( attribute "CDS_PART_NAME" "CAP_A_0603V-47UF,4V,20%,X5R,60A"
					( Origin gPackager )
				)
				( attribute "GROUP" "PWR_MLCC_CAP"
					( Origin gFrontEnd )
				)
				( attribute "BOM_SS" "NOPOP"
					( Origin gFrontEnd )
				)
				( objectStatus "C5T2" )
			)
			( gate "@baseboard_fab2_lib.baseboard_fab2(sch_1):page217_i209"
				( attribute "CDS_LIB" "dev_discrete"
					( Origin gPackager )
				)
				( attribute "CDS_LOCATION" "C5U11"
					( Origin gPackager )
				)
				( attribute "CDS_SEC" "1"
					( Origin gPackager )
				)
				( attribute "LOCATION" "C5U11"
					( Origin gFrontEnd )
				)
				( attribute "MATERIAL" "X5R"
					( Origin gFrontEnd )
				)
				( attribute "PACK_TYPE" "0603V"
					( Origin gFrontEnd )
				)
				( attribute "PART_NUMBER" "602433-106"
					( Origin gFrontEnd )
				)
				( attribute "PHYS_PAGE" "217"
					( Origin gFrontEnd )
				)
				( attribute "ROT" "0"
					( Origin gFrontEnd )
				)
				( attribute "SEC" "1"
					( Origin gFrontEnd )
				)
				( attribute "SEC_TYPE" "0603V"
					( Origin gFrontEnd )
				)
				( attribute "TOLERANCE" "20%"
					( Origin gFrontEnd )
				)
				( attribute "VALUE" "47UF"
					( Origin gFrontEnd )
				)
				( attribute "VER" "1"
					( Origin gFrontEnd )
				)
				( attribute "VOLTAGE" "4V"
					( Units "uVoltage" "V" 1.000000)
					( Origin gFrontEnd )
				)
				( attribute "XY" "(4350,1725)"
					( Origin gFrontEnd )
				)
				( attribute "CHIPS_PART_NAME" "CAP_A"
					( Origin gPackager )
				)
				( attribute "CDS_PART_NAME" "CAP_A_0603V-47UF,4V,20%,X5R,60A"
					( Origin gPackager )
				)
				( attribute "GROUP" "PWR_MLCC_CAP"
					( Origin gFrontEnd )
				)
				( attribute "BOM_SS" "NOPOP"
					( Origin gFrontEnd )
				)
				( objectStatus "C5U11" )
			)
			( gate "@baseboard_fab2_lib.baseboard_fab2(sch_1):page217_i210"
				( attribute "CDS_LIB" "dev_discrete"
					( Origin gPackager )
				)
				( attribute "CDS_LOCATION" "C5T13"
					( Origin gPackager )
				)
				( attribute "CDS_SEC" "1"
					( Origin gPackager )
				)
				( attribute "LOCATION" "C5T13"
					( Origin gFrontEnd )
				)
				( attribute "MATERIAL" "X5R"
					( Origin gFrontEnd )
				)
				( attribute "PACK_TYPE" "0603V"
					( Origin gFrontEnd )
				)
				( attribute "PART_NUMBER" "602433-106"
					( Origin gFrontEnd )
				)
				( attribute "PHYS_PAGE" "217"
					( Origin gFrontEnd )
				)
				( attribute "ROT" "0"
					( Origin gFrontEnd )
				)
				( attribute "SEC" "1"
					( Origin gFrontEnd )
				)
				( attribute "SEC_TYPE" "0603V"
					( Origin gFrontEnd )
				)
				( attribute "TOLERANCE" "20%"
					( Origin gFrontEnd )
				)
				( attribute "VALUE" "47UF"
					( Origin gFrontEnd )
				)
				( attribute "VER" "1"
					( Origin gFrontEnd )
				)
				( attribute "VOLTAGE" "4V"
					( Units "uVoltage" "V" 1.000000)
					( Origin gFrontEnd )
				)
				( attribute "XY" "(4750,1725)"
					( Origin gFrontEnd )
				)
				( attribute "CHIPS_PART_NAME" "CAP_A"
					( Origin gPackager )
				)
				( attribute "CDS_PART_NAME" "CAP_A_0603V-47UF,4V,20%,X5R,60A"
					( Origin gPackager )
				)
				( attribute "GROUP" "PWR_MLCC_CAP"
					( Origin gFrontEnd )
				)
				( attribute "BOM_SS" "NOPOP"
					( Origin gFrontEnd )
				)
				( objectStatus "C5T13" )
			)
			( gate "@baseboard_fab2_lib.baseboard_fab2(sch_1):page217_i211"
				( attribute "CDS_LIB" "dev_discrete"
					( Origin gPackager )
				)
				( attribute "CDS_LOCATION" "C5T4"
					( Origin gPackager )
				)
				( attribute "CDS_SEC" "1"
					( Origin gPackager )
				)
				( attribute "LOCATION" "C5T4"
					( Origin gFrontEnd )
				)
				( attribute "MATERIAL" "X5R"
					( Origin gFrontEnd )
				)
				( attribute "PACK_TYPE" "0603V"
					( Origin gFrontEnd )
				)
				( attribute "PART_NUMBER" "602433-106"
					( Origin gFrontEnd )
				)
				( attribute "PHYS_PAGE" "217"
					( Origin gFrontEnd )
				)
				( attribute "ROT" "0"
					( Origin gFrontEnd )
				)
				( attribute "SEC" "1"
					( Origin gFrontEnd )
				)
				( attribute "SEC_TYPE" "0603V"
					( Origin gFrontEnd )
				)
				( attribute "TOLERANCE" "20%"
					( Origin gFrontEnd )
				)
				( attribute "VALUE" "47UF"
					( Origin gFrontEnd )
				)
				( attribute "VER" "1"
					( Origin gFrontEnd )
				)
				( attribute "VOLTAGE" "4V"
					( Units "uVoltage" "V" 1.000000)
					( Origin gFrontEnd )
				)
				( attribute "XY" "(3650,1725)"
					( Origin gFrontEnd )
				)
				( attribute "CHIPS_PART_NAME" "CAP_A"
					( Origin gPackager )
				)
				( attribute "CDS_PART_NAME" "CAP_A_0603V-47UF,4V,20%,X5R,60A"
					( Origin gPackager )
				)
				( attribute "GROUP" "PWR_MLCC_CAP"
					( Origin gFrontEnd )
				)
				( attribute "BOM_SS" "078.1061T.M001"
					( Origin gFrontEnd )
				)
				( objectStatus "C5T4" )
			)
			( gate "@baseboard_fab2_lib.baseboard_fab2(sch_1):page217_i212"
				( attribute "CDS_LIB" "dev_discrete"
					( Origin gPackager )
				)
				( attribute "CDS_LOCATION" "C5T1"
					( Origin gPackager )
				)
				( attribute "CDS_SEC" "1"
					( Origin gPackager )
				)
				( attribute "LOCATION" "C5T1"
					( Origin gFrontEnd )
				)
				( attribute "MATERIAL" "X5R"
					( Origin gFrontEnd )
				)
				( attribute "PACK_TYPE" "0603V"
					( Origin gFrontEnd )
				)
				( attribute "PART_NUMBER" "602433-106"
					( Origin gFrontEnd )
				)
				( attribute "PHYS_PAGE" "217"
					( Origin gFrontEnd )
				)
				( attribute "ROT" "0"
					( Origin gFrontEnd )
				)
				( attribute "SEC" "1"
					( Origin gFrontEnd )
				)
				( attribute "SEC_TYPE" "0603V"
					( Origin gFrontEnd )
				)
				( attribute "TOLERANCE" "20%"
					( Origin gFrontEnd )
				)
				( attribute "VALUE" "47UF"
					( Origin gFrontEnd )
				)
				( attribute "VER" "1"
					( Origin gFrontEnd )
				)
				( attribute "VOLTAGE" "4V"
					( Units "uVoltage" "V" 1.000000)
					( Origin gFrontEnd )
				)
				( attribute "XY" "(3250,1725)"
					( Origin gFrontEnd )
				)
				( attribute "CHIPS_PART_NAME" "CAP_A"
					( Origin gPackager )
				)
				( attribute "CDS_PART_NAME" "CAP_A_0603V-47UF,4V,20%,X5R,60A"
					( Origin gPackager )
				)
				( attribute "GROUP" "PWR_MLCC_CAP"
					( Origin gFrontEnd )
				)
				( attribute "BOM_SS" "NOPOP"
					( Origin gFrontEnd )
				)
				( objectStatus "C5T1" )
			)
			( gate "@baseboard_fab2_lib.baseboard_fab2(sch_1):page217_i213"
				( attribute "CDS_LIB" "dev_discrete"
					( Origin gPackager )
				)
				( attribute "CDS_LOCATION" "C5G19"
					( Origin gPackager )
				)
				( attribute "CDS_SEC" "1"
					( Origin gPackager )
				)
				( attribute "LOCATION" "C5G19"
					( Origin gFrontEnd )
				)
				( attribute "MATERIAL" "X5R"
					( Origin gFrontEnd )
				)
				( attribute "PACK_TYPE" "0603V"
					( Origin gFrontEnd )
				)
				( attribute "PART_NUMBER" "602433-106"
					( Origin gFrontEnd )
				)
				( attribute "PHYS_PAGE" "217"
					( Origin gFrontEnd )
				)
				( attribute "ROT" "0"
					( Origin gFrontEnd )
				)
				( attribute "SEC" "1"
					( Origin gFrontEnd )
				)
				( attribute "SEC_TYPE" "0603V"
					( Origin gFrontEnd )
				)
				( attribute "TOLERANCE" "20%"
					( Origin gFrontEnd )
				)
				( attribute "VALUE" "47UF"
					( Origin gFrontEnd )
				)
				( attribute "VER" "1"
					( Origin gFrontEnd )
				)
				( attribute "VOLTAGE" "4V"
					( Units "uVoltage" "V" 1.000000)
					( Origin gFrontEnd )
				)
				( attribute "XY" "(2900,1725)"
					( Origin gFrontEnd )
				)
				( attribute "CHIPS_PART_NAME" "CAP_A"
					( Origin gPackager )
				)
				( attribute "CDS_PART_NAME" "CAP_A_0603V-47UF,4V,20%,X5R,60A"
					( Origin gPackager )
				)
				( attribute "GROUP" "PWR_MLCC_CAP"
					( Origin gFrontEnd )
				)
				( attribute "BOM_SS" "NOPOP"
					( Origin gFrontEnd )
				)
				( objectStatus "C5G19" )
			)
			( gate "@baseboard_fab2_lib.baseboard_fab2(sch_1):page217_i314"
				( attribute "CDS_LIB" "dev_discrete"
					( Origin gPackager )
				)
				( attribute "CDS_LOCATION" "C5G3"
					( Origin gPackager )
				)
				( attribute "CDS_SEC" "1"
					( Origin gPackager )
				)
				( attribute "LOCATION" "C5G3"
					( Origin gFrontEnd )
				)
				( attribute "MATERIAL" "X5R"
					( Origin gFrontEnd )
				)
				( attribute "PACK_TYPE" "0603V"
					( Origin gFrontEnd )
				)
				( attribute "PART_NUMBER" "602433-106"
					( Origin gFrontEnd )
				)
				( attribute "PHYS_PAGE" "217"
					( Origin gFrontEnd )
				)
				( attribute "ROT" "0"
					( Origin gFrontEnd )
				)
				( attribute "SEC" "1"
					( Origin gFrontEnd )
				)
				( attribute "SEC_TYPE" "0603V"
					( Origin gFrontEnd )
				)
				( attribute "TOLERANCE" "20%"
					( Origin gFrontEnd )
				)
				( attribute "VALUE" "47UF"
					( Origin gFrontEnd )
				)
				( attribute "VER" "1"
					( Origin gFrontEnd )
				)
				( attribute "VOLTAGE" "4V"
					( Units "uVoltage" "V" 1.000000)
					( Origin gFrontEnd )
				)
				( attribute "XY" "(2550,-650)"
					( Origin gFrontEnd )
				)
				( attribute "CHIPS_PART_NAME" "CAP_A"
					( Origin gPackager )
				)
				( attribute "CDS_PART_NAME" "CAP_A_0603V-47UF,4V,20%,X5R,60A"
					( Origin gPackager )
				)
				( attribute "GROUP" "PWR_MLCC_CAP"
					( Origin gFrontEnd )
				)
				( attribute "BOM_SS" "E15431-004"
					( Origin gFrontEnd )
				)
				( objectStatus "C5G3" )
			)
			( gate "@baseboard_fab2_lib.baseboard_fab2(sch_1):page220_i277"
				( attribute "CDS_LIB" "dev_discrete"
					( Origin gPackager )
				)
				( attribute "CDS_LOCATION" "C5A19"
					( Origin gPackager )
				)
				( attribute "CDS_SEC" "1"
					( Origin gPackager )
				)
				( attribute "LOCATION" "C5A19"
					( Origin gFrontEnd )
				)
				( attribute "MATERIAL" "X5R"
					( Origin gFrontEnd )
				)
				( attribute "PACK_TYPE" "0603V"
					( Origin gFrontEnd )
				)
				( attribute "PART_NUMBER" "602433-106"
					( Origin gFrontEnd )
				)
				( attribute "PHYS_PAGE" "220"
					( Origin gFrontEnd )
				)
				( attribute "ROT" "0"
					( Origin gFrontEnd )
				)
				( attribute "SEC" "1"
					( Origin gFrontEnd )
				)
				( attribute "SEC_TYPE" "0603V"
					( Origin gFrontEnd )
				)
				( attribute "TOLERANCE" "20%"
					( Origin gFrontEnd )
				)
				( attribute "VALUE" "47UF"
					( Origin gFrontEnd )
				)
				( attribute "VER" "1"
					( Origin gFrontEnd )
				)
				( attribute "VOLTAGE" "4V"
					( Units "uVoltage" "V" 1.000000)
					( Origin gFrontEnd )
				)
				( attribute "XY" "(2225,100)"
					( Origin gFrontEnd )
				)
				( attribute "CHIPS_PART_NAME" "CAP_A"
					( Origin gPackager )
				)
				( attribute "CDS_PART_NAME" "CAP_A_0603V-47UF,4V,20%,X5R,60A"
					( Origin gPackager )
				)
				( attribute "GROUP" "PWR_MLCC_CAP"
					( Origin gFrontEnd )
				)
				( attribute "BOM_SS" "E15431-004"
					( Origin gFrontEnd )
				)
				( objectStatus "C5A19" )
			)
			( gate "@baseboard_fab2_lib.baseboard_fab2(sch_1):page217_i313"
				( attribute "CDS_LIB" "dev_discrete"
					( Origin gPackager )
				)
				( attribute "CDS_LOCATION" "C5G15"
					( Origin gPackager )
				)
				( attribute "CDS_SEC" "1"
					( Origin gPackager )
				)
				( attribute "LOCATION" "C5G15"
					( Origin gFrontEnd )
				)
				( attribute "MATERIAL" "X5R"
					( Origin gFrontEnd )
				)
				( attribute "PACK_TYPE" "0603V"
					( Origin gFrontEnd )
				)
				( attribute "PART_NUMBER" "602433-106"
					( Origin gFrontEnd )
				)
				( attribute "PHYS_PAGE" "217"
					( Origin gFrontEnd )
				)
				( attribute "ROT" "0"
					( Origin gFrontEnd )
				)
				( attribute "SEC" "1"
					( Origin gFrontEnd )
				)
				( attribute "SEC_TYPE" "0603V"
					( Origin gFrontEnd )
				)
				( attribute "TOLERANCE" "20%"
					( Origin gFrontEnd )
				)
				( attribute "VALUE" "47UF"
					( Origin gFrontEnd )
				)
				( attribute "VER" "1"
					( Origin gFrontEnd )
				)
				( attribute "VOLTAGE" "4V"
					( Units "uVoltage" "V" 1.000000)
					( Origin gFrontEnd )
				)
				( attribute "XY" "(2275,-650)"
					( Origin gFrontEnd )
				)
				( attribute "CHIPS_PART_NAME" "CAP_A"
					( Origin gPackager )
				)
				( attribute "CDS_PART_NAME" "CAP_A_0603V-47UF,4V,20%,X5R,60A"
					( Origin gPackager )
				)
				( attribute "GROUP" "PWR_MLCC_CAP"
					( Origin gFrontEnd )
				)
				( attribute "BOM_SS" "E15431-004"
					( Origin gFrontEnd )
				)
				( objectStatus "C5G15" )
			)
			( gate "@baseboard_fab2_lib.baseboard_fab2(sch_1):page217_i312"
				( attribute "CDS_LIB" "dev_discrete"
					( Origin gPackager )
				)
				( attribute "CDS_LOCATION" "C5G16"
					( Origin gPackager )
				)
				( attribute "CDS_SEC" "1"
					( Origin gPackager )
				)
				( attribute "LOCATION" "C5G16"
					( Origin gFrontEnd )
				)
				( attribute "MATERIAL" "X5R"
					( Origin gFrontEnd )
				)
				( attribute "PACK_TYPE" "0603V"
					( Origin gFrontEnd )
				)
				( attribute "PART_NUMBER" "602433-106"
					( Origin gFrontEnd )
				)
				( attribute "PHYS_PAGE" "217"
					( Origin gFrontEnd )
				)
				( attribute "ROT" "0"
					( Origin gFrontEnd )
				)
				( attribute "SEC" "1"
					( Origin gFrontEnd )
				)
				( attribute "SEC_TYPE" "0603V"
					( Origin gFrontEnd )
				)
				( attribute "TOLERANCE" "20%"
					( Origin gFrontEnd )
				)
				( attribute "VALUE" "47UF"
					( Origin gFrontEnd )
				)
				( attribute "VER" "1"
					( Origin gFrontEnd )
				)
				( attribute "VOLTAGE" "4V"
					( Units "uVoltage" "V" 1.000000)
					( Origin gFrontEnd )
				)
				( attribute "XY" "(1975,-650)"
					( Origin gFrontEnd )
				)
				( attribute "CHIPS_PART_NAME" "CAP_A"
					( Origin gPackager )
				)
				( attribute "CDS_PART_NAME" "CAP_A_0603V-47UF,4V,20%,X5R,60A"
					( Origin gPackager )
				)
				( attribute "GROUP" "PWR_MLCC_CAP"
					( Origin gFrontEnd )
				)
				( attribute "BOM_SS" "E15431-004"
					( Origin gFrontEnd )
				)
				( objectStatus "C5G16" )
			)
			( gate "@baseboard_fab2_lib.baseboard_fab2(sch_1):page220_i276"
				( attribute "CDS_LIB" "dev_discrete"
					( Origin gPackager )
				)
				( attribute "CDS_LOCATION" "C5A18"
					( Origin gPackager )
				)
				( attribute "CDS_SEC" "1"
					( Origin gPackager )
				)
				( attribute "LOCATION" "C5A18"
					( Origin gFrontEnd )
				)
				( attribute "MATERIAL" "X5R"
					( Origin gFrontEnd )
				)
				( attribute "PACK_TYPE" "0603V"
					( Origin gFrontEnd )
				)
				( attribute "PART_NUMBER" "602433-106"
					( Origin gFrontEnd )
				)
				( attribute "PHYS_PAGE" "220"
					( Origin gFrontEnd )
				)
				( attribute "ROT" "0"
					( Origin gFrontEnd )
				)
				( attribute "SEC" "1"
					( Origin gFrontEnd )
				)
				( attribute "SEC_TYPE" "0603V"
					( Origin gFrontEnd )
				)
				( attribute "TOLERANCE" "20%"
					( Origin gFrontEnd )
				)
				( attribute "VALUE" "47UF"
					( Origin gFrontEnd )
				)
				( attribute "VER" "1"
					( Origin gFrontEnd )
				)
				( attribute "VOLTAGE" "4V"
					( Units "uVoltage" "V" 1.000000)
					( Origin gFrontEnd )
				)
				( attribute "XY" "(1950,100)"
					( Origin gFrontEnd )
				)
				( attribute "CHIPS_PART_NAME" "CAP_A"
					( Origin gPackager )
				)
				( attribute "CDS_PART_NAME" "CAP_A_0603V-47UF,4V,20%,X5R,60A"
					( Origin gPackager )
				)
				( attribute "GROUP" "PWR_MLCC_CAP"
					( Origin gFrontEnd )
				)
				( attribute "BOM_SS" "E15431-004"
					( Origin gFrontEnd )
				)
				( objectStatus "C5A18" )
			)
			( gate "@baseboard_fab2_lib.baseboard_fab2(sch_1):page220_i275"
				( attribute "CDS_LIB" "dev_discrete"
					( Origin gPackager )
				)
				( attribute "CDS_LOCATION" "C5A17"
					( Origin gPackager )
				)
				( attribute "CDS_SEC" "1"
					( Origin gPackager )
				)
				( attribute "LOCATION" "C5A17"
					( Origin gFrontEnd )
				)
				( attribute "MATERIAL" "X5R"
					( Origin gFrontEnd )
				)
				( attribute "PACK_TYPE" "0603V"
					( Origin gFrontEnd )
				)
				( attribute "PART_NUMBER" "602433-106"
					( Origin gFrontEnd )
				)
				( attribute "PHYS_PAGE" "220"
					( Origin gFrontEnd )
				)
				( attribute "ROT" "0"
					( Origin gFrontEnd )
				)
				( attribute "SEC" "1"
					( Origin gFrontEnd )
				)
				( attribute "SEC_TYPE" "0603V"
					( Origin gFrontEnd )
				)
				( attribute "TOLERANCE" "20%"
					( Origin gFrontEnd )
				)
				( attribute "VALUE" "47UF"
					( Origin gFrontEnd )
				)
				( attribute "VER" "1"
					( Origin gFrontEnd )
				)
				( attribute "VOLTAGE" "4V"
					( Units "uVoltage" "V" 1.000000)
					( Origin gFrontEnd )
				)
				( attribute "XY" "(1650,100)"
					( Origin gFrontEnd )
				)
				( attribute "CHIPS_PART_NAME" "CAP_A"
					( Origin gPackager )
				)
				( attribute "CDS_PART_NAME" "CAP_A_0603V-47UF,4V,20%,X5R,60A"
					( Origin gPackager )
				)
				( attribute "GROUP" "PWR_MLCC_CAP"
					( Origin gFrontEnd )
				)
				( attribute "BOM_SS" "E15431-004"
					( Origin gFrontEnd )
				)
				( objectStatus "C5A17" )
			)
			( gate "@baseboard_fab2_lib.baseboard_fab2(sch_1):page217_i311"
				( attribute "CDS_LIB" "dev_discrete"
					( Origin gPackager )
				)
				( attribute "CDS_LOCATION" "C5G14"
					( Origin gPackager )
				)
				( attribute "CDS_SEC" "1"
					( Origin gPackager )
				)
				( attribute "LOCATION" "C5G14"
					( Origin gFrontEnd )
				)
				( attribute "MATERIAL" "X5R"
					( Origin gFrontEnd )
				)
				( attribute "PACK_TYPE" "0603V"
					( Origin gFrontEnd )
				)
				( attribute "PART_NUMBER" "602433-106"
					( Origin gFrontEnd )
				)
				( attribute "PHYS_PAGE" "217"
					( Origin gFrontEnd )
				)
				( attribute "ROT" "0"
					( Origin gFrontEnd )
				)
				( attribute "SEC" "1"
					( Origin gFrontEnd )
				)
				( attribute "SEC_TYPE" "0603V"
					( Origin gFrontEnd )
				)
				( attribute "TOLERANCE" "20%"
					( Origin gFrontEnd )
				)
				( attribute "VALUE" "47UF"
					( Origin gFrontEnd )
				)
				( attribute "VER" "1"
					( Origin gFrontEnd )
				)
				( attribute "VOLTAGE" "4V"
					( Units "uVoltage" "V" 1.000000)
					( Origin gFrontEnd )
				)
				( attribute "XY" "(1675,-650)"
					( Origin gFrontEnd )
				)
				( attribute "CHIPS_PART_NAME" "CAP_A"
					( Origin gPackager )
				)
				( attribute "CDS_PART_NAME" "CAP_A_0603V-47UF,4V,20%,X5R,60A"
					( Origin gPackager )
				)
				( attribute "GROUP" "PWR_MLCC_CAP"
					( Origin gFrontEnd )
				)
				( attribute "BOM_SS" "E15431-004"
					( Origin gFrontEnd )
				)
				( objectStatus "C5G14" )
			)
			( gate "@baseboard_fab2_lib.baseboard_fab2(sch_1):page220_i274"
				( attribute "CDS_LIB" "dev_discrete"
					( Origin gPackager )
				)
				( attribute "CDS_LOCATION" "C5A4"
					( Origin gPackager )
				)
				( attribute "CDS_SEC" "1"
					( Origin gPackager )
				)
				( attribute "LOCATION" "C5A4"
					( Origin gFrontEnd )
				)
				( attribute "MATERIAL" "X5R"
					( Origin gFrontEnd )
				)
				( attribute "PACK_TYPE" "0603V"
					( Origin gFrontEnd )
				)
				( attribute "PART_NUMBER" "602433-106"
					( Origin gFrontEnd )
				)
				( attribute "PHYS_PAGE" "220"
					( Origin gFrontEnd )
				)
				( attribute "ROT" "0"
					( Origin gFrontEnd )
				)
				( attribute "SEC" "1"
					( Origin gFrontEnd )
				)
				( attribute "SEC_TYPE" "0603V"
					( Origin gFrontEnd )
				)
				( attribute "TOLERANCE" "20%"
					( Origin gFrontEnd )
				)
				( attribute "VALUE" "47UF"
					( Origin gFrontEnd )
				)
				( attribute "VER" "1"
					( Origin gFrontEnd )
				)
				( attribute "VOLTAGE" "4V"
					( Units "uVoltage" "V" 1.000000)
					( Origin gFrontEnd )
				)
				( attribute "XY" "(1350,100)"
					( Origin gFrontEnd )
				)
				( attribute "CHIPS_PART_NAME" "CAP_A"
					( Origin gPackager )
				)
				( attribute "CDS_PART_NAME" "CAP_A_0603V-47UF,4V,20%,X5R,60A"
					( Origin gPackager )
				)
				( attribute "GROUP" "PWR_MLCC_CAP"
					( Origin gFrontEnd )
				)
				( attribute "BOM_SS" "E15431-004"
					( Origin gFrontEnd )
				)
				( objectStatus "C5A4" )
			)
			( gate "@baseboard_fab2_lib.baseboard_fab2(sch_1):page217_i310"
				( attribute "CDS_LIB" "dev_discrete"
					( Origin gPackager )
				)
				( attribute "CDS_LOCATION" "C5G17"
					( Origin gPackager )
				)
				( attribute "CDS_SEC" "1"
					( Origin gPackager )
				)
				( attribute "LOCATION" "C5G17"
					( Origin gFrontEnd )
				)
				( attribute "MATERIAL" "X5R"
					( Origin gFrontEnd )
				)
				( attribute "PACK_TYPE" "0603V"
					( Origin gFrontEnd )
				)
				( attribute "PART_NUMBER" "602433-106"
					( Origin gFrontEnd )
				)
				( attribute "PHYS_PAGE" "217"
					( Origin gFrontEnd )
				)
				( attribute "ROT" "0"
					( Origin gFrontEnd )
				)
				( attribute "SEC" "1"
					( Origin gFrontEnd )
				)
				( attribute "SEC_TYPE" "0603V"
					( Origin gFrontEnd )
				)
				( attribute "TOLERANCE" "20%"
					( Origin gFrontEnd )
				)
				( attribute "VALUE" "47UF"
					( Origin gFrontEnd )
				)
				( attribute "VER" "1"
					( Origin gFrontEnd )
				)
				( attribute "VOLTAGE" "4V"
					( Units "uVoltage" "V" 1.000000)
					( Origin gFrontEnd )
				)
				( attribute "XY" "(1400,-650)"
					( Origin gFrontEnd )
				)
				( attribute "CHIPS_PART_NAME" "CAP_A"
					( Origin gPackager )
				)
				( attribute "CDS_PART_NAME" "CAP_A_0603V-47UF,4V,20%,X5R,60A"
					( Origin gPackager )
				)
				( attribute "GROUP" "PWR_MLCC_CAP"
					( Origin gFrontEnd )
				)
				( attribute "BOM_SS" "E15431-004"
					( Origin gFrontEnd )
				)
				( objectStatus "C5G17" )
			)
			( gate "@baseboard_fab2_lib.baseboard_fab2(sch_1):page217_i309"
				( attribute "CDS_LIB" "dev_discrete"
					( Origin gPackager )
				)
				( attribute "CDS_LOCATION" "C5G18"
					( Origin gPackager )
				)
				( attribute "CDS_SEC" "1"
					( Origin gPackager )
				)
				( attribute "LOCATION" "C5G18"
					( Origin gFrontEnd )
				)
				( attribute "MATERIAL" "X5R"
					( Origin gFrontEnd )
				)
				( attribute "PACK_TYPE" "0603V"
					( Origin gFrontEnd )
				)
				( attribute "PART_NUMBER" "602433-106"
					( Origin gFrontEnd )
				)
				( attribute "PHYS_PAGE" "217"
					( Origin gFrontEnd )
				)
				( attribute "ROT" "0"
					( Origin gFrontEnd )
				)
				( attribute "SEC" "1"
					( Origin gFrontEnd )
				)
				( attribute "SEC_TYPE" "0603V"
					( Origin gFrontEnd )
				)
				( attribute "TOLERANCE" "20%"
					( Origin gFrontEnd )
				)
				( attribute "VALUE" "47UF"
					( Origin gFrontEnd )
				)
				( attribute "VER" "1"
					( Origin gFrontEnd )
				)
				( attribute "VOLTAGE" "4V"
					( Units "uVoltage" "V" 1.000000)
					( Origin gFrontEnd )
				)
				( attribute "XY" "(1125,-650)"
					( Origin gFrontEnd )
				)
				( attribute "CHIPS_PART_NAME" "CAP_A"
					( Origin gPackager )
				)
				( attribute "CDS_PART_NAME" "CAP_A_0603V-47UF,4V,20%,X5R,60A"
					( Origin gPackager )
				)
				( attribute "GROUP" "PWR_MLCC_CAP"
					( Origin gFrontEnd )
				)
				( attribute "BOM_SS" "E15431-004"
					( Origin gFrontEnd )
				)
				( objectStatus "C5G18" )
			)
			( gate "@baseboard_fab2_lib.baseboard_fab2(sch_1):page220_i273"
				( attribute "CDS_LIB" "dev_discrete"
					( Origin gPackager )
				)
				( attribute "CDS_LOCATION" "C5A16"
					( Origin gPackager )
				)
				( attribute "CDS_SEC" "1"
					( Origin gPackager )
				)
				( attribute "LOCATION" "C5A16"
					( Origin gFrontEnd )
				)
				( attribute "MATERIAL" "X5R"
					( Origin gFrontEnd )
				)
				( attribute "PACK_TYPE" "0603V"
					( Origin gFrontEnd )
				)
				( attribute "PART_NUMBER" "602433-106"
					( Origin gFrontEnd )
				)
				( attribute "PHYS_PAGE" "220"
					( Origin gFrontEnd )
				)
				( attribute "ROT" "0"
					( Origin gFrontEnd )
				)
				( attribute "SEC" "1"
					( Origin gFrontEnd )
				)
				( attribute "SEC_TYPE" "0603V"
					( Origin gFrontEnd )
				)
				( attribute "TOLERANCE" "20%"
					( Origin gFrontEnd )
				)
				( attribute "VALUE" "47UF"
					( Origin gFrontEnd )
				)
				( attribute "VER" "1"
					( Origin gFrontEnd )
				)
				( attribute "VOLTAGE" "4V"
					( Units "uVoltage" "V" 1.000000)
					( Origin gFrontEnd )
				)
				( attribute "XY" "(1075,100)"
					( Origin gFrontEnd )
				)
				( attribute "CHIPS_PART_NAME" "CAP_A"
					( Origin gPackager )
				)
				( attribute "CDS_PART_NAME" "CAP_A_0603V-47UF,4V,20%,X5R,60A"
					( Origin gPackager )
				)
				( attribute "GROUP" "PWR_MLCC_CAP"
					( Origin gFrontEnd )
				)
				( attribute "BOM_SS" "E15431-004"
					( Origin gFrontEnd )
				)
				( objectStatus "C5A16" )
			)
			( gate "@baseboard_fab2_lib.baseboard_fab2(sch_1):page220_i272"
				( attribute "CDS_LIB" "dev_discrete"
					( Origin gPackager )
				)
				( attribute "CDS_LOCATION" "C5A9"
					( Origin gPackager )
				)
				( attribute "CDS_SEC" "1"
					( Origin gPackager )
				)
				( attribute "LOCATION" "C5A9"
					( Origin gFrontEnd )
				)
				( attribute "MATERIAL" "X5R"
					( Origin gFrontEnd )
				)
				( attribute "PACK_TYPE" "0603V"
					( Origin gFrontEnd )
				)
				( attribute "PART_NUMBER" "602433-106"
					( Origin gFrontEnd )
				)
				( attribute "PHYS_PAGE" "220"
					( Origin gFrontEnd )
				)
				( attribute "ROT" "0"
					( Origin gFrontEnd )
				)
				( attribute "SEC" "1"
					( Origin gFrontEnd )
				)
				( attribute "SEC_TYPE" "0603V"
					( Origin gFrontEnd )
				)
				( attribute "TOLERANCE" "20%"
					( Origin gFrontEnd )
				)
				( attribute "VALUE" "47UF"
					( Origin gFrontEnd )
				)
				( attribute "VER" "1"
					( Origin gFrontEnd )
				)
				( attribute "VOLTAGE" "4V"
					( Units "uVoltage" "V" 1.000000)
					( Origin gFrontEnd )
				)
				( attribute "XY" "(800,100)"
					( Origin gFrontEnd )
				)
				( attribute "CHIPS_PART_NAME" "CAP_A"
					( Origin gPackager )
				)
				( attribute "CDS_PART_NAME" "CAP_A_0603V-47UF,4V,20%,X5R,60A"
					( Origin gPackager )
				)
				( attribute "GROUP" "PWR_MLCC_CAP"
					( Origin gFrontEnd )
				)
				( attribute "BOM_SS" "E15431-004"
					( Origin gFrontEnd )
				)
				( objectStatus "C5A9" )
			)
			( gate "@baseboard_fab2_lib.baseboard_fab2(sch_1):page217_i308"
				( attribute "CDS_LIB" "dev_discrete"
					( Origin gPackager )
				)
				( attribute "CDS_LOCATION" "C5G8"
					( Origin gPackager )
				)
				( attribute "CDS_SEC" "1"
					( Origin gPackager )
				)
				( attribute "LOCATION" "C5G8"
					( Origin gFrontEnd )
				)
				( attribute "MATERIAL" "X5R"
					( Origin gFrontEnd )
				)
				( attribute "PACK_TYPE" "0603V"
					( Origin gFrontEnd )
				)
				( attribute "PART_NUMBER" "602433-106"
					( Origin gFrontEnd )
				)
				( attribute "PHYS_PAGE" "217"
					( Origin gFrontEnd )
				)
				( attribute "ROT" "0"
					( Origin gFrontEnd )
				)
				( attribute "SEC" "1"
					( Origin gFrontEnd )
				)
				( attribute "SEC_TYPE" "0603V"
					( Origin gFrontEnd )
				)
				( attribute "TOLERANCE" "20%"
					( Origin gFrontEnd )
				)
				( attribute "VALUE" "47UF"
					( Origin gFrontEnd )
				)
				( attribute "VER" "1"
					( Origin gFrontEnd )
				)
				( attribute "VOLTAGE" "4V"
					( Units "uVoltage" "V" 1.000000)
					( Origin gFrontEnd )
				)
				( attribute "XY" "(825,-650)"
					( Origin gFrontEnd )
				)
				( attribute "CHIPS_PART_NAME" "CAP_A"
					( Origin gPackager )
				)
				( attribute "CDS_PART_NAME" "CAP_A_0603V-47UF,4V,20%,X5R,60A"
					( Origin gPackager )
				)
				( attribute "GROUP" "PWR_MLCC_CAP"
					( Origin gFrontEnd )
				)
				( attribute "BOM_SS" "E15431-004"
					( Origin gFrontEnd )
				)
				( objectStatus "C5G8" )
			)
			( gate "@baseboard_fab2_lib.baseboard_fab2(sch_1):page217_i307"
				( attribute "CDS_LIB" "dev_discrete"
					( Origin gPackager )
				)
				( attribute "CDS_LOCATION" "C5G1"
					( Origin gPackager )
				)
				( attribute "CDS_SEC" "1"
					( Origin gPackager )
				)
				( attribute "LOCATION" "C5G1"
					( Origin gFrontEnd )
				)
				( attribute "MATERIAL" "X5R"
					( Origin gFrontEnd )
				)
				( attribute "PACK_TYPE" "0603V"
					( Origin gFrontEnd )
				)
				( attribute "PART_NUMBER" "602433-106"
					( Origin gFrontEnd )
				)
				( attribute "PHYS_PAGE" "217"
					( Origin gFrontEnd )
				)
				( attribute "ROT" "0"
					( Origin gFrontEnd )
				)
				( attribute "SEC" "1"
					( Origin gFrontEnd )
				)
				( attribute "SEC_TYPE" "0603V"
					( Origin gFrontEnd )
				)
				( attribute "TOLERANCE" "20%"
					( Origin gFrontEnd )
				)
				( attribute "VALUE" "47UF"
					( Origin gFrontEnd )
				)
				( attribute "VER" "1"
					( Origin gFrontEnd )
				)
				( attribute "VOLTAGE" "4V"
					( Units "uVoltage" "V" 1.000000)
					( Origin gFrontEnd )
				)
				( attribute "XY" "(525,-650)"
					( Origin gFrontEnd )
				)
				( attribute "CHIPS_PART_NAME" "CAP_A"
					( Origin gPackager )
				)
				( attribute "CDS_PART_NAME" "CAP_A_0603V-47UF,4V,20%,X5R,60A"
					( Origin gPackager )
				)
				( attribute "GROUP" "PWR_MLCC_CAP"
					( Origin gFrontEnd )
				)
				( attribute "BOM_SS" "E15431-004"
					( Origin gFrontEnd )
				)
				( objectStatus "C5G1" )
			)
			( gate "@baseboard_fab2_lib.baseboard_fab2(sch_1):page220_i271"
				( attribute "CDS_LIB" "dev_discrete"
					( Origin gPackager )
				)
				( attribute "CDS_LOCATION" "C5A8"
					( Origin gPackager )
				)
				( attribute "CDS_SEC" "1"
					( Origin gPackager )
				)
				( attribute "LOCATION" "C5A8"
					( Origin gFrontEnd )
				)
				( attribute "MATERIAL" "X5R"
					( Origin gFrontEnd )
				)
				( attribute "PACK_TYPE" "0603V"
					( Origin gFrontEnd )
				)
				( attribute "PART_NUMBER" "602433-106"
					( Origin gFrontEnd )
				)
				( attribute "PHYS_PAGE" "220"
					( Origin gFrontEnd )
				)
				( attribute "ROT" "0"
					( Origin gFrontEnd )
				)
				( attribute "SEC" "1"
					( Origin gFrontEnd )
				)
				( attribute "SEC_TYPE" "0603V"
					( Origin gFrontEnd )
				)
				( attribute "TOLERANCE" "20%"
					( Origin gFrontEnd )
				)
				( attribute "VALUE" "47UF"
					( Origin gFrontEnd )
				)
				( attribute "VER" "1"
					( Origin gFrontEnd )
				)
				( attribute "VOLTAGE" "4V"
					( Units "uVoltage" "V" 1.000000)
					( Origin gFrontEnd )
				)
				( attribute "XY" "(500,100)"
					( Origin gFrontEnd )
				)
				( attribute "CHIPS_PART_NAME" "CAP_A"
					( Origin gPackager )
				)
				( attribute "CDS_PART_NAME" "CAP_A_0603V-47UF,4V,20%,X5R,60A"
					( Origin gPackager )
				)
				( attribute "GROUP" "PWR_MLCC_CAP"
					( Origin gFrontEnd )
				)
				( attribute "BOM_SS" "E15431-004"
					( Origin gFrontEnd )
				)
				( objectStatus "C5A8" )
			)
			( gate "@baseboard_fab2_lib.baseboard_fab2(sch_1):page220_i270"
				( attribute "CDS_LIB" "dev_discrete"
					( Origin gPackager )
				)
				( attribute "CDS_LOCATION" "C5A3"
					( Origin gPackager )
				)
				( attribute "CDS_SEC" "1"
					( Origin gPackager )
				)
				( attribute "LOCATION" "C5A3"
					( Origin gFrontEnd )
				)
				( attribute "MATERIAL" "X5R"
					( Origin gFrontEnd )
				)
				( attribute "PACK_TYPE" "0603V"
					( Origin gFrontEnd )
				)
				( attribute "PART_NUMBER" "602433-106"
					( Origin gFrontEnd )
				)
				( attribute "PHYS_PAGE" "220"
					( Origin gFrontEnd )
				)
				( attribute "ROT" "0"
					( Origin gFrontEnd )
				)
				( attribute "SEC" "1"
					( Origin gFrontEnd )
				)
				( attribute "SEC_TYPE" "0603V"
					( Origin gFrontEnd )
				)
				( attribute "TOLERANCE" "20%"
					( Origin gFrontEnd )
				)
				( attribute "VALUE" "47UF"
					( Origin gFrontEnd )
				)
				( attribute "VER" "1"
					( Origin gFrontEnd )
				)
				( attribute "VOLTAGE" "4V"
					( Units "uVoltage" "V" 1.000000)
					( Origin gFrontEnd )
				)
				( attribute "XY" "(200,100)"
					( Origin gFrontEnd )
				)
				( attribute "CHIPS_PART_NAME" "CAP_A"
					( Origin gPackager )
				)
				( attribute "CDS_PART_NAME" "CAP_A_0603V-47UF,4V,20%,X5R,60A"
					( Origin gPackager )
				)
				( attribute "GROUP" "PWR_MLCC_CAP"
					( Origin gFrontEnd )
				)
				( attribute "BOM_SS" "E15431-004"
					( Origin gFrontEnd )
				)
				( objectStatus "C5A3" )
			)
			( gate "@baseboard_fab2_lib.baseboard_fab2(sch_1):page217_i306"
				( attribute "CDS_LIB" "dev_discrete"
					( Origin gPackager )
				)
				( attribute "CDS_LOCATION" "C5G7"
					( Origin gPackager )
				)
				( attribute "CDS_SEC" "1"
					( Origin gPackager )
				)
				( attribute "LOCATION" "C5G7"
					( Origin gFrontEnd )
				)
				( attribute "MATERIAL" "X5R"
					( Origin gFrontEnd )
				)
				( attribute "PACK_TYPE" "0603V"
					( Origin gFrontEnd )
				)
				( attribute "PART_NUMBER" "602433-106"
					( Origin gFrontEnd )
				)
				( attribute "PHYS_PAGE" "217"
					( Origin gFrontEnd )
				)
				( attribute "ROT" "0"
					( Origin gFrontEnd )
				)
				( attribute "SEC" "1"
					( Origin gFrontEnd )
				)
				( attribute "SEC_TYPE" "0603V"
					( Origin gFrontEnd )
				)
				( attribute "TOLERANCE" "20%"
					( Origin gFrontEnd )
				)
				( attribute "VALUE" "47UF"
					( Origin gFrontEnd )
				)
				( attribute "VER" "1"
					( Origin gFrontEnd )
				)
				( attribute "VOLTAGE" "4V"
					( Units "uVoltage" "V" 1.000000)
					( Origin gFrontEnd )
				)
				( attribute "XY" "(200,-650)"
					( Origin gFrontEnd )
				)
				( attribute "CHIPS_PART_NAME" "CAP_A"
					( Origin gPackager )
				)
				( attribute "CDS_PART_NAME" "CAP_A_0603V-47UF,4V,20%,X5R,60A"
					( Origin gPackager )
				)
				( attribute "GROUP" "PWR_MLCC_CAP"
					( Origin gFrontEnd )
				)
				( attribute "BOM_SS" "E15431-004"
					( Origin gFrontEnd )
				)
				( objectStatus "C5G7" )
			)
			( gate "@baseboard_fab2_lib.baseboard_fab2(sch_1):page217_i305"
				( attribute "CDS_LIB" "dev_discrete"
					( Origin gPackager )
				)
				( attribute "CDS_LOCATION" "C5G5"
					( Origin gPackager )
				)
				( attribute "CDS_SEC" "1"
					( Origin gPackager )
				)
				( attribute "LOCATION" "C5G5"
					( Origin gFrontEnd )
				)
				( attribute "MATERIAL" "X5R"
					( Origin gFrontEnd )
				)
				( attribute "PACK_TYPE" "0603V"
					( Origin gFrontEnd )
				)
				( attribute "PART_NUMBER" "602433-106"
					( Origin gFrontEnd )
				)
				( attribute "PHYS_PAGE" "217"
					( Origin gFrontEnd )
				)
				( attribute "ROT" "0"
					( Origin gFrontEnd )
				)
				( attribute "SEC" "1"
					( Origin gFrontEnd )
				)
				( attribute "SEC_TYPE" "0603V"
					( Origin gFrontEnd )
				)
				( attribute "TOLERANCE" "20%"
					( Origin gFrontEnd )
				)
				( attribute "VALUE" "47UF"
					( Origin gFrontEnd )
				)
				( attribute "VER" "1"
					( Origin gFrontEnd )
				)
				( attribute "VOLTAGE" "4V"
					( Units "uVoltage" "V" 1.000000)
					( Origin gFrontEnd )
				)
				( attribute "XY" "(-75,-650)"
					( Origin gFrontEnd )
				)
				( attribute "CHIPS_PART_NAME" "CAP_A"
					( Origin gPackager )
				)
				( attribute "CDS_PART_NAME" "CAP_A_0603V-47UF,4V,20%,X5R,60A"
					( Origin gPackager )
				)
				( attribute "GROUP" "PWR_MLCC_CAP"
					( Origin gFrontEnd )
				)
				( attribute "BOM_SS" "E15431-004"
					( Origin gFrontEnd )
				)
				( objectStatus "C5G5" )
			)
			( gate "@baseboard_fab2_lib.baseboard_fab2(sch_1):page220_i269"
				( attribute "CDS_LIB" "dev_discrete"
					( Origin gPackager )
				)
				( attribute "CDS_LOCATION" "C5A7"
					( Origin gPackager )
				)
				( attribute "CDS_SEC" "1"
					( Origin gPackager )
				)
				( attribute "LOCATION" "C5A7"
					( Origin gFrontEnd )
				)
				( attribute "MATERIAL" "X5R"
					( Origin gFrontEnd )
				)
				( attribute "PACK_TYPE" "0603V"
					( Origin gFrontEnd )
				)
				( attribute "PART_NUMBER" "602433-106"
					( Origin gFrontEnd )
				)
				( attribute "PHYS_PAGE" "220"
					( Origin gFrontEnd )
				)
				( attribute "ROT" "0"
					( Origin gFrontEnd )
				)
				( attribute "SEC" "1"
					( Origin gFrontEnd )
				)
				( attribute "SEC_TYPE" "0603V"
					( Origin gFrontEnd )
				)
				( attribute "TOLERANCE" "20%"
					( Origin gFrontEnd )
				)
				( attribute "VALUE" "47UF"
					( Origin gFrontEnd )
				)
				( attribute "VER" "1"
					( Origin gFrontEnd )
				)
				( attribute "VOLTAGE" "4V"
					( Units "uVoltage" "V" 1.000000)
					( Origin gFrontEnd )
				)
				( attribute "XY" "(-125,100)"
					( Origin gFrontEnd )
				)
				( attribute "CHIPS_PART_NAME" "CAP_A"
					( Origin gPackager )
				)
				( attribute "CDS_PART_NAME" "CAP_A_0603V-47UF,4V,20%,X5R,60A"
					( Origin gPackager )
				)
				( attribute "GROUP" "PWR_MLCC_CAP"
					( Origin gFrontEnd )
				)
				( attribute "BOM_SS" "E15431-004"
					( Origin gFrontEnd )
				)
				( objectStatus "C5A7" )
			)
			( gate "@baseboard_fab2_lib.baseboard_fab2(sch_1):page220_i268"
				( attribute "CDS_LIB" "dev_discrete"
					( Origin gPackager )
				)
				( attribute "CDS_LOCATION" "C5A6"
					( Origin gPackager )
				)
				( attribute "CDS_SEC" "1"
					( Origin gPackager )
				)
				( attribute "LOCATION" "C5A6"
					( Origin gFrontEnd )
				)
				( attribute "MATERIAL" "X5R"
					( Origin gFrontEnd )
				)
				( attribute "PACK_TYPE" "0603V"
					( Origin gFrontEnd )
				)
				( attribute "PART_NUMBER" "602433-106"
					( Origin gFrontEnd )
				)
				( attribute "PHYS_PAGE" "220"
					( Origin gFrontEnd )
				)
				( attribute "ROT" "0"
					( Origin gFrontEnd )
				)
				( attribute "SEC" "1"
					( Origin gFrontEnd )
				)
				( attribute "SEC_TYPE" "0603V"
					( Origin gFrontEnd )
				)
				( attribute "TOLERANCE" "20%"
					( Origin gFrontEnd )
				)
				( attribute "VALUE" "47UF"
					( Origin gFrontEnd )
				)
				( attribute "VER" "1"
					( Origin gFrontEnd )
				)
				( attribute "VOLTAGE" "4V"
					( Units "uVoltage" "V" 1.000000)
					( Origin gFrontEnd )
				)
				( attribute "XY" "(-400,100)"
					( Origin gFrontEnd )
				)
				( attribute "CHIPS_PART_NAME" "CAP_A"
					( Origin gPackager )
				)
				( attribute "CDS_PART_NAME" "CAP_A_0603V-47UF,4V,20%,X5R,60A"
					( Origin gPackager )
				)
				( attribute "GROUP" "PWR_MLCC_CAP"
					( Origin gFrontEnd )
				)
				( attribute "BOM_SS" "E15431-004"
					( Origin gFrontEnd )
				)
				( objectStatus "C5A6" )
			)
			( gate "@baseboard_fab2_lib.baseboard_fab2(sch_1):page217_i304"
				( attribute "CDS_LIB" "dev_discrete"
					( Origin gPackager )
				)
				( attribute "CDS_LOCATION" "C5G6"
					( Origin gPackager )
				)
				( attribute "CDS_SEC" "1"
					( Origin gPackager )
				)
				( attribute "LOCATION" "C5G6"
					( Origin gFrontEnd )
				)
				( attribute "MATERIAL" "X5R"
					( Origin gFrontEnd )
				)
				( attribute "PACK_TYPE" "0603V"
					( Origin gFrontEnd )
				)
				( attribute "PART_NUMBER" "602433-106"
					( Origin gFrontEnd )
				)
				( attribute "PHYS_PAGE" "217"
					( Origin gFrontEnd )
				)
				( attribute "ROT" "0"
					( Origin gFrontEnd )
				)
				( attribute "SEC" "1"
					( Origin gFrontEnd )
				)
				( attribute "SEC_TYPE" "0603V"
					( Origin gFrontEnd )
				)
				( attribute "TOLERANCE" "20%"
					( Origin gFrontEnd )
				)
				( attribute "VALUE" "47UF"
					( Origin gFrontEnd )
				)
				( attribute "VER" "1"
					( Origin gFrontEnd )
				)
				( attribute "VOLTAGE" "4V"
					( Units "uVoltage" "V" 1.000000)
					( Origin gFrontEnd )
				)
				( attribute "XY" "(-375,-650)"
					( Origin gFrontEnd )
				)
				( attribute "CHIPS_PART_NAME" "CAP_A"
					( Origin gPackager )
				)
				( attribute "CDS_PART_NAME" "CAP_A_0603V-47UF,4V,20%,X5R,60A"
					( Origin gPackager )
				)
				( attribute "GROUP" "PWR_MLCC_CAP"
					( Origin gFrontEnd )
				)
				( attribute "BOM_SS" "E15431-004"
					( Origin gFrontEnd )
				)
				( objectStatus "C5G6" )
			)
			( gate "@baseboard_fab2_lib.baseboard_fab2(sch_1):page220_i267"
				( attribute "CDS_LIB" "dev_discrete"
					( Origin gPackager )
				)
				( attribute "CDS_LOCATION" "C5A14"
					( Origin gPackager )
				)
				( attribute "CDS_SEC" "1"
					( Origin gPackager )
				)
				( attribute "LOCATION" "C5A14"
					( Origin gFrontEnd )
				)
				( attribute "MATERIAL" "X5R"
					( Origin gFrontEnd )
				)
				( attribute "PACK_TYPE" "0603V"
					( Origin gFrontEnd )
				)
				( attribute "PART_NUMBER" "602433-106"
					( Origin gFrontEnd )
				)
				( attribute "PHYS_PAGE" "220"
					( Origin gFrontEnd )
				)
				( attribute "ROT" "0"
					( Origin gFrontEnd )
				)
				( attribute "SEC" "1"
					( Origin gFrontEnd )
				)
				( attribute "SEC_TYPE" "0603V"
					( Origin gFrontEnd )
				)
				( attribute "TOLERANCE" "20%"
					( Origin gFrontEnd )
				)
				( attribute "VALUE" "47UF"
					( Origin gFrontEnd )
				)
				( attribute "VER" "1"
					( Origin gFrontEnd )
				)
				( attribute "VOLTAGE" "4V"
					( Units "uVoltage" "V" 1.000000)
					( Origin gFrontEnd )
				)
				( attribute "XY" "(-700,100)"
					( Origin gFrontEnd )
				)
				( attribute "CHIPS_PART_NAME" "CAP_A"
					( Origin gPackager )
				)
				( attribute "CDS_PART_NAME" "CAP_A_0603V-47UF,4V,20%,X5R,60A"
					( Origin gPackager )
				)
				( attribute "GROUP" "PWR_MLCC_CAP"
					( Origin gFrontEnd )
				)
				( attribute "BOM_SS" "E15431-004"
					( Origin gFrontEnd )
				)
				( objectStatus "C5A14" )
			)
			( gate "@baseboard_fab2_lib.baseboard_fab2(sch_1):page217_i303"
				( attribute "CDS_LIB" "dev_discrete"
					( Origin gPackager )
				)
				( attribute "CDS_LOCATION" "C5G13"
					( Origin gPackager )
				)
				( attribute "CDS_SEC" "1"
					( Origin gPackager )
				)
				( attribute "LOCATION" "C5G13"
					( Origin gFrontEnd )
				)
				( attribute "MATERIAL" "X5R"
					( Origin gFrontEnd )
				)
				( attribute "PACK_TYPE" "0603V"
					( Origin gFrontEnd )
				)
				( attribute "PART_NUMBER" "602433-106"
					( Origin gFrontEnd )
				)
				( attribute "PHYS_PAGE" "217"
					( Origin gFrontEnd )
				)
				( attribute "ROT" "0"
					( Origin gFrontEnd )
				)
				( attribute "SEC" "1"
					( Origin gFrontEnd )
				)
				( attribute "SEC_TYPE" "0603V"
					( Origin gFrontEnd )
				)
				( attribute "TOLERANCE" "20%"
					( Origin gFrontEnd )
				)
				( attribute "VALUE" "47UF"
					( Origin gFrontEnd )
				)
				( attribute "VER" "1"
					( Origin gFrontEnd )
				)
				( attribute "VOLTAGE" "4V"
					( Units "uVoltage" "V" 1.000000)
					( Origin gFrontEnd )
				)
				( attribute "XY" "(-675,-650)"
					( Origin gFrontEnd )
				)
				( attribute "CHIPS_PART_NAME" "CAP_A"
					( Origin gPackager )
				)
				( attribute "CDS_PART_NAME" "CAP_A_0603V-47UF,4V,20%,X5R,60A"
					( Origin gPackager )
				)
				( attribute "GROUP" "PWR_MLCC_CAP"
					( Origin gFrontEnd )
				)
				( attribute "BOM_SS" "E15431-004"
					( Origin gFrontEnd )
				)
				( objectStatus "C5G13" )
			)
			( gate "@baseboard_fab2_lib.baseboard_fab2(sch_1):page217_i302"
				( attribute "CDS_LIB" "dev_discrete"
					( Origin gPackager )
				)
				( attribute "CDS_LOCATION" "C5G4"
					( Origin gPackager )
				)
				( attribute "CDS_SEC" "1"
					( Origin gPackager )
				)
				( attribute "LOCATION" "C5G4"
					( Origin gFrontEnd )
				)
				( attribute "MATERIAL" "X5R"
					( Origin gFrontEnd )
				)
				( attribute "PACK_TYPE" "0603V"
					( Origin gFrontEnd )
				)
				( attribute "PART_NUMBER" "602433-106"
					( Origin gFrontEnd )
				)
				( attribute "PHYS_PAGE" "217"
					( Origin gFrontEnd )
				)
				( attribute "ROT" "0"
					( Origin gFrontEnd )
				)
				( attribute "SEC" "1"
					( Origin gFrontEnd )
				)
				( attribute "SEC_TYPE" "0603V"
					( Origin gFrontEnd )
				)
				( attribute "TOLERANCE" "20%"
					( Origin gFrontEnd )
				)
				( attribute "VALUE" "47UF"
					( Origin gFrontEnd )
				)
				( attribute "VER" "1"
					( Origin gFrontEnd )
				)
				( attribute "VOLTAGE" "4V"
					( Units "uVoltage" "V" 1.000000)
					( Origin gFrontEnd )
				)
				( attribute "XY" "(-950,-650)"
					( Origin gFrontEnd )
				)
				( attribute "CHIPS_PART_NAME" "CAP_A"
					( Origin gPackager )
				)
				( attribute "CDS_PART_NAME" "CAP_A_0603V-47UF,4V,20%,X5R,60A"
					( Origin gPackager )
				)
				( attribute "GROUP" "PWR_MLCC_CAP"
					( Origin gFrontEnd )
				)
				( attribute "BOM_SS" "E15431-004"
					( Origin gFrontEnd )
				)
				( objectStatus "C5G4" )
			)
			( gate "@baseboard_fab2_lib.baseboard_fab2(sch_1):page220_i266"
				( attribute "CDS_LIB" "dev_discrete"
					( Origin gPackager )
				)
				( attribute "CDS_LOCATION" "C5A2"
					( Origin gPackager )
				)
				( attribute "CDS_SEC" "1"
					( Origin gPackager )
				)
				( attribute "LOCATION" "C5A2"
					( Origin gFrontEnd )
				)
				( attribute "MATERIAL" "X5R"
					( Origin gFrontEnd )
				)
				( attribute "PACK_TYPE" "0603V"
					( Origin gFrontEnd )
				)
				( attribute "PART_NUMBER" "602433-106"
					( Origin gFrontEnd )
				)
				( attribute "PHYS_PAGE" "220"
					( Origin gFrontEnd )
				)
				( attribute "ROT" "0"
					( Origin gFrontEnd )
				)
				( attribute "SEC" "1"
					( Origin gFrontEnd )
				)
				( attribute "SEC_TYPE" "0603V"
					( Origin gFrontEnd )
				)
				( attribute "TOLERANCE" "20%"
					( Origin gFrontEnd )
				)
				( attribute "VALUE" "47UF"
					( Origin gFrontEnd )
				)
				( attribute "VER" "1"
					( Origin gFrontEnd )
				)
				( attribute "VOLTAGE" "4V"
					( Units "uVoltage" "V" 1.000000)
					( Origin gFrontEnd )
				)
				( attribute "XY" "(-1000,100)"
					( Origin gFrontEnd )
				)
				( attribute "CHIPS_PART_NAME" "CAP_A"
					( Origin gPackager )
				)
				( attribute "CDS_PART_NAME" "CAP_A_0603V-47UF,4V,20%,X5R,60A"
					( Origin gPackager )
				)
				( attribute "GROUP" "PWR_MLCC_CAP"
					( Origin gFrontEnd )
				)
				( attribute "BOM_SS" "E15431-004"
					( Origin gFrontEnd )
				)
				( objectStatus "C5A2" )
			)
			( gate "@baseboard_fab2_lib.baseboard_fab2(sch_1):page220_i261"
				( attribute "BOM_COST" "PROC_SOCKET"
					( Origin gFrontEnd )
				)
				( attribute "CDS_LIB" "dev_discrete"
					( Origin gPackager )
				)
				( attribute "CDS_LOCATION" "C5D8"
					( Origin gPackager )
				)
				( attribute "CDS_SEC" "1"
					( Origin gPackager )
				)
				( attribute "LOCATION" "C5D8"
					( Origin gFrontEnd )
				)
				( attribute "MATERIAL" "X6S"
					( Origin gFrontEnd )
				)
				( attribute "PACK_TYPE" "0603V"
					( Origin gFrontEnd )
				)
				( attribute "PART_NUMBER" "E15431-004"
					( Origin gFrontEnd )
				)
				( attribute "PHYS_PAGE" "220"
					( Origin gFrontEnd )
				)
				( attribute "ROOM" "PVCCIN_CPU0_DECAP_VR"
					( Origin gFrontEnd )
				)
				( attribute "ROT" "0"
					( Origin gFrontEnd )
				)
				( attribute "SEC" "1"
					( Origin gPackager )
				)
				( attribute "TOLERANCE" "20%"
					( Origin gFrontEnd )
				)
				( attribute "VALUE" "22.0UF"
					( Origin gFrontEnd )
				)
				( attribute "VER" "1"
					( Origin gFrontEnd )
				)
				( attribute "VOLTAGE" "4V"
					( Units "uVoltage" "V" 1.000000)
					( Origin gFrontEnd )
				)
				( attribute "XY" "(-400,2975)"
					( Origin gFrontEnd )
				)
				( attribute "CHIPS_PART_NAME" "CAP_A"
					( Origin gPackager )
				)
				( attribute "CDS_PART_NAME" "CAP_A_0603V-22.0UF,4V,20%,X6S,A"
					( Origin gPackager )
				)
				( attribute "GROUP" "PWR_MLCC_CAP"
					( Origin gFrontEnd )
				)
				( objectStatus "C5D8" )
			)
			( gate "@baseboard_fab2_lib.baseboard_fab2(sch_1):page217_i301"
				( attribute "CDS_LIB" "dev_discrete"
					( Origin gPackager )
				)
				( attribute "CDS_LOCATION" "C5G2"
					( Origin gPackager )
				)
				( attribute "CDS_SEC" "1"
					( Origin gPackager )
				)
				( attribute "LOCATION" "C5G2"
					( Origin gFrontEnd )
				)
				( attribute "MATERIAL" "X5R"
					( Origin gFrontEnd )
				)
				( attribute "PACK_TYPE" "0603V"
					( Origin gFrontEnd )
				)
				( attribute "PART_NUMBER" "602433-106"
					( Origin gFrontEnd )
				)
				( attribute "PHYS_PAGE" "217"
					( Origin gFrontEnd )
				)
				( attribute "ROT" "0"
					( Origin gFrontEnd )
				)
				( attribute "SEC" "1"
					( Origin gFrontEnd )
				)
				( attribute "SEC_TYPE" "0603V"
					( Origin gFrontEnd )
				)
				( attribute "TOLERANCE" "20%"
					( Origin gFrontEnd )
				)
				( attribute "VALUE" "47UF"
					( Origin gFrontEnd )
				)
				( attribute "VER" "1"
					( Origin gFrontEnd )
				)
				( attribute "VOLTAGE" "4V"
					( Units "uVoltage" "V" 1.000000)
					( Origin gFrontEnd )
				)
				( attribute "XY" "(-1225,-650)"
					( Origin gFrontEnd )
				)
				( attribute "CHIPS_PART_NAME" "CAP_A"
					( Origin gPackager )
				)
				( attribute "CDS_PART_NAME" "CAP_A_0603V-47UF,4V,20%,X5R,60A"
					( Origin gPackager )
				)
				( attribute "GROUP" "PWR_MLCC_CAP"
					( Origin gFrontEnd )
				)
				( attribute "BOM_SS" "E15431-004"
					( Origin gFrontEnd )
				)
				( objectStatus "C5G2" )
			)
			( gate "@baseboard_fab2_lib.baseboard_fab2(sch_1):page217_i300"
				( attribute "CDS_LIB" "dev_discrete"
					( Origin gPackager )
				)
				( attribute "CDS_LOCATION" "C5G12"
					( Origin gPackager )
				)
				( attribute "CDS_SEC" "1"
					( Origin gPackager )
				)
				( attribute "LOCATION" "C5G12"
					( Origin gFrontEnd )
				)
				( attribute "MATERIAL" "X5R"
					( Origin gFrontEnd )
				)
				( attribute "PACK_TYPE" "0603V"
					( Origin gFrontEnd )
				)
				( attribute "PART_NUMBER" "602433-106"
					( Origin gFrontEnd )
				)
				( attribute "PHYS_PAGE" "217"
					( Origin gFrontEnd )
				)
				( attribute "ROT" "0"
					( Origin gFrontEnd )
				)
				( attribute "SEC" "1"
					( Origin gFrontEnd )
				)
				( attribute "SEC_TYPE" "0603V"
					( Origin gFrontEnd )
				)
				( attribute "TOLERANCE" "20%"
					( Origin gFrontEnd )
				)
				( attribute "VALUE" "47UF"
					( Origin gFrontEnd )
				)
				( attribute "VER" "1"
					( Origin gFrontEnd )
				)
				( attribute "VOLTAGE" "4V"
					( Units "uVoltage" "V" 1.000000)
					( Origin gFrontEnd )
				)
				( attribute "XY" "(-1525,-650)"
					( Origin gFrontEnd )
				)
				( attribute "CHIPS_PART_NAME" "CAP_A"
					( Origin gPackager )
				)
				( attribute "CDS_PART_NAME" "CAP_A_0603V-47UF,4V,20%,X5R,60A"
					( Origin gPackager )
				)
				( attribute "GROUP" "PWR_MLCC_CAP"
					( Origin gFrontEnd )
				)
				( attribute "BOM_SS" "E15431-004"
					( Origin gFrontEnd )
				)
				( objectStatus "C5G12" )
			)
			( gate "@baseboard_fab2_lib.baseboard_fab2(sch_1):page220_i260"
				( attribute "BOM_COST" "PROC_SOCKET"
					( Origin gFrontEnd )
				)
				( attribute "CDS_LIB" "dev_discrete"
					( Origin gPackager )
				)
				( attribute "CDS_LOCATION" "C5D7"
					( Origin gPackager )
				)
				( attribute "CDS_SEC" "1"
					( Origin gPackager )
				)
				( attribute "LOCATION" "C5D7"
					( Origin gFrontEnd )
				)
				( attribute "MATERIAL" "X6S"
					( Origin gFrontEnd )
				)
				( attribute "PACK_TYPE" "0603V"
					( Origin gFrontEnd )
				)
				( attribute "PART_NUMBER" "E15431-004"
					( Origin gFrontEnd )
				)
				( attribute "PHYS_PAGE" "220"
					( Origin gFrontEnd )
				)
				( attribute "ROOM" "PVCCIN_CPU0_DECAP_VR"
					( Origin gFrontEnd )
				)
				( attribute "ROT" "0"
					( Origin gFrontEnd )
				)
				( attribute "SEC" "1"
					( Origin gPackager )
				)
				( attribute "TOLERANCE" "20%"
					( Origin gFrontEnd )
				)
				( attribute "VALUE" "22.0UF"
					( Origin gFrontEnd )
				)
				( attribute "VER" "1"
					( Origin gFrontEnd )
				)
				( attribute "VOLTAGE" "4V"
					( Units "uVoltage" "V" 1.000000)
					( Origin gFrontEnd )
				)
				( attribute "XY" "(-750,2975)"
					( Origin gFrontEnd )
				)
				( attribute "CHIPS_PART_NAME" "CAP_A"
					( Origin gPackager )
				)
				( attribute "CDS_PART_NAME" "CAP_A_0603V-22.0UF,4V,20%,X6S,A"
					( Origin gPackager )
				)
				( attribute "GROUP" "PWR_MLCC_CAP"
					( Origin gFrontEnd )
				)
				( objectStatus "C5D7" )
			)
			( gate "@baseboard_fab2_lib.baseboard_fab2(sch_1):page220_i259"
				( attribute "BOM_COST" "PROC_SOCKET"
					( Origin gFrontEnd )
				)
				( attribute "CDS_LIB" "dev_discrete"
					( Origin gPackager )
				)
				( attribute "CDS_LOCATION" "C5D6"
					( Origin gPackager )
				)
				( attribute "CDS_SEC" "1"
					( Origin gPackager )
				)
				( attribute "LOCATION" "C5D6"
					( Origin gFrontEnd )
				)
				( attribute "MATERIAL" "X6S"
					( Origin gFrontEnd )
				)
				( attribute "PACK_TYPE" "0603V"
					( Origin gFrontEnd )
				)
				( attribute "PART_NUMBER" "E15431-004"
					( Origin gFrontEnd )
				)
				( attribute "PHYS_PAGE" "220"
					( Origin gFrontEnd )
				)
				( attribute "ROOM" "PVCCIN_CPU0_DECAP_VR"
					( Origin gFrontEnd )
				)
				( attribute "ROT" "0"
					( Origin gFrontEnd )
				)
				( attribute "SEC" "1"
					( Origin gPackager )
				)
				( attribute "TOLERANCE" "20%"
					( Origin gFrontEnd )
				)
				( attribute "VALUE" "22.0UF"
					( Origin gFrontEnd )
				)
				( attribute "VER" "1"
					( Origin gFrontEnd )
				)
				( attribute "VOLTAGE" "4V"
					( Units "uVoltage" "V" 1.000000)
					( Origin gFrontEnd )
				)
				( attribute "XY" "(-1100,2975)"
					( Origin gFrontEnd )
				)
				( attribute "CHIPS_PART_NAME" "CAP_A"
					( Origin gPackager )
				)
				( attribute "CDS_PART_NAME" "CAP_A_0603V-22.0UF,4V,20%,X6S,A"
					( Origin gPackager )
				)
				( attribute "GROUP" "PWR_MLCC_CAP"
					( Origin gFrontEnd )
				)
				( objectStatus "C5D6" )
			)
			( gate "@baseboard_fab2_lib.baseboard_fab2(sch_1):page217_i299"
				( attribute "CDS_LIB" "dev_discrete"
					( Origin gPackager )
				)
				( attribute "CDS_LOCATION" "C5G11"
					( Origin gPackager )
				)
				( attribute "CDS_SEC" "1"
					( Origin gPackager )
				)
				( attribute "LOCATION" "C5G11"
					( Origin gFrontEnd )
				)
				( attribute "MATERIAL" "X5R"
					( Origin gFrontEnd )
				)
				( attribute "PACK_TYPE" "0603V"
					( Origin gFrontEnd )
				)
				( attribute "PART_NUMBER" "602433-106"
					( Origin gFrontEnd )
				)
				( attribute "PHYS_PAGE" "217"
					( Origin gFrontEnd )
				)
				( attribute "ROT" "0"
					( Origin gFrontEnd )
				)
				( attribute "SEC" "1"
					( Origin gFrontEnd )
				)
				( attribute "SEC_TYPE" "0603V"
					( Origin gFrontEnd )
				)
				( attribute "TOLERANCE" "20%"
					( Origin gFrontEnd )
				)
				( attribute "VALUE" "47UF"
					( Origin gFrontEnd )
				)
				( attribute "VER" "1"
					( Origin gFrontEnd )
				)
				( attribute "VOLTAGE" "4V"
					( Units "uVoltage" "V" 1.000000)
					( Origin gFrontEnd )
				)
				( attribute "XY" "(-1825,-650)"
					( Origin gFrontEnd )
				)
				( attribute "CHIPS_PART_NAME" "CAP_A"
					( Origin gPackager )
				)
				( attribute "CDS_PART_NAME" "CAP_A_0603V-47UF,4V,20%,X5R,60A"
					( Origin gPackager )
				)
				( attribute "GROUP" "PWR_MLCC_CAP"
					( Origin gFrontEnd )
				)
				( attribute "BOM_SS" "E15431-004"
					( Origin gFrontEnd )
				)
				( objectStatus "C5G11" )
			)
			( gate "@baseboard_fab2_lib.baseboard_fab2(sch_1):page220_i258"
				( attribute "BOM_COST" "PROC_SOCKET"
					( Origin gFrontEnd )
				)
				( attribute "CDS_LIB" "dev_discrete"
					( Origin gPackager )
				)
				( attribute "CDS_LOCATION" "C5D9"
					( Origin gPackager )
				)
				( attribute "CDS_SEC" "1"
					( Origin gPackager )
				)
				( attribute "LOCATION" "C5D9"
					( Origin gFrontEnd )
				)
				( attribute "MATERIAL" "X6S"
					( Origin gFrontEnd )
				)
				( attribute "PACK_TYPE" "0603V"
					( Origin gFrontEnd )
				)
				( attribute "PART_NUMBER" "E15431-004"
					( Origin gFrontEnd )
				)
				( attribute "PHYS_PAGE" "220"
					( Origin gFrontEnd )
				)
				( attribute "ROOM" "PVCCIN_CPU0_DECAP_VR"
					( Origin gFrontEnd )
				)
				( attribute "ROT" "0"
					( Origin gFrontEnd )
				)
				( attribute "SEC" "1"
					( Origin gPackager )
				)
				( attribute "TOLERANCE" "20%"
					( Origin gFrontEnd )
				)
				( attribute "VALUE" "22.0UF"
					( Origin gFrontEnd )
				)
				( attribute "VER" "1"
					( Origin gFrontEnd )
				)
				( attribute "VOLTAGE" "4V"
					( Units "uVoltage" "V" 1.000000)
					( Origin gFrontEnd )
				)
				( attribute "XY" "(-1450,2975)"
					( Origin gFrontEnd )
				)
				( attribute "CHIPS_PART_NAME" "CAP_A"
					( Origin gPackager )
				)
				( attribute "CDS_PART_NAME" "CAP_A_0603V-22.0UF,4V,20%,X6S,A"
					( Origin gPackager )
				)
				( attribute "GROUP" "PWR_MLCC_CAP"
					( Origin gFrontEnd )
				)
				( objectStatus "C5D9" )
			)
			( gate "@baseboard_fab2_lib.baseboard_fab2(sch_1):page217_i259"
				( attribute "CDS_LIB" "mstr_misc"
					( Origin gPackager )
				)
				( attribute "CDS_LOCATION" "SH4U1"
					( Origin gPackager )
				)
				( attribute "CDS_SEC" "1"
					( Origin gPackager )
				)
				( attribute "LOCATION" "SH4U1"
					( Origin gFrontEnd )
				)
				( attribute "MATERIAL" "EMPTY"
					( Origin gFrontEnd )
				)
				( attribute "PACK_TYPE" "SH0201"
					( Origin gFrontEnd )
				)
				( attribute "PART_NUMBER" "N_A"
					( Origin gFrontEnd )
				)
				( attribute "PHYS_PAGE" "217"
					( Origin gFrontEnd )
				)
				( attribute "PIN_SHORT" "A:B"
					( Origin gFrontEnd )
				)
				( attribute "ROT" "0"
					( Origin gFrontEnd )
				)
				( attribute "SEC" "1"
					( Origin gFrontEnd )
				)
				( attribute "SEC_TYPE" "SH0201"
					( Origin gFrontEnd )
				)
				( attribute "VER" "1"
					( Origin gFrontEnd )
				)
				( attribute "XY" "(125,1500)"
					( Origin gFrontEnd )
				)
				( attribute "CHIPS_PART_NAME" "SHUNT"
					( Origin gPackager )
				)
				( attribute "CDS_PART_NAME" "SHUNT_SH0201-EMPTY,N_A"
					( Origin gPackager )
				)
				( objectStatus "SH4U1" )
			)
			( gate "@baseboard_fab2_lib.baseboard_fab2(sch_1):page217_i260"
				( attribute "CDS_LIB" "mstr_misc"
					( Origin gPackager )
				)
				( attribute "CDS_LOCATION" "SH4U2"
					( Origin gPackager )
				)
				( attribute "CDS_SEC" "1"
					( Origin gPackager )
				)
				( attribute "LOCATION" "SH4U2"
					( Origin gFrontEnd )
				)
				( attribute "MATERIAL" "EMPTY"
					( Origin gFrontEnd )
				)
				( attribute "PACK_TYPE" "SH0201"
					( Origin gFrontEnd )
				)
				( attribute "PART_NUMBER" "N_A"
					( Origin gFrontEnd )
				)
				( attribute "PHYS_PAGE" "217"
					( Origin gFrontEnd )
				)
				( attribute "PIN_SHORT" "A:B"
					( Origin gFrontEnd )
				)
				( attribute "ROT" "0"
					( Origin gFrontEnd )
				)
				( attribute "SEC" "1"
					( Origin gFrontEnd )
				)
				( attribute "SEC_TYPE" "SH0201"
					( Origin gFrontEnd )
				)
				( attribute "VER" "1"
					( Origin gFrontEnd )
				)
				( attribute "XY" "(150,1950)"
					( Origin gFrontEnd )
				)
				( attribute "CHIPS_PART_NAME" "SHUNT"
					( Origin gPackager )
				)
				( attribute "CDS_PART_NAME" "SHUNT_SH0201-EMPTY,N_A"
					( Origin gPackager )
				)
				( objectStatus "SH4U2" )
			)
			( gate "@baseboard_fab2_lib.baseboard_fab2(sch_1):page223_i54"
				( attribute "CDS_LIB" "mstr_discrete"
					( Origin gPackager )
				)
				( attribute "CDS_LOCATION" "R1G12"
					( Origin gPackager )
				)
				( attribute "LOCATION" "R1G12"
					( Origin gFrontEnd )
				)
				( attribute "MATERIAL" "CHIP"
					( Origin gFrontEnd )
				)
				( attribute "PACK_TYPE" "0402"
					( Origin gFrontEnd )
				)
				( attribute "PART_NUMBER" "G21796-250"
					( Origin gFrontEnd )
				)
				( attribute "PHYS_PAGE" "223"
					( Origin gFrontEnd )
				)
				( attribute "ROOM" "VDDQ_GHJ_PWR_VR"
					( Origin gFrontEnd )
				)
				( attribute "ROT" "0"
					( Origin gFrontEnd )
				)
				( attribute "SEC" "1"
					( Origin gFrontEnd )
				)
				( attribute "TOLERANCE" "1.0%"
					( Origin gFrontEnd )
				)
				( attribute "VALUE" "22.1"
					( Origin gFrontEnd )
				)
				( attribute "VER" "1"
					( Origin gFrontEnd )
				)
				( attribute "WATTAGE" "1/16W"
					( Origin gFrontEnd )
				)
				( attribute "XY" "(3275,2200)"
					( Origin gFrontEnd )
				)
				( attribute "CHIPS_PART_NAME" "RES"
					( Origin gPackager )
				)
				( attribute "CDS_PART_NAME" "RES_0402-22.1,1.0%,1/16W,CHIP,A"
					( Origin gPackager )
				)
				( attribute "POP" "NOPOP"
					( Origin gFrontEnd )
				)
				( attribute "SEC_TYPE" "0402"
					( Origin gFrontEnd )
				)
				( attribute "CDS_SEC" "1"
					( Origin gPackager )
				)
				( objectStatus "R1G12" )
			)
			( gate "@baseboard_fab2_lib.baseboard_fab2(sch_1):page223_i49"
				( attribute "CDS_LIB" "mstr_discrete"
					( Origin gPackager )
				)
				( attribute "CDS_LOCATION" "R1G11"
					( Origin gPackager )
				)
				( attribute "CDS_SEC" "1"
					( Origin gPackager )
				)
				( attribute "LOCATION" "R1G11"
					( Origin gFrontEnd )
				)
				( attribute "MATERIAL" "CHIP"
					( Origin gFrontEnd )
				)
				( attribute "PACK_TYPE" "0402"
					( Origin gFrontEnd )
				)
				( attribute "PART_NUMBER" "G21796-026"
					( Origin gFrontEnd )
				)
				( attribute "PHYS_PAGE" "223"
					( Origin gFrontEnd )
				)
				( attribute "ROOM" "RQ_PVDDQ_GHJ_VRHOT_LVT3_N"
					( Origin gFrontEnd )
				)
				( attribute "ROT" "0"
					( Origin gFrontEnd )
				)
				( attribute "SEC" "1"
					( Origin gFrontEnd )
				)
				( attribute "SEC_TYPE" "0402"
					( Origin gFrontEnd )
				)
				( attribute "TOLERANCE" "1%"
					( Origin gFrontEnd )
				)
				( attribute "VALUE" "1.00K"
					( Origin gFrontEnd )
				)
				( attribute "VER" "2"
					( Origin gFrontEnd )
				)
				( attribute "WATTAGE" "1/16W"
					( Origin gFrontEnd )
				)
				( attribute "XY" "(2100,2750)"
					( Origin gFrontEnd )
				)
				( attribute "CHIPS_PART_NAME" "RES"
					( Origin gPackager )
				)
				( attribute "CDS_PART_NAME" "RES_0402-1.00K,1%,1/16W,CHIP,GA"
					( Origin gPackager )
				)
				( objectStatus "R1G11" )
			)
			( gate "@baseboard_fab2_lib.baseboard_fab2(sch_1):page221_i40"
				( attribute "CDS_LIB" "dev_discrete"
					( Origin gPackager )
				)
				( attribute "CDS_LOCATION" "C5T3"
					( Origin gPackager )
				)
				( attribute "CDS_SEC" "1"
					( Origin gPackager )
				)
				( attribute "LOCATION" "C5T3"
					( Origin gFrontEnd )
				)
				( attribute "MATERIAL" "X5R"
					( Origin gFrontEnd )
				)
				( attribute "PACK_TYPE" "0603V"
					( Origin gFrontEnd )
				)
				( attribute "PART_NUMBER" "602433-106"
					( Origin gFrontEnd )
				)
				( attribute "PHYS_PAGE" "221"
					( Origin gFrontEnd )
				)
				( attribute "ROT" "0"
					( Origin gFrontEnd )
				)
				( attribute "SEC" "1"
					( Origin gFrontEnd )
				)
				( attribute "SEC_TYPE" "0603V"
					( Origin gFrontEnd )
				)
				( attribute "TOLERANCE" "20%"
					( Origin gFrontEnd )
				)
				( attribute "VALUE" "47UF"
					( Origin gFrontEnd )
				)
				( attribute "VER" "1"
					( Origin gFrontEnd )
				)
				( attribute "VOLTAGE" "4V"
					( Units "uVoltage" "V" 1.000000)
					( Origin gFrontEnd )
				)
				( attribute "XY" "(4075,3300)"
					( Origin gFrontEnd )
				)
				( attribute "CHIPS_PART_NAME" "CAP_A"
					( Origin gPackager )
				)
				( attribute "CDS_PART_NAME" "CAP_A_0603V-47UF,4V,20%,X5R,60A"
					( Origin gPackager )
				)
				( attribute "GROUP" "PWR_MLCC_CAP"
					( Origin gFrontEnd )
				)
				( objectStatus "C5T3" )
			)
			( gate "@baseboard_fab2_lib.baseboard_fab2(sch_1):page218_i14"
				( attribute "CDS_LIB" "mstr_discrete"
					( Origin gPackager )
				)
				( attribute "CDS_LOCATION" "C7A28"
					( Origin gPackager )
				)
				( attribute "CDS_SEC" "1"
					( Origin gPackager )
				)
				( attribute "LOCATION" "C7A28"
					( Origin gFrontEnd )
				)
				( attribute "MATERIAL" "X7R"
					( Origin gFrontEnd )
				)
				( attribute "PACK_TYPE" "0402LF"
					( Origin gFrontEnd )
				)
				( attribute "PART_NUMBER" "A36096-050"
					( Origin gFrontEnd )
				)
				( attribute "PHYS_PAGE" "218"
					( Origin gFrontEnd )
				)
				( attribute "ROOM" "VDDQ_DEF_PWR_VR"
					( Origin gFrontEnd )
				)
				( attribute "ROT" "0"
					( Origin gFrontEnd )
				)
				( attribute "SEC" "1"
					( Origin gFrontEnd )
				)
				( attribute "SEC_TYPE" "0402LF"
					( Origin gFrontEnd )
				)
				( attribute "TOLERANCE" "10%"
					( Origin gFrontEnd )
				)
				( attribute "VALUE" "220PF"
					( Origin gFrontEnd )
				)
				( attribute "VER" "1"
					( Origin gFrontEnd )
				)
				( attribute "VOLTAGE" "50V"
					( Units "uVoltage" "V" 1.000000)
					( Origin gFrontEnd )
				)
				( attribute "XY" "(-2650,725)"
					( Origin gFrontEnd )
				)
				( attribute "CHIPS_PART_NAME" "CAP"
					( Origin gPackager )
				)
				( attribute "CDS_PART_NAME" "CAP_0402LF-220PF,50V,10%,X7R,AA"
					( Origin gPackager )
				)
				( objectStatus "C7A28" )
			)
			( gate "@baseboard_fab2_lib.baseboard_fab2(sch_1):page218_i15"
				( attribute "CDS_LIB" "mstr_discrete"
					( Origin gPackager )
				)
				( attribute "CDS_LOCATION" "R3M6"
					( Origin gPackager )
				)
				( attribute "CDS_SEC" "1"
					( Origin gPackager )
				)
				( attribute "LOCATION" "R3M6"
					( Origin gFrontEnd )
				)
				( attribute "MATERIAL" "CHIP"
					( Origin gFrontEnd )
				)
				( attribute "PACK_TYPE" "0402"
					( Origin gFrontEnd )
				)
				( attribute "PART_NUMBER" "G21497-005"
					( Origin gFrontEnd )
				)
				( attribute "PHYS_PAGE" "218"
					( Origin gFrontEnd )
				)
				( attribute "ROOM" "VDDQ_DEF_PWR_VR"
					( Origin gFrontEnd )
				)
				( attribute "ROT" "0"
					( Origin gFrontEnd )
				)
				( attribute "SEC" "1"
					( Origin gFrontEnd )
				)
				( attribute "SEC_TYPE" "0402"
					( Origin gFrontEnd )
				)
				( attribute "TOLERANCE" "5%"
					( Origin gFrontEnd )
				)
				( attribute "VALUE" "0.0"
					( Origin gFrontEnd )
				)
				( attribute "VER" "1"
					( Origin gFrontEnd )
				)
				( attribute "WATTAGE" "1/16W"
					( Origin gFrontEnd )
				)
				( attribute "XY" "(-2900,1200)"
					( Origin gFrontEnd )
				)
				( attribute "CHIPS_PART_NAME" "RES"
					( Origin gPackager )
				)
				( attribute "CDS_PART_NAME" "RES_0402-0.0,5%,1/16W,CHIP,G21A"
					( Origin gPackager )
				)
				( objectStatus "R3M6" )
			)
			( gate "@baseboard_fab2_lib.baseboard_fab2(sch_1):page218_i16"
				( attribute "CDS_LIB" "mstr_discrete"
					( Origin gPackager )
				)
				( attribute "CDS_LOCATION" "C7A29"
					( Origin gPackager )
				)
				( attribute "CDS_SEC" "1"
					( Origin gPackager )
				)
				( attribute "LOCATION" "C7A29"
					( Origin gFrontEnd )
				)
				( attribute "MATERIAL" "X7R"
					( Origin gFrontEnd )
				)
				( attribute "PACK_TYPE" "0402LF"
					( Origin gFrontEnd )
				)
				( attribute "PART_NUMBER" "A36096-050"
					( Origin gFrontEnd )
				)
				( attribute "PHYS_PAGE" "218"
					( Origin gFrontEnd )
				)
				( attribute "ROOM" "VDDQ_DEF_PWR_VR"
					( Origin gFrontEnd )
				)
				( attribute "ROT" "2"
					( Origin gFrontEnd )
				)
				( attribute "SEC" "1"
					( Origin gFrontEnd )
				)
				( attribute "SEC_TYPE" "0402LF"
					( Origin gFrontEnd )
				)
				( attribute "TOLERANCE" "10%"
					( Origin gFrontEnd )
				)
				( attribute "VALUE" "220PF"
					( Origin gFrontEnd )
				)
				( attribute "VER" "1"
					( Origin gFrontEnd )
				)
				( attribute "VOLTAGE" "50V"
					( Units "uVoltage" "V" 1.000000)
					( Origin gFrontEnd )
				)
				( attribute "XY" "(-1250,450)"
					( Origin gFrontEnd )
				)
				( attribute "CHIPS_PART_NAME" "CAP"
					( Origin gPackager )
				)
				( attribute "CDS_PART_NAME" "CAP_0402LF-220PF,50V,10%,X7R,AA"
					( Origin gPackager )
				)
				( objectStatus "C7A29" )
			)
			( gate "@baseboard_fab2_lib.baseboard_fab2(sch_1):page218_i17"
				( attribute "CDS_LIB" "w_hdl"
					( Origin gPackager )
				)
				( attribute "CDS_LMAN_SYM_OUTLINE" "-50,25,50,-25"
					( Origin gPackager )
				)
				( attribute "CDS_LOCATION" "CF17"
					( Origin gPackager )
				)
				( attribute "CDS_SEC" "1"
					( Origin gPackager )
				)
				( attribute "LOCATION" "CF17"
					( Origin gFrontEnd )
				)
				( attribute "PACK_TYPE" "SMD-BCG"
					( Origin gFrontEnd )
				)
				( attribute "PART_NUMBER" "78.22034.1FL"
					( Origin gFrontEnd )
				)
				( attribute "PHYS_PAGE" "218"
					( Origin gFrontEnd )
				)
				( attribute "ROT" "1"
					( Origin gFrontEnd )
				)
				( attribute "SEC" "1"
					( Origin gPackager )
				)
				( attribute "VALUE" "SC22P50V2JN-4GP"
					( Origin gFrontEnd )
				)
				( attribute "VER" "1"
					( Origin gFrontEnd )
				)
				( attribute "XY" "(-2200,2250)"
					( Origin gFrontEnd )
				)
				( attribute "CHIPS_PART_NAME" "SC22P50V2JN-4GP"
					( Origin gPackager )
				)
				( attribute "CDS_PART_NAME" "SC22P50V2JN-4GP_SMD-BCG-SC22P5A"
					( Origin gPackager )
				)
				( attribute "ATTRIBUTE" "22PF"
					( Origin gFrontEnd )
				)
				( attribute "PACK_SIZE" "0402"
					( Origin gFrontEnd )
				)
				( attribute "RATED" "50V"
					( Origin gFrontEnd )
				)
				( attribute "TOLERANCE" "5%"
					( Origin gFrontEnd )
				)
				( attribute "TYPE" "NPO"
					( Origin gFrontEnd )
				)
				( attribute "GROUP" "POWER_FAIR"
					( Origin gFrontEnd )
				)
				( objectStatus "CF17" )
			)
			( gate "@baseboard_fab2_lib.baseboard_fab2(sch_1):page218_i21"
				( attribute "CDS_LIB" "mstr_discrete"
					( Origin gPackager )
				)
				( attribute "CDS_LOCATION" "R7A17"
					( Origin gPackager )
				)
				( attribute "LOCATION" "R7A17"
					( Origin gFrontEnd )
				)
				( attribute "MATERIAL" "CHIP"
					( Origin gFrontEnd )
				)
				( attribute "PACK_TYPE" "0402"
					( Origin gFrontEnd )
				)
				( attribute "PART_NUMBER" "G21796-009"
					( Origin gFrontEnd )
				)
				( attribute "PHYS_PAGE" "218"
					( Origin gFrontEnd )
				)
				( attribute "ROOM" "VDDQ_DEF_PWR_VR"
					( Origin gFrontEnd )
				)
				( attribute "ROT" "0"
					( Origin gFrontEnd )
				)
				( attribute "SEC" "1"
					( Origin gFrontEnd )
				)
				( attribute "TOLERANCE" "1%"
					( Origin gFrontEnd )
				)
				( attribute "VALUE" "150.0"
					( Origin gFrontEnd )
				)
				( attribute "VER" "1"
					( Origin gFrontEnd )
				)
				( attribute "WATTAGE" "1/16W"
					( Origin gFrontEnd )
				)
				( attribute "XY" "(-1475,2725)"
					( Origin gFrontEnd )
				)
				( attribute "CHIPS_PART_NAME" "RES"
					( Origin gPackager )
				)
				( attribute "CDS_PART_NAME" "RES_0402-150.0,1%,1/16W,CHIP,GA"
					( Origin gPackager )
				)
				( attribute "SEC_TYPE" "0402"
					( Origin gFrontEnd )
				)
				( attribute "CDS_SEC" "1"
					( Origin gPackager )
				)
				( objectStatus "R7A17" )
			)
			( gate "@baseboard_fab2_lib.baseboard_fab2(sch_1):page230_i41"
				( attribute "BOM_COST" "MEM_VRD_PVDDQ_CD"
					( Origin gFrontEnd )
				)
				( attribute "CDS_LIB" "mstr_discrete"
					( Origin gPackager )
				)
				( attribute "CDS_LOCATION" "C8L3"
					( Origin gPackager )
				)
				( attribute "CDS_SEC" "1"
					( Origin gPackager )
				)
				( attribute "LOCATION" "C8L3"
					( Origin gFrontEnd )
				)
				( attribute "MATERIAL" "X5R"
					( Origin gFrontEnd )
				)
				( attribute "NEW_MATERIAL" "X6S"
					( Origin gFrontEnd )
				)
				( attribute "PACK_TYPE" "0805"
					( Origin gFrontEnd )
				)
				( attribute "PART_NUMBER" "602433-112"
					( Origin gFrontEnd )
				)
				( attribute "PHYS_PAGE" "230"
					( Origin gFrontEnd )
				)
				( attribute "ROOM" "VDDQ_ABC_PWR_VR"
					( Origin gFrontEnd )
				)
				( attribute "ROT" "0"
					( Origin gFrontEnd )
				)
				( attribute "SEC" "1"
					( Origin gFrontEnd )
				)
				( attribute "SEC_TYPE" "0805"
					( Origin gFrontEnd )
				)
				( attribute "TOLERANCE" "20%"
					( Origin gFrontEnd )
				)
				( attribute "VALUE" "100UF"
					( Origin gFrontEnd )
				)
				( attribute "VER" "1"
					( Origin gFrontEnd )
				)
				( attribute "VOLTAGE" "4V"
					( Units "uVoltage" "V" 1.000000)
					( Origin gFrontEnd )
				)
				( attribute "XY" "(1750,2675)"
					( Origin gFrontEnd )
				)
				( attribute "CHIPS_PART_NAME" "CAP"
					( Origin gPackager )
				)
				( attribute "CDS_PART_NAME" "CAP_0805-100UF,4V,20%,X5R,6024A"
					( Origin gPackager )
				)
				( attribute "GROUP" "PWR_MLCC_CAP"
					( Origin gFrontEnd )
				)
				( attribute "NEW_PN" "078.1071T.M002"
					( Origin gFrontEnd )
				)
				( objectStatus "C8L3" )
			)
			( gate "@baseboard_fab2_lib.baseboard_fab2(sch_1):page222_i45"
				( attribute "BOM_COST" "MEM_VRD_PVDDQ_CD"
					( Origin gFrontEnd )
				)
				( attribute "CDS_LIB" "mstr_discrete"
					( Origin gPackager )
				)
				( attribute "CDS_LOCATION" "C5L4"
					( Origin gPackager )
				)
				( attribute "CDS_SEC" "1"
					( Origin gPackager )
				)
				( attribute "LOCATION" "C5L4"
					( Origin gFrontEnd )
				)
				( attribute "MATERIAL" "X5R"
					( Origin gFrontEnd )
				)
				( attribute "NEW_MATERIAL" "X6S"
					( Origin gFrontEnd )
				)
				( attribute "PACK_TYPE" "0805"
					( Origin gFrontEnd )
				)
				( attribute "PART_NUMBER" "602433-112"
					( Origin gFrontEnd )
				)
				( attribute "PHYS_PAGE" "222"
					( Origin gFrontEnd )
				)
				( attribute "ROOM" "VDDQ_ABC_PWR_VR"
					( Origin gFrontEnd )
				)
				( attribute "ROT" "0"
					( Origin gFrontEnd )
				)
				( attribute "SEC" "1"
					( Origin gFrontEnd )
				)
				( attribute "SEC_TYPE" "0805"
					( Origin gFrontEnd )
				)
				( attribute "TOLERANCE" "20%"
					( Origin gFrontEnd )
				)
				( attribute "VALUE" "100UF"
					( Origin gFrontEnd )
				)
				( attribute "VER" "1"
					( Origin gFrontEnd )
				)
				( attribute "VOLTAGE" "4V"
					( Units "uVoltage" "V" 1.000000)
					( Origin gFrontEnd )
				)
				( attribute "XY" "(2750,2825)"
					( Origin gFrontEnd )
				)
				( attribute "CHIPS_PART_NAME" "CAP"
					( Origin gPackager )
				)
				( attribute "CDS_PART_NAME" "CAP_0805-100UF,4V,20%,X5R,6024A"
					( Origin gPackager )
				)
				( attribute "GROUP" "PWR_MLCC_CAP"
					( Origin gFrontEnd )
				)
				( attribute "NEW_PN" "078.1071T.M002"
					( Origin gFrontEnd )
				)
				( objectStatus "C5L4" )
			)
			( gate "@baseboard_fab2_lib.baseboard_fab2(sch_1):page222_i23"
				( attribute "BOM_COST" "MEM_VRD_VTT_DEF"
					( Origin gFrontEnd )
				)
				( attribute "CDS_LIB" "mstr_discrete"
					( Origin gPackager )
				)
				( attribute "CDS_LOCATION" "R6L9"
					( Origin gPackager )
				)
				( attribute "CDS_SEC" "1"
					( Origin gPackager )
				)
				( attribute "LOCATION" "R6L9"
					( Origin gFrontEnd )
				)
				( attribute "MATERIAL" "CHIP"
					( Origin gFrontEnd )
				)
				( attribute "PACK_TYPE" "0402"
					( Origin gFrontEnd )
				)
				( attribute "PART_NUMBER" "G21796-016"
					( Origin gFrontEnd )
				)
				( attribute "PHYS_PAGE" "222"
					( Origin gFrontEnd )
				)
				( attribute "ROOM" "VTT_DEF_PWR_VR"
					( Origin gFrontEnd )
				)
				( attribute "ROT" "0"
					( Origin gFrontEnd )
				)
				( attribute "SEC" "1"
					( Origin gFrontEnd )
				)
				( attribute "SEC_TYPE" "0402"
					( Origin gFrontEnd )
				)
				( attribute "TOLERANCE" "1%"
					( Origin gFrontEnd )
				)
				( attribute "VALUE" "10.0K"
					( Origin gFrontEnd )
				)
				( attribute "VER" "2"
					( Origin gFrontEnd )
				)
				( attribute "WATTAGE" "1/16W"
					( Origin gFrontEnd )
				)
				( attribute "XY" "(2500,1650)"
					( Origin gFrontEnd )
				)
				( attribute "CHIPS_PART_NAME" "RES"
					( Origin gPackager )
				)
				( attribute "CDS_PART_NAME" "RES_0402-10.0K,1%,1/16W,CHIP,GA"
					( Origin gPackager )
				)
				( objectStatus "R6L9" )
			)
			( gate "@baseboard_fab2_lib.baseboard_fab2(sch_1):page222_i22"
				( attribute "BOM_COST" "MEM_VRD_VTT_DEF"
					( Origin gFrontEnd )
				)
				( attribute "CDS_LIB" "mstr_discrete"
					( Origin gPackager )
				)
				( attribute "CDS_LOCATION" "C4A12"
					( Origin gPackager )
				)
				( attribute "CDS_SEC" "1"
					( Origin gPackager )
				)
				( attribute "LOCATION" "C4A12"
					( Origin gFrontEnd )
				)
				( attribute "MATERIAL" "X7R"
					( Origin gFrontEnd )
				)
				( attribute "PACK_TYPE" "0402LF"
					( Origin gFrontEnd )
				)
				( attribute "PART_NUMBER" "A36096-046"
					( Origin gFrontEnd )
				)
				( attribute "PHYS_PAGE" "222"
					( Origin gFrontEnd )
				)
				( attribute "ROOM" "VTT_DEF_PWR_VR"
					( Origin gFrontEnd )
				)
				( attribute "ROT" "0"
					( Origin gFrontEnd )
				)
				( attribute "SEC" "1"
					( Origin gFrontEnd )
				)
				( attribute "SEC_TYPE" "0402LF"
					( Origin gFrontEnd )
				)
				( attribute "TOLERANCE" "10%"
					( Origin gFrontEnd )
				)
				( attribute "VALUE" "1000PF"
					( Origin gFrontEnd )
				)
				( attribute "VER" "1"
					( Origin gFrontEnd )
				)
				( attribute "VOLTAGE" "50V"
					( Units "uVoltage" "V" 1.000000)
					( Origin gFrontEnd )
				)
				( attribute "XY" "(3075,1175)"
					( Origin gFrontEnd )
				)
				( attribute "CHIPS_PART_NAME" "CAP"
					( Origin gPackager )
				)
				( attribute "CDS_PART_NAME" "CAP_0402LF-1000PF,50V,10%,X7R,A"
					( Origin gPackager )
				)
				( objectStatus "C4A12" )
			)
			( gate "@baseboard_fab2_lib.baseboard_fab2(sch_1):page222_i20"
				( attribute "BOM_COST" "MEM_VRD_VTT_DEF"
					( Origin gFrontEnd )
				)
				( attribute "CDS_LIB" "mstr_discrete"
					( Origin gPackager )
				)
				( attribute "CDS_LOCATION" "C4A9"
					( Origin gPackager )
				)
				( attribute "CDS_SEC" "1"
					( Origin gPackager )
				)
				( attribute "LOCATION" "C4A9"
					( Origin gFrontEnd )
				)
				( attribute "MATERIAL" "X6S"
					( Origin gFrontEnd )
				)
				( attribute "PACK_TYPE" "0402"
					( Origin gFrontEnd )
				)
				( attribute "PART_NUMBER" "D97712-011"
					( Origin gFrontEnd )
				)
				( attribute "PHYS_PAGE" "222"
					( Origin gFrontEnd )
				)
				( attribute "ROOM" "VTT_DEF_PWR_VR"
					( Origin gFrontEnd )
				)
				( attribute "ROT" "0"
					( Origin gFrontEnd )
				)
				( attribute "SEC" "1"
					( Origin gFrontEnd )
				)
				( attribute "SEC_TYPE" "0402"
					( Origin gFrontEnd )
				)
				( attribute "TOLERANCE" "10%"
					( Origin gFrontEnd )
				)
				( attribute "VALUE" "1.0UF"
					( Origin gFrontEnd )
				)
				( attribute "VER" "1"
					( Origin gFrontEnd )
				)
				( attribute "VOLTAGE" "16V"
					( Units "uVoltage" "V" 1.000000)
					( Origin gFrontEnd )
				)
				( attribute "XY" "(1625,400)"
					( Origin gFrontEnd )
				)
				( attribute "CHIPS_PART_NAME" "CAP"
					( Origin gPackager )
				)
				( attribute "CDS_PART_NAME" "CAP_0402-1.0UF,16V,10%,X6S,D97A"
					( Origin gPackager )
				)
				( objectStatus "C4A9" )
			)
			( gate "@baseboard_fab2_lib.baseboard_fab2(sch_1):page226_i72"
				( attribute "CDS_LIB" "mstr_discrete"
					( Origin gPackager )
				)
				( attribute "LOCATION" "R1B12"
					( Origin gFrontEnd )
				)
				( attribute "MATERIAL" "CHIP"
					( Origin gFrontEnd )
				)
				( attribute "PACK_TYPE" "0402"
					( Origin gFrontEnd )
				)
				( attribute "PART_NUMBER" "G21796-317"
					( Origin gFrontEnd )
				)
				( attribute "PHYS_PAGE" "226"
					( Origin gFrontEnd )
				)
				( attribute "ROOM" "VDDQ_ABC_PWR_VR"
					( Origin gFrontEnd )
				)
				( attribute "ROT" "0"
					( Origin gFrontEnd )
				)
				( attribute "TOLERANCE" "1.0%"
					( Origin gFrontEnd )
				)
				( attribute "VALUE" "16K"
					( Origin gFrontEnd )
				)
				( attribute "VER" "2"
					( Origin gFrontEnd )
				)
				( attribute "WATTAGE" "1/16W"
					( Origin gFrontEnd )
				)
				( attribute "XY" "(-50,-600)"
					( Origin gFrontEnd )
				)
				( attribute "CHIPS_PART_NAME" "RES"
					( Origin gPackager )
				)
				( attribute "CDS_PART_NAME" "RES_0402-16K,1.0%,1/16W,CHIP,GA"
					( Origin gPackager )
				)
				( attribute "CDS_LOCATION" "R1B12"
					( Origin gPackager )
				)
				( attribute "CDS_SEC" "1"
					( Origin gPackager )
				)
				( attribute "SEC" "1"
					( Origin gPackager )
				)
				( objectStatus "R1B12" )
			)
			( gate "@baseboard_fab2_lib.baseboard_fab2(sch_1):page218_i34"
				( attribute "CDS_LIB" "mstr_discrete"
					( Origin gPackager )
				)
				( attribute "CDS_LOCATION" "R3M5"
					( Origin gPackager )
				)
				( attribute "CDS_SEC" "1"
					( Origin gPackager )
				)
				( attribute "LOCATION" "R3M5"
					( Origin gFrontEnd )
				)
				( attribute "MATERIAL" "EMPTY"
					( Origin gFrontEnd )
				)
				( attribute "PACK_TYPE" "0402"
					( Origin gFrontEnd )
				)
				( attribute "PART_NUMBER" "G21796-010"
					( Origin gFrontEnd )
				)
				( attribute "PHYS_PAGE" "218"
					( Origin gFrontEnd )
				)
				( attribute "ROOM" "VDDQ_DEF_PWR_VR"
					( Origin gFrontEnd )
				)
				( attribute "ROT" "0"
					( Origin gFrontEnd )
				)
				( attribute "SEC" "1"
					( Origin gFrontEnd )
				)
				( attribute "SEC_TYPE" "0402"
					( Origin gFrontEnd )
				)
				( attribute "TOLERANCE" "1%"
					( Origin gFrontEnd )
				)
				( attribute "VALUE" "100.0K"
					( Origin gFrontEnd )
				)
				( attribute "VER" "2"
					( Origin gFrontEnd )
				)
				( attribute "WATTAGE" "1/16W"
					( Origin gFrontEnd )
				)
				( attribute "XY" "(-1150,3225)"
					( Origin gFrontEnd )
				)
				( attribute "CHIPS_PART_NAME" "RES"
					( Origin gPackager )
				)
				( attribute "CDS_PART_NAME" "RES_0402-100.0K,1%,1/16W,EMPTYA"
					( Origin gPackager )
				)
				( attribute "BOM_COST" "SM_CONTROLLER"
					( Origin gFrontEnd )
				)
				( objectStatus "R3M5" )
			)
			( gate "@baseboard_fab2_lib.baseboard_fab2(sch_1):page218_i35"
				( attribute "CDS_LIB" "mstr_discrete"
					( Origin gPackager )
				)
				( attribute "CDS_LOCATION" "R3M1"
					( Origin gPackager )
				)
				( attribute "LOCATION" "R3M1"
					( Origin gFrontEnd )
				)
				( attribute "MATERIAL" "CHIP"
					( Origin gFrontEnd )
				)
				( attribute "PACK_TYPE" "0402"
					( Origin gFrontEnd )
				)
				( attribute "PART_NUMBER" "G21497-005"
					( Origin gFrontEnd )
				)
				( attribute "PHYS_PAGE" "218"
					( Origin gFrontEnd )
				)
				( attribute "ROOM" "VDDQ_DEF_PWR_VR"
					( Origin gFrontEnd )
				)
				( attribute "ROT" "0"
					( Origin gFrontEnd )
				)
				( attribute "SEC" "1"
					( Origin gFrontEnd )
				)
				( attribute "TOLERANCE" "5%"
					( Origin gFrontEnd )
				)
				( attribute "VALUE" "0.0"
					( Origin gFrontEnd )
				)
				( attribute "VER" "2"
					( Origin gFrontEnd )
				)
				( attribute "WATTAGE" "1/16W"
					( Origin gFrontEnd )
				)
				( attribute "XY" "(-450,3150)"
					( Origin gFrontEnd )
				)
				( attribute "CHIPS_PART_NAME" "RES"
					( Origin gPackager )
				)
				( attribute "CDS_PART_NAME" "RES_0402-0.0,5%,1/16W,CHIP,G21A"
					( Origin gPackager )
				)
				( attribute "SEC_TYPE" "0402"
					( Origin gFrontEnd )
				)
				( attribute "CDS_SEC" "1"
					( Origin gPackager )
				)
				( objectStatus "R3M1" )
			)
			( gate "@baseboard_fab2_lib.baseboard_fab2(sch_1):page222_i17"
				( attribute "BOM_COST" "MEM_VRD_VTT_DEF"
					( Origin gFrontEnd )
				)
				( attribute "CDS_LIB" "mstr_discrete"
					( Origin gPackager )
				)
				( attribute "CDS_LOCATION" "C6L3"
					( Origin gPackager )
				)
				( attribute "CDS_SEC" "1"
					( Origin gPackager )
				)
				( attribute "LOCATION" "C6L3"
					( Origin gFrontEnd )
				)
				( attribute "MATERIAL" "X6S"
					( Origin gFrontEnd )
				)
				( attribute "PACK_TYPE" "0603LF"
					( Origin gFrontEnd )
				)
				( attribute "PART_NUMBER" "E15431-001"
					( Origin gFrontEnd )
				)
				( attribute "PHYS_PAGE" "222"
					( Origin gFrontEnd )
				)
				( attribute "ROOM" "VTT_DEF_PWR_VR"
					( Origin gFrontEnd )
				)
				( attribute "ROT" "0"
					( Origin gFrontEnd )
				)
				( attribute "SEC" "1"
					( Origin gFrontEnd )
				)
				( attribute "SEC_TYPE" "0603LF"
					( Origin gFrontEnd )
				)
				( attribute "TOLERANCE" "20%"
					( Origin gFrontEnd )
				)
				( attribute "VALUE" "10UF"
					( Origin gFrontEnd )
				)
				( attribute "VER" "1"
					( Origin gFrontEnd )
				)
				( attribute "VOLTAGE" "4V"
					( Units "uVoltage" "V" 1.000000)
					( Origin gFrontEnd )
				)
				( attribute "XY" "(-325,1925)"
					( Origin gFrontEnd )
				)
				( attribute "CHIPS_PART_NAME" "CAP"
					( Origin gPackager )
				)
				( attribute "CDS_PART_NAME" "CAP_0603LF-10UF,4V,20%,X6S,E15A"
					( Origin gPackager )
				)
				( objectStatus "C6L3" )
			)
			( gate "@baseboard_fab2_lib.baseboard_fab2(sch_1):page222_i15"
				( attribute "BOM_COST" "MEM_VRD_VTT_DEF"
					( Origin gFrontEnd )
				)
				( attribute "CDS_LIB" "mstr_discrete"
					( Origin gPackager )
				)
				( attribute "CDS_LOCATION" "C6L4"
					( Origin gPackager )
				)
				( attribute "CDS_SEC" "1"
					( Origin gPackager )
				)
				( attribute "LOCATION" "C6L4"
					( Origin gFrontEnd )
				)
				( attribute "MATERIAL" "X6S"
					( Origin gFrontEnd )
				)
				( attribute "PACK_TYPE" "0603LF"
					( Origin gFrontEnd )
				)
				( attribute "PART_NUMBER" "E15431-001"
					( Origin gFrontEnd )
				)
				( attribute "PHYS_PAGE" "222"
					( Origin gFrontEnd )
				)
				( attribute "ROOM" "VTT_DEF_PWR_VR"
					( Origin gFrontEnd )
				)
				( attribute "ROT" "0"
					( Origin gFrontEnd )
				)
				( attribute "SEC" "1"
					( Origin gFrontEnd )
				)
				( attribute "SEC_TYPE" "0603LF"
					( Origin gFrontEnd )
				)
				( attribute "TOLERANCE" "20%"
					( Origin gFrontEnd )
				)
				( attribute "VALUE" "10UF"
					( Origin gFrontEnd )
				)
				( attribute "VER" "1"
					( Origin gFrontEnd )
				)
				( attribute "VOLTAGE" "4V"
					( Units "uVoltage" "V" 1.000000)
					( Origin gFrontEnd )
				)
				( attribute "XY" "(-750,1900)"
					( Origin gFrontEnd )
				)
				( attribute "CHIPS_PART_NAME" "CAP"
					( Origin gPackager )
				)
				( attribute "CDS_PART_NAME" "CAP_0603LF-10UF,4V,20%,X6S,E15A"
					( Origin gPackager )
				)
				( objectStatus "C6L4" )
			)
			( gate "@baseboard_fab2_lib.baseboard_fab2(sch_1):page218_i40"
				( attribute "CDS_LIB" "dev_discrete"
					( Origin gPackager )
				)
				( attribute "CDS_LOCATION" "C7A37"
					( Origin gPackager )
				)
				( attribute "CDS_SEC" "1"
					( Origin gPackager )
				)
				( attribute "LOCATION" "C7A37"
					( Origin gFrontEnd )
				)
				( attribute "MATERIAL" "X6S"
					( Origin gFrontEnd )
				)
				( attribute "PACK_TYPE" "0402V"
					( Origin gFrontEnd )
				)
				( attribute "PART_NUMBER" "D97712-004"
					( Origin gFrontEnd )
				)
				( attribute "PHYS_PAGE" "218"
					( Origin gFrontEnd )
				)
				( attribute "ROOM" "VDDQ_DEF_PWR_VR"
					( Origin gFrontEnd )
				)
				( attribute "ROT" "0"
					( Origin gFrontEnd )
				)
				( attribute "SEC" "1"
					( Origin gFrontEnd )
				)
				( attribute "SEC_TYPE" "0402V"
					( Origin gFrontEnd )
				)
				( attribute "TOLERANCE" "10%"
					( Origin gFrontEnd )
				)
				( attribute "VALUE" "1.0UF"
					( Origin gFrontEnd )
				)
				( attribute "VER" "1"
					( Origin gFrontEnd )
				)
				( attribute "VOLTAGE" "6.3V"
					( Units "uVoltage" "V" 1.000000)
					( Origin gFrontEnd )
				)
				( attribute "XY" "(250,2800)"
					( Origin gFrontEnd )
				)
				( attribute "CHIPS_PART_NAME" "CAP_A"
					( Origin gPackager )
				)
				( attribute "CDS_PART_NAME" "CAP_A_0402V-1.0UF,6.3V,10%,X6SA"
					( Origin gPackager )
				)
				( objectStatus "C7A37" )
			)
			( gate "@baseboard_fab2_lib.baseboard_fab2(sch_1):page223_i75"
				( attribute "BOM_COST" "PROC_SIDEBAND"
					( Origin gFrontEnd )
				)
				( attribute "CDS_LIB" "mstr_discrete"
					( Origin gPackager )
				)
				( attribute "CDS_LOCATION" "R12W31"
					( Origin gPackager )
				)
				( attribute "CDS_SEC" "1"
					( Origin gPackager )
				)
				( attribute "LOCATION" "R12W31"
					( Origin gFrontEnd )
				)
				( attribute "MATERIAL" "CHIP"
					( Origin gFrontEnd )
				)
				( attribute "PACK_TYPE" "0402"
					( Origin gFrontEnd )
				)
				( attribute "PART_NUMBER" "G21497-005"
					( Origin gFrontEnd )
				)
				( attribute "PHYS_PAGE" "223"
					( Origin gFrontEnd )
				)
				( attribute "ROOM" "CPU0"
					( Origin gFrontEnd )
				)
				( attribute "ROT" "0"
					( Origin gFrontEnd )
				)
				( attribute "SEC" "1"
					( Origin gFrontEnd )
				)
				( attribute "SEC_TYPE" "0402"
					( Origin gFrontEnd )
				)
				( attribute "TOLERANCE" "5%"
					( Origin gFrontEnd )
				)
				( attribute "VALUE" "0.0"
					( Origin gFrontEnd )
				)
				( attribute "VER" "1"
					( Origin gFrontEnd )
				)
				( attribute "WATTAGE" "1/16W"
					( Origin gFrontEnd )
				)
				( attribute "XY" "(3250,1550)"
					( Origin gFrontEnd )
				)
				( attribute "CHIPS_PART_NAME" "RES"
					( Origin gPackager )
				)
				( attribute "CDS_PART_NAME" "RES_0402-0.0,5%,1/16W,CHIP,G21A"
					( Origin gPackager )
				)
				( objectStatus "R12W31" )
			)
			( gate "@baseboard_fab2_lib.baseboard_fab2(sch_1):page222_i13"
				( attribute "BOM_COST" "MEM_VRD_VTT_DEF"
					( Origin gFrontEnd )
				)
				( attribute "CDS_LIB" "mstr_vreg"
					( Origin gPackager )
				)
				( attribute "CDS_LMAN_SYM_OUTLINE" "-250,350,250,-350"
					( Origin gPackager )
				)
				( attribute "CDS_LOCATION" "EU4A1"
					( Origin gPackager )
				)
				( attribute "CDS_SEC" "1"
					( Origin gPackager )
				)
				( attribute "LOCATION" "EU4A1"
					( Origin gFrontEnd )
				)
				( attribute "MATERIAL" "IC"
					( Origin gFrontEnd )
				)
				( attribute "PACK_TYPE" "DFN"
					( Origin gFrontEnd )
				)
				( attribute "PART_NUMBER" "H55101-001"
					( Origin gFrontEnd )
				)
				( attribute "PHYS_PAGE" "222"
					( Origin gFrontEnd )
				)
				( attribute "ROOM" "VTT_DEF_PWR_VR"
					( Origin gFrontEnd )
				)
				( attribute "ROT" "0"
					( Origin gFrontEnd )
				)
				( attribute "SEC" "1"
					( Origin gFrontEnd )
				)
				( attribute "SEC_TYPE" "DFN"
					( Origin gFrontEnd )
				)
				( attribute "VER" "1"
					( Origin gFrontEnd )
				)
				( attribute "XY" "(775,600)"
					( Origin gFrontEnd )
				)
				( attribute "CHIPS_PART_NAME" "MIC5166"
					( Origin gPackager )
				)
				( attribute "CDS_PART_NAME" "MIC5166_DFN-IC,H55101-001"
					( Origin gPackager )
				)
				( objectStatus "EU4A1" )
			)
			( gate "@baseboard_fab2_lib.baseboard_fab2(sch_1):page218_i59"
				( attribute "CDS_LIB" "mstr_discrete"
					( Origin gPackager )
				)
				( attribute "CDS_LOCATION" "R7B1"
					( Origin gPackager )
				)
				( attribute "LOCATION" "R7B1"
					( Origin gFrontEnd )
				)
				( attribute "MATERIAL" "CHIP"
					( Origin gFrontEnd )
				)
				( attribute "PACK_TYPE" "0402"
					( Origin gFrontEnd )
				)
				( attribute "PART_NUMBER" "G21796-074"
					( Origin gFrontEnd )
				)
				( attribute "PHYS_PAGE" "218"
					( Origin gFrontEnd )
				)
				( attribute "ROT" "0"
					( Origin gFrontEnd )
				)
				( attribute "SEC" "1"
					( Origin gFrontEnd )
				)
				( attribute "TOLERANCE" "1%"
					( Origin gFrontEnd )
				)
				( attribute "VALUE" "33.2"
					( Origin gFrontEnd )
				)
				( attribute "VER" "1"
					( Origin gFrontEnd )
				)
				( attribute "WATTAGE" "1/16W"
					( Origin gFrontEnd )
				)
				( attribute "XY" "(1825,2150)"
					( Origin gFrontEnd )
				)
				( attribute "CHIPS_PART_NAME" "RES"
					( Origin gPackager )
				)
				( attribute "CDS_PART_NAME" "RES_0402-33.2,1%,1/16W,CHIP,G2A"
					( Origin gPackager )
				)
				( attribute "SEC_TYPE" "0402"
					( Origin gFrontEnd )
				)
				( attribute "CDS_SEC" "1"
					( Origin gPackager )
				)
				( objectStatus "R7B1" )
			)
			( gate "@baseboard_fab2_lib.baseboard_fab2(sch_1):page218_i60"
				( attribute "CDS_LIB" "mstr_discrete"
					( Origin gPackager )
				)
				( attribute "CDS_LOCATION" "R3M3"
					( Origin gPackager )
				)
				( attribute "CDS_SEC" "1"
					( Origin gPackager )
				)
				( attribute "LOCATION" "R3M3"
					( Origin gFrontEnd )
				)
				( attribute "MATERIAL" "CHIP"
					( Origin gFrontEnd )
				)
				( attribute "PACK_TYPE" "0402"
					( Origin gFrontEnd )
				)
				( attribute "PART_NUMBER" "G21796-250"
					( Origin gFrontEnd )
				)
				( attribute "PHYS_PAGE" "218"
					( Origin gFrontEnd )
				)
				( attribute "ROOM" "VDDQ_DEF_PWR_VR"
					( Origin gFrontEnd )
				)
				( attribute "ROT" "0"
					( Origin gFrontEnd )
				)
				( attribute "SEC" "1"
					( Origin gFrontEnd )
				)
				( attribute "SEC_TYPE" "0402"
					( Origin gFrontEnd )
				)
				( attribute "TOLERANCE" "1.0%"
					( Origin gFrontEnd )
				)
				( attribute "VALUE" "22.1"
					( Origin gFrontEnd )
				)
				( attribute "VER" "1"
					( Origin gFrontEnd )
				)
				( attribute "WATTAGE" "1/16W"
					( Origin gFrontEnd )
				)
				( attribute "XY" "(1925,2250)"
					( Origin gFrontEnd )
				)
				( attribute "CHIPS_PART_NAME" "RES"
					( Origin gPackager )
				)
				( attribute "CDS_PART_NAME" "RES_0402-22.1,1.0%,1/16W,CHIP,A"
					( Origin gPackager )
				)
				( attribute "POP" "NOPOP"
					( Origin gFrontEnd )
				)
				( objectStatus "R3M3" )
			)
			( gate "@baseboard_fab2_lib.baseboard_fab2(sch_1):page222_i10"
				( attribute "BOM_COST" "MEM_VRD_VTT_DEF"
					( Origin gFrontEnd )
				)
				( attribute "CDS_LIB" "mstr_discrete"
					( Origin gPackager )
				)
				( attribute "CDS_LOCATION" "R6L11"
					( Origin gPackager )
				)
				( attribute "CDS_SEC" "1"
					( Origin gPackager )
				)
				( attribute "LOCATION" "R6L11"
					( Origin gFrontEnd )
				)
				( attribute "MATERIAL" "CHIP"
					( Origin gFrontEnd )
				)
				( attribute "PACK_TYPE" "0402"
					( Origin gFrontEnd )
				)
				( attribute "PART_NUMBER" "G21497-005"
					( Origin gFrontEnd )
				)
				( attribute "PHYS_PAGE" "222"
					( Origin gFrontEnd )
				)
				( attribute "ROOM" "VTT_DEF_PWR_VR"
					( Origin gFrontEnd )
				)
				( attribute "ROT" "0"
					( Origin gFrontEnd )
				)
				( attribute "SEC" "1"
					( Origin gFrontEnd )
				)
				( attribute "SEC_TYPE" "0402"
					( Origin gFrontEnd )
				)
				( attribute "TOLERANCE" "5%"
					( Origin gFrontEnd )
				)
				( attribute "VALUE" "0.0"
					( Origin gFrontEnd )
				)
				( attribute "VER" "1"
					( Origin gFrontEnd )
				)
				( attribute "WATTAGE" "1/16W"
					( Origin gFrontEnd )
				)
				( attribute "XY" "(-650,1300)"
					( Origin gFrontEnd )
				)
				( attribute "CHIPS_PART_NAME" "RES"
					( Origin gPackager )
				)
				( attribute "CDS_PART_NAME" "RES_0402-0.0,5%,1/16W,CHIP,G21A"
					( Origin gPackager )
				)
				( objectStatus "R6L11" )
			)
			( gate "@baseboard_fab2_lib.baseboard_fab2(sch_1):page222_i9"
				( attribute "CDS_LIB" "mstr_discrete"
					( Origin gPackager )
				)
				( attribute "CDS_LOCATION" "C4A11"
					( Origin gPackager )
				)
				( attribute "CDS_SEC" "1"
					( Origin gPackager )
				)
				( attribute "LOCATION" "C4A11"
					( Origin gFrontEnd )
				)
				( attribute "MATERIAL" "X6S"
					( Origin gFrontEnd )
				)
				( attribute "PACK_TYPE" "0603"
					( Origin gFrontEnd )
				)
				( attribute "PART_NUMBER" "E15431-003"
					( Origin gFrontEnd )
				)
				( attribute "PHYS_PAGE" "222"
					( Origin gFrontEnd )
				)
				( attribute "ROOM" "VTT_DEF_PWR_VR"
					( Origin gFrontEnd )
				)
				( attribute "ROT" "0"
					( Origin gFrontEnd )
				)
				( attribute "SEC" "1"
					( Origin gFrontEnd )
				)
				( attribute "SEC_TYPE" "0603"
					( Origin gFrontEnd )
				)
				( attribute "TOLERANCE" "10%"
					( Origin gFrontEnd )
				)
				( attribute "VALUE" "4.7UF"
					( Origin gFrontEnd )
				)
				( attribute "VER" "1"
					( Origin gFrontEnd )
				)
				( attribute "VOLTAGE" "6.3V"
					( Units "uVoltage" "V" 1.000000)
					( Origin gFrontEnd )
				)
				( attribute "XY" "(-675,525)"
					( Origin gFrontEnd )
				)
				( attribute "CHIPS_PART_NAME" "CAP"
					( Origin gPackager )
				)
				( attribute "CDS_PART_NAME" "CAP_0603-4.7UF,6.3V,10%,X6S,E1A"
					( Origin gPackager )
				)
				( objectStatus "C4A11" )
			)
			( gate "@baseboard_fab2_lib.baseboard_fab2(sch_1):page219_i44"
				( attribute "CDS_LIB" "mstr_discrete"
					( Origin gPackager )
				)
				( attribute "CDS_LOCATION" "C7A12"
					( Origin gPackager )
				)
				( attribute "LOCATION" "C7A12"
					( Origin gFrontEnd )
				)
				( attribute "MATERIAL" "X7R"
					( Origin gFrontEnd )
				)
				( attribute "PACK_TYPE" "0402"
					( Origin gFrontEnd )
				)
				( attribute "PART_NUMBER" "A36096-104"
					( Origin gFrontEnd )
				)
				( attribute "PHYS_PAGE" "219"
					( Origin gFrontEnd )
				)
				( attribute "ROOM" "VDDQ_DEF_PWR_VR"
					( Origin gFrontEnd )
				)
				( attribute "ROT" "2"
					( Origin gFrontEnd )
				)
				( attribute "SEC" "1"
					( Origin gFrontEnd )
				)
				( attribute "SPOF" "TRUE"
					( Origin gFrontEnd )
				)
				( attribute "TOLERANCE" "10%"
					( Origin gFrontEnd )
				)
				( attribute "VALUE" "0.220UF"
					( Origin gFrontEnd )
				)
				( attribute "VER" "1"
					( Origin gFrontEnd )
				)
				( attribute "VOLTAGE" "16V"
					( Units "uVoltage" "V" 1.000000)
					( Origin gFrontEnd )
				)
				( attribute "XY" "(-1100,1775)"
					( Origin gFrontEnd )
				)
				( attribute "CHIPS_PART_NAME" "CAP"
					( Origin gPackager )
				)
				( attribute "CDS_PART_NAME" "CAP_0402-0.220UF,16V,10%,X7R,AA"
					( Origin gPackager )
				)
				( attribute "SEC_TYPE" "0402"
					( Origin gFrontEnd )
				)
				( attribute "CDS_SEC" "1"
					( Origin gPackager )
				)
				( objectStatus "C7A12" )
			)
			( gate "@baseboard_fab2_lib.baseboard_fab2(sch_1):page219_i45"
				( attribute "CDS_LIB" "mstr_discrete"
					( Origin gPackager )
				)
				( attribute "CDS_LOCATION" "C3L2"
					( Origin gPackager )
				)
				( attribute "LOCATION" "C3L2"
					( Origin gFrontEnd )
				)
				( attribute "MATERIAL" "X6S"
					( Origin gFrontEnd )
				)
				( attribute "PACK_TYPE" "0805"
					( Origin gFrontEnd )
				)
				( attribute "PART_NUMBER" "C95333-007"
					( Origin gFrontEnd )
				)
				( attribute "PHYS_PAGE" "219"
					( Origin gFrontEnd )
				)
				( attribute "ROOM" "VDDQ_DEF_PWR_VR"
					( Origin gFrontEnd )
				)
				( attribute "ROT" "0"
					( Origin gFrontEnd )
				)
				( attribute "SEC" "1"
					( Origin gFrontEnd )
				)
				( attribute "TOLERANCE" "10%"
					( Origin gFrontEnd )
				)
				( attribute "VALUE" "10UF"
					( Origin gFrontEnd )
				)
				( attribute "VER" "1"
					( Origin gFrontEnd )
				)
				( attribute "VOLTAGE" "16V"
					( Units "uVoltage" "V" 1.000000)
					( Origin gFrontEnd )
				)
				( attribute "XY" "(-2225,2425)"
					( Origin gFrontEnd )
				)
				( attribute "CHIPS_PART_NAME" "CAP"
					( Origin gPackager )
				)
				( attribute "CDS_PART_NAME" "CAP_0805-10UF,16V,10%,X6S,C953A"
					( Origin gPackager )
				)
				( attribute "SEC_TYPE" "0805"
					( Origin gFrontEnd )
				)
				( attribute "CDS_SEC" "1"
					( Origin gPackager )
				)
				( objectStatus "C3L2" )
			)
			( gate "@baseboard_fab2_lib.baseboard_fab2(sch_1):page219_i46"
				( attribute "CDS_LIB" "mstr_discrete"
					( Origin gPackager )
				)
				( attribute "CDS_LOCATION" "C3L4"
					( Origin gPackager )
				)
				( attribute "LOCATION" "C3L4"
					( Origin gFrontEnd )
				)
				( attribute "MATERIAL" "X6S"
					( Origin gFrontEnd )
				)
				( attribute "PACK_TYPE" "0805"
					( Origin gFrontEnd )
				)
				( attribute "PART_NUMBER" "C95333-007"
					( Origin gFrontEnd )
				)
				( attribute "PHYS_PAGE" "219"
					( Origin gFrontEnd )
				)
				( attribute "ROOM" "VDDQ_DEF_PWR_VR"
					( Origin gFrontEnd )
				)
				( attribute "ROT" "0"
					( Origin gFrontEnd )
				)
				( attribute "SEC" "1"
					( Origin gFrontEnd )
				)
				( attribute "TOLERANCE" "10%"
					( Origin gFrontEnd )
				)
				( attribute "VALUE" "10UF"
					( Origin gFrontEnd )
				)
				( attribute "VER" "1"
					( Origin gFrontEnd )
				)
				( attribute "VOLTAGE" "16V"
					( Units "uVoltage" "V" 1.000000)
					( Origin gFrontEnd )
				)
				( attribute "XY" "(-2000,2425)"
					( Origin gFrontEnd )
				)
				( attribute "CHIPS_PART_NAME" "CAP"
					( Origin gPackager )
				)
				( attribute "CDS_PART_NAME" "CAP_0805-10UF,16V,10%,X6S,C953A"
					( Origin gPackager )
				)
				( attribute "SEC_TYPE" "0805"
					( Origin gFrontEnd )
				)
				( attribute "CDS_SEC" "1"
					( Origin gPackager )
				)
				( objectStatus "C3L4" )
			)
			( gate "@baseboard_fab2_lib.baseboard_fab2(sch_1):page219_i47"
				( attribute "CDS_LIB" "mstr_discrete"
					( Origin gPackager )
				)
				( attribute "CDS_LOCATION" "C3L13"
					( Origin gPackager )
				)
				( attribute "LOCATION" "C3L13"
					( Origin gFrontEnd )
				)
				( attribute "MATERIAL" "X6S"
					( Origin gFrontEnd )
				)
				( attribute "PACK_TYPE" "0805"
					( Origin gFrontEnd )
				)
				( attribute "PART_NUMBER" "C95333-007"
					( Origin gFrontEnd )
				)
				( attribute "PHYS_PAGE" "219"
					( Origin gFrontEnd )
				)
				( attribute "ROOM" "VDDQ_DEF_PWR_VR"
					( Origin gFrontEnd )
				)
				( attribute "ROT" "0"
					( Origin gFrontEnd )
				)
				( attribute "SEC" "1"
					( Origin gFrontEnd )
				)
				( attribute "TOLERANCE" "10%"
					( Origin gFrontEnd )
				)
				( attribute "VALUE" "10UF"
					( Origin gFrontEnd )
				)
				( attribute "VER" "1"
					( Origin gFrontEnd )
				)
				( attribute "VOLTAGE" "16V"
					( Units "uVoltage" "V" 1.000000)
					( Origin gFrontEnd )
				)
				( attribute "XY" "(-1775,2425)"
					( Origin gFrontEnd )
				)
				( attribute "CHIPS_PART_NAME" "CAP"
					( Origin gPackager )
				)
				( attribute "CDS_PART_NAME" "CAP_0805-10UF,16V,10%,X6S,C953A"
					( Origin gPackager )
				)
				( attribute "SEC_TYPE" "0805"
					( Origin gFrontEnd )
				)
				( attribute "CDS_SEC" "1"
					( Origin gPackager )
				)
				( objectStatus "C3L13" )
			)
			( gate "@baseboard_fab2_lib.baseboard_fab2(sch_1):page219_i48"
				( attribute "CDS_LIB" "mstr_discrete"
					( Origin gPackager )
				)
				( attribute "CDS_LOCATION" "C7A11"
					( Origin gPackager )
				)
				( attribute "LOCATION" "C7A11"
					( Origin gFrontEnd )
				)
				( attribute "MATERIAL" "X6S"
					( Origin gFrontEnd )
				)
				( attribute "PACK_TYPE" "0402"
					( Origin gFrontEnd )
				)
				( attribute "PART_NUMBER" "D97712-011"
					( Origin gFrontEnd )
				)
				( attribute "PHYS_PAGE" "219"
					( Origin gFrontEnd )
				)
				( attribute "ROOM" "VDDQ_DEF_PWR_VR"
					( Origin gFrontEnd )
				)
				( attribute "ROT" "0"
					( Origin gFrontEnd )
				)
				( attribute "SEC" "1"
					( Origin gFrontEnd )
				)
				( attribute "TOLERANCE" "10%"
					( Origin gFrontEnd )
				)
				( attribute "VALUE" "1.0UF"
					( Origin gFrontEnd )
				)
				( attribute "VER" "1"
					( Origin gFrontEnd )
				)
				( attribute "VOLTAGE" "16V"
					( Units "uVoltage" "V" 1.000000)
					( Origin gFrontEnd )
				)
				( attribute "XY" "(-1475,2425)"
					( Origin gFrontEnd )
				)
				( attribute "CHIPS_PART_NAME" "CAP"
					( Origin gPackager )
				)
				( attribute "CDS_PART_NAME" "CAP_0402-1.0UF,16V,10%,X6S,D97A"
					( Origin gPackager )
				)
				( attribute "SEC_TYPE" "0402"
					( Origin gFrontEnd )
				)
				( attribute "CDS_SEC" "1"
					( Origin gPackager )
				)
				( objectStatus "C7A11" )
			)
			( gate "@baseboard_fab2_lib.baseboard_fab2(sch_1):page219_i50"
				( attribute "CDS_LIB" "mstr_discrete"
					( Origin gPackager )
				)
				( attribute "CDS_LOCATION" "C7A16"
					( Origin gPackager )
				)
				( attribute "LOCATION" "C7A16"
					( Origin gFrontEnd )
				)
				( attribute "MATERIAL" "X6S"
					( Origin gFrontEnd )
				)
				( attribute "PACK_TYPE" "0402"
					( Origin gFrontEnd )
				)
				( attribute "PART_NUMBER" "D97712-011"
					( Origin gFrontEnd )
				)
				( attribute "PHYS_PAGE" "219"
					( Origin gFrontEnd )
				)
				( attribute "ROOM" "VDDQ_DEF_PWR_VR"
					( Origin gFrontEnd )
				)
				( attribute "ROT" "0"
					( Origin gFrontEnd )
				)
				( attribute "SEC" "1"
					( Origin gFrontEnd )
				)
				( attribute "TOLERANCE" "10%"
					( Origin gFrontEnd )
				)
				( attribute "VALUE" "1.0UF"
					( Origin gFrontEnd )
				)
				( attribute "VER" "1"
					( Origin gFrontEnd )
				)
				( attribute "VOLTAGE" "16V"
					( Units "uVoltage" "V" 1.000000)
					( Origin gFrontEnd )
				)
				( attribute "XY" "(-875,2425)"
					( Origin gFrontEnd )
				)
				( attribute "CHIPS_PART_NAME" "CAP"
					( Origin gPackager )
				)
				( attribute "CDS_PART_NAME" "CAP_0402-1.0UF,16V,10%,X6S,D97A"
					( Origin gPackager )
				)
				( attribute "SEC_TYPE" "0402"
					( Origin gFrontEnd )
				)
				( attribute "CDS_SEC" "1"
					( Origin gPackager )
				)
				( objectStatus "C7A16" )
			)
			( gate "@baseboard_fab2_lib.baseboard_fab2(sch_1):page219_i51"
				( attribute "CDS_LIB" "dev_discrete"
					( Origin gPackager )
				)
				( attribute "CDS_LOCATION" "C7A5"
					( Origin gPackager )
				)
				( attribute "LOCATION" "C7A5"
					( Origin gFrontEnd )
				)
				( attribute "MATERIAL" "X7R"
					( Origin gFrontEnd )
				)
				( attribute "PACK_TYPE" "0402V"
					( Origin gFrontEnd )
				)
				( attribute "PART_NUMBER" "A36096-030"
					( Origin gFrontEnd )
				)
				( attribute "PHYS_PAGE" "219"
					( Origin gFrontEnd )
				)
				( attribute "ROOM" "VDDQ_DEF_PWR_VR"
					( Origin gFrontEnd )
				)
				( attribute "ROT" "0"
					( Origin gFrontEnd )
				)
				( attribute "SEC" "1"
					( Origin gFrontEnd )
				)
				( attribute "TOLERANCE" "10%"
					( Origin gFrontEnd )
				)
				( attribute "VALUE" "0.1UF"
					( Origin gFrontEnd )
				)
				( attribute "VER" "1"
					( Origin gFrontEnd )
				)
				( attribute "VOLTAGE" "16V"
					( Units "uVoltage" "V" 1.000000)
					( Origin gFrontEnd )
				)
				( attribute "XY" "(-1175,2425)"
					( Origin gFrontEnd )
				)
				( attribute "CHIPS_PART_NAME" "CAP_A"
					( Origin gPackager )
				)
				( attribute "CDS_PART_NAME" "CAP_A_0402V-0.1UF,16V,10%,X7R,A"
					( Origin gPackager )
				)
				( attribute "SEC_TYPE" "0402V"
					( Origin gFrontEnd )
				)
				( attribute "CDS_SEC" "1"
					( Origin gPackager )
				)
				( objectStatus "C7A5" )
			)
			( gate "@baseboard_fab2_lib.baseboard_fab2(sch_1):page224_i151"
				( attribute "BOM_COST" "PROC_SIDEBAND"
					( Origin gFrontEnd )
				)
				( attribute "CDS_LIB" "mstr_discrete"
					( Origin gPackager )
				)
				( attribute "CDS_LOCATION" "R9U12"
					( Origin gPackager )
				)
				( attribute "CDS_SEC" "1"
					( Origin gPackager )
				)
				( attribute "LOCATION" "R9U12"
					( Origin gFrontEnd )
				)
				( attribute "MATERIAL" "CHIP"
					( Origin gFrontEnd )
				)
				( attribute "PACK_TYPE" "0402"
					( Origin gFrontEnd )
				)
				( attribute "PART_NUMBER" "G21497-005"
					( Origin gFrontEnd )
				)
				( attribute "PHYS_PAGE" "224"
					( Origin gFrontEnd )
				)
				( attribute "ROOM" "CPU0"
					( Origin gFrontEnd )
				)
				( attribute "ROT" "0"
					( Origin gFrontEnd )
				)
				( attribute "SEC" "1"
					( Origin gFrontEnd )
				)
				( attribute "SEC_TYPE" "0402"
					( Origin gFrontEnd )
				)
				( attribute "TOLERANCE" "5%"
					( Origin gFrontEnd )
				)
				( attribute "VALUE" "0.0"
					( Origin gFrontEnd )
				)
				( attribute "VER" "1"
					( Origin gFrontEnd )
				)
				( attribute "WATTAGE" "1/16W"
					( Origin gFrontEnd )
				)
				( attribute "XY" "(-550,675)"
					( Origin gFrontEnd )
				)
				( attribute "CHIPS_PART_NAME" "RES"
					( Origin gPackager )
				)
				( attribute "CDS_PART_NAME" "RES_0402-0.0,5%,1/16W,CHIP,G21A"
					( Origin gPackager )
				)
				( attribute "BOM_SS" "NOPOP"
					( Origin gFrontEnd )
				)
				( objectStatus "R9U12" )
			)
			( gate "@baseboard_fab2_lib.baseboard_fab2(sch_1):page216_i150"
				( attribute "CDS_LIB" "w_hdl"
					( Origin gPackager )
				)
				( attribute "CDS_LMAN_SYM_OUTLINE" "-50,25,50,-25"
					( Origin gPackager )
				)
				( attribute "LOCATION" "C7G42"
					( Origin gFrontEnd )
				)
				( attribute "PACK_TYPE" "SMD-BCG6"
					( Origin gFrontEnd )
				)
				( attribute "PART_NUMBER" "78.10523.8FL"
					( Origin gFrontEnd )
				)
				( attribute "PHYS_PAGE" "216"
					( Origin gFrontEnd )
				)
				( attribute "ROT" "0"
					( Origin gFrontEnd )
				)
				( attribute "SEC" "1"
					( Origin gFrontEnd )
				)
				( attribute "SEC_TYPE" "SMD-BCG6"
					( Origin gFrontEnd )
				)
				( attribute "VALUE" "SC1U10V2KX-4-GP"
					( Origin gFrontEnd )
				)
				( attribute "VER" "1"
					( Origin gFrontEnd )
				)
				( attribute "XY" "(-325,175)"
					( Origin gFrontEnd )
				)
				( attribute "CHIPS_PART_NAME" "SC1U10V2KX-4-GP"
					( Origin gPackager )
				)
				( attribute "CDS_PART_NAME" "SC1U10V2KX-4-GP_SMD-BCG6-SC1U1A"
					( Origin gPackager )
				)
				( attribute "CDS_LOCATION" "C7G42"
					( Origin gPackager )
				)
				( attribute "CDS_SEC" "1"
					( Origin gPackager )
				)
				( attribute "ATTRIBUTE" "1UF"
					( Origin gFrontEnd )
				)
				( attribute "PACK_SIZE" "0402"
					( Origin gFrontEnd )
				)
				( attribute "RATED" "10V"
					( Origin gFrontEnd )
				)
				( attribute "TOLERANCE" "10%"
					( Origin gFrontEnd )
				)
				( attribute "BOM_SS" "NOPOP"
					( Origin gFrontEnd )
				)
				( objectStatus "C7G42" )
			)
			( gate "@baseboard_fab2_lib.baseboard_fab2(sch_1):page219_i54"
				( attribute "CDS_LIB" "mstr_discrete"
					( Origin gPackager )
				)
				( attribute "CDS_LOCATION" "C7A17"
					( Origin gPackager )
				)
				( attribute "LOCATION" "C7A17"
					( Origin gFrontEnd )
				)
				( attribute "MATERIAL" "X7R"
					( Origin gFrontEnd )
				)
				( attribute "PACK_TYPE" "0402"
					( Origin gFrontEnd )
				)
				( attribute "PART_NUMBER" "A36096-155"
					( Origin gFrontEnd )
				)
				( attribute "PHYS_PAGE" "219"
					( Origin gFrontEnd )
				)
				( attribute "ROOM" "VDDQ_DEF_PWR_VR"
					( Origin gFrontEnd )
				)
				( attribute "ROT" "0"
					( Origin gFrontEnd )
				)
				( attribute "SEC" "1"
					( Origin gFrontEnd )
				)
				( attribute "TOLERANCE" "10%"
					( Origin gFrontEnd )
				)
				( attribute "VALUE" "0.22UF"
					( Origin gFrontEnd )
				)
				( attribute "VER" "1"
					( Origin gFrontEnd )
				)
				( attribute "VOLTAGE" "16V"
					( Units "uVoltage" "V" 1.000000)
					( Origin gFrontEnd )
				)
				( attribute "XY" "(-125,2425)"
					( Origin gFrontEnd )
				)
				( attribute "CHIPS_PART_NAME" "CAP"
					( Origin gPackager )
				)
				( attribute "CDS_PART_NAME" "CAP_0402-0.22UF,16V,10%,X7R,A3A"
					( Origin gPackager )
				)
				( attribute "SEC_TYPE" "0402"
					( Origin gFrontEnd )
				)
				( attribute "CDS_SEC" "1"
					( Origin gPackager )
				)
				( objectStatus "C7A17" )
			)
			( gate "@baseboard_fab2_lib.baseboard_fab2(sch_1):page216_i153"
				( attribute "ATTRIBUTE" "120NH"
					( Origin gFrontEnd )
				)
				( attribute "CDS_LIB" "w_hdl"
					( Origin gPackager )
				)
				( attribute "CDS_LMAN_SYM_OUTLINE" "-75,100,75,-100"
					( Origin gPackager )
				)
				( attribute "CDS_LOCATION" "L7G1"
					( Origin gPackager )
				)
				( attribute "CDS_SEC" "1"
					( Origin gPackager )
				)
				( attribute "LOCATION" "L7G1"
					( Origin gFrontEnd )
				)
				( attribute "NEW_PACK_SIZE" "DCR=0.17MOHM"
					( Origin gFrontEnd )
				)
				( attribute "NEW_RATED" "DS_ISAT=134A@25C"
					( Origin gFrontEnd )
				)
				( attribute "NEW_TYPE" "IRMS=66A@DELTA_T<40C"
					( Origin gFrontEnd )
				)
				( attribute "PACK_SIZE" "DCR=0.17MOHM"
					( Origin gFrontEnd )
				)
				( attribute "PACK_TYPE" "DISCRET-GB2"
					( Origin gFrontEnd )
				)
				( attribute "PART_NUMBER" "068.1202N.M001"
					( Origin gFrontEnd )
				)
				( attribute "PHYS_PAGE" "216"
					( Origin gFrontEnd )
				)
				( attribute "RATED" "ISAT=94A@25C"
					( Origin gFrontEnd )
				)
				( attribute "ROT" "1"
					( Origin gFrontEnd )
				)
				( attribute "SEC" "1"
					( Origin gFrontEnd )
				)
				( attribute "SEC_TYPE" "DISCRET-GB2"
					( Origin gFrontEnd )
				)
				( attribute "TYPE" "IRMS=66A@DELTA_T<40C"
					( Origin gFrontEnd )
				)
				( attribute "VALUE" "IND-120NH-30-GP"
					( Origin gFrontEnd )
				)
				( attribute "VER" "1"
					( Origin gFrontEnd )
				)
				( attribute "XY" "(3900,2025)"
					( Origin gFrontEnd )
				)
				( attribute "CHIPS_PART_NAME" "IND-120NH-30-GP"
					( Origin gPackager )
				)
				( attribute "CDS_PART_NAME" "IND-120NH-30-GP_DISCRET-GB2-INA"
					( Origin gPackager )
				)
				( attribute "BOM_DS" "068.9002N.1021"
					( Origin gFrontEnd )
				)
				( attribute "DS_VALUE" "90NH"
					( Origin gFrontEnd )
				)
				( attribute "BOM_SS" "068.1202N.M001"
					( Origin gFrontEnd )
				)
				( attribute "SS_ISAT" "94A@25C"
					( Origin gFrontEnd )
				)
				( attribute "SS_VALUE" "120NH"
					( Origin gFrontEnd )
				)
				( objectStatus "L7G1" )
			)
			( gate "@baseboard_fab2_lib.baseboard_fab2(sch_1):page219_i158"
				( attribute "ATTRIBUTE" "120NH"
					( Origin gFrontEnd )
				)
				( attribute "BOM_DS" "068.9002N.1021"
					( Origin gFrontEnd )
				)
				( attribute "BOM_SS" "NOPOP"
					( Origin gFrontEnd )
				)
				( attribute "CDS_LIB" "w_hdl"
					( Origin gPackager )
				)
				( attribute "CDS_LMAN_SYM_OUTLINE" "-75,100,75,-100"
					( Origin gPackager )
				)
				( attribute "CDS_LOCATION" "L7A3"
					( Origin gPackager )
				)
				( attribute "CDS_SEC" "1"
					( Origin gPackager )
				)
				( attribute "DS_VALUE" "90NH"
					( Origin gFrontEnd )
				)
				( attribute "LOCATION" "L7A3"
					( Origin gFrontEnd )
				)
				( attribute "NEW_PACK_SIZE" "DCR=0.17MOHM"
					( Origin gFrontEnd )
				)
				( attribute "NEW_RATED" "DS_ISAT=134A@25C"
					( Origin gFrontEnd )
				)
				( attribute "NEW_TYPE" "IRMS=66A@DELTA_T<40C"
					( Origin gFrontEnd )
				)
				( attribute "PACK_SIZE" "DCR=0.17MOHM"
					( Origin gFrontEnd )
				)
				( attribute "PACK_TYPE" "DISCRET-GB2"
					( Origin gFrontEnd )
				)
				( attribute "PART_NUMBER" "068.1202N.M001"
					( Origin gFrontEnd )
				)
				( attribute "PHYS_PAGE" "219"
					( Origin gFrontEnd )
				)
				( attribute "RATED" "ISAT=94A@25C"
					( Origin gFrontEnd )
				)
				( attribute "ROT" "1"
					( Origin gFrontEnd )
				)
				( attribute "SEC" "1"
					( Origin gFrontEnd )
				)
				( attribute "SEC_TYPE" "DISCRET-GB2"
					( Origin gFrontEnd )
				)
				( attribute "TYPE" "IRMS=66A@DELTA_T<40C"
					( Origin gFrontEnd )
				)
				( attribute "VALUE" "IND-120NH-30-GP"
					( Origin gFrontEnd )
				)
				( attribute "VER" "1"
					( Origin gFrontEnd )
				)
				( attribute "XY" "(3850,-400)"
					( Origin gFrontEnd )
				)
				( attribute "CHIPS_PART_NAME" "IND-120NH-30-GP"
					( Origin gPackager )
				)
				( attribute "CDS_PART_NAME" "IND-120NH-30-GP_DISCRET-GB2-INA"
					( Origin gPackager )
				)
				( objectStatus "L7A3" )
			)
			( gate "@baseboard_fab2_lib.baseboard_fab2(sch_1):page219_i68"
				( attribute "BOM_COST" "PROC_VRD_VCCIN_CPU0"
					( Origin gFrontEnd )
				)
				( attribute "CDS_LIB" "mstr_discrete"
					( Origin gPackager )
				)
				( attribute "CDS_LOCATION" "C6A4"
					( Origin gPackager )
				)
				( attribute "CDS_SEC" "1"
					( Origin gPackager )
				)
				( attribute "LOCATION" "C6A4"
					( Origin gFrontEnd )
				)
				( attribute "MATERIAL" "X6S"
					( Origin gFrontEnd )
				)
				( attribute "PACK_TYPE" "0805LF"
					( Origin gFrontEnd )
				)
				( attribute "PART_NUMBER" "C95333-002"
					( Origin gFrontEnd )
				)
				( attribute "PHYS_PAGE" "219"
					( Origin gFrontEnd )
				)
				( attribute "ROOM" "VDDQ_DEF_PWR_VR"
					( Origin gFrontEnd )
				)
				( attribute "ROT" "0"
					( Origin gFrontEnd )
				)
				( attribute "SEC" "1"
					( Origin gFrontEnd )
				)
				( attribute "SEC_TYPE" "0805LF"
					( Origin gFrontEnd )
				)
				( attribute "TOLERANCE" "20%"
					( Origin gFrontEnd )
				)
				( attribute "VALUE" "22UF"
					( Origin gFrontEnd )
				)
				( attribute "VER" "1"
					( Origin gFrontEnd )
				)
				( attribute "VOLTAGE" "4V"
					( Units "uVoltage" "V" 1.000000)
					( Origin gFrontEnd )
				)
				( attribute "XY" "(4500,-575)"
					( Origin gFrontEnd )
				)
				( attribute "CHIPS_PART_NAME" "CAP"
					( Origin gPackager )
				)
				( attribute "CDS_PART_NAME" "CAP_0805LF-22UF,4V,20%,X6S,C95A"
					( Origin gPackager )
				)
				( attribute "GROUP" "PWR_MLCC_CAP"
					( Origin gFrontEnd )
				)
				( attribute "BOM_SS" "NOPOP"
					( Origin gFrontEnd )
				)
				( objectStatus "C6A4" )
			)
			( gate "@baseboard_fab2_lib.baseboard_fab2(sch_1):page219_i72"
				( attribute "CDS_LIB" "mstr_discrete"
					( Origin gPackager )
				)
				( attribute "CDS_LOCATION" "C7A25"
					( Origin gPackager )
				)
				( attribute "CDS_SEC" "1"
					( Origin gPackager )
				)
				( attribute "LOCATION" "C7A25"
					( Origin gFrontEnd )
				)
				( attribute "MATERIAL" "X7R"
					( Origin gFrontEnd )
				)
				( attribute "PACK_TYPE" "0402"
					( Origin gFrontEnd )
				)
				( attribute "PART_NUMBER" "A36096-155"
					( Origin gFrontEnd )
				)
				( attribute "PHYS_PAGE" "219"
					( Origin gFrontEnd )
				)
				( attribute "ROOM" "VDDQ_DEF_PWR_VR"
					( Origin gFrontEnd )
				)
				( attribute "ROT" "0"
					( Origin gFrontEnd )
				)
				( attribute "SEC" "1"
					( Origin gFrontEnd )
				)
				( attribute "SEC_TYPE" "0402"
					( Origin gFrontEnd )
				)
				( attribute "TOLERANCE" "10%"
					( Origin gFrontEnd )
				)
				( attribute "VALUE" "0.22UF"
					( Origin gFrontEnd )
				)
				( attribute "VER" "1"
					( Origin gFrontEnd )
				)
				( attribute "VOLTAGE" "16V"
					( Units "uVoltage" "V" 1.000000)
					( Origin gFrontEnd )
				)
				( attribute "XY" "(-100,175)"
					( Origin gFrontEnd )
				)
				( attribute "CHIPS_PART_NAME" "CAP"
					( Origin gPackager )
				)
				( attribute "CDS_PART_NAME" "CAP_0402-0.22UF,16V,10%,X7R,A3A"
					( Origin gPackager )
				)
				( attribute "BOM_SS" "NOPOP"
					( Origin gFrontEnd )
				)
				( objectStatus "C7A25" )
			)
			( gate "@baseboard_fab2_lib.baseboard_fab2(sch_1):page212_i143"
				( attribute "CDS_LIB" "w_hdl"
					( Origin gPackager )
				)
				( attribute "CDS_LMAN_SYM_OUTLINE" "-50,25,50,-25"
					( Origin gPackager )
				)
				( attribute "LOCATION" "C7C20"
					( Origin gFrontEnd )
				)
				( attribute "PACK_TYPE" "SMD-BCG6"
					( Origin gFrontEnd )
				)
				( attribute "PART_NUMBER" "78.10523.8FL"
					( Origin gFrontEnd )
				)
				( attribute "PHYS_PAGE" "212"
					( Origin gFrontEnd )
				)
				( attribute "ROT" "0"
					( Origin gFrontEnd )
				)
				( attribute "SEC" "1"
					( Origin gFrontEnd )
				)
				( attribute "SEC_TYPE" "SMD-BCG6"
					( Origin gFrontEnd )
				)
				( attribute "VALUE" "SC1U10V2KX-4-GP"
					( Origin gFrontEnd )
				)
				( attribute "VER" "1"
					( Origin gFrontEnd )
				)
				( attribute "XY" "(-825,4200)"
					( Origin gFrontEnd )
				)
				( attribute "CHIPS_PART_NAME" "SC1U10V2KX-4-GP"
					( Origin gPackager )
				)
				( attribute "CDS_PART_NAME" "SC1U10V2KX-4-GP_SMD-BCG6-SC1U1A"
					( Origin gPackager )
				)
				( attribute "CDS_LOCATION" "C7C20"
					( Origin gPackager )
				)
				( attribute "CDS_SEC" "1"
					( Origin gPackager )
				)
				( attribute "ATTRIBUTE" "1UF"
					( Origin gFrontEnd )
				)
				( attribute "PACK_SIZE" "0402"
					( Origin gFrontEnd )
				)
				( attribute "RATED" "10V"
					( Origin gFrontEnd )
				)
				( attribute "TOLERANCE" "10%"
					( Origin gFrontEnd )
				)
				( objectStatus "C7C20" )
			)
			( gate "@baseboard_fab2_lib.baseboard_fab2(sch_1):page219_i75"
				( attribute "CDS_LIB" "mstr_discrete"
					( Origin gPackager )
				)
				( attribute "CDS_LOCATION" "C7A22"
					( Origin gPackager )
				)
				( attribute "LOCATION" "C7A22"
					( Origin gFrontEnd )
				)
				( attribute "MATERIAL" "X7R"
					( Origin gFrontEnd )
				)
				( attribute "PACK_TYPE" "0402"
					( Origin gFrontEnd )
				)
				( attribute "PART_NUMBER" "A36096-104"
					( Origin gFrontEnd )
				)
				( attribute "PHYS_PAGE" "219"
					( Origin gFrontEnd )
				)
				( attribute "ROOM" "VDDQ_DEF_PWR_VR"
					( Origin gFrontEnd )
				)
				( attribute "ROT" "2"
					( Origin gFrontEnd )
				)
				( attribute "SEC" "1"
					( Origin gFrontEnd )
				)
				( attribute "SPOF" "TRUE"
					( Origin gFrontEnd )
				)
				( attribute "TOLERANCE" "10%"
					( Origin gFrontEnd )
				)
				( attribute "VALUE" "0.220UF"
					( Origin gFrontEnd )
				)
				( attribute "VER" "1"
					( Origin gFrontEnd )
				)
				( attribute "VOLTAGE" "16V"
					( Units "uVoltage" "V" 1.000000)
					( Origin gFrontEnd )
				)
				( attribute "XY" "(-800,-525)"
					( Origin gFrontEnd )
				)
				( attribute "CHIPS_PART_NAME" "CAP"
					( Origin gPackager )
				)
				( attribute "CDS_PART_NAME" "CAP_0402-0.220UF,16V,10%,X7R,AA"
					( Origin gPackager )
				)
				( attribute "SEC_TYPE" "0402"
					( Origin gFrontEnd )
				)
				( attribute "CDS_SEC" "1"
					( Origin gPackager )
				)
				( attribute "BOM_SS" "NOPOP"
					( Origin gFrontEnd )
				)
				( objectStatus "C7A22" )
			)
			( gate "@baseboard_fab2_lib.baseboard_fab2(sch_1):page224_i150"
				( attribute "BOM_COST" "PROC_SIDEBAND"
					( Origin gFrontEnd )
				)
				( attribute "CDS_LIB" "mstr_discrete"
					( Origin gPackager )
				)
				( attribute "CDS_LOCATION" "R9U1"
					( Origin gPackager )
				)
				( attribute "CDS_SEC" "1"
					( Origin gPackager )
				)
				( attribute "LOCATION" "R9U1"
					( Origin gFrontEnd )
				)
				( attribute "MATERIAL" "CHIP"
					( Origin gFrontEnd )
				)
				( attribute "PACK_TYPE" "0402"
					( Origin gFrontEnd )
				)
				( attribute "PART_NUMBER" "G21497-005"
					( Origin gFrontEnd )
				)
				( attribute "PHYS_PAGE" "224"
					( Origin gFrontEnd )
				)
				( attribute "ROOM" "CPU0"
					( Origin gFrontEnd )
				)
				( attribute "ROT" "0"
					( Origin gFrontEnd )
				)
				( attribute "SEC" "1"
					( Origin gFrontEnd )
				)
				( attribute "SEC_TYPE" "0402"
					( Origin gFrontEnd )
				)
				( attribute "TOLERANCE" "5%"
					( Origin gFrontEnd )
				)
				( attribute "VALUE" "0.0"
					( Origin gFrontEnd )
				)
				( attribute "VER" "1"
					( Origin gFrontEnd )
				)
				( attribute "WATTAGE" "1/16W"
					( Origin gFrontEnd )
				)
				( attribute "XY" "(-700,3050)"
					( Origin gFrontEnd )
				)
				( attribute "CHIPS_PART_NAME" "RES"
					( Origin gPackager )
				)
				( attribute "CDS_PART_NAME" "RES_0402-0.0,5%,1/16W,CHIP,G21A"
					( Origin gPackager )
				)
				( objectStatus "R9U1" )
			)
			( gate "@baseboard_fab2_lib.baseboard_fab2(sch_1):page219_i77"
				( attribute "CDS_LIB" "mstr_discrete"
					( Origin gPackager )
				)
				( attribute "CDS_LOCATION" "C7A24"
					( Origin gPackager )
				)
				( attribute "CDS_SEC" "1"
					( Origin gPackager )
				)
				( attribute "LOCATION" "C7A24"
					( Origin gFrontEnd )
				)
				( attribute "MATERIAL" "X6S"
					( Origin gFrontEnd )
				)
				( attribute "PACK_TYPE" "0402"
					( Origin gFrontEnd )
				)
				( attribute "PART_NUMBER" "D97712-011"
					( Origin gFrontEnd )
				)
				( attribute "PHYS_PAGE" "219"
					( Origin gFrontEnd )
				)
				( attribute "ROOM" "VDDQ_DEF_PWR_VR"
					( Origin gFrontEnd )
				)
				( attribute "ROT" "0"
					( Origin gFrontEnd )
				)
				( attribute "SEC" "1"
					( Origin gFrontEnd )
				)
				( attribute "SEC_TYPE" "0402"
					( Origin gFrontEnd )
				)
				( attribute "TOLERANCE" "10%"
					( Origin gFrontEnd )
				)
				( attribute "VALUE" "1.0UF"
					( Origin gFrontEnd )
				)
				( attribute "VER" "1"
					( Origin gFrontEnd )
				)
				( attribute "VOLTAGE" "16V"
					( Units "uVoltage" "V" 1.000000)
					( Origin gFrontEnd )
				)
				( attribute "XY" "(-925,75)"
					( Origin gFrontEnd )
				)
				( attribute "CHIPS_PART_NAME" "CAP"
					( Origin gPackager )
				)
				( attribute "CDS_PART_NAME" "CAP_0402-1.0UF,16V,10%,X6S,D97A"
					( Origin gPackager )
				)
				( attribute "BOM_SS" "NOPOP"
					( Origin gFrontEnd )
				)
				( objectStatus "C7A24" )
			)
			( gate "@baseboard_fab2_lib.baseboard_fab2(sch_1):page219_i78"
				( attribute "CDS_LIB" "dev_discrete"
					( Origin gPackager )
				)
				( attribute "CDS_LOCATION" "C7A20"
					( Origin gPackager )
				)
				( attribute "CDS_SEC" "1"
					( Origin gPackager )
				)
				( attribute "LOCATION" "C7A20"
					( Origin gFrontEnd )
				)
				( attribute "MATERIAL" "X7R"
					( Origin gFrontEnd )
				)
				( attribute "PACK_TYPE" "0402V"
					( Origin gFrontEnd )
				)
				( attribute "PART_NUMBER" "A36096-030"
					( Origin gFrontEnd )
				)
				( attribute "PHYS_PAGE" "219"
					( Origin gFrontEnd )
				)
				( attribute "ROOM" "VDDQ_DEF_PWR_VR"
					( Origin gFrontEnd )
				)
				( attribute "ROT" "0"
					( Origin gFrontEnd )
				)
				( attribute "SEC" "1"
					( Origin gFrontEnd )
				)
				( attribute "SEC_TYPE" "0402V"
					( Origin gFrontEnd )
				)
				( attribute "TOLERANCE" "10%"
					( Origin gFrontEnd )
				)
				( attribute "VALUE" "0.1UF"
					( Origin gFrontEnd )
				)
				( attribute "VER" "1"
					( Origin gFrontEnd )
				)
				( attribute "VOLTAGE" "16V"
					( Units "uVoltage" "V" 1.000000)
					( Origin gFrontEnd )
				)
				( attribute "XY" "(-1250,75)"
					( Origin gFrontEnd )
				)
				( attribute "CHIPS_PART_NAME" "CAP_A"
					( Origin gPackager )
				)
				( attribute "CDS_PART_NAME" "CAP_A_0402V-0.1UF,16V,10%,X7R,A"
					( Origin gPackager )
				)
				( objectStatus "C7A20" )
			)
			( gate "@baseboard_fab2_lib.baseboard_fab2(sch_1):page219_i79"
				( attribute "CDS_LIB" "mstr_discrete"
					( Origin gPackager )
				)
				( attribute "CDS_LOCATION" "C7A21"
					( Origin gPackager )
				)
				( attribute "CDS_SEC" "1"
					( Origin gPackager )
				)
				( attribute "LOCATION" "C7A21"
					( Origin gFrontEnd )
				)
				( attribute "MATERIAL" "X6S"
					( Origin gFrontEnd )
				)
				( attribute "PACK_TYPE" "0402"
					( Origin gFrontEnd )
				)
				( attribute "PART_NUMBER" "D97712-011"
					( Origin gFrontEnd )
				)
				( attribute "PHYS_PAGE" "219"
					( Origin gFrontEnd )
				)
				( attribute "ROOM" "VDDQ_DEF_PWR_VR"
					( Origin gFrontEnd )
				)
				( attribute "ROT" "0"
					( Origin gFrontEnd )
				)
				( attribute "SEC" "1"
					( Origin gFrontEnd )
				)
				( attribute "SEC_TYPE" "0402"
					( Origin gFrontEnd )
				)
				( attribute "TOLERANCE" "10%"
					( Origin gFrontEnd )
				)
				( attribute "VALUE" "1.0UF"
					( Origin gFrontEnd )
				)
				( attribute "VER" "1"
					( Origin gFrontEnd )
				)
				( attribute "VOLTAGE" "16V"
					( Units "uVoltage" "V" 1.000000)
					( Origin gFrontEnd )
				)
				( attribute "XY" "(-1525,75)"
					( Origin gFrontEnd )
				)
				( attribute "CHIPS_PART_NAME" "CAP"
					( Origin gPackager )
				)
				( attribute "CDS_PART_NAME" "CAP_0402-1.0UF,16V,10%,X6S,D97A"
					( Origin gPackager )
				)
				( objectStatus "C7A21" )
			)
			( gate "@baseboard_fab2_lib.baseboard_fab2(sch_1):page219_i80"
				( attribute "CDS_LIB" "mstr_discrete"
					( Origin gPackager )
				)
				( attribute "CDS_LOCATION" "C3L17"
					( Origin gPackager )
				)
				( attribute "CDS_SEC" "1"
					( Origin gPackager )
				)
				( attribute "LOCATION" "C3L17"
					( Origin gFrontEnd )
				)
				( attribute "MATERIAL" "X6S"
					( Origin gFrontEnd )
				)
				( attribute "PACK_TYPE" "0805"
					( Origin gFrontEnd )
				)
				( attribute "PART_NUMBER" "C95333-007"
					( Origin gFrontEnd )
				)
				( attribute "PHYS_PAGE" "219"
					( Origin gFrontEnd )
				)
				( attribute "ROOM" "VDDQ_DEF_PWR_VR"
					( Origin gFrontEnd )
				)
				( attribute "ROT" "0"
					( Origin gFrontEnd )
				)
				( attribute "SEC" "1"
					( Origin gFrontEnd )
				)
				( attribute "SEC_TYPE" "0805"
					( Origin gFrontEnd )
				)
				( attribute "TOLERANCE" "10%"
					( Origin gFrontEnd )
				)
				( attribute "VALUE" "10UF"
					( Origin gFrontEnd )
				)
				( attribute "VER" "1"
					( Origin gFrontEnd )
				)
				( attribute "VOLTAGE" "16V"
					( Units "uVoltage" "V" 1.000000)
					( Origin gFrontEnd )
				)
				( attribute "XY" "(-1750,75)"
					( Origin gFrontEnd )
				)
				( attribute "CHIPS_PART_NAME" "CAP"
					( Origin gPackager )
				)
				( attribute "CDS_PART_NAME" "CAP_0805-10UF,16V,10%,X6S,C953A"
					( Origin gPackager )
				)
				( objectStatus "C3L17" )
			)
			( gate "@baseboard_fab2_lib.baseboard_fab2(sch_1):page219_i81"
				( attribute "CDS_LIB" "mstr_discrete"
					( Origin gPackager )
				)
				( attribute "CDS_LOCATION" "C3L16"
					( Origin gPackager )
				)
				( attribute "CDS_SEC" "1"
					( Origin gPackager )
				)
				( attribute "LOCATION" "C3L16"
					( Origin gFrontEnd )
				)
				( attribute "MATERIAL" "X6S"
					( Origin gFrontEnd )
				)
				( attribute "PACK_TYPE" "0805"
					( Origin gFrontEnd )
				)
				( attribute "PART_NUMBER" "C95333-007"
					( Origin gFrontEnd )
				)
				( attribute "PHYS_PAGE" "219"
					( Origin gFrontEnd )
				)
				( attribute "ROOM" "VDDQ_DEF_PWR_VR"
					( Origin gFrontEnd )
				)
				( attribute "ROT" "0"
					( Origin gFrontEnd )
				)
				( attribute "SEC" "1"
					( Origin gFrontEnd )
				)
				( attribute "SEC_TYPE" "0805"
					( Origin gFrontEnd )
				)
				( attribute "TOLERANCE" "10%"
					( Origin gFrontEnd )
				)
				( attribute "VALUE" "10UF"
					( Origin gFrontEnd )
				)
				( attribute "VER" "1"
					( Origin gFrontEnd )
				)
				( attribute "VOLTAGE" "16V"
					( Units "uVoltage" "V" 1.000000)
					( Origin gFrontEnd )
				)
				( attribute "XY" "(-1975,75)"
					( Origin gFrontEnd )
				)
				( attribute "CHIPS_PART_NAME" "CAP"
					( Origin gPackager )
				)
				( attribute "CDS_PART_NAME" "CAP_0805-10UF,16V,10%,X6S,C953A"
					( Origin gPackager )
				)
				( objectStatus "C3L16" )
			)
			( gate "@baseboard_fab2_lib.baseboard_fab2(sch_1):page219_i84"
				( attribute "CDS_LIB" "mstr_discrete"
					( Origin gPackager )
				)
				( attribute "CDS_LOCATION" "C3L15"
					( Origin gPackager )
				)
				( attribute "CDS_SEC" "1"
					( Origin gPackager )
				)
				( attribute "LOCATION" "C3L15"
					( Origin gFrontEnd )
				)
				( attribute "MATERIAL" "X6S"
					( Origin gFrontEnd )
				)
				( attribute "PACK_TYPE" "0805"
					( Origin gFrontEnd )
				)
				( attribute "PART_NUMBER" "C95333-007"
					( Origin gFrontEnd )
				)
				( attribute "PHYS_PAGE" "219"
					( Origin gFrontEnd )
				)
				( attribute "ROOM" "VDDQ_DEF_PWR_VR"
					( Origin gFrontEnd )
				)
				( attribute "ROT" "0"
					( Origin gFrontEnd )
				)
				( attribute "SEC" "1"
					( Origin gFrontEnd )
				)
				( attribute "SEC_TYPE" "0805"
					( Origin gFrontEnd )
				)
				( attribute "TOLERANCE" "10%"
					( Origin gFrontEnd )
				)
				( attribute "VALUE" "10UF"
					( Origin gFrontEnd )
				)
				( attribute "VER" "1"
					( Origin gFrontEnd )
				)
				( attribute "VOLTAGE" "16V"
					( Units "uVoltage" "V" 1.000000)
					( Origin gFrontEnd )
				)
				( attribute "XY" "(-2200,75)"
					( Origin gFrontEnd )
				)
				( attribute "CHIPS_PART_NAME" "CAP"
					( Origin gPackager )
				)
				( attribute "CDS_PART_NAME" "CAP_0805-10UF,16V,10%,X6S,C953A"
					( Origin gPackager )
				)
				( objectStatus "C3L15" )
			)
			( gate "@baseboard_fab2_lib.baseboard_fab2(sch_1):page219_i87"
				( attribute "BOM_COST" "PROC_VRD_VCCIN_CPU0"
					( Origin gFrontEnd )
				)
				( attribute "CDS_LIB" "mstr_discrete"
					( Origin gPackager )
				)
				( attribute "CDS_LOCATION" "C6A1"
					( Origin gPackager )
				)
				( attribute "LOCATION" "C6A1"
					( Origin gFrontEnd )
				)
				( attribute "MATERIAL" "X6S"
					( Origin gFrontEnd )
				)
				( attribute "PACK_TYPE" "0805LF"
					( Origin gFrontEnd )
				)
				( attribute "PART_NUMBER" "C95333-002"
					( Origin gFrontEnd )
				)
				( attribute "PHYS_PAGE" "219"
					( Origin gFrontEnd )
				)
				( attribute "ROOM" "VDDQ_DEF_PWR_VR"
					( Origin gFrontEnd )
				)
				( attribute "ROT" "0"
					( Origin gFrontEnd )
				)
				( attribute "SEC" "1"
					( Origin gFrontEnd )
				)
				( attribute "TOLERANCE" "20%"
					( Origin gFrontEnd )
				)
				( attribute "VALUE" "22UF"
					( Origin gFrontEnd )
				)
				( attribute "VER" "1"
					( Origin gFrontEnd )
				)
				( attribute "VOLTAGE" "4V"
					( Units "uVoltage" "V" 1.000000)
					( Origin gFrontEnd )
				)
				( attribute "XY" "(4450,1675)"
					( Origin gFrontEnd )
				)
				( attribute "CHIPS_PART_NAME" "CAP"
					( Origin gPackager )
				)
				( attribute "CDS_PART_NAME" "CAP_0805LF-22UF,4V,20%,X6S,C95A"
					( Origin gPackager )
				)
				( attribute "SEC_TYPE" "0805LF"
					( Origin gFrontEnd )
				)
				( attribute "CDS_SEC" "1"
					( Origin gPackager )
				)
				( attribute "GROUP" "PWR_MLCC_CAP"
					( Origin gFrontEnd )
				)
				( objectStatus "C6A1" )
			)
			( gate "@baseboard_fab2_lib.baseboard_fab2(sch_1):page219_i106"
				( attribute "CDS_LIB" "mstr_discrete"
					( Origin gPackager )
				)
				( attribute "CDS_LOCATION" "EU7A1"
					( Origin gPackager )
				)
				( attribute "CDS_SEC" "1"
					( Origin gPackager )
				)
				( attribute "LOCATION" "EU7A1"
					( Origin gFrontEnd )
				)
				( attribute "MATERIAL" "IC"
					( Origin gFrontEnd )
				)
				( attribute "NO_XNET_CONNECTION" "1"
					( Origin gFrontEnd )
				)
				( attribute "PACK_TYPE" "SM"
					( Origin gFrontEnd )
				)
				( attribute "PART_NUMBER" "H73688-001"
					( Origin gFrontEnd )
				)
				( attribute "PHYS_PAGE" "219"
					( Origin gFrontEnd )
				)
				( attribute "ROT" "0"
					( Origin gFrontEnd )
				)
				( attribute "SEC" "1"
					( Origin gFrontEnd )
				)
				( attribute "SEC_TYPE" "SM"
					( Origin gFrontEnd )
				)
				( attribute "VALUE" "IR35411"
					( Origin gFrontEnd )
				)
				( attribute "VER" "1"
					( Origin gFrontEnd )
				)
				( attribute "XY" "(1750,2125)"
					( Origin gFrontEnd )
				)
				( attribute "CHIPS_PART_NAME" "IR354XX"
					( Origin gPackager )
				)
				( attribute "CDS_PART_NAME" "IR354XX_SM-IR35411,IC,H73688-0A"
					( Origin gPackager )
				)
				( objectStatus "EU7A1" )
			)
			( gate "@baseboard_fab2_lib.baseboard_fab2(sch_1):page219_i107"
				( attribute "CDS_LIB" "mstr_discrete"
					( Origin gPackager )
				)
				( attribute "CDS_LOCATION" "EU7A4"
					( Origin gPackager )
				)
				( attribute "CDS_SEC" "1"
					( Origin gPackager )
				)
				( attribute "LOCATION" "EU7A4"
					( Origin gFrontEnd )
				)
				( attribute "MATERIAL" "IC"
					( Origin gFrontEnd )
				)
				( attribute "NO_XNET_CONNECTION" "1"
					( Origin gFrontEnd )
				)
				( attribute "PACK_TYPE" "SM"
					( Origin gFrontEnd )
				)
				( attribute "PART_NUMBER" "H73688-001"
					( Origin gFrontEnd )
				)
				( attribute "PHYS_PAGE" "219"
					( Origin gFrontEnd )
				)
				( attribute "ROT" "0"
					( Origin gFrontEnd )
				)
				( attribute "SEC" "1"
					( Origin gFrontEnd )
				)
				( attribute "SEC_TYPE" "SM"
					( Origin gFrontEnd )
				)
				( attribute "VALUE" "IR35411"
					( Origin gFrontEnd )
				)
				( attribute "VER" "1"
					( Origin gFrontEnd )
				)
				( attribute "XY" "(1775,-125)"
					( Origin gFrontEnd )
				)
				( attribute "CHIPS_PART_NAME" "IR354XX"
					( Origin gPackager )
				)
				( attribute "CDS_PART_NAME" "IR354XX_SM-IR35411,IC,H73688-0A"
					( Origin gPackager )
				)
				( attribute "BOM_SS" "NOPOP"
					( Origin gFrontEnd )
				)
				( objectStatus "EU7A4" )
			)
			( gate "@baseboard_fab2_lib.baseboard_fab2(sch_1):page219_i108"
				( attribute "CDS_LIB" "mstr_discrete"
					( Origin gPackager )
				)
				( attribute "CDS_LOCATION" "R7A20"
					( Origin gPackager )
				)
				( attribute "CDS_SEC" "1"
					( Origin gPackager )
				)
				( attribute "LOCATION" "R7A20"
					( Origin gFrontEnd )
				)
				( attribute "MATERIAL" "EMPTY"
					( Origin gFrontEnd )
				)
				( attribute "PACK_TYPE" "0402"
					( Origin gFrontEnd )
				)
				( attribute "PART_NUMBER" "G21796-187"
					( Origin gFrontEnd )
				)
				( attribute "PHYS_PAGE" "219"
					( Origin gFrontEnd )
				)
				( attribute "ROT" "0"
					( Origin gFrontEnd )
				)
				( attribute "SEC" "1"
					( Origin gPackager )
				)
				( attribute "TOLERANCE" "1%"
					( Origin gFrontEnd )
				)
				( attribute "VALUE" "68.1K"
					( Origin gFrontEnd )
				)
				( attribute "VER" "2"
					( Origin gFrontEnd )
				)
				( attribute "WATTAGE" "1/16W"
					( Origin gFrontEnd )
				)
				( attribute "XY" "(4575,2300)"
					( Origin gFrontEnd )
				)
				( attribute "CHIPS_PART_NAME" "RES"
					( Origin gPackager )
				)
				( attribute "CDS_PART_NAME" "RES_0402-68.1K,1%,1/16W,EMPTY,A"
					( Origin gPackager )
				)
				( objectStatus "R7A20" )
			)
			( gate "@baseboard_fab2_lib.baseboard_fab2(sch_1):page219_i110"
				( attribute "CDS_LIB" "mstr_discrete"
					( Origin gPackager )
				)
				( attribute "CDS_LOCATION" "R7A21"
					( Origin gPackager )
				)
				( attribute "LOCATION" "R7A21"
					( Origin gFrontEnd )
				)
				( attribute "MATERIAL" "EMPTY"
					( Origin gFrontEnd )
				)
				( attribute "PACK_TYPE" "0402"
					( Origin gFrontEnd )
				)
				( attribute "PART_NUMBER" "G21796-187"
					( Origin gFrontEnd )
				)
				( attribute "PHYS_PAGE" "219"
					( Origin gFrontEnd )
				)
				( attribute "ROT" "0"
					( Origin gFrontEnd )
				)
				( attribute "SEC" "1"
					( Origin gFrontEnd )
				)
				( attribute "TOLERANCE" "1%"
					( Origin gFrontEnd )
				)
				( attribute "VALUE" "68.1K"
					( Origin gFrontEnd )
				)
				( attribute "VER" "2"
					( Origin gFrontEnd )
				)
				( attribute "WATTAGE" "1/16W"
					( Origin gFrontEnd )
				)
				( attribute "XY" "(4575,25)"
					( Origin gFrontEnd )
				)
				( attribute "CHIPS_PART_NAME" "RES"
					( Origin gPackager )
				)
				( attribute "CDS_PART_NAME" "RES_0402-68.1K,1%,1/16W,EMPTY,A"
					( Origin gPackager )
				)
				( attribute "SEC_TYPE" "0402"
					( Origin gFrontEnd )
				)
				( attribute "CDS_SEC" "1"
					( Origin gPackager )
				)
				( attribute "BOM_SS" "NOPOP"
					( Origin gFrontEnd )
				)
				( objectStatus "R7A21" )
			)
			( gate "@baseboard_fab2_lib.baseboard_fab2(sch_1):page220_i58"
				( attribute "BOM_COST" "MEM_VRD_PVPP_DEF"
					( Origin gFrontEnd )
				)
				( attribute "CDS_LIB" "mstr_discrete"
					( Origin gPackager )
				)
				( attribute "CDS_LOCATION" "R4L4"
					( Origin gPackager )
				)
				( attribute "CDS_SEC" "1"
					( Origin gPackager )
				)
				( attribute "LOCATION" "R4L4"
					( Origin gFrontEnd )
				)
				( attribute "MATERIAL" "CHIP"
					( Origin gFrontEnd )
				)
				( attribute "PACK_TYPE" "0603"
					( Origin gFrontEnd )
				)
				( attribute "PART_NUMBER" "G22026-003"
					( Origin gFrontEnd )
				)
				( attribute "PHYS_PAGE" "220"
					( Origin gFrontEnd )
				)
				( attribute "ROOM" "VDDQ_DEF_PWR_VR"
					( Origin gFrontEnd )
				)
				( attribute "ROT" "0"
					( Origin gFrontEnd )
				)
				( attribute "SEC" "1"
					( Origin gPackager )
				)
				( attribute "TOLERANCE" "1%"
					( Origin gFrontEnd )
				)
				( attribute "VALUE" "120.0"
					( Origin gFrontEnd )
				)
				( attribute "VER" "2"
					( Origin gFrontEnd )
				)
				( attribute "WATTAGE" "1/10W"
					( Origin gFrontEnd )
				)
				( attribute "XY" "(4100,-100)"
					( Origin gFrontEnd )
				)
				( attribute "CHIPS_PART_NAME" "RES"
					( Origin gPackager )
				)
				( attribute "CDS_PART_NAME" "RES_0603-120.0,1%,1/10W,CHIP,GA"
					( Origin gPackager )
				)
				( objectStatus "R4L4" )
			)
			( gate "@baseboard_fab2_lib.baseboard_fab2(sch_1):page220_i74"
				( attribute "CDS_LIB" "mstr_discrete"
					( Origin gPackager )
				)
				( attribute "CDS_LOCATION" "R4L2"
					( Origin gPackager )
				)
				( attribute "CDS_SEC" "1"
					( Origin gPackager )
				)
				( attribute "LOCATION" "R4L2"
					( Origin gFrontEnd )
				)
				( attribute "MATERIAL" "EMPTY"
					( Origin gFrontEnd )
				)
				( attribute "PACK_TYPE" "0402"
					( Origin gFrontEnd )
				)
				( attribute "PART_NUMBER" "G21796-017"
					( Origin gFrontEnd )
				)
				( attribute "PHYS_PAGE" "220"
					( Origin gFrontEnd )
				)
				( attribute "ROOM" "VDDQ_DEF_PWR_VR"
					( Origin gFrontEnd )
				)
				( attribute "ROT" "0"
					( Origin gFrontEnd )
				)
				( attribute "SEC" "1"
					( Origin gFrontEnd )
				)
				( attribute "SEC_TYPE" "0402"
					( Origin gFrontEnd )
				)
				( attribute "TOLERANCE" "1%"
					( Origin gFrontEnd )
				)
				( attribute "VALUE" "100.0"
					( Origin gFrontEnd )
				)
				( attribute "VER" "2"
					( Origin gFrontEnd )
				)
				( attribute "WATTAGE" "1/16W"
					( Origin gFrontEnd )
				)
				( attribute "XY" "(-700,1825)"
					( Origin gFrontEnd )
				)
				( attribute "CHIPS_PART_NAME" "RES"
					( Origin gPackager )
				)
				( attribute "CDS_PART_NAME" "RES_0402-100.0,1%,1/16W,EMPTY,A"
					( Origin gPackager )
				)
				( objectStatus "R4L2" )
			)
			( gate "@baseboard_fab2_lib.baseboard_fab2(sch_1):page220_i75"
				( attribute "CDS_LIB" "mstr_discrete"
					( Origin gPackager )
				)
				( attribute "CDS_LOCATION" "C3L6"
					( Origin gPackager )
				)
				( attribute "CDS_SEC" "1"
					( Origin gPackager )
				)
				( attribute "LOCATION" "C3L6"
					( Origin gFrontEnd )
				)
				( attribute "MATERIAL" "ALUM"
					( Origin gFrontEnd )
				)
				( attribute "PACK_TYPE" "3018"
					( Origin gFrontEnd )
				)
				( attribute "PART_NUMBER" "699013-049"
					( Origin gFrontEnd )
				)
				( attribute "PHYS_PAGE" "220"
					( Origin gFrontEnd )
				)
				( attribute "ROOM" "VDDQ_DEF_PWR_VR"
					( Origin gFrontEnd )
				)
				( attribute "ROT" "0"
					( Origin gFrontEnd )
				)
				( attribute "SEC" "1"
					( Origin gFrontEnd )
				)
				( attribute "SEC_TYPE" "3018"
					( Origin gFrontEnd )
				)
				( attribute "TOLERANCE" "20%"
					( Origin gFrontEnd )
				)
				( attribute "VALUE" "470UF"
					( Origin gFrontEnd )
				)
				( attribute "VER" "1"
					( Origin gFrontEnd )
				)
				( attribute "VOLTAGE" "2.5V"
					( Units "uVoltage" "V" 1.000000)
					( Origin gFrontEnd )
				)
				( attribute "XY" "(2900,-100)"
					( Origin gFrontEnd )
				)
				( attribute "CHIPS_PART_NAME" "CAPP"
					( Origin gPackager )
				)
				( attribute "CDS_PART_NAME" "CAPP_3018-470UF,2.5V,20%,ALUM,A"
					( Origin gPackager )
				)
				( attribute "GROUP" "PWR_BULK_CAP"
					( Origin gFrontEnd )
				)
				( objectStatus "C3L6" )
			)
			( gate "@baseboard_fab2_lib.baseboard_fab2(sch_1):page220_i76"
				( attribute "CDS_LIB" "mstr_discrete"
					( Origin gPackager )
				)
				( attribute "CDS_LOCATION" "C3L14"
					( Origin gPackager )
				)
				( attribute "CDS_SEC" "1"
					( Origin gPackager )
				)
				( attribute "LOCATION" "C3L14"
					( Origin gFrontEnd )
				)
				( attribute "MATERIAL" "ALUM"
					( Origin gFrontEnd )
				)
				( attribute "PACK_TYPE" "3018"
					( Origin gFrontEnd )
				)
				( attribute "PART_NUMBER" "699013-049"
					( Origin gFrontEnd )
				)
				( attribute "PHYS_PAGE" "220"
					( Origin gFrontEnd )
				)
				( attribute "ROOM" "VDDQ_DEF_PWR_VR"
					( Origin gFrontEnd )
				)
				( attribute "ROT" "0"
					( Origin gFrontEnd )
				)
				( attribute "SEC" "1"
					( Origin gFrontEnd )
				)
				( attribute "SEC_TYPE" "3018"
					( Origin gFrontEnd )
				)
				( attribute "TOLERANCE" "20%"
					( Origin gFrontEnd )
				)
				( attribute "VALUE" "470UF"
					( Origin gFrontEnd )
				)
				( attribute "VER" "1"
					( Origin gFrontEnd )
				)
				( attribute "VOLTAGE" "2.5V"
					( Units "uVoltage" "V" 1.000000)
					( Origin gFrontEnd )
				)
				( attribute "XY" "(3200,-100)"
					( Origin gFrontEnd )
				)
				( attribute "CHIPS_PART_NAME" "CAPP"
					( Origin gPackager )
				)
				( attribute "CDS_PART_NAME" "CAPP_3018-470UF,2.5V,20%,ALUM,A"
					( Origin gPackager )
				)
				( attribute "GROUP" "PWR_BULK_CAP"
					( Origin gFrontEnd )
				)
				( objectStatus "C3L14" )
			)
			( gate "@baseboard_fab2_lib.baseboard_fab2(sch_1):page220_i77"
				( attribute "CDS_LIB" "mstr_discrete"
					( Origin gPackager )
				)
				( attribute "CDS_LOCATION" "C6A5"
					( Origin gPackager )
				)
				( attribute "CDS_SEC" "1"
					( Origin gPackager )
				)
				( attribute "LOCATION" "C6A5"
					( Origin gFrontEnd )
				)
				( attribute "MATERIAL" "ALUM"
					( Origin gFrontEnd )
				)
				( attribute "PACK_TYPE" "3018"
					( Origin gFrontEnd )
				)
				( attribute "PART_NUMBER" "699013-049"
					( Origin gFrontEnd )
				)
				( attribute "PHYS_PAGE" "220"
					( Origin gFrontEnd )
				)
				( attribute "ROOM" "VDDQ_DEF_PWR_VR"
					( Origin gFrontEnd )
				)
				( attribute "ROT" "0"
					( Origin gFrontEnd )
				)
				( attribute "SEC" "1"
					( Origin gFrontEnd )
				)
				( attribute "SEC_TYPE" "3018"
					( Origin gFrontEnd )
				)
				( attribute "TOLERANCE" "20%"
					( Origin gFrontEnd )
				)
				( attribute "VALUE" "470UF"
					( Origin gFrontEnd )
				)
				( attribute "VER" "1"
					( Origin gFrontEnd )
				)
				( attribute "VOLTAGE" "2.5V"
					( Units "uVoltage" "V" 1.000000)
					( Origin gFrontEnd )
				)
				( attribute "XY" "(3500,-100)"
					( Origin gFrontEnd )
				)
				( attribute "CHIPS_PART_NAME" "CAPP"
					( Origin gPackager )
				)
				( attribute "CDS_PART_NAME" "CAPP_3018-470UF,2.5V,20%,ALUM,A"
					( Origin gPackager )
				)
				( attribute "GROUP" "PWR_BULK_CAP"
					( Origin gFrontEnd )
				)
				( objectStatus "C6A5" )
			)
			( gate "@baseboard_fab2_lib.baseboard_fab2(sch_1):page220_i78"
				( attribute "CDS_LIB" "mstr_discrete"
					( Origin gPackager )
				)
				( attribute "CDS_LOCATION" "C4L5"
					( Origin gPackager )
				)
				( attribute "CDS_SEC" "1"
					( Origin gPackager )
				)
				( attribute "LOCATION" "C4L5"
					( Origin gFrontEnd )
				)
				( attribute "MATERIAL" "ALUM"
					( Origin gFrontEnd )
				)
				( attribute "PACK_TYPE" "3018"
					( Origin gFrontEnd )
				)
				( attribute "PART_NUMBER" "699013-049"
					( Origin gFrontEnd )
				)
				( attribute "PHYS_PAGE" "220"
					( Origin gFrontEnd )
				)
				( attribute "ROOM" "VDDQ_DEF_PWR_VR"
					( Origin gFrontEnd )
				)
				( attribute "ROT" "0"
					( Origin gFrontEnd )
				)
				( attribute "SEC" "1"
					( Origin gFrontEnd )
				)
				( attribute "SEC_TYPE" "3018"
					( Origin gFrontEnd )
				)
				( attribute "TOLERANCE" "20%"
					( Origin gFrontEnd )
				)
				( attribute "VALUE" "470UF"
					( Origin gFrontEnd )
				)
				( attribute "VER" "1"
					( Origin gFrontEnd )
				)
				( attribute "VOLTAGE" "2.5V"
					( Units "uVoltage" "V" 1.000000)
					( Origin gFrontEnd )
				)
				( attribute "XY" "(3800,-100)"
					( Origin gFrontEnd )
				)
				( attribute "CHIPS_PART_NAME" "CAPP"
					( Origin gPackager )
				)
				( attribute "CDS_PART_NAME" "CAPP_3018-470UF,2.5V,20%,ALUM,A"
					( Origin gPackager )
				)
				( attribute "GROUP" "PWR_BULK_CAP"
					( Origin gFrontEnd )
				)
				( objectStatus "C4L5" )
			)
			( gate "@baseboard_fab2_lib.baseboard_fab2(sch_1):page220_i317"
				( attribute "BOM_COST" "MEM_VRD_PVDDQ_CD"
					( Origin gFrontEnd )
				)
				( attribute "CDS_LIB" "mstr_discrete"
					( Origin gPackager )
				)
				( attribute "CDS_LOCATION" "C5P5"
					( Origin gPackager )
				)
				( attribute "CDS_SEC" "1"
					( Origin gPackager )
				)
				( attribute "LOCATION" "C5P5"
					( Origin gFrontEnd )
				)
				( attribute "MATERIAL" "X5R"
					( Origin gFrontEnd )
				)
				( attribute "NEW_MATERIAL" "X6S"
					( Origin gFrontEnd )
				)
				( attribute "PACK_TYPE" "0805"
					( Origin gFrontEnd )
				)
				( attribute "PART_NUMBER" "602433-112"
					( Origin gFrontEnd )
				)
				( attribute "PHYS_PAGE" "220"
					( Origin gFrontEnd )
				)
				( attribute "ROOM" "VDDQ_ABC_PWR_VR"
					( Origin gFrontEnd )
				)
				( attribute "ROT" "0"
					( Origin gFrontEnd )
				)
				( attribute "SEC" "1"
					( Origin gFrontEnd )
				)
				( attribute "SEC_TYPE" "0805"
					( Origin gFrontEnd )
				)
				( attribute "TOLERANCE" "20%"
					( Origin gFrontEnd )
				)
				( attribute "VALUE" "100UF"
					( Origin gFrontEnd )
				)
				( attribute "VER" "1"
					( Origin gFrontEnd )
				)
				( attribute "VOLTAGE" "4V"
					( Units "uVoltage" "V" 1.000000)
					( Origin gFrontEnd )
				)
				( attribute "XY" "(500,2925)"
					( Origin gFrontEnd )
				)
				( attribute "CHIPS_PART_NAME" "CAP"
					( Origin gPackager )
				)
				( attribute "CDS_PART_NAME" "CAP_0805-100UF,4V,20%,X5R,6024A"
					( Origin gPackager )
				)
				( attribute "GROUP" "PWR_MLCC_CAP"
					( Origin gFrontEnd )
				)
				( attribute "NEW_PN" "078.1071T.M002"
					( Origin gFrontEnd )
				)
				( attribute "BOM_SS" "NOPOP"
					( Origin gFrontEnd )
				)
				( objectStatus "C5P5" )
			)
			( gate "@baseboard_fab2_lib.baseboard_fab2(sch_1):page220_i315"
				( attribute "BOM_COST" "MEM_VRD_PVDDQ_CD"
					( Origin gFrontEnd )
				)
				( attribute "CDS_LIB" "mstr_discrete"
					( Origin gPackager )
				)
				( attribute "CDS_LOCATION" "C5P3"
					( Origin gPackager )
				)
				( attribute "CDS_SEC" "1"
					( Origin gPackager )
				)
				( attribute "LOCATION" "C5P3"
					( Origin gFrontEnd )
				)
				( attribute "MATERIAL" "X5R"
					( Origin gFrontEnd )
				)
				( attribute "NEW_MATERIAL" "X6S"
					( Origin gFrontEnd )
				)
				( attribute "PACK_TYPE" "0805"
					( Origin gFrontEnd )
				)
				( attribute "PART_NUMBER" "602433-112"
					( Origin gFrontEnd )
				)
				( attribute "PHYS_PAGE" "220"
					( Origin gFrontEnd )
				)
				( attribute "ROOM" "VDDQ_ABC_PWR_VR"
					( Origin gFrontEnd )
				)
				( attribute "ROT" "0"
					( Origin gFrontEnd )
				)
				( attribute "SEC" "1"
					( Origin gFrontEnd )
				)
				( attribute "SEC_TYPE" "0805"
					( Origin gFrontEnd )
				)
				( attribute "TOLERANCE" "20%"
					( Origin gFrontEnd )
				)
				( attribute "VALUE" "100UF"
					( Origin gFrontEnd )
				)
				( attribute "VER" "1"
					( Origin gFrontEnd )
				)
				( attribute "VOLTAGE" "4V"
					( Units "uVoltage" "V" 1.000000)
					( Origin gFrontEnd )
				)
				( attribute "XY" "(1600,2950)"
					( Origin gFrontEnd )
				)
				( attribute "CHIPS_PART_NAME" "CAP"
					( Origin gPackager )
				)
				( attribute "CDS_PART_NAME" "CAP_0805-100UF,4V,20%,X5R,6024A"
					( Origin gPackager )
				)
				( attribute "GROUP" "PWR_MLCC_CAP"
					( Origin gFrontEnd )
				)
				( attribute "NEW_PN" "078.1071T.M002"
					( Origin gFrontEnd )
				)
				( attribute "BOM_SS" "NOPOP"
					( Origin gFrontEnd )
				)
				( objectStatus "C5P3" )
			)
			( gate "@baseboard_fab2_lib.baseboard_fab2(sch_1):page220_i313"
				( attribute "BOM_COST" "MEM_VRD_PVDDQ_CD"
					( Origin gFrontEnd )
				)
				( attribute "CDS_LIB" "mstr_discrete"
					( Origin gPackager )
				)
				( attribute "CDS_LOCATION" "C5L14"
					( Origin gPackager )
				)
				( attribute "CDS_SEC" "1"
					( Origin gPackager )
				)
				( attribute "LOCATION" "C5L14"
					( Origin gFrontEnd )
				)
				( attribute "MATERIAL" "X5R"
					( Origin gFrontEnd )
				)
				( attribute "NEW_MATERIAL" "X6S"
					( Origin gFrontEnd )
				)
				( attribute "PACK_TYPE" "0805"
					( Origin gFrontEnd )
				)
				( attribute "PART_NUMBER" "602433-112"
					( Origin gFrontEnd )
				)
				( attribute "PHYS_PAGE" "220"
					( Origin gFrontEnd )
				)
				( attribute "ROOM" "VDDQ_ABC_PWR_VR"
					( Origin gFrontEnd )
				)
				( attribute "ROT" "0"
					( Origin gFrontEnd )
				)
				( attribute "SEC" "1"
					( Origin gFrontEnd )
				)
				( attribute "SEC_TYPE" "0805"
					( Origin gFrontEnd )
				)
				( attribute "TOLERANCE" "20%"
					( Origin gFrontEnd )
				)
				( attribute "VALUE" "100UF"
					( Origin gFrontEnd )
				)
				( attribute "VER" "1"
					( Origin gFrontEnd )
				)
				( attribute "VOLTAGE" "4V"
					( Units "uVoltage" "V" 1.000000)
					( Origin gFrontEnd )
				)
				( attribute "XY" "(4600,2825)"
					( Origin gFrontEnd )
				)
				( attribute "CHIPS_PART_NAME" "CAP"
					( Origin gPackager )
				)
				( attribute "CDS_PART_NAME" "CAP_0805-100UF,4V,20%,X5R,6024A"
					( Origin gPackager )
				)
				( attribute "GROUP" "PWR_MLCC_CAP"
					( Origin gFrontEnd )
				)
				( attribute "NEW_PN" "078.1071T.M002"
					( Origin gFrontEnd )
				)
				( attribute "BOM_SS" "NOPOP"
					( Origin gFrontEnd )
				)
				( objectStatus "C5L14" )
			)
			( gate "@baseboard_fab2_lib.baseboard_fab2(sch_1):page220_i318"
				( attribute "BOM_COST" "MEM_VRD_PVDDQ_CD"
					( Origin gFrontEnd )
				)
				( attribute "CDS_LIB" "mstr_discrete"
					( Origin gPackager )
				)
				( attribute "CDS_LOCATION" "C5P4"
					( Origin gPackager )
				)
				( attribute "CDS_SEC" "1"
					( Origin gPackager )
				)
				( attribute "LOCATION" "C5P4"
					( Origin gFrontEnd )
				)
				( attribute "MATERIAL" "X5R"
					( Origin gFrontEnd )
				)
				( attribute "NEW_MATERIAL" "X6S"
					( Origin gFrontEnd )
				)
				( attribute "PACK_TYPE" "0805"
					( Origin gFrontEnd )
				)
				( attribute "PART_NUMBER" "602433-112"
					( Origin gFrontEnd )
				)
				( attribute "PHYS_PAGE" "220"
					( Origin gFrontEnd )
				)
				( attribute "ROOM" "VDDQ_ABC_PWR_VR"
					( Origin gFrontEnd )
				)
				( attribute "ROT" "0"
					( Origin gFrontEnd )
				)
				( attribute "SEC" "1"
					( Origin gFrontEnd )
				)
				( attribute "SEC_TYPE" "0805"
					( Origin gFrontEnd )
				)
				( attribute "TOLERANCE" "20%"
					( Origin gFrontEnd )
				)
				( attribute "VALUE" "100UF"
					( Origin gFrontEnd )
				)
				( attribute "VER" "1"
					( Origin gFrontEnd )
				)
				( attribute "VOLTAGE" "4V"
					( Units "uVoltage" "V" 1.000000)
					( Origin gFrontEnd )
				)
				( attribute "XY" "(800,2925)"
					( Origin gFrontEnd )
				)
				( attribute "CHIPS_PART_NAME" "CAP"
					( Origin gPackager )
				)
				( attribute "CDS_PART_NAME" "CAP_0805-100UF,4V,20%,X5R,6024A"
					( Origin gPackager )
				)
				( attribute "GROUP" "PWR_MLCC_CAP"
					( Origin gFrontEnd )
				)
				( attribute "NEW_PN" "078.1071T.M002"
					( Origin gFrontEnd )
				)
				( attribute "BOM_SS" "NOPOP"
					( Origin gFrontEnd )
				)
				( objectStatus "C5P4" )
			)
			( gate "@baseboard_fab2_lib.baseboard_fab2(sch_1):page220_i312"
				( attribute "BOM_COST" "MEM_VRD_PVDDQ_CD"
					( Origin gFrontEnd )
				)
				( attribute "CDS_LIB" "mstr_discrete"
					( Origin gPackager )
				)
				( attribute "CDS_LOCATION" "C5M12"
					( Origin gPackager )
				)
				( attribute "CDS_SEC" "1"
					( Origin gPackager )
				)
				( attribute "LOCATION" "C5M12"
					( Origin gFrontEnd )
				)
				( attribute "MATERIAL" "X5R"
					( Origin gFrontEnd )
				)
				( attribute "NEW_MATERIAL" "X6S"
					( Origin gFrontEnd )
				)
				( attribute "PACK_TYPE" "0805"
					( Origin gFrontEnd )
				)
				( attribute "PART_NUMBER" "602433-112"
					( Origin gFrontEnd )
				)
				( attribute "PHYS_PAGE" "220"
					( Origin gFrontEnd )
				)
				( attribute "ROOM" "VDDQ_ABC_PWR_VR"
					( Origin gFrontEnd )
				)
				( attribute "ROT" "0"
					( Origin gFrontEnd )
				)
				( attribute "SEC" "1"
					( Origin gFrontEnd )
				)
				( attribute "SEC_TYPE" "0805"
					( Origin gFrontEnd )
				)
				( attribute "TOLERANCE" "20%"
					( Origin gFrontEnd )
				)
				( attribute "VALUE" "100UF"
					( Origin gFrontEnd )
				)
				( attribute "VER" "1"
					( Origin gFrontEnd )
				)
				( attribute "VOLTAGE" "4V"
					( Units "uVoltage" "V" 1.000000)
					( Origin gFrontEnd )
				)
				( attribute "XY" "(4250,2825)"
					( Origin gFrontEnd )
				)
				( attribute "CHIPS_PART_NAME" "CAP"
					( Origin gPackager )
				)
				( attribute "CDS_PART_NAME" "CAP_0805-100UF,4V,20%,X5R,6024A"
					( Origin gPackager )
				)
				( attribute "GROUP" "PWR_MLCC_CAP"
					( Origin gFrontEnd )
				)
				( attribute "NEW_PN" "078.1071T.M002"
					( Origin gFrontEnd )
				)
				( attribute "BOM_SS" "NOPOP"
					( Origin gFrontEnd )
				)
				( objectStatus "C5M12" )
			)
			( gate "@baseboard_fab2_lib.baseboard_fab2(sch_1):page220_i314"
				( attribute "BOM_COST" "MEM_VRD_PVDDQ_CD"
					( Origin gFrontEnd )
				)
				( attribute "CDS_LIB" "mstr_discrete"
					( Origin gPackager )
				)
				( attribute "CDS_LOCATION" "C5M8"
					( Origin gPackager )
				)
				( attribute "CDS_SEC" "1"
					( Origin gPackager )
				)
				( attribute "LOCATION" "C5M8"
					( Origin gFrontEnd )
				)
				( attribute "MATERIAL" "X5R"
					( Origin gFrontEnd )
				)
				( attribute "NEW_MATERIAL" "X6S"
					( Origin gFrontEnd )
				)
				( attribute "PACK_TYPE" "0805"
					( Origin gFrontEnd )
				)
				( attribute "PART_NUMBER" "602433-112"
					( Origin gFrontEnd )
				)
				( attribute "PHYS_PAGE" "220"
					( Origin gFrontEnd )
				)
				( attribute "ROOM" "VDDQ_ABC_PWR_VR"
					( Origin gFrontEnd )
				)
				( attribute "ROT" "0"
					( Origin gFrontEnd )
				)
				( attribute "SEC" "1"
					( Origin gFrontEnd )
				)
				( attribute "SEC_TYPE" "0805"
					( Origin gFrontEnd )
				)
				( attribute "TOLERANCE" "20%"
					( Origin gFrontEnd )
				)
				( attribute "VALUE" "100UF"
					( Origin gFrontEnd )
				)
				( attribute "VER" "1"
					( Origin gFrontEnd )
				)
				( attribute "VOLTAGE" "4V"
					( Units "uVoltage" "V" 1.000000)
					( Origin gFrontEnd )
				)
				( attribute "XY" "(5000,2825)"
					( Origin gFrontEnd )
				)
				( attribute "CHIPS_PART_NAME" "CAP"
					( Origin gPackager )
				)
				( attribute "CDS_PART_NAME" "CAP_0805-100UF,4V,20%,X5R,6024A"
					( Origin gPackager )
				)
				( attribute "GROUP" "PWR_MLCC_CAP"
					( Origin gFrontEnd )
				)
				( attribute "NEW_PN" "078.1071T.M002"
					( Origin gFrontEnd )
				)
				( attribute "BOM_SS" "NOPOP"
					( Origin gFrontEnd )
				)
				( objectStatus "C5M8" )
			)
			( gate "@baseboard_fab2_lib.baseboard_fab2(sch_1):page220_i311"
				( attribute "BOM_COST" "MEM_VRD_PVDDQ_CD"
					( Origin gFrontEnd )
				)
				( attribute "CDS_LIB" "mstr_discrete"
					( Origin gPackager )
				)
				( attribute "LOCATION" "C5L2"
					( Origin gFrontEnd )
				)
				( attribute "MATERIAL" "X5R"
					( Origin gFrontEnd )
				)
				( attribute "NEW_MATERIAL" "X6S"
					( Origin gFrontEnd )
				)
				( attribute "PACK_TYPE" "0805"
					( Origin gFrontEnd )
				)
				( attribute "PART_NUMBER" "602433-112"
					( Origin gFrontEnd )
				)
				( attribute "PHYS_PAGE" "220"
					( Origin gFrontEnd )
				)
				( attribute "ROOM" "VDDQ_ABC_PWR_VR"
					( Origin gFrontEnd )
				)
				( attribute "ROT" "0"
					( Origin gFrontEnd )
				)
				( attribute "TOLERANCE" "20%"
					( Origin gFrontEnd )
				)
				( attribute "VALUE" "100UF"
					( Origin gFrontEnd )
				)
				( attribute "VER" "1"
					( Origin gFrontEnd )
				)
				( attribute "VOLTAGE" "4V"
					( Units "uVoltage" "V" 1.000000)
					( Origin gFrontEnd )
				)
				( attribute "XY" "(3500,2825)"
					( Origin gFrontEnd )
				)
				( attribute "CHIPS_PART_NAME" "CAP"
					( Origin gPackager )
				)
				( attribute "CDS_PART_NAME" "CAP_0805-100UF,4V,20%,X5R,6024A"
					( Origin gPackager )
				)
				( attribute "CDS_LOCATION" "C5L2"
					( Origin gPackager )
				)
				( attribute "CDS_SEC" "1"
					( Origin gPackager )
				)
				( attribute "SEC" "1"
					( Origin gPackager )
				)
				( attribute "GROUP" "PWR_MLCC_CAP"
					( Origin gFrontEnd )
				)
				( attribute "NEW_PN" "078.1071T.M002"
					( Origin gFrontEnd )
				)
				( attribute "BOM_SS" "NOPOP"
					( Origin gFrontEnd )
				)
				( objectStatus "C5L2" )
			)
			( gate "@baseboard_fab2_lib.baseboard_fab2(sch_1):page221_i44"
				( attribute "BOM_COST" "MEM_VRD_PVDDQ_CD"
					( Origin gFrontEnd )
				)
				( attribute "CDS_LIB" "mstr_discrete"
					( Origin gPackager )
				)
				( attribute "CDS_LOCATION" "C6W11"
					( Origin gPackager )
				)
				( attribute "CDS_SEC" "1"
					( Origin gPackager )
				)
				( attribute "LOCATION" "C6W11"
					( Origin gFrontEnd )
				)
				( attribute "MATERIAL" "X5R"
					( Origin gFrontEnd )
				)
				( attribute "NEW_MATERIAL" "X6S"
					( Origin gFrontEnd )
				)
				( attribute "PACK_TYPE" "0805"
					( Origin gFrontEnd )
				)
				( attribute "PART_NUMBER" "602433-112"
					( Origin gFrontEnd )
				)
				( attribute "PHYS_PAGE" "221"
					( Origin gFrontEnd )
				)
				( attribute "ROOM" "VDDQ_ABC_PWR_VR"
					( Origin gFrontEnd )
				)
				( attribute "ROT" "0"
					( Origin gFrontEnd )
				)
				( attribute "SEC" "1"
					( Origin gFrontEnd )
				)
				( attribute "SEC_TYPE" "0805"
					( Origin gFrontEnd )
				)
				( attribute "TOLERANCE" "20%"
					( Origin gFrontEnd )
				)
				( attribute "VALUE" "100UF"
					( Origin gFrontEnd )
				)
				( attribute "VER" "1"
					( Origin gFrontEnd )
				)
				( attribute "VOLTAGE" "4V"
					( Units "uVoltage" "V" 1.000000)
					( Origin gFrontEnd )
				)
				( attribute "XY" "(4425,975)"
					( Origin gFrontEnd )
				)
				( attribute "CHIPS_PART_NAME" "CAP"
					( Origin gPackager )
				)
				( attribute "CDS_PART_NAME" "CAP_0805-100UF,4V,20%,X5R,6024A"
					( Origin gPackager )
				)
				( attribute "GROUP" "PWR_MLCC_CAP"
					( Origin gFrontEnd )
				)
				( attribute "NEW_PN" "078.1071T.M002"
					( Origin gFrontEnd )
				)
				( objectStatus "C6W11" )
			)
			( gate "@baseboard_fab2_lib.baseboard_fab2(sch_1):page225_i253"
				( attribute "CDS_LIB" "w_hdl"
					( Origin gPackager )
				)
				( attribute "CDS_LMAN_SYM_OUTLINE" "-75,100,75,-100"
					( Origin gPackager )
				)
				( attribute "LOCATION" "L1F1"
					( Origin gFrontEnd )
				)
				( attribute "PACK_TYPE" "DISCRET-G8"
					( Origin gFrontEnd )
				)
				( attribute "PART_NUMBER" "068.1011N.M001"
					( Origin gFrontEnd )
				)
				( attribute "PHYS_PAGE" "225"
					( Origin gFrontEnd )
				)
				( attribute "ROT" "1"
					( Origin gFrontEnd )
				)
				( attribute "SEC" "1"
					( Origin gFrontEnd )
				)
				( attribute "SEC_TYPE" "DISCRET-G8"
					( Origin gFrontEnd )
				)
				( attribute "VALUE" "IND-100NH-35-GP"
					( Origin gFrontEnd )
				)
				( attribute "VER" "1"
					( Origin gFrontEnd )
				)
				( attribute "XY" "(-1750,1375)"
					( Origin gFrontEnd )
				)
				( attribute "CHIPS_PART_NAME" "IND-100NH-35-GP"
					( Origin gPackager )
				)
				( attribute "CDS_PART_NAME" "IND-100NH-35-GP_DISCRET-G8-INDA"
					( Origin gPackager )
				)
				( attribute "CDS_LOCATION" "L1F1"
					( Origin gPackager )
				)
				( attribute "CDS_SEC" "1"
					( Origin gPackager )
				)
				( attribute "ATTRIBUTE" "100NH"
					( Origin gFrontEnd )
				)
				( attribute "PACK_SIZE" "DCR=0.16MOHM"
					( Origin gFrontEnd )
				)
				( attribute "RATED" "ISAT=16A@25C"
					( Origin gFrontEnd )
				)
				( attribute "TYPE" "IRMS=29A@DELTA_T<45C"
					( Origin gFrontEnd )
				)
				( objectStatus "L1F1" )
			)
			( gate "@baseboard_fab2_lib.baseboard_fab2(sch_1):page225_i315"
				( attribute "BOM_COST" "MEM_VRD_PVDDQ_CD"
					( Origin gFrontEnd )
				)
				( attribute "CDS_LIB" "mstr_discrete"
					( Origin gPackager )
				)
				( attribute "CDS_LOCATION" "C8P34"
					( Origin gPackager )
				)
				( attribute "CDS_SEC" "1"
					( Origin gPackager )
				)
				( attribute "LOCATION" "C8P34"
					( Origin gFrontEnd )
				)
				( attribute "MATERIAL" "X5R"
					( Origin gFrontEnd )
				)
				( attribute "NEW_MATERIAL" "X6S"
					( Origin gFrontEnd )
				)
				( attribute "PACK_TYPE" "0805"
					( Origin gFrontEnd )
				)
				( attribute "PART_NUMBER" "602433-112"
					( Origin gFrontEnd )
				)
				( attribute "PHYS_PAGE" "225"
					( Origin gFrontEnd )
				)
				( attribute "ROOM" "VDDQ_ABC_PWR_VR"
					( Origin gFrontEnd )
				)
				( attribute "ROT" "0"
					( Origin gFrontEnd )
				)
				( attribute "SEC" "1"
					( Origin gFrontEnd )
				)
				( attribute "SEC_TYPE" "0805"
					( Origin gFrontEnd )
				)
				( attribute "TOLERANCE" "20%"
					( Origin gFrontEnd )
				)
				( attribute "VALUE" "100UF"
					( Origin gFrontEnd )
				)
				( attribute "VER" "1"
					( Origin gFrontEnd )
				)
				( attribute "VOLTAGE" "4V"
					( Units "uVoltage" "V" 1.000000)
					( Origin gFrontEnd )
				)
				( attribute "XY" "(100,3025)"
					( Origin gFrontEnd )
				)
				( attribute "CHIPS_PART_NAME" "CAP"
					( Origin gPackager )
				)
				( attribute "CDS_PART_NAME" "CAP_0805-100UF,4V,20%,X5R,6024A"
					( Origin gPackager )
				)
				( attribute "GROUP" "PWR_MLCC_CAP"
					( Origin gFrontEnd )
				)
				( attribute "NEW_PN" "078.1071T.M002"
					( Origin gFrontEnd )
				)
				( attribute "BOM_SS" "NOPOP"
					( Origin gFrontEnd )
				)
				( objectStatus "C8P34" )
			)
			( gate "@baseboard_fab2_lib.baseboard_fab2(sch_1):page225_i314"
				( attribute "BOM_COST" "MEM_VRD_PVDDQ_CD"
					( Origin gFrontEnd )
				)
				( attribute "CDS_LIB" "mstr_discrete"
					( Origin gPackager )
				)
				( attribute "CDS_LOCATION" "C8P31"
					( Origin gPackager )
				)
				( attribute "CDS_SEC" "1"
					( Origin gPackager )
				)
				( attribute "LOCATION" "C8P31"
					( Origin gFrontEnd )
				)
				( attribute "MATERIAL" "X5R"
					( Origin gFrontEnd )
				)
				( attribute "NEW_MATERIAL" "X6S"
					( Origin gFrontEnd )
				)
				( attribute "PACK_TYPE" "0805"
					( Origin gFrontEnd )
				)
				( attribute "PART_NUMBER" "602433-112"
					( Origin gFrontEnd )
				)
				( attribute "PHYS_PAGE" "225"
					( Origin gFrontEnd )
				)
				( attribute "ROOM" "VDDQ_ABC_PWR_VR"
					( Origin gFrontEnd )
				)
				( attribute "ROT" "0"
					( Origin gFrontEnd )
				)
				( attribute "SEC" "1"
					( Origin gFrontEnd )
				)
				( attribute "SEC_TYPE" "0805"
					( Origin gFrontEnd )
				)
				( attribute "TOLERANCE" "20%"
					( Origin gFrontEnd )
				)
				( attribute "VALUE" "100UF"
					( Origin gFrontEnd )
				)
				( attribute "VER" "1"
					( Origin gFrontEnd )
				)
				( attribute "VOLTAGE" "4V"
					( Units "uVoltage" "V" 1.000000)
					( Origin gFrontEnd )
				)
				( attribute "XY" "(-1975,3100)"
					( Origin gFrontEnd )
				)
				( attribute "CHIPS_PART_NAME" "CAP"
					( Origin gPackager )
				)
				( attribute "CDS_PART_NAME" "CAP_0805-100UF,4V,20%,X5R,6024A"
					( Origin gPackager )
				)
				( attribute "GROUP" "PWR_MLCC_CAP"
					( Origin gFrontEnd )
				)
				( attribute "NEW_PN" "078.1071T.M002"
					( Origin gFrontEnd )
				)
				( attribute "BOM_SS" "NOPOP"
					( Origin gFrontEnd )
				)
				( objectStatus "C8P31" )
			)
			( gate "@baseboard_fab2_lib.baseboard_fab2(sch_1):page220_i265"
				( attribute "CDS_LIB" "dev_discrete"
					( Origin gPackager )
				)
				( attribute "CDS_LOCATION" "C5A13"
					( Origin gPackager )
				)
				( attribute "CDS_SEC" "1"
					( Origin gPackager )
				)
				( attribute "LOCATION" "C5A13"
					( Origin gFrontEnd )
				)
				( attribute "MATERIAL" "X5R"
					( Origin gFrontEnd )
				)
				( attribute "PACK_TYPE" "0603V"
					( Origin gFrontEnd )
				)
				( attribute "PART_NUMBER" "602433-106"
					( Origin gFrontEnd )
				)
				( attribute "PHYS_PAGE" "220"
					( Origin gFrontEnd )
				)
				( attribute "ROT" "0"
					( Origin gFrontEnd )
				)
				( attribute "SEC" "1"
					( Origin gFrontEnd )
				)
				( attribute "SEC_TYPE" "0603V"
					( Origin gFrontEnd )
				)
				( attribute "TOLERANCE" "20%"
					( Origin gFrontEnd )
				)
				( attribute "VALUE" "47UF"
					( Origin gFrontEnd )
				)
				( attribute "VER" "1"
					( Origin gFrontEnd )
				)
				( attribute "VOLTAGE" "4V"
					( Units "uVoltage" "V" 1.000000)
					( Origin gFrontEnd )
				)
				( attribute "XY" "(-1275,100)"
					( Origin gFrontEnd )
				)
				( attribute "CHIPS_PART_NAME" "CAP_A"
					( Origin gPackager )
				)
				( attribute "CDS_PART_NAME" "CAP_A_0603V-47UF,4V,20%,X5R,60A"
					( Origin gPackager )
				)
				( attribute "GROUP" "PWR_MLCC_CAP"
					( Origin gFrontEnd )
				)
				( attribute "BOM_SS" "E15431-004"
					( Origin gFrontEnd )
				)
				( objectStatus "C5A13" )
			)
			( gate "@baseboard_fab2_lib.baseboard_fab2(sch_1):page220_i264"
				( attribute "CDS_LIB" "dev_discrete"
					( Origin gPackager )
				)
				( attribute "CDS_LOCATION" "C5A12"
					( Origin gPackager )
				)
				( attribute "CDS_SEC" "1"
					( Origin gPackager )
				)
				( attribute "LOCATION" "C5A12"
					( Origin gFrontEnd )
				)
				( attribute "MATERIAL" "X5R"
					( Origin gFrontEnd )
				)
				( attribute "PACK_TYPE" "0603V"
					( Origin gFrontEnd )
				)
				( attribute "PART_NUMBER" "602433-106"
					( Origin gFrontEnd )
				)
				( attribute "PHYS_PAGE" "220"
					( Origin gFrontEnd )
				)
				( attribute "ROT" "0"
					( Origin gFrontEnd )
				)
				( attribute "SEC" "1"
					( Origin gFrontEnd )
				)
				( attribute "SEC_TYPE" "0603V"
					( Origin gFrontEnd )
				)
				( attribute "TOLERANCE" "20%"
					( Origin gFrontEnd )
				)
				( attribute "VALUE" "47UF"
					( Origin gFrontEnd )
				)
				( attribute "VER" "1"
					( Origin gFrontEnd )
				)
				( attribute "VOLTAGE" "4V"
					( Units "uVoltage" "V" 1.000000)
					( Origin gFrontEnd )
				)
				( attribute "XY" "(-1550,100)"
					( Origin gFrontEnd )
				)
				( attribute "CHIPS_PART_NAME" "CAP_A"
					( Origin gPackager )
				)
				( attribute "CDS_PART_NAME" "CAP_A_0603V-47UF,4V,20%,X5R,60A"
					( Origin gPackager )
				)
				( attribute "GROUP" "PWR_MLCC_CAP"
					( Origin gFrontEnd )
				)
				( attribute "BOM_SS" "E15431-004"
					( Origin gFrontEnd )
				)
				( objectStatus "C5A12" )
			)
			( gate "@baseboard_fab2_lib.baseboard_fab2(sch_1):page220_i263"
				( attribute "CDS_LIB" "dev_discrete"
					( Origin gPackager )
				)
				( attribute "CDS_LOCATION" "C5A15"
					( Origin gPackager )
				)
				( attribute "CDS_SEC" "1"
					( Origin gPackager )
				)
				( attribute "LOCATION" "C5A15"
					( Origin gFrontEnd )
				)
				( attribute "MATERIAL" "X5R"
					( Origin gFrontEnd )
				)
				( attribute "PACK_TYPE" "0603V"
					( Origin gFrontEnd )
				)
				( attribute "PART_NUMBER" "602433-106"
					( Origin gFrontEnd )
				)
				( attribute "PHYS_PAGE" "220"
					( Origin gFrontEnd )
				)
				( attribute "ROT" "0"
					( Origin gFrontEnd )
				)
				( attribute "SEC" "1"
					( Origin gFrontEnd )
				)
				( attribute "SEC_TYPE" "0603V"
					( Origin gFrontEnd )
				)
				( attribute "TOLERANCE" "20%"
					( Origin gFrontEnd )
				)
				( attribute "VALUE" "47UF"
					( Origin gFrontEnd )
				)
				( attribute "VER" "1"
					( Origin gFrontEnd )
				)
				( attribute "VOLTAGE" "4V"
					( Units "uVoltage" "V" 1.000000)
					( Origin gFrontEnd )
				)
				( attribute "XY" "(-1850,100)"
					( Origin gFrontEnd )
				)
				( attribute "CHIPS_PART_NAME" "CAP_A"
					( Origin gPackager )
				)
				( attribute "CDS_PART_NAME" "CAP_A_0603V-47UF,4V,20%,X5R,60A"
					( Origin gPackager )
				)
				( attribute "GROUP" "PWR_MLCC_CAP"
					( Origin gFrontEnd )
				)
				( attribute "BOM_SS" "E15431-004"
					( Origin gFrontEnd )
				)
				( objectStatus "C5A15" )
			)
			( gate "@baseboard_fab2_lib.baseboard_fab2(sch_1):page220_i262"
				( attribute "CDS_LIB" "dev_discrete"
					( Origin gPackager )
				)
				( attribute "CDS_LOCATION" "C5A1"
					( Origin gPackager )
				)
				( attribute "CDS_SEC" "1"
					( Origin gPackager )
				)
				( attribute "LOCATION" "C5A1"
					( Origin gFrontEnd )
				)
				( attribute "MATERIAL" "X5R"
					( Origin gFrontEnd )
				)
				( attribute "PACK_TYPE" "0603V"
					( Origin gFrontEnd )
				)
				( attribute "PART_NUMBER" "602433-106"
					( Origin gFrontEnd )
				)
				( attribute "PHYS_PAGE" "220"
					( Origin gFrontEnd )
				)
				( attribute "ROT" "0"
					( Origin gFrontEnd )
				)
				( attribute "SEC" "1"
					( Origin gFrontEnd )
				)
				( attribute "SEC_TYPE" "0603V"
					( Origin gFrontEnd )
				)
				( attribute "TOLERANCE" "20%"
					( Origin gFrontEnd )
				)
				( attribute "VALUE" "47UF"
					( Origin gFrontEnd )
				)
				( attribute "VER" "1"
					( Origin gFrontEnd )
				)
				( attribute "VOLTAGE" "4V"
					( Units "uVoltage" "V" 1.000000)
					( Origin gFrontEnd )
				)
				( attribute "XY" "(-2150,100)"
					( Origin gFrontEnd )
				)
				( attribute "CHIPS_PART_NAME" "CAP_A"
					( Origin gPackager )
				)
				( attribute "CDS_PART_NAME" "CAP_A_0603V-47UF,4V,20%,X5R,60A"
					( Origin gPackager )
				)
				( attribute "GROUP" "PWR_MLCC_CAP"
					( Origin gFrontEnd )
				)
				( attribute "BOM_SS" "E15431-004"
					( Origin gFrontEnd )
				)
				( objectStatus "C5A1" )
			)
			( gate "@baseboard_fab2_lib.baseboard_fab2(sch_1):page220_i192"
				( attribute "CDS_LIB" "dev_discrete"
					( Origin gPackager )
				)
				( attribute "CDS_LOCATION" "C5L15"
					( Origin gPackager )
				)
				( attribute "CDS_SEC" "1"
					( Origin gPackager )
				)
				( attribute "LOCATION" "C5L15"
					( Origin gFrontEnd )
				)
				( attribute "MATERIAL" "X5R"
					( Origin gFrontEnd )
				)
				( attribute "PACK_TYPE" "0603V"
					( Origin gFrontEnd )
				)
				( attribute "PART_NUMBER" "602433-106"
					( Origin gFrontEnd )
				)
				( attribute "PHYS_PAGE" "220"
					( Origin gFrontEnd )
				)
				( attribute "ROT" "0"
					( Origin gFrontEnd )
				)
				( attribute "SEC" "1"
					( Origin gFrontEnd )
				)
				( attribute "SEC_TYPE" "0603V"
					( Origin gFrontEnd )
				)
				( attribute "TOLERANCE" "20%"
					( Origin gFrontEnd )
				)
				( attribute "VALUE" "47UF"
					( Origin gFrontEnd )
				)
				( attribute "VER" "1"
					( Origin gFrontEnd )
				)
				( attribute "VOLTAGE" "4V"
					( Units "uVoltage" "V" 1.000000)
					( Origin gFrontEnd )
				)
				( attribute "XY" "(2650,950)"
					( Origin gFrontEnd )
				)
				( attribute "CHIPS_PART_NAME" "CAP_A"
					( Origin gPackager )
				)
				( attribute "CDS_PART_NAME" "CAP_A_0603V-47UF,4V,20%,X5R,60A"
					( Origin gPackager )
				)
				( attribute "GROUP" "PWR_MLCC_CAP"
					( Origin gFrontEnd )
				)
				( attribute "BOM_SS" "NOPOP"
					( Origin gFrontEnd )
				)
				( objectStatus "C5L15" )
			)
			( gate "@baseboard_fab2_lib.baseboard_fab2(sch_1):page220_i193"
				( attribute "CDS_LIB" "dev_discrete"
					( Origin gPackager )
				)
				( attribute "CDS_LOCATION" "C5A5"
					( Origin gPackager )
				)
				( attribute "CDS_SEC" "1"
					( Origin gPackager )
				)
				( attribute "LOCATION" "C5A5"
					( Origin gFrontEnd )
				)
				( attribute "MATERIAL" "X5R"
					( Origin gFrontEnd )
				)
				( attribute "PACK_TYPE" "0603V"
					( Origin gFrontEnd )
				)
				( attribute "PART_NUMBER" "602433-106"
					( Origin gFrontEnd )
				)
				( attribute "PHYS_PAGE" "220"
					( Origin gFrontEnd )
				)
				( attribute "ROT" "0"
					( Origin gFrontEnd )
				)
				( attribute "SEC" "1"
					( Origin gFrontEnd )
				)
				( attribute "SEC_TYPE" "0603V"
					( Origin gFrontEnd )
				)
				( attribute "TOLERANCE" "20%"
					( Origin gFrontEnd )
				)
				( attribute "VALUE" "47UF"
					( Origin gFrontEnd )
				)
				( attribute "VER" "1"
					( Origin gFrontEnd )
				)
				( attribute "VOLTAGE" "4V"
					( Units "uVoltage" "V" 1.000000)
					( Origin gFrontEnd )
				)
				( attribute "XY" "(3000,950)"
					( Origin gFrontEnd )
				)
				( attribute "CHIPS_PART_NAME" "CAP_A"
					( Origin gPackager )
				)
				( attribute "CDS_PART_NAME" "CAP_A_0603V-47UF,4V,20%,X5R,60A"
					( Origin gPackager )
				)
				( attribute "GROUP" "PWR_MLCC_CAP"
					( Origin gFrontEnd )
				)
				( attribute "BOM_SS" "NOPOP"
					( Origin gFrontEnd )
				)
				( objectStatus "C5A5" )
			)
			( gate "@baseboard_fab2_lib.baseboard_fab2(sch_1):page220_i194"
				( attribute "CDS_LIB" "dev_discrete"
					( Origin gPackager )
				)
				( attribute "CDS_LOCATION" "C5B1"
					( Origin gPackager )
				)
				( attribute "CDS_SEC" "1"
					( Origin gPackager )
				)
				( attribute "LOCATION" "C5B1"
					( Origin gFrontEnd )
				)
				( attribute "MATERIAL" "X5R"
					( Origin gFrontEnd )
				)
				( attribute "PACK_TYPE" "0603V"
					( Origin gFrontEnd )
				)
				( attribute "PART_NUMBER" "602433-106"
					( Origin gFrontEnd )
				)
				( attribute "PHYS_PAGE" "220"
					( Origin gFrontEnd )
				)
				( attribute "ROT" "0"
					( Origin gFrontEnd )
				)
				( attribute "SEC" "1"
					( Origin gFrontEnd )
				)
				( attribute "SEC_TYPE" "0603V"
					( Origin gFrontEnd )
				)
				( attribute "TOLERANCE" "20%"
					( Origin gFrontEnd )
				)
				( attribute "VALUE" "47UF"
					( Origin gFrontEnd )
				)
				( attribute "VER" "1"
					( Origin gFrontEnd )
				)
				( attribute "VOLTAGE" "4V"
					( Units "uVoltage" "V" 1.000000)
					( Origin gFrontEnd )
				)
				( attribute "XY" "(3400,950)"
					( Origin gFrontEnd )
				)
				( attribute "CHIPS_PART_NAME" "CAP_A"
					( Origin gPackager )
				)
				( attribute "CDS_PART_NAME" "CAP_A_0603V-47UF,4V,20%,X5R,60A"
					( Origin gPackager )
				)
				( attribute "GROUP" "PWR_MLCC_CAP"
					( Origin gFrontEnd )
				)
				( attribute "BOM_SS" "NOPOP"
					( Origin gFrontEnd )
				)
				( objectStatus "C5B1" )
			)
			( gate "@baseboard_fab2_lib.baseboard_fab2(sch_1):page220_i195"
				( attribute "CDS_LIB" "dev_discrete"
					( Origin gPackager )
				)
				( attribute "CDS_LOCATION" "C5M9"
					( Origin gPackager )
				)
				( attribute "CDS_SEC" "1"
					( Origin gPackager )
				)
				( attribute "LOCATION" "C5M9"
					( Origin gFrontEnd )
				)
				( attribute "MATERIAL" "X5R"
					( Origin gFrontEnd )
				)
				( attribute "PACK_TYPE" "0603V"
					( Origin gFrontEnd )
				)
				( attribute "PART_NUMBER" "602433-106"
					( Origin gFrontEnd )
				)
				( attribute "PHYS_PAGE" "220"
					( Origin gFrontEnd )
				)
				( attribute "ROT" "0"
					( Origin gFrontEnd )
				)
				( attribute "SEC" "1"
					( Origin gFrontEnd )
				)
				( attribute "SEC_TYPE" "0603V"
					( Origin gFrontEnd )
				)
				( attribute "TOLERANCE" "20%"
					( Origin gFrontEnd )
				)
				( attribute "VALUE" "47UF"
					( Origin gFrontEnd )
				)
				( attribute "VER" "1"
					( Origin gFrontEnd )
				)
				( attribute "VOLTAGE" "4V"
					( Units "uVoltage" "V" 1.000000)
					( Origin gFrontEnd )
				)
				( attribute "XY" "(4125,1675)"
					( Origin gFrontEnd )
				)
				( attribute "CHIPS_PART_NAME" "CAP_A"
					( Origin gPackager )
				)
				( attribute "CDS_PART_NAME" "CAP_A_0603V-47UF,4V,20%,X5R,60A"
					( Origin gPackager )
				)
				( attribute "GROUP" "PWR_MLCC_CAP"
					( Origin gFrontEnd )
				)
				( attribute "BOM_SS" "NOPOP"
					( Origin gFrontEnd )
				)
				( objectStatus "C5M9" )
			)
			( gate "@baseboard_fab2_lib.baseboard_fab2(sch_1):page220_i196"
				( attribute "CDS_LIB" "dev_discrete"
					( Origin gPackager )
				)
				( attribute "CDS_LOCATION" "C4M5"
					( Origin gPackager )
				)
				( attribute "CDS_SEC" "1"
					( Origin gPackager )
				)
				( attribute "LOCATION" "C4M5"
					( Origin gFrontEnd )
				)
				( attribute "MATERIAL" "X5R"
					( Origin gFrontEnd )
				)
				( attribute "PACK_TYPE" "0603V"
					( Origin gFrontEnd )
				)
				( attribute "PART_NUMBER" "602433-106"
					( Origin gFrontEnd )
				)
				( attribute "PHYS_PAGE" "220"
					( Origin gFrontEnd )
				)
				( attribute "ROT" "0"
					( Origin gFrontEnd )
				)
				( attribute "SEC" "1"
					( Origin gFrontEnd )
				)
				( attribute "SEC_TYPE" "0603V"
					( Origin gFrontEnd )
				)
				( attribute "TOLERANCE" "20%"
					( Origin gFrontEnd )
				)
				( attribute "VALUE" "47UF"
					( Origin gFrontEnd )
				)
				( attribute "VER" "1"
					( Origin gFrontEnd )
				)
				( attribute "VOLTAGE" "4V"
					( Units "uVoltage" "V" 1.000000)
					( Origin gFrontEnd )
				)
				( attribute "XY" "(3775,1675)"
					( Origin gFrontEnd )
				)
				( attribute "CHIPS_PART_NAME" "CAP_A"
					( Origin gPackager )
				)
				( attribute "CDS_PART_NAME" "CAP_A_0603V-47UF,4V,20%,X5R,60A"
					( Origin gPackager )
				)
				( attribute "GROUP" "PWR_MLCC_CAP"
					( Origin gFrontEnd )
				)
				( attribute "BOM_SS" "078.1061T.M001"
					( Origin gFrontEnd )
				)
				( objectStatus "C4M5" )
			)
			( gate "@baseboard_fab2_lib.baseboard_fab2(sch_1):page220_i197"
				( attribute "CDS_LIB" "dev_discrete"
					( Origin gPackager )
				)
				( attribute "CDS_LOCATION" "C5B2"
					( Origin gPackager )
				)
				( attribute "CDS_SEC" "1"
					( Origin gPackager )
				)
				( attribute "LOCATION" "C5B2"
					( Origin gFrontEnd )
				)
				( attribute "MATERIAL" "X5R"
					( Origin gFrontEnd )
				)
				( attribute "PACK_TYPE" "0603V"
					( Origin gFrontEnd )
				)
				( attribute "PART_NUMBER" "602433-106"
					( Origin gFrontEnd )
				)
				( attribute "PHYS_PAGE" "220"
					( Origin gFrontEnd )
				)
				( attribute "ROT" "0"
					( Origin gFrontEnd )
				)
				( attribute "SEC" "1"
					( Origin gFrontEnd )
				)
				( attribute "SEC_TYPE" "0603V"
					( Origin gFrontEnd )
				)
				( attribute "TOLERANCE" "20%"
					( Origin gFrontEnd )
				)
				( attribute "VALUE" "47UF"
					( Origin gFrontEnd )
				)
				( attribute "VER" "1"
					( Origin gFrontEnd )
				)
				( attribute "VOLTAGE" "4V"
					( Units "uVoltage" "V" 1.000000)
					( Origin gFrontEnd )
				)
				( attribute "XY" "(2675,1675)"
					( Origin gFrontEnd )
				)
				( attribute "CHIPS_PART_NAME" "CAP_A"
					( Origin gPackager )
				)
				( attribute "CDS_PART_NAME" "CAP_A_0603V-47UF,4V,20%,X5R,60A"
					( Origin gPackager )
				)
				( attribute "GROUP" "PWR_MLCC_CAP"
					( Origin gFrontEnd )
				)
				( attribute "BOM_SS" "NOPOP"
					( Origin gFrontEnd )
				)
				( objectStatus "C5B2" )
			)
			( gate "@baseboard_fab2_lib.baseboard_fab2(sch_1):page220_i198"
				( attribute "CDS_LIB" "dev_discrete"
					( Origin gPackager )
				)
				( attribute "CDS_LOCATION" "C5M10"
					( Origin gPackager )
				)
				( attribute "CDS_SEC" "1"
					( Origin gPackager )
				)
				( attribute "LOCATION" "C5M10"
					( Origin gFrontEnd )
				)
				( attribute "MATERIAL" "X5R"
					( Origin gFrontEnd )
				)
				( attribute "PACK_TYPE" "0603V"
					( Origin gFrontEnd )
				)
				( attribute "PART_NUMBER" "602433-106"
					( Origin gFrontEnd )
				)
				( attribute "PHYS_PAGE" "220"
					( Origin gFrontEnd )
				)
				( attribute "ROT" "0"
					( Origin gFrontEnd )
				)
				( attribute "SEC" "1"
					( Origin gFrontEnd )
				)
				( attribute "SEC_TYPE" "0603V"
					( Origin gFrontEnd )
				)
				( attribute "TOLERANCE" "20%"
					( Origin gFrontEnd )
				)
				( attribute "VALUE" "47UF"
					( Origin gFrontEnd )
				)
				( attribute "VER" "1"
					( Origin gFrontEnd )
				)
				( attribute "VOLTAGE" "4V"
					( Units "uVoltage" "V" 1.000000)
					( Origin gFrontEnd )
				)
				( attribute "XY" "(3025,1675)"
					( Origin gFrontEnd )
				)
				( attribute "CHIPS_PART_NAME" "CAP_A"
					( Origin gPackager )
				)
				( attribute "CDS_PART_NAME" "CAP_A_0603V-47UF,4V,20%,X5R,60A"
					( Origin gPackager )
				)
				( attribute "GROUP" "PWR_MLCC_CAP"
					( Origin gFrontEnd )
				)
				( attribute "BOM_SS" "NOPOP"
					( Origin gFrontEnd )
				)
				( objectStatus "C5M10" )
			)
			( gate "@baseboard_fab2_lib.baseboard_fab2(sch_1):page220_i199"
				( attribute "CDS_LIB" "dev_discrete"
					( Origin gPackager )
				)
				( attribute "CDS_LOCATION" "C5M3"
					( Origin gPackager )
				)
				( attribute "CDS_SEC" "1"
					( Origin gPackager )
				)
				( attribute "LOCATION" "C5M3"
					( Origin gFrontEnd )
				)
				( attribute "MATERIAL" "X5R"
					( Origin gFrontEnd )
				)
				( attribute "PACK_TYPE" "0603V"
					( Origin gFrontEnd )
				)
				( attribute "PART_NUMBER" "602433-106"
					( Origin gFrontEnd )
				)
				( attribute "PHYS_PAGE" "220"
					( Origin gFrontEnd )
				)
				( attribute "ROT" "0"
					( Origin gFrontEnd )
				)
				( attribute "SEC" "1"
					( Origin gFrontEnd )
				)
				( attribute "SEC_TYPE" "0603V"
					( Origin gFrontEnd )
				)
				( attribute "TOLERANCE" "20%"
					( Origin gFrontEnd )
				)
				( attribute "VALUE" "47UF"
					( Origin gFrontEnd )
				)
				( attribute "VER" "1"
					( Origin gFrontEnd )
				)
				( attribute "VOLTAGE" "4V"
					( Units "uVoltage" "V" 1.000000)
					( Origin gFrontEnd )
				)
				( attribute "XY" "(3425,1675)"
					( Origin gFrontEnd )
				)
				( attribute "CHIPS_PART_NAME" "CAP_A"
					( Origin gPackager )
				)
				( attribute "CDS_PART_NAME" "CAP_A_0603V-47UF,4V,20%,X5R,60A"
					( Origin gPackager )
				)
				( attribute "GROUP" "PWR_MLCC_CAP"
					( Origin gFrontEnd )
				)
				( attribute "BOM_SS" "NOPOP"
					( Origin gFrontEnd )
				)
				( objectStatus "C5M3" )
			)
			( gate "@baseboard_fab2_lib.baseboard_fab2(sch_1):page220_i200"
				( attribute "CDS_LIB" "dev_discrete"
					( Origin gPackager )
				)
				( attribute "CDS_LOCATION" "C5M11"
					( Origin gPackager )
				)
				( attribute "CDS_SEC" "1"
					( Origin gPackager )
				)
				( attribute "LOCATION" "C5M11"
					( Origin gFrontEnd )
				)
				( attribute "MATERIAL" "X5R"
					( Origin gFrontEnd )
				)
				( attribute "PACK_TYPE" "0603V"
					( Origin gFrontEnd )
				)
				( attribute "PART_NUMBER" "602433-106"
					( Origin gFrontEnd )
				)
				( attribute "PHYS_PAGE" "220"
					( Origin gFrontEnd )
				)
				( attribute "ROT" "0"
					( Origin gFrontEnd )
				)
				( attribute "SEC" "1"
					( Origin gFrontEnd )
				)
				( attribute "SEC_TYPE" "0603V"
					( Origin gFrontEnd )
				)
				( attribute "TOLERANCE" "20%"
					( Origin gFrontEnd )
				)
				( attribute "VALUE" "47UF"
					( Origin gFrontEnd )
				)
				( attribute "VER" "1"
					( Origin gFrontEnd )
				)
				( attribute "VOLTAGE" "4V"
					( Units "uVoltage" "V" 1.000000)
					( Origin gFrontEnd )
				)
				( attribute "XY" "(4525,1675)"
					( Origin gFrontEnd )
				)
				( attribute "CHIPS_PART_NAME" "CAP_A"
					( Origin gPackager )
				)
				( attribute "CDS_PART_NAME" "CAP_A_0603V-47UF,4V,20%,X5R,60A"
					( Origin gPackager )
				)
				( attribute "GROUP" "PWR_MLCC_CAP"
					( Origin gFrontEnd )
				)
				( attribute "BOM_SS" "NOPOP"
					( Origin gFrontEnd )
				)
				( objectStatus "C5M11" )
			)
			( gate "@baseboard_fab2_lib.baseboard_fab2(sch_1):page220_i293"
				( attribute "CDS_LIB" "dev_discrete"
					( Origin gPackager )
				)
				( attribute "CDS_LOCATION" "C5A11"
					( Origin gPackager )
				)
				( attribute "CDS_SEC" "1"
					( Origin gPackager )
				)
				( attribute "LOCATION" "C5A11"
					( Origin gFrontEnd )
				)
				( attribute "MATERIAL" "X5R"
					( Origin gFrontEnd )
				)
				( attribute "PACK_TYPE" "0603V"
					( Origin gFrontEnd )
				)
				( attribute "PART_NUMBER" "602433-106"
					( Origin gFrontEnd )
				)
				( attribute "PHYS_PAGE" "220"
					( Origin gFrontEnd )
				)
				( attribute "ROT" "0"
					( Origin gFrontEnd )
				)
				( attribute "SEC" "1"
					( Origin gFrontEnd )
				)
				( attribute "SEC_TYPE" "0603V"
					( Origin gFrontEnd )
				)
				( attribute "TOLERANCE" "20%"
					( Origin gFrontEnd )
				)
				( attribute "VALUE" "47UF"
					( Origin gFrontEnd )
				)
				( attribute "VER" "1"
					( Origin gFrontEnd )
				)
				( attribute "VOLTAGE" "4V"
					( Units "uVoltage" "V" 1.000000)
					( Origin gFrontEnd )
				)
				( attribute "XY" "(2225,-650)"
					( Origin gFrontEnd )
				)
				( attribute "CHIPS_PART_NAME" "CAP_A"
					( Origin gPackager )
				)
				( attribute "CDS_PART_NAME" "CAP_A_0603V-47UF,4V,20%,X5R,60A"
					( Origin gPackager )
				)
				( attribute "GROUP" "PWR_MLCC_CAP"
					( Origin gFrontEnd )
				)
				( attribute "BOM_SS" "E15431-004"
					( Origin gFrontEnd )
				)
				( objectStatus "C5A11" )
			)
			( gate "@baseboard_fab2_lib.baseboard_fab2(sch_1):page220_i292"
				( attribute "CDS_LIB" "dev_discrete"
					( Origin gPackager )
				)
				( attribute "CDS_LOCATION" "C4M2"
					( Origin gPackager )
				)
				( attribute "CDS_SEC" "1"
					( Origin gPackager )
				)
				( attribute "LOCATION" "C4M2"
					( Origin gFrontEnd )
				)
				( attribute "MATERIAL" "X5R"
					( Origin gFrontEnd )
				)
				( attribute "PACK_TYPE" "0603V"
					( Origin gFrontEnd )
				)
				( attribute "PART_NUMBER" "602433-106"
					( Origin gFrontEnd )
				)
				( attribute "PHYS_PAGE" "220"
					( Origin gFrontEnd )
				)
				( attribute "ROT" "0"
					( Origin gFrontEnd )
				)
				( attribute "SEC" "1"
					( Origin gFrontEnd )
				)
				( attribute "SEC_TYPE" "0603V"
					( Origin gFrontEnd )
				)
				( attribute "TOLERANCE" "20%"
					( Origin gFrontEnd )
				)
				( attribute "VALUE" "47UF"
					( Origin gFrontEnd )
				)
				( attribute "VER" "1"
					( Origin gFrontEnd )
				)
				( attribute "VOLTAGE" "4V"
					( Units "uVoltage" "V" 1.000000)
					( Origin gFrontEnd )
				)
				( attribute "XY" "(1950,-650)"
					( Origin gFrontEnd )
				)
				( attribute "CHIPS_PART_NAME" "CAP_A"
					( Origin gPackager )
				)
				( attribute "CDS_PART_NAME" "CAP_A_0603V-47UF,4V,20%,X5R,60A"
					( Origin gPackager )
				)
				( attribute "GROUP" "PWR_MLCC_CAP"
					( Origin gFrontEnd )
				)
				( attribute "BOM_SS" "E15431-004"
					( Origin gFrontEnd )
				)
				( objectStatus "C4M2" )
			)
			( gate "@baseboard_fab2_lib.baseboard_fab2(sch_1):page220_i291"
				( attribute "CDS_LIB" "dev_discrete"
					( Origin gPackager )
				)
				( attribute "CDS_LOCATION" "C5M1"
					( Origin gPackager )
				)
				( attribute "CDS_SEC" "1"
					( Origin gPackager )
				)
				( attribute "LOCATION" "C5M1"
					( Origin gFrontEnd )
				)
				( attribute "MATERIAL" "X5R"
					( Origin gFrontEnd )
				)
				( attribute "PACK_TYPE" "0603V"
					( Origin gFrontEnd )
				)
				( attribute "PART_NUMBER" "602433-106"
					( Origin gFrontEnd )
				)
				( attribute "PHYS_PAGE" "220"
					( Origin gFrontEnd )
				)
				( attribute "ROT" "0"
					( Origin gFrontEnd )
				)
				( attribute "SEC" "1"
					( Origin gFrontEnd )
				)
				( attribute "SEC_TYPE" "0603V"
					( Origin gFrontEnd )
				)
				( attribute "TOLERANCE" "20%"
					( Origin gFrontEnd )
				)
				( attribute "VALUE" "47UF"
					( Origin gFrontEnd )
				)
				( attribute "VER" "1"
					( Origin gFrontEnd )
				)
				( attribute "VOLTAGE" "4V"
					( Units "uVoltage" "V" 1.000000)
					( Origin gFrontEnd )
				)
				( attribute "XY" "(1650,-650)"
					( Origin gFrontEnd )
				)
				( attribute "CHIPS_PART_NAME" "CAP_A"
					( Origin gPackager )
				)
				( attribute "CDS_PART_NAME" "CAP_A_0603V-47UF,4V,20%,X5R,60A"
					( Origin gPackager )
				)
				( attribute "GROUP" "PWR_MLCC_CAP"
					( Origin gFrontEnd )
				)
				( attribute "BOM_SS" "E15431-004"
					( Origin gFrontEnd )
				)
				( objectStatus "C5M1" )
			)
			( gate "@baseboard_fab2_lib.baseboard_fab2(sch_1):page220_i290"
				( attribute "CDS_LIB" "dev_discrete"
					( Origin gPackager )
				)
				( attribute "CDS_LOCATION" "C5M2"
					( Origin gPackager )
				)
				( attribute "CDS_SEC" "1"
					( Origin gPackager )
				)
				( attribute "LOCATION" "C5M2"
					( Origin gFrontEnd )
				)
				( attribute "MATERIAL" "X5R"
					( Origin gFrontEnd )
				)
				( attribute "PACK_TYPE" "0603V"
					( Origin gFrontEnd )
				)
				( attribute "PART_NUMBER" "602433-106"
					( Origin gFrontEnd )
				)
				( attribute "PHYS_PAGE" "220"
					( Origin gFrontEnd )
				)
				( attribute "ROT" "0"
					( Origin gFrontEnd )
				)
				( attribute "SEC" "1"
					( Origin gFrontEnd )
				)
				( attribute "SEC_TYPE" "0603V"
					( Origin gFrontEnd )
				)
				( attribute "TOLERANCE" "20%"
					( Origin gFrontEnd )
				)
				( attribute "VALUE" "47UF"
					( Origin gFrontEnd )
				)
				( attribute "VER" "1"
					( Origin gFrontEnd )
				)
				( attribute "VOLTAGE" "4V"
					( Units "uVoltage" "V" 1.000000)
					( Origin gFrontEnd )
				)
				( attribute "XY" "(1350,-650)"
					( Origin gFrontEnd )
				)
				( attribute "CHIPS_PART_NAME" "CAP_A"
					( Origin gPackager )
				)
				( attribute "CDS_PART_NAME" "CAP_A_0603V-47UF,4V,20%,X5R,60A"
					( Origin gPackager )
				)
				( attribute "GROUP" "PWR_MLCC_CAP"
					( Origin gFrontEnd )
				)
				( attribute "BOM_SS" "E15431-004"
					( Origin gFrontEnd )
				)
				( objectStatus "C5M2" )
			)
			( gate "@baseboard_fab2_lib.baseboard_fab2(sch_1):page220_i289"
				( attribute "CDS_LIB" "dev_discrete"
					( Origin gPackager )
				)
				( attribute "CDS_LOCATION" "C5M4"
					( Origin gPackager )
				)
				( attribute "CDS_SEC" "1"
					( Origin gPackager )
				)
				( attribute "LOCATION" "C5M4"
					( Origin gFrontEnd )
				)
				( attribute "MATERIAL" "X5R"
					( Origin gFrontEnd )
				)
				( attribute "PACK_TYPE" "0603V"
					( Origin gFrontEnd )
				)
				( attribute "PART_NUMBER" "602433-106"
					( Origin gFrontEnd )
				)
				( attribute "PHYS_PAGE" "220"
					( Origin gFrontEnd )
				)
				( attribute "ROT" "0"
					( Origin gFrontEnd )
				)
				( attribute "SEC" "1"
					( Origin gFrontEnd )
				)
				( attribute "SEC_TYPE" "0603V"
					( Origin gFrontEnd )
				)
				( attribute "TOLERANCE" "20%"
					( Origin gFrontEnd )
				)
				( attribute "VALUE" "47UF"
					( Origin gFrontEnd )
				)
				( attribute "VER" "1"
					( Origin gFrontEnd )
				)
				( attribute "VOLTAGE" "4V"
					( Units "uVoltage" "V" 1.000000)
					( Origin gFrontEnd )
				)
				( attribute "XY" "(1075,-650)"
					( Origin gFrontEnd )
				)
				( attribute "CHIPS_PART_NAME" "CAP_A"
					( Origin gPackager )
				)
				( attribute "CDS_PART_NAME" "CAP_A_0603V-47UF,4V,20%,X5R,60A"
					( Origin gPackager )
				)
				( attribute "GROUP" "PWR_MLCC_CAP"
					( Origin gFrontEnd )
				)
				( attribute "BOM_SS" "E15431-004"
					( Origin gFrontEnd )
				)
				( objectStatus "C5M4" )
			)
			( gate "@baseboard_fab2_lib.baseboard_fab2(sch_1):page220_i288"
				( attribute "CDS_LIB" "dev_discrete"
					( Origin gPackager )
				)
				( attribute "CDS_LOCATION" "C5M5"
					( Origin gPackager )
				)
				( attribute "CDS_SEC" "1"
					( Origin gPackager )
				)
				( attribute "LOCATION" "C5M5"
					( Origin gFrontEnd )
				)
				( attribute "MATERIAL" "X5R"
					( Origin gFrontEnd )
				)
				( attribute "PACK_TYPE" "0603V"
					( Origin gFrontEnd )
				)
				( attribute "PART_NUMBER" "602433-106"
					( Origin gFrontEnd )
				)
				( attribute "PHYS_PAGE" "220"
					( Origin gFrontEnd )
				)
				( attribute "ROT" "0"
					( Origin gFrontEnd )
				)
				( attribute "SEC" "1"
					( Origin gFrontEnd )
				)
				( attribute "SEC_TYPE" "0603V"
					( Origin gFrontEnd )
				)
				( attribute "TOLERANCE" "20%"
					( Origin gFrontEnd )
				)
				( attribute "VALUE" "47UF"
					( Origin gFrontEnd )
				)
				( attribute "VER" "1"
					( Origin gFrontEnd )
				)
				( attribute "VOLTAGE" "4V"
					( Units "uVoltage" "V" 1.000000)
					( Origin gFrontEnd )
				)
				( attribute "XY" "(800,-650)"
					( Origin gFrontEnd )
				)
				( attribute "CHIPS_PART_NAME" "CAP_A"
					( Origin gPackager )
				)
				( attribute "CDS_PART_NAME" "CAP_A_0603V-47UF,4V,20%,X5R,60A"
					( Origin gPackager )
				)
				( attribute "GROUP" "PWR_MLCC_CAP"
					( Origin gFrontEnd )
				)
				( attribute "BOM_SS" "E15431-004"
					( Origin gFrontEnd )
				)
				( objectStatus "C5M5" )
			)
			( gate "@baseboard_fab2_lib.baseboard_fab2(sch_1):page220_i287"
				( attribute "CDS_LIB" "dev_discrete"
					( Origin gPackager )
				)
				( attribute "CDS_LOCATION" "C5M6"
					( Origin gPackager )
				)
				( attribute "CDS_SEC" "1"
					( Origin gPackager )
				)
				( attribute "LOCATION" "C5M6"
					( Origin gFrontEnd )
				)
				( attribute "MATERIAL" "X5R"
					( Origin gFrontEnd )
				)
				( attribute "PACK_TYPE" "0603V"
					( Origin gFrontEnd )
				)
				( attribute "PART_NUMBER" "602433-106"
					( Origin gFrontEnd )
				)
				( attribute "PHYS_PAGE" "220"
					( Origin gFrontEnd )
				)
				( attribute "ROT" "0"
					( Origin gFrontEnd )
				)
				( attribute "SEC" "1"
					( Origin gFrontEnd )
				)
				( attribute "SEC_TYPE" "0603V"
					( Origin gFrontEnd )
				)
				( attribute "TOLERANCE" "20%"
					( Origin gFrontEnd )
				)
				( attribute "VALUE" "47UF"
					( Origin gFrontEnd )
				)
				( attribute "VER" "1"
					( Origin gFrontEnd )
				)
				( attribute "VOLTAGE" "4V"
					( Units "uVoltage" "V" 1.000000)
					( Origin gFrontEnd )
				)
				( attribute "XY" "(500,-650)"
					( Origin gFrontEnd )
				)
				( attribute "CHIPS_PART_NAME" "CAP_A"
					( Origin gPackager )
				)
				( attribute "CDS_PART_NAME" "CAP_A_0603V-47UF,4V,20%,X5R,60A"
					( Origin gPackager )
				)
				( attribute "GROUP" "PWR_MLCC_CAP"
					( Origin gFrontEnd )
				)
				( attribute "BOM_SS" "E15431-004"
					( Origin gFrontEnd )
				)
				( objectStatus "C5M6" )
			)
			( gate "@baseboard_fab2_lib.baseboard_fab2(sch_1):page220_i286"
				( attribute "CDS_LIB" "dev_discrete"
					( Origin gPackager )
				)
				( attribute "CDS_LOCATION" "C5M7"
					( Origin gPackager )
				)
				( attribute "CDS_SEC" "1"
					( Origin gPackager )
				)
				( attribute "LOCATION" "C5M7"
					( Origin gFrontEnd )
				)
				( attribute "MATERIAL" "X5R"
					( Origin gFrontEnd )
				)
				( attribute "PACK_TYPE" "0603V"
					( Origin gFrontEnd )
				)
				( attribute "PART_NUMBER" "602433-106"
					( Origin gFrontEnd )
				)
				( attribute "PHYS_PAGE" "220"
					( Origin gFrontEnd )
				)
				( attribute "ROT" "0"
					( Origin gFrontEnd )
				)
				( attribute "SEC" "1"
					( Origin gFrontEnd )
				)
				( attribute "SEC_TYPE" "0603V"
					( Origin gFrontEnd )
				)
				( attribute "TOLERANCE" "20%"
					( Origin gFrontEnd )
				)
				( attribute "VALUE" "47UF"
					( Origin gFrontEnd )
				)
				( attribute "VER" "1"
					( Origin gFrontEnd )
				)
				( attribute "VOLTAGE" "4V"
					( Units "uVoltage" "V" 1.000000)
					( Origin gFrontEnd )
				)
				( attribute "XY" "(200,-650)"
					( Origin gFrontEnd )
				)
				( attribute "CHIPS_PART_NAME" "CAP_A"
					( Origin gPackager )
				)
				( attribute "CDS_PART_NAME" "CAP_A_0603V-47UF,4V,20%,X5R,60A"
					( Origin gPackager )
				)
				( attribute "GROUP" "PWR_MLCC_CAP"
					( Origin gFrontEnd )
				)
				( attribute "BOM_SS" "E15431-004"
					( Origin gFrontEnd )
				)
				( objectStatus "C5M7" )
			)
			( gate "@baseboard_fab2_lib.baseboard_fab2(sch_1):page220_i285"
				( attribute "CDS_LIB" "dev_discrete"
					( Origin gPackager )
				)
				( attribute "CDS_LOCATION" "C5L13"
					( Origin gPackager )
				)
				( attribute "CDS_SEC" "1"
					( Origin gPackager )
				)
				( attribute "LOCATION" "C5L13"
					( Origin gFrontEnd )
				)
				( attribute "MATERIAL" "X5R"
					( Origin gFrontEnd )
				)
				( attribute "PACK_TYPE" "0603V"
					( Origin gFrontEnd )
				)
				( attribute "PART_NUMBER" "602433-106"
					( Origin gFrontEnd )
				)
				( attribute "PHYS_PAGE" "220"
					( Origin gFrontEnd )
				)
				( attribute "ROT" "0"
					( Origin gFrontEnd )
				)
				( attribute "SEC" "1"
					( Origin gFrontEnd )
				)
				( attribute "SEC_TYPE" "0603V"
					( Origin gFrontEnd )
				)
				( attribute "TOLERANCE" "20%"
					( Origin gFrontEnd )
				)
				( attribute "VALUE" "47UF"
					( Origin gFrontEnd )
				)
				( attribute "VER" "1"
					( Origin gFrontEnd )
				)
				( attribute "VOLTAGE" "4V"
					( Units "uVoltage" "V" 1.000000)
					( Origin gFrontEnd )
				)
				( attribute "XY" "(-125,-650)"
					( Origin gFrontEnd )
				)
				( attribute "CHIPS_PART_NAME" "CAP_A"
					( Origin gPackager )
				)
				( attribute "CDS_PART_NAME" "CAP_A_0603V-47UF,4V,20%,X5R,60A"
					( Origin gPackager )
				)
				( attribute "GROUP" "PWR_MLCC_CAP"
					( Origin gFrontEnd )
				)
				( attribute "BOM_SS" "E15431-004"
					( Origin gFrontEnd )
				)
				( objectStatus "C5L13" )
			)
			( gate "@baseboard_fab2_lib.baseboard_fab2(sch_1):page220_i284"
				( attribute "CDS_LIB" "dev_discrete"
					( Origin gPackager )
				)
				( attribute "CDS_LOCATION" "C5L12"
					( Origin gPackager )
				)
				( attribute "CDS_SEC" "1"
					( Origin gPackager )
				)
				( attribute "LOCATION" "C5L12"
					( Origin gFrontEnd )
				)
				( attribute "MATERIAL" "X5R"
					( Origin gFrontEnd )
				)
				( attribute "PACK_TYPE" "0603V"
					( Origin gFrontEnd )
				)
				( attribute "PART_NUMBER" "602433-106"
					( Origin gFrontEnd )
				)
				( attribute "PHYS_PAGE" "220"
					( Origin gFrontEnd )
				)
				( attribute "ROT" "0"
					( Origin gFrontEnd )
				)
				( attribute "SEC" "1"
					( Origin gFrontEnd )
				)
				( attribute "SEC_TYPE" "0603V"
					( Origin gFrontEnd )
				)
				( attribute "TOLERANCE" "20%"
					( Origin gFrontEnd )
				)
				( attribute "VALUE" "47UF"
					( Origin gFrontEnd )
				)
				( attribute "VER" "1"
					( Origin gFrontEnd )
				)
				( attribute "VOLTAGE" "4V"
					( Units "uVoltage" "V" 1.000000)
					( Origin gFrontEnd )
				)
				( attribute "XY" "(-400,-650)"
					( Origin gFrontEnd )
				)
				( attribute "CHIPS_PART_NAME" "CAP_A"
					( Origin gPackager )
				)
				( attribute "CDS_PART_NAME" "CAP_A_0603V-47UF,4V,20%,X5R,60A"
					( Origin gPackager )
				)
				( attribute "GROUP" "PWR_MLCC_CAP"
					( Origin gFrontEnd )
				)
				( attribute "BOM_SS" "E15431-004"
					( Origin gFrontEnd )
				)
				( objectStatus "C5L12" )
			)
			( gate "@baseboard_fab2_lib.baseboard_fab2(sch_1):page220_i283"
				( attribute "CDS_LIB" "dev_discrete"
					( Origin gPackager )
				)
				( attribute "CDS_LOCATION" "C5L11"
					( Origin gPackager )
				)
				( attribute "CDS_SEC" "1"
					( Origin gPackager )
				)
				( attribute "LOCATION" "C5L11"
					( Origin gFrontEnd )
				)
				( attribute "MATERIAL" "X5R"
					( Origin gFrontEnd )
				)
				( attribute "PACK_TYPE" "0603V"
					( Origin gFrontEnd )
				)
				( attribute "PART_NUMBER" "602433-106"
					( Origin gFrontEnd )
				)
				( attribute "PHYS_PAGE" "220"
					( Origin gFrontEnd )
				)
				( attribute "ROT" "0"
					( Origin gFrontEnd )
				)
				( attribute "SEC" "1"
					( Origin gFrontEnd )
				)
				( attribute "SEC_TYPE" "0603V"
					( Origin gFrontEnd )
				)
				( attribute "TOLERANCE" "20%"
					( Origin gFrontEnd )
				)
				( attribute "VALUE" "47UF"
					( Origin gFrontEnd )
				)
				( attribute "VER" "1"
					( Origin gFrontEnd )
				)
				( attribute "VOLTAGE" "4V"
					( Units "uVoltage" "V" 1.000000)
					( Origin gFrontEnd )
				)
				( attribute "XY" "(-700,-650)"
					( Origin gFrontEnd )
				)
				( attribute "CHIPS_PART_NAME" "CAP_A"
					( Origin gPackager )
				)
				( attribute "CDS_PART_NAME" "CAP_A_0603V-47UF,4V,20%,X5R,60A"
					( Origin gPackager )
				)
				( attribute "GROUP" "PWR_MLCC_CAP"
					( Origin gFrontEnd )
				)
				( attribute "BOM_SS" "E15431-004"
					( Origin gFrontEnd )
				)
				( objectStatus "C5L11" )
			)
			( gate "@baseboard_fab2_lib.baseboard_fab2(sch_1):page220_i282"
				( attribute "CDS_LIB" "dev_discrete"
					( Origin gPackager )
				)
				( attribute "CDS_LOCATION" "C5L10"
					( Origin gPackager )
				)
				( attribute "CDS_SEC" "1"
					( Origin gPackager )
				)
				( attribute "LOCATION" "C5L10"
					( Origin gFrontEnd )
				)
				( attribute "MATERIAL" "X5R"
					( Origin gFrontEnd )
				)
				( attribute "PACK_TYPE" "0603V"
					( Origin gFrontEnd )
				)
				( attribute "PART_NUMBER" "602433-106"
					( Origin gFrontEnd )
				)
				( attribute "PHYS_PAGE" "220"
					( Origin gFrontEnd )
				)
				( attribute "ROT" "0"
					( Origin gFrontEnd )
				)
				( attribute "SEC" "1"
					( Origin gFrontEnd )
				)
				( attribute "SEC_TYPE" "0603V"
					( Origin gFrontEnd )
				)
				( attribute "TOLERANCE" "20%"
					( Origin gFrontEnd )
				)
				( attribute "VALUE" "47UF"
					( Origin gFrontEnd )
				)
				( attribute "VER" "1"
					( Origin gFrontEnd )
				)
				( attribute "VOLTAGE" "4V"
					( Units "uVoltage" "V" 1.000000)
					( Origin gFrontEnd )
				)
				( attribute "XY" "(-1000,-650)"
					( Origin gFrontEnd )
				)
				( attribute "CHIPS_PART_NAME" "CAP_A"
					( Origin gPackager )
				)
				( attribute "CDS_PART_NAME" "CAP_A_0603V-47UF,4V,20%,X5R,60A"
					( Origin gPackager )
				)
				( attribute "GROUP" "PWR_MLCC_CAP"
					( Origin gFrontEnd )
				)
				( attribute "BOM_SS" "E15431-004"
					( Origin gFrontEnd )
				)
				( objectStatus "C5L10" )
			)
			( gate "@baseboard_fab2_lib.baseboard_fab2(sch_1):page220_i281"
				( attribute "CDS_LIB" "dev_discrete"
					( Origin gPackager )
				)
				( attribute "CDS_LOCATION" "C5L9"
					( Origin gPackager )
				)
				( attribute "CDS_SEC" "1"
					( Origin gPackager )
				)
				( attribute "LOCATION" "C5L9"
					( Origin gFrontEnd )
				)
				( attribute "MATERIAL" "X5R"
					( Origin gFrontEnd )
				)
				( attribute "PACK_TYPE" "0603V"
					( Origin gFrontEnd )
				)
				( attribute "PART_NUMBER" "602433-106"
					( Origin gFrontEnd )
				)
				( attribute "PHYS_PAGE" "220"
					( Origin gFrontEnd )
				)
				( attribute "ROT" "0"
					( Origin gFrontEnd )
				)
				( attribute "SEC" "1"
					( Origin gFrontEnd )
				)
				( attribute "SEC_TYPE" "0603V"
					( Origin gFrontEnd )
				)
				( attribute "TOLERANCE" "20%"
					( Origin gFrontEnd )
				)
				( attribute "VALUE" "47UF"
					( Origin gFrontEnd )
				)
				( attribute "VER" "1"
					( Origin gFrontEnd )
				)
				( attribute "VOLTAGE" "4V"
					( Units "uVoltage" "V" 1.000000)
					( Origin gFrontEnd )
				)
				( attribute "XY" "(-1275,-650)"
					( Origin gFrontEnd )
				)
				( attribute "CHIPS_PART_NAME" "CAP_A"
					( Origin gPackager )
				)
				( attribute "CDS_PART_NAME" "CAP_A_0603V-47UF,4V,20%,X5R,60A"
					( Origin gPackager )
				)
				( attribute "GROUP" "PWR_MLCC_CAP"
					( Origin gFrontEnd )
				)
				( attribute "BOM_SS" "E15431-004"
					( Origin gFrontEnd )
				)
				( objectStatus "C5L9" )
			)
			( gate "@baseboard_fab2_lib.baseboard_fab2(sch_1):page220_i280"
				( attribute "CDS_LIB" "dev_discrete"
					( Origin gPackager )
				)
				( attribute "CDS_LOCATION" "C5L8"
					( Origin gPackager )
				)
				( attribute "CDS_SEC" "1"
					( Origin gPackager )
				)
				( attribute "LOCATION" "C5L8"
					( Origin gFrontEnd )
				)
				( attribute "MATERIAL" "X5R"
					( Origin gFrontEnd )
				)
				( attribute "PACK_TYPE" "0603V"
					( Origin gFrontEnd )
				)
				( attribute "PART_NUMBER" "602433-106"
					( Origin gFrontEnd )
				)
				( attribute "PHYS_PAGE" "220"
					( Origin gFrontEnd )
				)
				( attribute "ROT" "0"
					( Origin gFrontEnd )
				)
				( attribute "SEC" "1"
					( Origin gFrontEnd )
				)
				( attribute "SEC_TYPE" "0603V"
					( Origin gFrontEnd )
				)
				( attribute "TOLERANCE" "20%"
					( Origin gFrontEnd )
				)
				( attribute "VALUE" "47UF"
					( Origin gFrontEnd )
				)
				( attribute "VER" "1"
					( Origin gFrontEnd )
				)
				( attribute "VOLTAGE" "4V"
					( Units "uVoltage" "V" 1.000000)
					( Origin gFrontEnd )
				)
				( attribute "XY" "(-1550,-650)"
					( Origin gFrontEnd )
				)
				( attribute "CHIPS_PART_NAME" "CAP_A"
					( Origin gPackager )
				)
				( attribute "CDS_PART_NAME" "CAP_A_0603V-47UF,4V,20%,X5R,60A"
					( Origin gPackager )
				)
				( attribute "GROUP" "PWR_MLCC_CAP"
					( Origin gFrontEnd )
				)
				( attribute "BOM_SS" "E15431-004"
					( Origin gFrontEnd )
				)
				( objectStatus "C5L8" )
			)
			( gate "@baseboard_fab2_lib.baseboard_fab2(sch_1):page220_i279"
				( attribute "CDS_LIB" "dev_discrete"
					( Origin gPackager )
				)
				( attribute "CDS_LOCATION" "C5L7"
					( Origin gPackager )
				)
				( attribute "CDS_SEC" "1"
					( Origin gPackager )
				)
				( attribute "LOCATION" "C5L7"
					( Origin gFrontEnd )
				)
				( attribute "MATERIAL" "X5R"
					( Origin gFrontEnd )
				)
				( attribute "PACK_TYPE" "0603V"
					( Origin gFrontEnd )
				)
				( attribute "PART_NUMBER" "602433-106"
					( Origin gFrontEnd )
				)
				( attribute "PHYS_PAGE" "220"
					( Origin gFrontEnd )
				)
				( attribute "ROT" "0"
					( Origin gFrontEnd )
				)
				( attribute "SEC" "1"
					( Origin gFrontEnd )
				)
				( attribute "SEC_TYPE" "0603V"
					( Origin gFrontEnd )
				)
				( attribute "TOLERANCE" "20%"
					( Origin gFrontEnd )
				)
				( attribute "VALUE" "47UF"
					( Origin gFrontEnd )
				)
				( attribute "VER" "1"
					( Origin gFrontEnd )
				)
				( attribute "VOLTAGE" "4V"
					( Units "uVoltage" "V" 1.000000)
					( Origin gFrontEnd )
				)
				( attribute "XY" "(-1850,-650)"
					( Origin gFrontEnd )
				)
				( attribute "CHIPS_PART_NAME" "CAP_A"
					( Origin gPackager )
				)
				( attribute "CDS_PART_NAME" "CAP_A_0603V-47UF,4V,20%,X5R,60A"
					( Origin gPackager )
				)
				( attribute "GROUP" "PWR_MLCC_CAP"
					( Origin gFrontEnd )
				)
				( attribute "BOM_SS" "E15431-004"
					( Origin gFrontEnd )
				)
				( objectStatus "C5L7" )
			)
			( gate "@baseboard_fab2_lib.baseboard_fab2(sch_1):page220_i278"
				( attribute "CDS_LIB" "dev_discrete"
					( Origin gPackager )
				)
				( attribute "CDS_LOCATION" "C5L6"
					( Origin gPackager )
				)
				( attribute "CDS_SEC" "1"
					( Origin gPackager )
				)
				( attribute "LOCATION" "C5L6"
					( Origin gFrontEnd )
				)
				( attribute "MATERIAL" "X5R"
					( Origin gFrontEnd )
				)
				( attribute "PACK_TYPE" "0603V"
					( Origin gFrontEnd )
				)
				( attribute "PART_NUMBER" "602433-106"
					( Origin gFrontEnd )
				)
				( attribute "PHYS_PAGE" "220"
					( Origin gFrontEnd )
				)
				( attribute "ROT" "0"
					( Origin gFrontEnd )
				)
				( attribute "SEC" "1"
					( Origin gFrontEnd )
				)
				( attribute "SEC_TYPE" "0603V"
					( Origin gFrontEnd )
				)
				( attribute "TOLERANCE" "20%"
					( Origin gFrontEnd )
				)
				( attribute "VALUE" "47UF"
					( Origin gFrontEnd )
				)
				( attribute "VER" "1"
					( Origin gFrontEnd )
				)
				( attribute "VOLTAGE" "4V"
					( Units "uVoltage" "V" 1.000000)
					( Origin gFrontEnd )
				)
				( attribute "XY" "(-2150,-650)"
					( Origin gFrontEnd )
				)
				( attribute "CHIPS_PART_NAME" "CAP_A"
					( Origin gPackager )
				)
				( attribute "CDS_PART_NAME" "CAP_A_0603V-47UF,4V,20%,X5R,60A"
					( Origin gPackager )
				)
				( attribute "GROUP" "PWR_MLCC_CAP"
					( Origin gFrontEnd )
				)
				( attribute "BOM_SS" "E15431-004"
					( Origin gFrontEnd )
				)
				( objectStatus "C5L6" )
			)
			( gate "@baseboard_fab2_lib.baseboard_fab2(sch_1):page225_i287"
				( attribute "CDS_LIB" "dev_discrete"
					( Origin gPackager )
				)
				( attribute "CDS_LOCATION" "C2G14"
					( Origin gPackager )
				)
				( attribute "CDS_SEC" "1"
					( Origin gPackager )
				)
				( attribute "LOCATION" "C2G14"
					( Origin gFrontEnd )
				)
				( attribute "MATERIAL" "X5R"
					( Origin gFrontEnd )
				)
				( attribute "PACK_TYPE" "0603V"
					( Origin gFrontEnd )
				)
				( attribute "PART_NUMBER" "602433-106"
					( Origin gFrontEnd )
				)
				( attribute "PHYS_PAGE" "225"
					( Origin gFrontEnd )
				)
				( attribute "ROT" "0"
					( Origin gFrontEnd )
				)
				( attribute "SEC" "1"
					( Origin gFrontEnd )
				)
				( attribute "SEC_TYPE" "0603V"
					( Origin gFrontEnd )
				)
				( attribute "TOLERANCE" "20%"
					( Origin gFrontEnd )
				)
				( attribute "VALUE" "47UF"
					( Origin gFrontEnd )
				)
				( attribute "VER" "1"
					( Origin gFrontEnd )
				)
				( attribute "VOLTAGE" "4V"
					( Units "uVoltage" "V" 1.000000)
					( Origin gFrontEnd )
				)
				( attribute "XY" "(1525,250)"
					( Origin gFrontEnd )
				)
				( attribute "CHIPS_PART_NAME" "CAP_A"
					( Origin gPackager )
				)
				( attribute "CDS_PART_NAME" "CAP_A_0603V-47UF,4V,20%,X5R,60A"
					( Origin gPackager )
				)
				( attribute "GROUP" "PWR_MLCC_CAP"
					( Origin gFrontEnd )
				)
				( attribute "BOM_SS" "E15431-004"
					( Origin gFrontEnd )
				)
				( objectStatus "C2G14" )
			)
			( gate "@baseboard_fab2_lib.baseboard_fab2(sch_1):page225_i286"
				( attribute "CDS_LIB" "dev_discrete"
					( Origin gPackager )
				)
				( attribute "CDS_LOCATION" "C2G13"
					( Origin gPackager )
				)
				( attribute "CDS_SEC" "1"
					( Origin gPackager )
				)
				( attribute "LOCATION" "C2G13"
					( Origin gFrontEnd )
				)
				( attribute "MATERIAL" "X5R"
					( Origin gFrontEnd )
				)
				( attribute "PACK_TYPE" "0603V"
					( Origin gFrontEnd )
				)
				( attribute "PART_NUMBER" "602433-106"
					( Origin gFrontEnd )
				)
				( attribute "PHYS_PAGE" "225"
					( Origin gFrontEnd )
				)
				( attribute "ROT" "0"
					( Origin gFrontEnd )
				)
				( attribute "SEC" "1"
					( Origin gFrontEnd )
				)
				( attribute "SEC_TYPE" "0603V"
					( Origin gFrontEnd )
				)
				( attribute "TOLERANCE" "20%"
					( Origin gFrontEnd )
				)
				( attribute "VALUE" "47UF"
					( Origin gFrontEnd )
				)
				( attribute "VER" "1"
					( Origin gFrontEnd )
				)
				( attribute "VOLTAGE" "4V"
					( Units "uVoltage" "V" 1.000000)
					( Origin gFrontEnd )
				)
				( attribute "XY" "(1225,250)"
					( Origin gFrontEnd )
				)
				( attribute "CHIPS_PART_NAME" "CAP_A"
					( Origin gPackager )
				)
				( attribute "CDS_PART_NAME" "CAP_A_0603V-47UF,4V,20%,X5R,60A"
					( Origin gPackager )
				)
				( attribute "GROUP" "PWR_MLCC_CAP"
					( Origin gFrontEnd )
				)
				( attribute "BOM_SS" "E15431-004"
					( Origin gFrontEnd )
				)
				( objectStatus "C2G13" )
			)
			( gate "@baseboard_fab2_lib.baseboard_fab2(sch_1):page225_i285"
				( attribute "CDS_LIB" "dev_discrete"
					( Origin gPackager )
				)
				( attribute "CDS_LOCATION" "C3G2"
					( Origin gPackager )
				)
				( attribute "CDS_SEC" "1"
					( Origin gPackager )
				)
				( attribute "LOCATION" "C3G2"
					( Origin gFrontEnd )
				)
				( attribute "MATERIAL" "X5R"
					( Origin gFrontEnd )
				)
				( attribute "PACK_TYPE" "0603V"
					( Origin gFrontEnd )
				)
				( attribute "PART_NUMBER" "602433-106"
					( Origin gFrontEnd )
				)
				( attribute "PHYS_PAGE" "225"
					( Origin gFrontEnd )
				)
				( attribute "ROT" "0"
					( Origin gFrontEnd )
				)
				( attribute "SEC" "1"
					( Origin gFrontEnd )
				)
				( attribute "SEC_TYPE" "0603V"
					( Origin gFrontEnd )
				)
				( attribute "TOLERANCE" "20%"
					( Origin gFrontEnd )
				)
				( attribute "VALUE" "47UF"
					( Origin gFrontEnd )
				)
				( attribute "VER" "1"
					( Origin gFrontEnd )
				)
				( attribute "VOLTAGE" "4V"
					( Units "uVoltage" "V" 1.000000)
					( Origin gFrontEnd )
				)
				( attribute "XY" "(950,250)"
					( Origin gFrontEnd )
				)
				( attribute "CHIPS_PART_NAME" "CAP_A"
					( Origin gPackager )
				)
				( attribute "CDS_PART_NAME" "CAP_A_0603V-47UF,4V,20%,X5R,60A"
					( Origin gPackager )
				)
				( attribute "GROUP" "PWR_MLCC_CAP"
					( Origin gFrontEnd )
				)
				( attribute "BOM_SS" "E15431-004"
					( Origin gFrontEnd )
				)
				( objectStatus "C3G2" )
			)
			( gate "@baseboard_fab2_lib.baseboard_fab2(sch_1):page225_i284"
				( attribute "CDS_LIB" "dev_discrete"
					( Origin gPackager )
				)
				( attribute "CDS_LOCATION" "C3G1"
					( Origin gPackager )
				)
				( attribute "CDS_SEC" "1"
					( Origin gPackager )
				)
				( attribute "LOCATION" "C3G1"
					( Origin gFrontEnd )
				)
				( attribute "MATERIAL" "X5R"
					( Origin gFrontEnd )
				)
				( attribute "PACK_TYPE" "0603V"
					( Origin gFrontEnd )
				)
				( attribute "PART_NUMBER" "602433-106"
					( Origin gFrontEnd )
				)
				( attribute "PHYS_PAGE" "225"
					( Origin gFrontEnd )
				)
				( attribute "ROT" "0"
					( Origin gFrontEnd )
				)
				( attribute "SEC" "1"
					( Origin gFrontEnd )
				)
				( attribute "SEC_TYPE" "0603V"
					( Origin gFrontEnd )
				)
				( attribute "TOLERANCE" "20%"
					( Origin gFrontEnd )
				)
				( attribute "VALUE" "47UF"
					( Origin gFrontEnd )
				)
				( attribute "VER" "1"
					( Origin gFrontEnd )
				)
				( attribute "VOLTAGE" "4V"
					( Units "uVoltage" "V" 1.000000)
					( Origin gFrontEnd )
				)
				( attribute "XY" "(675,250)"
					( Origin gFrontEnd )
				)
				( attribute "CHIPS_PART_NAME" "CAP_A"
					( Origin gPackager )
				)
				( attribute "CDS_PART_NAME" "CAP_A_0603V-47UF,4V,20%,X5R,60A"
					( Origin gPackager )
				)
				( attribute "GROUP" "PWR_MLCC_CAP"
					( Origin gFrontEnd )
				)
				( attribute "BOM_SS" "E15431-004"
					( Origin gFrontEnd )
				)
				( objectStatus "C3G1" )
			)
			( gate "@baseboard_fab2_lib.baseboard_fab2(sch_1):page225_i283"
				( attribute "CDS_LIB" "dev_discrete"
					( Origin gPackager )
				)
				( attribute "CDS_LOCATION" "C2G6"
					( Origin gPackager )
				)
				( attribute "CDS_SEC" "1"
					( Origin gPackager )
				)
				( attribute "LOCATION" "C2G6"
					( Origin gFrontEnd )
				)
				( attribute "MATERIAL" "X5R"
					( Origin gFrontEnd )
				)
				( attribute "PACK_TYPE" "0603V"
					( Origin gFrontEnd )
				)
				( attribute "PART_NUMBER" "602433-106"
					( Origin gFrontEnd )
				)
				( attribute "PHYS_PAGE" "225"
					( Origin gFrontEnd )
				)
				( attribute "ROT" "0"
					( Origin gFrontEnd )
				)
				( attribute "SEC" "1"
					( Origin gFrontEnd )
				)
				( attribute "SEC_TYPE" "0603V"
					( Origin gFrontEnd )
				)
				( attribute "TOLERANCE" "20%"
					( Origin gFrontEnd )
				)
				( attribute "VALUE" "47UF"
					( Origin gFrontEnd )
				)
				( attribute "VER" "1"
					( Origin gFrontEnd )
				)
				( attribute "VOLTAGE" "4V"
					( Units "uVoltage" "V" 1.000000)
					( Origin gFrontEnd )
				)
				( attribute "XY" "(375,250)"
					( Origin gFrontEnd )
				)
				( attribute "CHIPS_PART_NAME" "CAP_A"
					( Origin gPackager )
				)
				( attribute "CDS_PART_NAME" "CAP_A_0603V-47UF,4V,20%,X5R,60A"
					( Origin gPackager )
				)
				( attribute "GROUP" "PWR_MLCC_CAP"
					( Origin gFrontEnd )
				)
				( attribute "BOM_SS" "E15431-004"
					( Origin gFrontEnd )
				)
				( objectStatus "C2G6" )
			)
			( gate "@baseboard_fab2_lib.baseboard_fab2(sch_1):page225_i282"
				( attribute "CDS_LIB" "dev_discrete"
					( Origin gPackager )
				)
				( attribute "CDS_LOCATION" "C2G5"
					( Origin gPackager )
				)
				( attribute "CDS_SEC" "1"
					( Origin gPackager )
				)
				( attribute "LOCATION" "C2G5"
					( Origin gFrontEnd )
				)
				( attribute "MATERIAL" "X5R"
					( Origin gFrontEnd )
				)
				( attribute "PACK_TYPE" "0603V"
					( Origin gFrontEnd )
				)
				( attribute "PART_NUMBER" "602433-106"
					( Origin gFrontEnd )
				)
				( attribute "PHYS_PAGE" "225"
					( Origin gFrontEnd )
				)
				( attribute "ROT" "0"
					( Origin gFrontEnd )
				)
				( attribute "SEC" "1"
					( Origin gFrontEnd )
				)
				( attribute "SEC_TYPE" "0603V"
					( Origin gFrontEnd )
				)
				( attribute "TOLERANCE" "20%"
					( Origin gFrontEnd )
				)
				( attribute "VALUE" "47UF"
					( Origin gFrontEnd )
				)
				( attribute "VER" "1"
					( Origin gFrontEnd )
				)
				( attribute "VOLTAGE" "4V"
					( Units "uVoltage" "V" 1.000000)
					( Origin gFrontEnd )
				)
				( attribute "XY" "(75,250)"
					( Origin gFrontEnd )
				)
				( attribute "CHIPS_PART_NAME" "CAP_A"
					( Origin gPackager )
				)
				( attribute "CDS_PART_NAME" "CAP_A_0603V-47UF,4V,20%,X5R,60A"
					( Origin gPackager )
				)
				( attribute "GROUP" "PWR_MLCC_CAP"
					( Origin gFrontEnd )
				)
				( attribute "BOM_SS" "E15431-004"
					( Origin gFrontEnd )
				)
				( objectStatus "C2G5" )
			)
			( gate "@baseboard_fab2_lib.baseboard_fab2(sch_1):page225_i281"
				( attribute "CDS_LIB" "dev_discrete"
					( Origin gPackager )
				)
				( attribute "CDS_LOCATION" "C2G4"
					( Origin gPackager )
				)
				( attribute "CDS_SEC" "1"
					( Origin gPackager )
				)
				( attribute "LOCATION" "C2G4"
					( Origin gFrontEnd )
				)
				( attribute "MATERIAL" "X5R"
					( Origin gFrontEnd )
				)
				( attribute "PACK_TYPE" "0603V"
					( Origin gFrontEnd )
				)
				( attribute "PART_NUMBER" "602433-106"
					( Origin gFrontEnd )
				)
				( attribute "PHYS_PAGE" "225"
					( Origin gFrontEnd )
				)
				( attribute "ROT" "0"
					( Origin gFrontEnd )
				)
				( attribute "SEC" "1"
					( Origin gFrontEnd )
				)
				( attribute "SEC_TYPE" "0603V"
					( Origin gFrontEnd )
				)
				( attribute "TOLERANCE" "20%"
					( Origin gFrontEnd )
				)
				( attribute "VALUE" "47UF"
					( Origin gFrontEnd )
				)
				( attribute "VER" "1"
					( Origin gFrontEnd )
				)
				( attribute "VOLTAGE" "4V"
					( Units "uVoltage" "V" 1.000000)
					( Origin gFrontEnd )
				)
				( attribute "XY" "(-250,250)"
					( Origin gFrontEnd )
				)
				( attribute "CHIPS_PART_NAME" "CAP_A"
					( Origin gPackager )
				)
				( attribute "CDS_PART_NAME" "CAP_A_0603V-47UF,4V,20%,X5R,60A"
					( Origin gPackager )
				)
				( attribute "GROUP" "PWR_MLCC_CAP"
					( Origin gFrontEnd )
				)
				( attribute "BOM_SS" "E15431-004"
					( Origin gFrontEnd )
				)
				( objectStatus "C2G4" )
			)
			( gate "@baseboard_fab2_lib.baseboard_fab2(sch_1):page225_i280"
				( attribute "CDS_LIB" "dev_discrete"
					( Origin gPackager )
				)
				( attribute "CDS_LOCATION" "C2G3"
					( Origin gPackager )
				)
				( attribute "CDS_SEC" "1"
					( Origin gPackager )
				)
				( attribute "LOCATION" "C2G3"
					( Origin gFrontEnd )
				)
				( attribute "MATERIAL" "X5R"
					( Origin gFrontEnd )
				)
				( attribute "PACK_TYPE" "0603V"
					( Origin gFrontEnd )
				)
				( attribute "PART_NUMBER" "602433-106"
					( Origin gFrontEnd )
				)
				( attribute "PHYS_PAGE" "225"
					( Origin gFrontEnd )
				)
				( attribute "ROT" "0"
					( Origin gFrontEnd )
				)
				( attribute "SEC" "1"
					( Origin gFrontEnd )
				)
				( attribute "SEC_TYPE" "0603V"
					( Origin gFrontEnd )
				)
				( attribute "TOLERANCE" "20%"
					( Origin gFrontEnd )
				)
				( attribute "VALUE" "47UF"
					( Origin gFrontEnd )
				)
				( attribute "VER" "1"
					( Origin gFrontEnd )
				)
				( attribute "VOLTAGE" "4V"
					( Units "uVoltage" "V" 1.000000)
					( Origin gFrontEnd )
				)
				( attribute "XY" "(-525,250)"
					( Origin gFrontEnd )
				)
				( attribute "CHIPS_PART_NAME" "CAP_A"
					( Origin gPackager )
				)
				( attribute "CDS_PART_NAME" "CAP_A_0603V-47UF,4V,20%,X5R,60A"
					( Origin gPackager )
				)
				( attribute "GROUP" "PWR_MLCC_CAP"
					( Origin gFrontEnd )
				)
				( attribute "BOM_SS" "E15431-004"
					( Origin gFrontEnd )
				)
				( objectStatus "C2G3" )
			)
			( gate "@baseboard_fab2_lib.baseboard_fab2(sch_1):page225_i279"
				( attribute "CDS_LIB" "dev_discrete"
					( Origin gPackager )
				)
				( attribute "CDS_LOCATION" "C2G2"
					( Origin gPackager )
				)
				( attribute "CDS_SEC" "1"
					( Origin gPackager )
				)
				( attribute "LOCATION" "C2G2"
					( Origin gFrontEnd )
				)
				( attribute "MATERIAL" "X5R"
					( Origin gFrontEnd )
				)
				( attribute "PACK_TYPE" "0603V"
					( Origin gFrontEnd )
				)
				( attribute "PART_NUMBER" "602433-106"
					( Origin gFrontEnd )
				)
				( attribute "PHYS_PAGE" "225"
					( Origin gFrontEnd )
				)
				( attribute "ROT" "0"
					( Origin gFrontEnd )
				)
				( attribute "SEC" "1"
					( Origin gFrontEnd )
				)
				( attribute "SEC_TYPE" "0603V"
					( Origin gFrontEnd )
				)
				( attribute "TOLERANCE" "20%"
					( Origin gFrontEnd )
				)
				( attribute "VALUE" "47UF"
					( Origin gFrontEnd )
				)
				( attribute "VER" "1"
					( Origin gFrontEnd )
				)
				( attribute "VOLTAGE" "4V"
					( Units "uVoltage" "V" 1.000000)
					( Origin gFrontEnd )
				)
				( attribute "XY" "(-825,250)"
					( Origin gFrontEnd )
				)
				( attribute "CHIPS_PART_NAME" "CAP_A"
					( Origin gPackager )
				)
				( attribute "CDS_PART_NAME" "CAP_A_0603V-47UF,4V,20%,X5R,60A"
					( Origin gPackager )
				)
				( attribute "GROUP" "PWR_MLCC_CAP"
					( Origin gFrontEnd )
				)
				( attribute "BOM_SS" "E15431-004"
					( Origin gFrontEnd )
				)
				( objectStatus "C2G2" )
			)
			( gate "@baseboard_fab2_lib.baseboard_fab2(sch_1):page225_i278"
				( attribute "CDS_LIB" "dev_discrete"
					( Origin gPackager )
				)
				( attribute "CDS_LOCATION" "C2G9"
					( Origin gPackager )
				)
				( attribute "CDS_SEC" "1"
					( Origin gPackager )
				)
				( attribute "LOCATION" "C2G9"
					( Origin gFrontEnd )
				)
				( attribute "MATERIAL" "X5R"
					( Origin gFrontEnd )
				)
				( attribute "PACK_TYPE" "0603V"
					( Origin gFrontEnd )
				)
				( attribute "PART_NUMBER" "602433-106"
					( Origin gFrontEnd )
				)
				( attribute "PHYS_PAGE" "225"
					( Origin gFrontEnd )
				)
				( attribute "ROT" "0"
					( Origin gFrontEnd )
				)
				( attribute "SEC" "1"
					( Origin gFrontEnd )
				)
				( attribute "SEC_TYPE" "0603V"
					( Origin gFrontEnd )
				)
				( attribute "TOLERANCE" "20%"
					( Origin gFrontEnd )
				)
				( attribute "VALUE" "47UF"
					( Origin gFrontEnd )
				)
				( attribute "VER" "1"
					( Origin gFrontEnd )
				)
				( attribute "VOLTAGE" "4V"
					( Units "uVoltage" "V" 1.000000)
					( Origin gFrontEnd )
				)
				( attribute "XY" "(-1125,250)"
					( Origin gFrontEnd )
				)
				( attribute "CHIPS_PART_NAME" "CAP_A"
					( Origin gPackager )
				)
				( attribute "CDS_PART_NAME" "CAP_A_0603V-47UF,4V,20%,X5R,60A"
					( Origin gPackager )
				)
				( attribute "GROUP" "PWR_MLCC_CAP"
					( Origin gFrontEnd )
				)
				( attribute "BOM_SS" "E15431-004"
					( Origin gFrontEnd )
				)
				( objectStatus "C2G9" )
			)
			( gate "@baseboard_fab2_lib.baseboard_fab2(sch_1):page225_i277"
				( attribute "CDS_LIB" "dev_discrete"
					( Origin gPackager )
				)
				( attribute "CDS_LOCATION" "C2G1"
					( Origin gPackager )
				)
				( attribute "CDS_SEC" "1"
					( Origin gPackager )
				)
				( attribute "LOCATION" "C2G1"
					( Origin gFrontEnd )
				)
				( attribute "MATERIAL" "X5R"
					( Origin gFrontEnd )
				)
				( attribute "PACK_TYPE" "0603V"
					( Origin gFrontEnd )
				)
				( attribute "PART_NUMBER" "602433-106"
					( Origin gFrontEnd )
				)
				( attribute "PHYS_PAGE" "225"
					( Origin gFrontEnd )
				)
				( attribute "ROT" "0"
					( Origin gFrontEnd )
				)
				( attribute "SEC" "1"
					( Origin gFrontEnd )
				)
				( attribute "SEC_TYPE" "0603V"
					( Origin gFrontEnd )
				)
				( attribute "TOLERANCE" "20%"
					( Origin gFrontEnd )
				)
				( attribute "VALUE" "47UF"
					( Origin gFrontEnd )
				)
				( attribute "VER" "1"
					( Origin gFrontEnd )
				)
				( attribute "VOLTAGE" "4V"
					( Units "uVoltage" "V" 1.000000)
					( Origin gFrontEnd )
				)
				( attribute "XY" "(-1400,250)"
					( Origin gFrontEnd )
				)
				( attribute "CHIPS_PART_NAME" "CAP_A"
					( Origin gPackager )
				)
				( attribute "CDS_PART_NAME" "CAP_A_0603V-47UF,4V,20%,X5R,60A"
					( Origin gPackager )
				)
				( attribute "GROUP" "PWR_MLCC_CAP"
					( Origin gFrontEnd )
				)
				( attribute "BOM_SS" "E15431-004"
					( Origin gFrontEnd )
				)
				( objectStatus "C2G1" )
			)
			( gate "@baseboard_fab2_lib.baseboard_fab2(sch_1):page225_i276"
				( attribute "CDS_LIB" "dev_discrete"
					( Origin gPackager )
				)
				( attribute "CDS_LOCATION" "C2G12"
					( Origin gPackager )
				)
				( attribute "CDS_SEC" "1"
					( Origin gPackager )
				)
				( attribute "LOCATION" "C2G12"
					( Origin gFrontEnd )
				)
				( attribute "MATERIAL" "X5R"
					( Origin gFrontEnd )
				)
				( attribute "PACK_TYPE" "0603V"
					( Origin gFrontEnd )
				)
				( attribute "PART_NUMBER" "602433-106"
					( Origin gFrontEnd )
				)
				( attribute "PHYS_PAGE" "225"
					( Origin gFrontEnd )
				)
				( attribute "ROT" "0"
					( Origin gFrontEnd )
				)
				( attribute "SEC" "1"
					( Origin gFrontEnd )
				)
				( attribute "SEC_TYPE" "0603V"
					( Origin gFrontEnd )
				)
				( attribute "TOLERANCE" "20%"
					( Origin gFrontEnd )
				)
				( attribute "VALUE" "47UF"
					( Origin gFrontEnd )
				)
				( attribute "VER" "1"
					( Origin gFrontEnd )
				)
				( attribute "VOLTAGE" "4V"
					( Units "uVoltage" "V" 1.000000)
					( Origin gFrontEnd )
				)
				( attribute "XY" "(-1675,250)"
					( Origin gFrontEnd )
				)
				( attribute "CHIPS_PART_NAME" "CAP_A"
					( Origin gPackager )
				)
				( attribute "CDS_PART_NAME" "CAP_A_0603V-47UF,4V,20%,X5R,60A"
					( Origin gPackager )
				)
				( attribute "GROUP" "PWR_MLCC_CAP"
					( Origin gFrontEnd )
				)
				( attribute "BOM_SS" "E15431-004"
					( Origin gFrontEnd )
				)
				( objectStatus "C2G12" )
			)
			( gate "@baseboard_fab2_lib.baseboard_fab2(sch_1):page225_i273"
				( attribute "BOM_COST" "PROC_SOCKET"
					( Origin gFrontEnd )
				)
				( attribute "CDS_LIB" "dev_discrete"
					( Origin gPackager )
				)
				( attribute "CDS_LOCATION" "C2D42"
					( Origin gPackager )
				)
				( attribute "CDS_SEC" "1"
					( Origin gPackager )
				)
				( attribute "LOCATION" "C2D42"
					( Origin gFrontEnd )
				)
				( attribute "MATERIAL" "X6S"
					( Origin gFrontEnd )
				)
				( attribute "PACK_TYPE" "0603V"
					( Origin gFrontEnd )
				)
				( attribute "PART_NUMBER" "E15431-004"
					( Origin gFrontEnd )
				)
				( attribute "PHYS_PAGE" "225"
					( Origin gFrontEnd )
				)
				( attribute "ROOM" "PVCCIN_CPU0_DECAP_VR"
					( Origin gFrontEnd )
				)
				( attribute "ROT" "0"
					( Origin gFrontEnd )
				)
				( attribute "SEC" "1"
					( Origin gPackager )
				)
				( attribute "TOLERANCE" "20%"
					( Origin gFrontEnd )
				)
				( attribute "VALUE" "22.0UF"
					( Origin gFrontEnd )
				)
				( attribute "VER" "1"
					( Origin gFrontEnd )
				)
				( attribute "VOLTAGE" "4V"
					( Units "uVoltage" "V" 1.000000)
					( Origin gFrontEnd )
				)
				( attribute "XY" "(-350,3100)"
					( Origin gFrontEnd )
				)
				( attribute "CHIPS_PART_NAME" "CAP_A"
					( Origin gPackager )
				)
				( attribute "CDS_PART_NAME" "CAP_A_0603V-22.0UF,4V,20%,X6S,A"
					( Origin gPackager )
				)
				( attribute "GROUP" "PWR_MLCC_CAP"
					( Origin gFrontEnd )
				)
				( objectStatus "C2D42" )
			)
			( gate "@baseboard_fab2_lib.baseboard_fab2(sch_1):page225_i272"
				( attribute "BOM_COST" "PROC_SOCKET"
					( Origin gFrontEnd )
				)
				( attribute "CDS_LIB" "dev_discrete"
					( Origin gPackager )
				)
				( attribute "CDS_LOCATION" "C2D44"
					( Origin gPackager )
				)
				( attribute "CDS_SEC" "1"
					( Origin gPackager )
				)
				( attribute "LOCATION" "C2D44"
					( Origin gFrontEnd )
				)
				( attribute "MATERIAL" "X6S"
					( Origin gFrontEnd )
				)
				( attribute "PACK_TYPE" "0603V"
					( Origin gFrontEnd )
				)
				( attribute "PART_NUMBER" "E15431-004"
					( Origin gFrontEnd )
				)
				( attribute "PHYS_PAGE" "225"
					( Origin gFrontEnd )
				)
				( attribute "ROOM" "PVCCIN_CPU0_DECAP_VR"
					( Origin gFrontEnd )
				)
				( attribute "ROT" "0"
					( Origin gFrontEnd )
				)
				( attribute "SEC" "1"
					( Origin gPackager )
				)
				( attribute "TOLERANCE" "20%"
					( Origin gFrontEnd )
				)
				( attribute "VALUE" "22.0UF"
					( Origin gFrontEnd )
				)
				( attribute "VER" "1"
					( Origin gFrontEnd )
				)
				( attribute "VOLTAGE" "4V"
					( Units "uVoltage" "V" 1.000000)
					( Origin gFrontEnd )
				)
				( attribute "XY" "(-750,3100)"
					( Origin gFrontEnd )
				)
				( attribute "CHIPS_PART_NAME" "CAP_A"
					( Origin gPackager )
				)
				( attribute "CDS_PART_NAME" "CAP_A_0603V-22.0UF,4V,20%,X6S,A"
					( Origin gPackager )
				)
				( attribute "GROUP" "PWR_MLCC_CAP"
					( Origin gFrontEnd )
				)
				( objectStatus "C2D44" )
			)
			( gate "@baseboard_fab2_lib.baseboard_fab2(sch_1):page225_i271"
				( attribute "BOM_COST" "PROC_SOCKET"
					( Origin gFrontEnd )
				)
				( attribute "CDS_LIB" "dev_discrete"
					( Origin gPackager )
				)
				( attribute "CDS_LOCATION" "C2D41"
					( Origin gPackager )
				)
				( attribute "CDS_SEC" "1"
					( Origin gPackager )
				)
				( attribute "LOCATION" "C2D41"
					( Origin gFrontEnd )
				)
				( attribute "MATERIAL" "X6S"
					( Origin gFrontEnd )
				)
				( attribute "PACK_TYPE" "0603V"
					( Origin gFrontEnd )
				)
				( attribute "PART_NUMBER" "E15431-004"
					( Origin gFrontEnd )
				)
				( attribute "PHYS_PAGE" "225"
					( Origin gFrontEnd )
				)
				( attribute "ROOM" "PVCCIN_CPU0_DECAP_VR"
					( Origin gFrontEnd )
				)
				( attribute "ROT" "0"
					( Origin gFrontEnd )
				)
				( attribute "SEC" "1"
					( Origin gPackager )
				)
				( attribute "TOLERANCE" "20%"
					( Origin gFrontEnd )
				)
				( attribute "VALUE" "22.0UF"
					( Origin gFrontEnd )
				)
				( attribute "VER" "1"
					( Origin gFrontEnd )
				)
				( attribute "VOLTAGE" "4V"
					( Units "uVoltage" "V" 1.000000)
					( Origin gFrontEnd )
				)
				( attribute "XY" "(-1100,3100)"
					( Origin gFrontEnd )
				)
				( attribute "CHIPS_PART_NAME" "CAP_A"
					( Origin gPackager )
				)
				( attribute "CDS_PART_NAME" "CAP_A_0603V-22.0UF,4V,20%,X6S,A"
					( Origin gPackager )
				)
				( attribute "GROUP" "PWR_MLCC_CAP"
					( Origin gFrontEnd )
				)
				( objectStatus "C2D41" )
			)
			( gate "@baseboard_fab2_lib.baseboard_fab2(sch_1):page225_i270"
				( attribute "BOM_COST" "PROC_SOCKET"
					( Origin gFrontEnd )
				)
				( attribute "CDS_LIB" "dev_discrete"
					( Origin gPackager )
				)
				( attribute "CDS_LOCATION" "C2D43"
					( Origin gPackager )
				)
				( attribute "CDS_SEC" "1"
					( Origin gPackager )
				)
				( attribute "LOCATION" "C2D43"
					( Origin gFrontEnd )
				)
				( attribute "MATERIAL" "X6S"
					( Origin gFrontEnd )
				)
				( attribute "PACK_TYPE" "0603V"
					( Origin gFrontEnd )
				)
				( attribute "PART_NUMBER" "E15431-004"
					( Origin gFrontEnd )
				)
				( attribute "PHYS_PAGE" "225"
					( Origin gFrontEnd )
				)
				( attribute "ROOM" "PVCCIN_CPU0_DECAP_VR"
					( Origin gFrontEnd )
				)
				( attribute "ROT" "0"
					( Origin gFrontEnd )
				)
				( attribute "SEC" "1"
					( Origin gPackager )
				)
				( attribute "TOLERANCE" "20%"
					( Origin gFrontEnd )
				)
				( attribute "VALUE" "22.0UF"
					( Origin gFrontEnd )
				)
				( attribute "VER" "1"
					( Origin gFrontEnd )
				)
				( attribute "VOLTAGE" "4V"
					( Units "uVoltage" "V" 1.000000)
					( Origin gFrontEnd )
				)
				( attribute "XY" "(-1450,3100)"
					( Origin gFrontEnd )
				)
				( attribute "CHIPS_PART_NAME" "CAP_A"
					( Origin gPackager )
				)
				( attribute "CDS_PART_NAME" "CAP_A_0603V-22.0UF,4V,20%,X6S,A"
					( Origin gPackager )
				)
				( attribute "GROUP" "PWR_MLCC_CAP"
					( Origin gFrontEnd )
				)
				( objectStatus "C2D43" )
			)
			( gate "@baseboard_fab2_lib.baseboard_fab2(sch_1):page220_i239"
				( attribute "CDS_LIB" "mstr_misc"
					( Origin gPackager )
				)
				( attribute "CDS_LOCATION" "SH4L2"
					( Origin gPackager )
				)
				( attribute "CDS_SEC" "1"
					( Origin gPackager )
				)
				( attribute "LOCATION" "SH4L2"
					( Origin gFrontEnd )
				)
				( attribute "MATERIAL" "EMPTY"
					( Origin gFrontEnd )
				)
				( attribute "PACK_TYPE" "SH0201"
					( Origin gFrontEnd )
				)
				( attribute "PART_NUMBER" "N_A"
					( Origin gFrontEnd )
				)
				( attribute "PHYS_PAGE" "220"
					( Origin gFrontEnd )
				)
				( attribute "PIN_SHORT" "A:B"
					( Origin gFrontEnd )
				)
				( attribute "ROT" "0"
					( Origin gFrontEnd )
				)
				( attribute "SEC" "1"
					( Origin gFrontEnd )
				)
				( attribute "SEC_TYPE" "SH0201"
					( Origin gFrontEnd )
				)
				( attribute "VER" "1"
					( Origin gFrontEnd )
				)
				( attribute "XY" "(-300,2075)"
					( Origin gFrontEnd )
				)
				( attribute "CHIPS_PART_NAME" "SHUNT"
					( Origin gPackager )
				)
				( attribute "CDS_PART_NAME" "SHUNT_SH0201-EMPTY,N_A"
					( Origin gPackager )
				)
				( objectStatus "SH4L2" )
			)
			( gate "@baseboard_fab2_lib.baseboard_fab2(sch_1):page220_i240"
				( attribute "CDS_LIB" "mstr_misc"
					( Origin gPackager )
				)
				( attribute "CDS_LOCATION" "SH4L1"
					( Origin gPackager )
				)
				( attribute "CDS_SEC" "1"
					( Origin gPackager )
				)
				( attribute "LOCATION" "SH4L1"
					( Origin gFrontEnd )
				)
				( attribute "MATERIAL" "EMPTY"
					( Origin gFrontEnd )
				)
				( attribute "PACK_TYPE" "SH0201"
					( Origin gFrontEnd )
				)
				( attribute "PART_NUMBER" "N_A"
					( Origin gFrontEnd )
				)
				( attribute "PHYS_PAGE" "220"
					( Origin gFrontEnd )
				)
				( attribute "PIN_SHORT" "A:B"
					( Origin gFrontEnd )
				)
				( attribute "ROT" "0"
					( Origin gFrontEnd )
				)
				( attribute "SEC" "1"
					( Origin gFrontEnd )
				)
				( attribute "SEC_TYPE" "SH0201"
					( Origin gFrontEnd )
				)
				( attribute "VER" "1"
					( Origin gFrontEnd )
				)
				( attribute "XY" "(-325,1625)"
					( Origin gFrontEnd )
				)
				( attribute "CHIPS_PART_NAME" "SHUNT"
					( Origin gPackager )
				)
				( attribute "CDS_PART_NAME" "SHUNT_SH0201-EMPTY,N_A"
					( Origin gPackager )
				)
				( objectStatus "SH4L1" )
			)
			( gate "@baseboard_fab2_lib.baseboard_fab2(sch_1):page218_i57"
				( attribute "CDS_LIB" "mstr_discrete"
					( Origin gPackager )
				)
				( attribute "CDS_LOCATION" "R7B4"
					( Origin gPackager )
				)
				( attribute "CDS_SEC" "1"
					( Origin gPackager )
				)
				( attribute "LOCATION" "R7B4"
					( Origin gFrontEnd )
				)
				( attribute "MATERIAL" "CHIP"
					( Origin gFrontEnd )
				)
				( attribute "PACK_TYPE" "0402"
					( Origin gFrontEnd )
				)
				( attribute "PART_NUMBER" "G21796-026"
					( Origin gFrontEnd )
				)
				( attribute "PHYS_PAGE" "218"
					( Origin gFrontEnd )
				)
				( attribute "ROOM" "VDDQ_DEF_PWR_VR"
					( Origin gFrontEnd )
				)
				( attribute "ROT" "0"
					( Origin gFrontEnd )
				)
				( attribute "SEC" "1"
					( Origin gFrontEnd )
				)
				( attribute "SEC_TYPE" "0402"
					( Origin gFrontEnd )
				)
				( attribute "TOLERANCE" "1%"
					( Origin gFrontEnd )
				)
				( attribute "VALUE" "1.00K"
					( Origin gFrontEnd )
				)
				( attribute "VER" "2"
					( Origin gFrontEnd )
				)
				( attribute "WATTAGE" "1/16W"
					( Origin gFrontEnd )
				)
				( attribute "XY" "(975,2800)"
					( Origin gFrontEnd )
				)
				( attribute "CHIPS_PART_NAME" "RES"
					( Origin gPackager )
				)
				( attribute "CDS_PART_NAME" "RES_0402-1.00K,1%,1/16W,CHIP,GA"
					( Origin gPackager )
				)
				( objectStatus "R7B4" )
			)
			( gate "@baseboard_fab2_lib.baseboard_fab2(sch_1):page221_i15"
				( attribute "BOM_COST" "MEM_VRD_VTT_ABC"
					( Origin gFrontEnd )
				)
				( attribute "CDS_LIB" "mstr_vreg"
					( Origin gPackager )
				)
				( attribute "CDS_LMAN_SYM_OUTLINE" "-250,350,250,-350"
					( Origin gPackager )
				)
				( attribute "CDS_LOCATION" "EU4G3"
					( Origin gPackager )
				)
				( attribute "CDS_SEC" "1"
					( Origin gPackager )
				)
				( attribute "LOCATION" "EU4G3"
					( Origin gFrontEnd )
				)
				( attribute "MATERIAL" "IC"
					( Origin gFrontEnd )
				)
				( attribute "PACK_TYPE" "DFN"
					( Origin gFrontEnd )
				)
				( attribute "PART_NUMBER" "H55101-001"
					( Origin gFrontEnd )
				)
				( attribute "PHYS_PAGE" "221"
					( Origin gFrontEnd )
				)
				( attribute "ROOM" "VTT_ABC_PWR_VR"
					( Origin gFrontEnd )
				)
				( attribute "ROT" "0"
					( Origin gFrontEnd )
				)
				( attribute "SEC" "1"
					( Origin gFrontEnd )
				)
				( attribute "SEC_TYPE" "DFN"
					( Origin gFrontEnd )
				)
				( attribute "VER" "1"
					( Origin gFrontEnd )
				)
				( attribute "XY" "(1275,975)"
					( Origin gFrontEnd )
				)
				( attribute "CHIPS_PART_NAME" "MIC5166"
					( Origin gPackager )
				)
				( attribute "CDS_PART_NAME" "MIC5166_DFN-IC,H55101-001"
					( Origin gPackager )
				)
				( objectStatus "EU4G3" )
			)
			( gate "@baseboard_fab2_lib.baseboard_fab2(sch_1):page218_i56"
				( attribute "CDS_LIB" "mstr_discrete"
					( Origin gPackager )
				)
				( attribute "CDS_LOCATION" "R7A11"
					( Origin gPackager )
				)
				( attribute "CDS_SEC" "1"
					( Origin gPackager )
				)
				( attribute "LOCATION" "R7A11"
					( Origin gFrontEnd )
				)
				( attribute "MATERIAL" "CHIP"
					( Origin gFrontEnd )
				)
				( attribute "PACK_TYPE" "0402"
					( Origin gFrontEnd )
				)
				( attribute "PART_NUMBER" "G21497-005"
					( Origin gFrontEnd )
				)
				( attribute "PHYS_PAGE" "218"
					( Origin gFrontEnd )
				)
				( attribute "ROOM" "VDDQ_DEF_PWR_VR"
					( Origin gFrontEnd )
				)
				( attribute "ROT" "0"
					( Origin gFrontEnd )
				)
				( attribute "SEC" "1"
					( Origin gFrontEnd )
				)
				( attribute "SEC_TYPE" "0402"
					( Origin gFrontEnd )
				)
				( attribute "TOLERANCE" "5%"
					( Origin gFrontEnd )
				)
				( attribute "VALUE" "0.0"
					( Origin gFrontEnd )
				)
				( attribute "VER" "1"
					( Origin gFrontEnd )
				)
				( attribute "WATTAGE" "1/16W"
					( Origin gFrontEnd )
				)
				( attribute "XY" "(1350,2100)"
					( Origin gFrontEnd )
				)
				( attribute "CHIPS_PART_NAME" "RES"
					( Origin gPackager )
				)
				( attribute "CDS_PART_NAME" "RES_0402-0.0,5%,1/16W,CHIP,G21A"
					( Origin gPackager )
				)
				( objectStatus "R7A11" )
			)
			( gate "@baseboard_fab2_lib.baseboard_fab2(sch_1):page221_i22"
				( attribute "BOM_COST" "MEM_VRD_VTT_ABC"
					( Origin gFrontEnd )
				)
				( attribute "CDS_LIB" "mstr_discrete"
					( Origin gPackager )
				)
				( attribute "CDS_LOCATION" "C4G16"
					( Origin gPackager )
				)
				( attribute "CDS_SEC" "1"
					( Origin gPackager )
				)
				( attribute "LOCATION" "C4G16"
					( Origin gFrontEnd )
				)
				( attribute "MATERIAL" "X6S"
					( Origin gFrontEnd )
				)
				( attribute "PACK_TYPE" "0402"
					( Origin gFrontEnd )
				)
				( attribute "PART_NUMBER" "D97712-011"
					( Origin gFrontEnd )
				)
				( attribute "PHYS_PAGE" "221"
					( Origin gFrontEnd )
				)
				( attribute "ROOM" "VTT_ABC_PWR_VR"
					( Origin gFrontEnd )
				)
				( attribute "ROT" "0"
					( Origin gFrontEnd )
				)
				( attribute "SEC" "1"
					( Origin gFrontEnd )
				)
				( attribute "SEC_TYPE" "0402"
					( Origin gFrontEnd )
				)
				( attribute "TOLERANCE" "10%"
					( Origin gFrontEnd )
				)
				( attribute "VALUE" "1.0UF"
					( Origin gFrontEnd )
				)
				( attribute "VER" "1"
					( Origin gFrontEnd )
				)
				( attribute "VOLTAGE" "16V"
					( Units "uVoltage" "V" 1.000000)
					( Origin gFrontEnd )
				)
				( attribute "XY" "(2100,750)"
					( Origin gFrontEnd )
				)
				( attribute "CHIPS_PART_NAME" "CAP"
					( Origin gPackager )
				)
				( attribute "CDS_PART_NAME" "CAP_0402-1.0UF,16V,10%,X6S,D97A"
					( Origin gPackager )
				)
				( objectStatus "C4G16" )
			)
			( gate "@baseboard_fab2_lib.baseboard_fab2(sch_1):page221_i24"
				( attribute "BOM_COST" "MEM_VRD_VTT_ABC"
					( Origin gFrontEnd )
				)
				( attribute "CDS_LIB" "mstr_discrete"
					( Origin gPackager )
				)
				( attribute "CDS_LOCATION" "C4G24"
					( Origin gPackager )
				)
				( attribute "CDS_SEC" "1"
					( Origin gPackager )
				)
				( attribute "LOCATION" "C4G24"
					( Origin gFrontEnd )
				)
				( attribute "MATERIAL" "X6S"
					( Origin gFrontEnd )
				)
				( attribute "PACK_TYPE" "0805LF"
					( Origin gFrontEnd )
				)
				( attribute "PART_NUMBER" "C95333-002"
					( Origin gFrontEnd )
				)
				( attribute "PHYS_PAGE" "221"
					( Origin gFrontEnd )
				)
				( attribute "ROOM" "VTT_ABC_PWR_VR"
					( Origin gFrontEnd )
				)
				( attribute "ROT" "0"
					( Origin gFrontEnd )
				)
				( attribute "SEC" "1"
					( Origin gFrontEnd )
				)
				( attribute "TOLERANCE" "20%"
					( Origin gFrontEnd )
				)
				( attribute "VALUE" "22UF"
					( Origin gFrontEnd )
				)
				( attribute "VER" "1"
					( Origin gFrontEnd )
				)
				( attribute "VOLTAGE" "4V"
					( Units "uVoltage" "V" 1.000000)
					( Origin gFrontEnd )
				)
				( attribute "XY" "(3700,950)"
					( Origin gFrontEnd )
				)
				( attribute "CHIPS_PART_NAME" "CAP"
					( Origin gPackager )
				)
				( attribute "CDS_PART_NAME" "CAP_0805LF-22UF,4V,20%,X6S,C95A"
					( Origin gPackager )
				)
				( attribute "SEC_TYPE" "0805LF"
					( Origin gFrontEnd )
				)
				( attribute "GROUP" "PWR_MLCC_CAP"
					( Origin gFrontEnd )
				)
				( objectStatus "C4G24" )
			)
			( gate "@baseboard_fab2_lib.baseboard_fab2(sch_1):page218_i55"
				( attribute "BOM_COST" "MEM_NV"
					( Origin gFrontEnd )
				)
				( attribute "CDS_LIB" "mstr_discrete"
					( Origin gPackager )
				)
				( attribute "CDS_LOCATION" "R12W30"
					( Origin gPackager )
				)
				( attribute "CDS_SEC" "1"
					( Origin gPackager )
				)
				( attribute "LOCATION" "R12W30"
					( Origin gFrontEnd )
				)
				( attribute "MATERIAL" "EMPTY"
					( Origin gFrontEnd )
				)
				( attribute "PACK_TYPE" "0402"
					( Origin gFrontEnd )
				)
				( attribute "PART_NUMBER" "G21497-005"
					( Origin gFrontEnd )
				)
				( attribute "PHYS_PAGE" "218"
					( Origin gFrontEnd )
				)
				( attribute "ROOM" "NV_DIMM"
					( Origin gFrontEnd )
				)
				( attribute "ROT" "0"
					( Origin gFrontEnd )
				)
				( attribute "SEC" "1"
					( Origin gFrontEnd )
				)
				( attribute "SEC_TYPE" "0402"
					( Origin gFrontEnd )
				)
				( attribute "TOLERANCE" "5%"
					( Origin gFrontEnd )
				)
				( attribute "VALUE" "0.0"
					( Origin gFrontEnd )
				)
				( attribute "VER" "1"
					( Origin gFrontEnd )
				)
				( attribute "WATTAGE" "1/16W"
					( Origin gFrontEnd )
				)
				( attribute "XY" "(1825,1950)"
					( Origin gFrontEnd )
				)
				( attribute "CHIPS_PART_NAME" "RES"
					( Origin gPackager )
				)
				( attribute "CDS_PART_NAME" "RES_0402-0.0,5%,1/16W,EMPTY,G2A"
					( Origin gPackager )
				)
				( objectStatus "R12W30" )
			)
			( gate "@baseboard_fab2_lib.baseboard_fab2(sch_1):page218_i46"
				( attribute "BOM_COST" "MEM_NV"
					( Origin gFrontEnd )
				)
				( attribute "CDS_LIB" "mstr_discrete"
					( Origin gPackager )
				)
				( attribute "CDS_LOCATION" "R12W29"
					( Origin gPackager )
				)
				( attribute "CDS_SEC" "1"
					( Origin gPackager )
				)
				( attribute "LOCATION" "R12W29"
					( Origin gFrontEnd )
				)
				( attribute "MATERIAL" "EMPTY"
					( Origin gFrontEnd )
				)
				( attribute "PACK_TYPE" "0402"
					( Origin gFrontEnd )
				)
				( attribute "PART_NUMBER" "G21497-005"
					( Origin gFrontEnd )
				)
				( attribute "PHYS_PAGE" "218"
					( Origin gFrontEnd )
				)
				( attribute "ROOM" "NV_DIMM"
					( Origin gFrontEnd )
				)
				( attribute "ROT" "0"
					( Origin gFrontEnd )
				)
				( attribute "SEC" "1"
					( Origin gFrontEnd )
				)
				( attribute "SEC_TYPE" "0402"
					( Origin gFrontEnd )
				)
				( attribute "TOLERANCE" "5%"
					( Origin gFrontEnd )
				)
				( attribute "VALUE" "0.0"
					( Origin gFrontEnd )
				)
				( attribute "VER" "1"
					( Origin gFrontEnd )
				)
				( attribute "WATTAGE" "1/16W"
					( Origin gFrontEnd )
				)
				( attribute "XY" "(1825,1550)"
					( Origin gFrontEnd )
				)
				( attribute "CHIPS_PART_NAME" "RES"
					( Origin gPackager )
				)
				( attribute "CDS_PART_NAME" "RES_0402-0.0,5%,1/16W,EMPTY,G2A"
					( Origin gPackager )
				)
				( objectStatus "R12W29" )
			)
			( gate "@baseboard_fab2_lib.baseboard_fab2(sch_1):page218_i45"
				( attribute "CDS_LIB" "mstr_discrete"
					( Origin gPackager )
				)
				( attribute "CDS_LOCATION" "R7A12"
					( Origin gPackager )
				)
				( attribute "CDS_SEC" "1"
					( Origin gPackager )
				)
				( attribute "LOCATION" "R7A12"
					( Origin gFrontEnd )
				)
				( attribute "MATERIAL" "CHIP"
					( Origin gFrontEnd )
				)
				( attribute "PACK_TYPE" "0402"
					( Origin gFrontEnd )
				)
				( attribute "PART_NUMBER" "G21497-005"
					( Origin gFrontEnd )
				)
				( attribute "PHYS_PAGE" "218"
					( Origin gFrontEnd )
				)
				( attribute "ROOM" "VDDQ_DEF_PWR_VR"
					( Origin gFrontEnd )
				)
				( attribute "ROT" "0"
					( Origin gFrontEnd )
				)
				( attribute "SEC" "1"
					( Origin gFrontEnd )
				)
				( attribute "SEC_TYPE" "0402"
					( Origin gFrontEnd )
				)
				( attribute "TOLERANCE" "5%"
					( Origin gFrontEnd )
				)
				( attribute "VALUE" "0.0"
					( Origin gFrontEnd )
				)
				( attribute "VER" "1"
					( Origin gFrontEnd )
				)
				( attribute "WATTAGE" "1/16W"
					( Origin gFrontEnd )
				)
				( attribute "XY" "(1500,1400)"
					( Origin gFrontEnd )
				)
				( attribute "CHIPS_PART_NAME" "RES"
					( Origin gPackager )
				)
				( attribute "CDS_PART_NAME" "RES_0402-0.0,5%,1/16W,CHIP,G21A"
					( Origin gPackager )
				)
				( objectStatus "R7A12" )
			)
			( gate "@baseboard_fab2_lib.baseboard_fab2(sch_1):page225_i309"
				( attribute "BOM_COST" "MEM_VRD_PVDDQ_CD"
					( Origin gFrontEnd )
				)
				( attribute "CDS_LIB" "mstr_discrete"
					( Origin gPackager )
				)
				( attribute "CDS_LOCATION" "C7T1"
					( Origin gPackager )
				)
				( attribute "CDS_SEC" "1"
					( Origin gPackager )
				)
				( attribute "LOCATION" "C7T1"
					( Origin gFrontEnd )
				)
				( attribute "MATERIAL" "X5R"
					( Origin gFrontEnd )
				)
				( attribute "NEW_MATERIAL" "X6S"
					( Origin gFrontEnd )
				)
				( attribute "PACK_TYPE" "0805"
					( Origin gFrontEnd )
				)
				( attribute "PART_NUMBER" "602433-112"
					( Origin gFrontEnd )
				)
				( attribute "PHYS_PAGE" "225"
					( Origin gFrontEnd )
				)
				( attribute "ROOM" "VDDQ_ABC_PWR_VR"
					( Origin gFrontEnd )
				)
				( attribute "ROT" "0"
					( Origin gFrontEnd )
				)
				( attribute "SEC" "1"
					( Origin gFrontEnd )
				)
				( attribute "SEC_TYPE" "0805"
					( Origin gFrontEnd )
				)
				( attribute "TOLERANCE" "20%"
					( Origin gFrontEnd )
				)
				( attribute "VALUE" "100UF"
					( Origin gFrontEnd )
				)
				( attribute "VER" "1"
					( Origin gFrontEnd )
				)
				( attribute "VOLTAGE" "4V"
					( Units "uVoltage" "V" 1.000000)
					( Origin gFrontEnd )
				)
				( attribute "XY" "(3500,2825)"
					( Origin gFrontEnd )
				)
				( attribute "CHIPS_PART_NAME" "CAP"
					( Origin gPackager )
				)
				( attribute "CDS_PART_NAME" "CAP_0805-100UF,4V,20%,X5R,6024A"
					( Origin gPackager )
				)
				( attribute "GROUP" "PWR_MLCC_CAP"
					( Origin gFrontEnd )
				)
				( attribute "NEW_PN" "078.1071T.M002"
					( Origin gFrontEnd )
				)
				( attribute "BOM_SS" "NOPOP"
					( Origin gFrontEnd )
				)
				( objectStatus "C7T1" )
			)
			( gate "@baseboard_fab2_lib.baseboard_fab2(sch_1):page218_i41"
				( attribute "CDS_LIB" "mstr_discrete"
					( Origin gPackager )
				)
				( attribute "CDS_LOCATION" "C7B3"
					( Origin gPackager )
				)
				( attribute "CDS_SEC" "1"
					( Origin gPackager )
				)
				( attribute "LOCATION" "C7B3"
					( Origin gFrontEnd )
				)
				( attribute "MATERIAL" "X7R"
					( Origin gFrontEnd )
				)
				( attribute "PACK_TYPE" "0402LF"
					( Origin gFrontEnd )
				)
				( attribute "PART_NUMBER" "A36096-046"
					( Origin gFrontEnd )
				)
				( attribute "PHYS_PAGE" "218"
					( Origin gFrontEnd )
				)
				( attribute "ROOM" "VDDQ_DEF_PWR_VR"
					( Origin gFrontEnd )
				)
				( attribute "ROT" "0"
					( Origin gFrontEnd )
				)
				( attribute "SEC" "1"
					( Origin gFrontEnd )
				)
				( attribute "SEC_TYPE" "0402LF"
					( Origin gFrontEnd )
				)
				( attribute "TOLERANCE" "10%"
					( Origin gFrontEnd )
				)
				( attribute "VALUE" "1000PF"
					( Origin gFrontEnd )
				)
				( attribute "VER" "1"
					( Origin gFrontEnd )
				)
				( attribute "VOLTAGE" "50V"
					( Units "uVoltage" "V" 1.000000)
					( Origin gFrontEnd )
				)
				( attribute "XY" "(1625,925)"
					( Origin gFrontEnd )
				)
				( attribute "CHIPS_PART_NAME" "CAP"
					( Origin gPackager )
				)
				( attribute "CDS_PART_NAME" "CAP_0402LF-1000PF,50V,10%,X7R,A"
					( Origin gPackager )
				)
				( objectStatus "C7B3" )
			)
			( gate "@baseboard_fab2_lib.baseboard_fab2(sch_1):page218_i38"
				( attribute "CDS_LIB" "dev_discrete"
					( Origin gPackager )
				)
				( attribute "CDS_LOCATION" "C7A38"
					( Origin gPackager )
				)
				( attribute "CDS_SEC" "1"
					( Origin gPackager )
				)
				( attribute "LOCATION" "C7A38"
					( Origin gFrontEnd )
				)
				( attribute "MATERIAL" "X7R"
					( Origin gFrontEnd )
				)
				( attribute "PACK_TYPE" "0402V"
					( Origin gFrontEnd )
				)
				( attribute "PART_NUMBER" "A36096-030"
					( Origin gFrontEnd )
				)
				( attribute "PHYS_PAGE" "218"
					( Origin gFrontEnd )
				)
				( attribute "ROOM" "VDDQ_DEF_PWR_VR"
					( Origin gFrontEnd )
				)
				( attribute "ROT" "0"
					( Origin gFrontEnd )
				)
				( attribute "SEC" "1"
					( Origin gFrontEnd )
				)
				( attribute "SEC_TYPE" "0402V"
					( Origin gFrontEnd )
				)
				( attribute "TOLERANCE" "10%"
					( Origin gFrontEnd )
				)
				( attribute "VALUE" "0.1UF"
					( Origin gFrontEnd )
				)
				( attribute "VER" "1"
					( Origin gFrontEnd )
				)
				( attribute "VOLTAGE" "16V"
					( Units "uVoltage" "V" 1.000000)
					( Origin gFrontEnd )
				)
				( attribute "XY" "(-150,2800)"
					( Origin gFrontEnd )
				)
				( attribute "CHIPS_PART_NAME" "CAP_A"
					( Origin gPackager )
				)
				( attribute "CDS_PART_NAME" "CAP_A_0402V-0.1UF,16V,10%,X7R,A"
					( Origin gPackager )
				)
				( objectStatus "C7A38" )
			)
			( gate "@baseboard_fab2_lib.baseboard_fab2(sch_1):page223_i74"
				( attribute "CDS_LIB" "mstr_discrete"
					( Origin gPackager )
				)
				( attribute "CDS_LOCATION" "R1G22"
					( Origin gPackager )
				)
				( attribute "CDS_SEC" "1"
					( Origin gPackager )
				)
				( attribute "LOCATION" "R1G22"
					( Origin gFrontEnd )
				)
				( attribute "MATERIAL" "CHIP"
					( Origin gFrontEnd )
				)
				( attribute "PACK_TYPE" "0402"
					( Origin gFrontEnd )
				)
				( attribute "PART_NUMBER" "G21796-043"
					( Origin gFrontEnd )
				)
				( attribute "PHYS_PAGE" "223"
					( Origin gFrontEnd )
				)
				( attribute "ROOM" "PVCCIN_CPU1_VR"
					( Origin gFrontEnd )
				)
				( attribute "ROT" "0"
					( Origin gFrontEnd )
				)
				( attribute "SEC" "1"
					( Origin gFrontEnd )
				)
				( attribute "SEC_TYPE" "0402"
					( Origin gFrontEnd )
				)
				( attribute "TOLERANCE" "1%"
					( Origin gFrontEnd )
				)
				( attribute "VALUE" "3.16K"
					( Origin gFrontEnd )
				)
				( attribute "VER" "2"
					( Origin gFrontEnd )
				)
				( attribute "WATTAGE" "1/16W"
					( Origin gFrontEnd )
				)
				( attribute "XY" "(625,-250)"
					( Origin gFrontEnd )
				)
				( attribute "CHIPS_PART_NAME" "RES"
					( Origin gPackager )
				)
				( attribute "CDS_PART_NAME" "RES_0402-3.16K,1%,1/16W,CHIP,GA"
					( Origin gPackager )
				)
				( objectStatus "R1G22" )
			)
			( gate "@baseboard_fab2_lib.baseboard_fab2(sch_1):page218_i30"
				( attribute "CDS_LIB" "dev_discrete"
					( Origin gPackager )
				)
				( attribute "CDS_LOCATION" "C7B1"
					( Origin gPackager )
				)
				( attribute "CDS_SEC" "1"
					( Origin gPackager )
				)
				( attribute "LOCATION" "C7B1"
					( Origin gFrontEnd )
				)
				( attribute "MATERIAL" "X6S"
					( Origin gFrontEnd )
				)
				( attribute "PACK_TYPE" "0402V"
					( Origin gFrontEnd )
				)
				( attribute "PART_NUMBER" "D97712-004"
					( Origin gFrontEnd )
				)
				( attribute "PHYS_PAGE" "218"
					( Origin gFrontEnd )
				)
				( attribute "ROOM" "VDDQ_DEF_PWR_VR"
					( Origin gFrontEnd )
				)
				( attribute "ROT" "0"
					( Origin gFrontEnd )
				)
				( attribute "SEC" "1"
					( Origin gFrontEnd )
				)
				( attribute "SEC_TYPE" "0402V"
					( Origin gFrontEnd )
				)
				( attribute "TOLERANCE" "10%"
					( Origin gFrontEnd )
				)
				( attribute "VALUE" "1.0UF"
					( Origin gFrontEnd )
				)
				( attribute "VER" "1"
					( Origin gFrontEnd )
				)
				( attribute "VOLTAGE" "6.3V"
					( Units "uVoltage" "V" 1.000000)
					( Origin gFrontEnd )
				)
				( attribute "XY" "(2350,-100)"
					( Origin gFrontEnd )
				)
				( attribute "CHIPS_PART_NAME" "CAP_A"
					( Origin gPackager )
				)
				( attribute "CDS_PART_NAME" "CAP_A_0402V-1.0UF,6.3V,10%,X6SA"
					( Origin gPackager )
				)
				( objectStatus "C7B1" )
			)
			( gate "@baseboard_fab2_lib.baseboard_fab2(sch_1):page218_i28"
				( attribute "CDS_LIB" "dev_discrete"
					( Origin gPackager )
				)
				( attribute "CDS_LOCATION" "C7B2"
					( Origin gPackager )
				)
				( attribute "CDS_SEC" "1"
					( Origin gPackager )
				)
				( attribute "LOCATION" "C7B2"
					( Origin gFrontEnd )
				)
				( attribute "MATERIAL" "X7R"
					( Origin gFrontEnd )
				)
				( attribute "PACK_TYPE" "0402V"
					( Origin gFrontEnd )
				)
				( attribute "PART_NUMBER" "A36096-030"
					( Origin gFrontEnd )
				)
				( attribute "PHYS_PAGE" "218"
					( Origin gFrontEnd )
				)
				( attribute "ROOM" "VDDQ_DEF_PWR_VR"
					( Origin gFrontEnd )
				)
				( attribute "ROT" "0"
					( Origin gFrontEnd )
				)
				( attribute "SEC" "1"
					( Origin gFrontEnd )
				)
				( attribute "SEC_TYPE" "0402V"
					( Origin gFrontEnd )
				)
				( attribute "TOLERANCE" "10%"
					( Origin gFrontEnd )
				)
				( attribute "VALUE" "0.1UF"
					( Origin gFrontEnd )
				)
				( attribute "VER" "1"
					( Origin gFrontEnd )
				)
				( attribute "VOLTAGE" "16V"
					( Units "uVoltage" "V" 1.000000)
					( Origin gFrontEnd )
				)
				( attribute "XY" "(1950,-100)"
					( Origin gFrontEnd )
				)
				( attribute "CHIPS_PART_NAME" "CAP_A"
					( Origin gPackager )
				)
				( attribute "CDS_PART_NAME" "CAP_A_0402V-0.1UF,16V,10%,X7R,A"
					( Origin gPackager )
				)
				( objectStatus "C7B2" )
			)
			( gate "@baseboard_fab2_lib.baseboard_fab2(sch_1):page218_i20"
				( attribute "CDS_LIB" "w_hdl"
					( Origin gPackager )
				)
				( attribute "CDS_LMAN_SYM_OUTLINE" "-50,25,50,-25"
					( Origin gPackager )
				)
				( attribute "CDS_LOCATION" "CF18"
					( Origin gPackager )
				)
				( attribute "CDS_SEC" "1"
					( Origin gPackager )
				)
				( attribute "LOCATION" "CF18"
					( Origin gFrontEnd )
				)
				( attribute "PACK_TYPE" "SMD-BCG"
					( Origin gFrontEnd )
				)
				( attribute "PART_NUMBER" "78.22034.1FL"
					( Origin gFrontEnd )
				)
				( attribute "PHYS_PAGE" "218"
					( Origin gFrontEnd )
				)
				( attribute "ROT" "1"
					( Origin gFrontEnd )
				)
				( attribute "SEC" "1"
					( Origin gPackager )
				)
				( attribute "VALUE" "SC22P50V2JN-4GP"
					( Origin gFrontEnd )
				)
				( attribute "VER" "1"
					( Origin gFrontEnd )
				)
				( attribute "XY" "(-1550,2250)"
					( Origin gFrontEnd )
				)
				( attribute "CHIPS_PART_NAME" "SC22P50V2JN-4GP"
					( Origin gPackager )
				)
				( attribute "CDS_PART_NAME" "SC22P50V2JN-4GP_SMD-BCG-SC22P5A"
					( Origin gPackager )
				)
				( attribute "ATTRIBUTE" "22PF"
					( Origin gFrontEnd )
				)
				( attribute "PACK_SIZE" "0402"
					( Origin gFrontEnd )
				)
				( attribute "RATED" "50V"
					( Origin gFrontEnd )
				)
				( attribute "TOLERANCE" "5%"
					( Origin gFrontEnd )
				)
				( attribute "TYPE" "NPO"
					( Origin gFrontEnd )
				)
				( attribute "GROUP" "POWER_FAIR"
					( Origin gFrontEnd )
				)
				( attribute "BOM_SS" "NOPOP"
					( Origin gFrontEnd )
				)
				( objectStatus "CF18" )
			)
			( gate "@baseboard_fab2_lib.baseboard_fab2(sch_1):page218_i19"
				( attribute "CDS_LIB" "mstr_discrete"
					( Origin gPackager )
				)
				( attribute "CDS_LOCATION" "RF18"
					( Origin gPackager )
				)
				( attribute "LOCATION" "RF18"
					( Origin gFrontEnd )
				)
				( attribute "MATERIAL" "CHIP"
					( Origin gFrontEnd )
				)
				( attribute "PACK_TYPE" "0402"
					( Origin gFrontEnd )
				)
				( attribute "PART_NUMBER" "G85996-004"
					( Origin gFrontEnd )
				)
				( attribute "PHYS_PAGE" "218"
					( Origin gFrontEnd )
				)
				( attribute "ROOM" "SB"
					( Origin gFrontEnd )
				)
				( attribute "ROT" "0"
					( Origin gFrontEnd )
				)
				( attribute "SEC" "1"
					( Origin gFrontEnd )
				)
				( attribute "TOLERANCE" "0.1%"
					( Origin gFrontEnd )
				)
				( attribute "VALUE" "1.0K"
					( Origin gFrontEnd )
				)
				( attribute "VER" "1"
					( Origin gFrontEnd )
				)
				( attribute "WATTAGE" "1/16W"
					( Origin gFrontEnd )
				)
				( attribute "XY" "(-1550,2400)"
					( Origin gFrontEnd )
				)
				( attribute "CHIPS_PART_NAME" "RES"
					( Origin gPackager )
				)
				( attribute "CDS_PART_NAME" "RES_0402-1.0K,0.1%,1/16W,CHIP,A"
					( Origin gPackager )
				)
				( attribute "SEC_TYPE" "0402"
					( Origin gFrontEnd )
				)
				( attribute "CDS_SEC" "1"
					( Origin gPackager )
				)
				( attribute "GROUP" "POWER_FAIR"
					( Origin gFrontEnd )
				)
				( attribute "BOM_SS" "NOPOP"
					( Origin gFrontEnd )
				)
				( objectStatus "RF18" )
			)
			( gate "@baseboard_fab2_lib.baseboard_fab2(sch_1):page218_i18"
				( attribute "CDS_LIB" "mstr_discrete"
					( Origin gPackager )
				)
				( attribute "CDS_LOCATION" "RF17"
					( Origin gPackager )
				)
				( attribute "LOCATION" "RF17"
					( Origin gFrontEnd )
				)
				( attribute "MATERIAL" "CHIP"
					( Origin gFrontEnd )
				)
				( attribute "PACK_TYPE" "0402"
					( Origin gFrontEnd )
				)
				( attribute "PART_NUMBER" "G85996-004"
					( Origin gFrontEnd )
				)
				( attribute "PHYS_PAGE" "218"
					( Origin gFrontEnd )
				)
				( attribute "ROOM" "SB"
					( Origin gFrontEnd )
				)
				( attribute "ROT" "0"
					( Origin gFrontEnd )
				)
				( attribute "SEC" "1"
					( Origin gFrontEnd )
				)
				( attribute "TOLERANCE" "0.1%"
					( Origin gFrontEnd )
				)
				( attribute "VALUE" "1.0K"
					( Origin gFrontEnd )
				)
				( attribute "VER" "1"
					( Origin gFrontEnd )
				)
				( attribute "WATTAGE" "1/16W"
					( Origin gFrontEnd )
				)
				( attribute "XY" "(-2200,2400)"
					( Origin gFrontEnd )
				)
				( attribute "CHIPS_PART_NAME" "RES"
					( Origin gPackager )
				)
				( attribute "CDS_PART_NAME" "RES_0402-1.0K,0.1%,1/16W,CHIP,A"
					( Origin gPackager )
				)
				( attribute "SEC_TYPE" "0402"
					( Origin gFrontEnd )
				)
				( attribute "CDS_SEC" "1"
					( Origin gPackager )
				)
				( attribute "GROUP" "POWER_FAIR"
					( Origin gFrontEnd )
				)
				( attribute "FAIR_SS" "064.9530D.M001"
					( Origin gFrontEnd )
				)
				( objectStatus "RF17" )
			)
			( gate "@baseboard_fab2_lib.baseboard_fab2(sch_1):page218_i13"
				( attribute "CDS_LIB" "mstr_discrete"
					( Origin gPackager )
				)
				( attribute "CDS_LOCATION" "R7A7"
					( Origin gPackager )
				)
				( attribute "CDS_SEC" "1"
					( Origin gPackager )
				)
				( attribute "LOCATION" "R7A7"
					( Origin gFrontEnd )
				)
				( attribute "MATERIAL" "CHIP"
					( Origin gFrontEnd )
				)
				( attribute "PACK_TYPE" "0402"
					( Origin gFrontEnd )
				)
				( attribute "PART_NUMBER" "G21796-066"
					( Origin gFrontEnd )
				)
				( attribute "PHYS_PAGE" "218"
					( Origin gFrontEnd )
				)
				( attribute "ROOM" "VDDQ_DEF_PWR_VR"
					( Origin gFrontEnd )
				)
				( attribute "ROT" "0"
					( Origin gFrontEnd )
				)
				( attribute "SEC" "1"
					( Origin gFrontEnd )
				)
				( attribute "SEC_TYPE" "0402"
					( Origin gFrontEnd )
				)
				( attribute "TOLERANCE" "1%"
					( Origin gFrontEnd )
				)
				( attribute "VALUE" "10.0"
					( Origin gFrontEnd )
				)
				( attribute "VER" "1"
					( Origin gFrontEnd )
				)
				( attribute "WATTAGE" "1/16W"
					( Origin gFrontEnd )
				)
				( attribute "XY" "(-2925,875)"
					( Origin gFrontEnd )
				)
				( attribute "CHIPS_PART_NAME" "RES"
					( Origin gPackager )
				)
				( attribute "CDS_PART_NAME" "RES_0402-10.0,1%,1/16W,CHIP,G2A"
					( Origin gPackager )
				)
				( objectStatus "R7A7" )
			)
			( gate "@baseboard_fab2_lib.baseboard_fab2(sch_1):page222_i12"
				( attribute "BOM_COST" "MEM_VRD_VTT_DEF"
					( Origin gFrontEnd )
				)
				( attribute "CDS_LIB" "mstr_discrete"
					( Origin gPackager )
				)
				( attribute "CDS_LOCATION" "C4A10"
					( Origin gPackager )
				)
				( attribute "CDS_SEC" "1"
					( Origin gPackager )
				)
				( attribute "LOCATION" "C4A10"
					( Origin gFrontEnd )
				)
				( attribute "MATERIAL" "X6S"
					( Origin gFrontEnd )
				)
				( attribute "PACK_TYPE" "0402"
					( Origin gFrontEnd )
				)
				( attribute "PART_NUMBER" "D97712-011"
					( Origin gFrontEnd )
				)
				( attribute "PHYS_PAGE" "222"
					( Origin gFrontEnd )
				)
				( attribute "ROOM" "VTT_DEF_PWR_VR"
					( Origin gFrontEnd )
				)
				( attribute "ROT" "0"
					( Origin gFrontEnd )
				)
				( attribute "SEC" "1"
					( Origin gFrontEnd )
				)
				( attribute "SEC_TYPE" "0402"
					( Origin gFrontEnd )
				)
				( attribute "TOLERANCE" "10%"
					( Origin gFrontEnd )
				)
				( attribute "VALUE" "1.0UF"
					( Origin gFrontEnd )
				)
				( attribute "VER" "1"
					( Origin gFrontEnd )
				)
				( attribute "VOLTAGE" "16V"
					( Units "uVoltage" "V" 1.000000)
					( Origin gFrontEnd )
				)
				( attribute "XY" "(-325,1050)"
					( Origin gFrontEnd )
				)
				( attribute "CHIPS_PART_NAME" "CAP"
					( Origin gPackager )
				)
				( attribute "CDS_PART_NAME" "CAP_0402-1.0UF,16V,10%,X6S,D97A"
					( Origin gPackager )
				)
				( objectStatus "C4A10" )
			)
			( gate "@baseboard_fab2_lib.baseboard_fab2(sch_1):page223_i48"
				( attribute "CDS_LIB" "mstr_discrete"
					( Origin gPackager )
				)
				( attribute "CDS_LOCATION" "R1G16"
					( Origin gPackager )
				)
				( attribute "CDS_SEC" "1"
					( Origin gPackager )
				)
				( attribute "LOCATION" "R1G16"
					( Origin gFrontEnd )
				)
				( attribute "MATERIAL" "CHIP"
					( Origin gFrontEnd )
				)
				( attribute "PACK_TYPE" "0402"
					( Origin gFrontEnd )
				)
				( attribute "PART_NUMBER" "G21796-026"
					( Origin gFrontEnd )
				)
				( attribute "PHYS_PAGE" "223"
					( Origin gFrontEnd )
				)
				( attribute "ROOM" "VDDQ_GHJ_PWR_VR"
					( Origin gFrontEnd )
				)
				( attribute "ROT" "0"
					( Origin gFrontEnd )
				)
				( attribute "SEC" "1"
					( Origin gFrontEnd )
				)
				( attribute "SEC_TYPE" "0402"
					( Origin gFrontEnd )
				)
				( attribute "TOLERANCE" "1%"
					( Origin gFrontEnd )
				)
				( attribute "VALUE" "1.00K"
					( Origin gFrontEnd )
				)
				( attribute "VER" "2"
					( Origin gFrontEnd )
				)
				( attribute "WATTAGE" "1/16W"
					( Origin gFrontEnd )
				)
				( attribute "XY" "(2400,2750)"
					( Origin gFrontEnd )
				)
				( attribute "CHIPS_PART_NAME" "RES"
					( Origin gPackager )
				)
				( attribute "CDS_PART_NAME" "RES_0402-1.00K,1%,1/16W,CHIP,GA"
					( Origin gPackager )
				)
				( objectStatus "R1G16" )
			)
			( gate "@baseboard_fab2_lib.baseboard_fab2(sch_1):page226_i74"
				( attribute "BOM_COST" "PROC_SIDEBAND"
					( Origin gFrontEnd )
				)
				( attribute "CDS_LIB" "mstr_discrete"
					( Origin gPackager )
				)
				( attribute "CDS_LOCATION" "R12W34"
					( Origin gPackager )
				)
				( attribute "CDS_SEC" "1"
					( Origin gPackager )
				)
				( attribute "LOCATION" "R12W34"
					( Origin gFrontEnd )
				)
				( attribute "MATERIAL" "CHIP"
					( Origin gFrontEnd )
				)
				( attribute "PACK_TYPE" "0402"
					( Origin gFrontEnd )
				)
				( attribute "PART_NUMBER" "G21497-005"
					( Origin gFrontEnd )
				)
				( attribute "PHYS_PAGE" "226"
					( Origin gFrontEnd )
				)
				( attribute "ROOM" "CPU0"
					( Origin gFrontEnd )
				)
				( attribute "ROT" "0"
					( Origin gFrontEnd )
				)
				( attribute "SEC" "1"
					( Origin gFrontEnd )
				)
				( attribute "SEC_TYPE" "0402"
					( Origin gFrontEnd )
				)
				( attribute "TOLERANCE" "5%"
					( Origin gFrontEnd )
				)
				( attribute "VALUE" "0.0"
					( Origin gFrontEnd )
				)
				( attribute "VER" "1"
					( Origin gFrontEnd )
				)
				( attribute "WATTAGE" "1/16W"
					( Origin gFrontEnd )
				)
				( attribute "XY" "(2950,1175)"
					( Origin gFrontEnd )
				)
				( attribute "CHIPS_PART_NAME" "RES"
					( Origin gPackager )
				)
				( attribute "CDS_PART_NAME" "RES_0402-0.0,5%,1/16W,CHIP,G21A"
					( Origin gPackager )
				)
				( objectStatus "R12W34" )
			)
			( gate "@baseboard_fab2_lib.baseboard_fab2(sch_1):page223_i45"
				( attribute "BOM_COST" "MEM_NV"
					( Origin gFrontEnd )
				)
				( attribute "CDS_LIB" "mstr_discrete"
					( Origin gPackager )
				)
				( attribute "CDS_LOCATION" "R12W32"
					( Origin gPackager )
				)
				( attribute "CDS_SEC" "1"
					( Origin gPackager )
				)
				( attribute "LOCATION" "R12W32"
					( Origin gFrontEnd )
				)
				( attribute "MATERIAL" "EMPTY"
					( Origin gFrontEnd )
				)
				( attribute "PACK_TYPE" "0402"
					( Origin gFrontEnd )
				)
				( attribute "PART_NUMBER" "G21497-005"
					( Origin gFrontEnd )
				)
				( attribute "PHYS_PAGE" "223"
					( Origin gFrontEnd )
				)
				( attribute "ROOM" "NV_DIMM"
					( Origin gFrontEnd )
				)
				( attribute "ROT" "0"
					( Origin gFrontEnd )
				)
				( attribute "SEC" "1"
					( Origin gFrontEnd )
				)
				( attribute "SEC_TYPE" "0402"
					( Origin gFrontEnd )
				)
				( attribute "TOLERANCE" "5%"
					( Origin gFrontEnd )
				)
				( attribute "VALUE" "0.0"
					( Origin gFrontEnd )
				)
				( attribute "VER" "1"
					( Origin gFrontEnd )
				)
				( attribute "WATTAGE" "1/16W"
					( Origin gFrontEnd )
				)
				( attribute "XY" "(3250,1500)"
					( Origin gFrontEnd )
				)
				( attribute "CHIPS_PART_NAME" "RES"
					( Origin gPackager )
				)
				( attribute "CDS_PART_NAME" "RES_0402-0.0,5%,1/16W,EMPTY,G2A"
					( Origin gPackager )
				)
				( objectStatus "R12W32" )
			)
			( gate "@baseboard_fab2_lib.baseboard_fab2(sch_1):page229_i43"
				( attribute "BOM_COST" "MEM_VRD_PVDDQ_CD"
					( Origin gFrontEnd )
				)
				( attribute "CDS_LIB" "mstr_discrete"
					( Origin gPackager )
				)
				( attribute "CDS_LOCATION" "C6W12"
					( Origin gPackager )
				)
				( attribute "CDS_SEC" "1"
					( Origin gPackager )
				)
				( attribute "LOCATION" "C6W12"
					( Origin gFrontEnd )
				)
				( attribute "MATERIAL" "X5R"
					( Origin gFrontEnd )
				)
				( attribute "NEW_MATERIAL" "X6S"
					( Origin gFrontEnd )
				)
				( attribute "PACK_TYPE" "0805"
					( Origin gFrontEnd )
				)
				( attribute "PART_NUMBER" "602433-112"
					( Origin gFrontEnd )
				)
				( attribute "PHYS_PAGE" "229"
					( Origin gFrontEnd )
				)
				( attribute "ROOM" "VDDQ_ABC_PWR_VR"
					( Origin gFrontEnd )
				)
				( attribute "ROT" "0"
					( Origin gFrontEnd )
				)
				( attribute "SEC" "1"
					( Origin gFrontEnd )
				)
				( attribute "SEC_TYPE" "0805"
					( Origin gFrontEnd )
				)
				( attribute "TOLERANCE" "20%"
					( Origin gFrontEnd )
				)
				( attribute "VALUE" "100UF"
					( Origin gFrontEnd )
				)
				( attribute "VER" "1"
					( Origin gFrontEnd )
				)
				( attribute "VOLTAGE" "4V"
					( Units "uVoltage" "V" 1.000000)
					( Origin gFrontEnd )
				)
				( attribute "XY" "(4700,900)"
					( Origin gFrontEnd )
				)
				( attribute "CHIPS_PART_NAME" "CAP"
					( Origin gPackager )
				)
				( attribute "CDS_PART_NAME" "CAP_0805-100UF,4V,20%,X5R,6024A"
					( Origin gPackager )
				)
				( attribute "GROUP" "PWR_MLCC_CAP"
					( Origin gFrontEnd )
				)
				( attribute "NEW_PN" "078.1071T.M002"
					( Origin gFrontEnd )
				)
				( objectStatus "C6W12" )
			)
			( gate "@baseboard_fab2_lib.baseboard_fab2(sch_1):page222_i28"
				( attribute "BOM_COST" "MEM_VRD_VTT_DEF"
					( Origin gFrontEnd )
				)
				( attribute "CDS_LIB" "mstr_discrete"
					( Origin gPackager )
				)
				( attribute "CDS_LOCATION" "C4A1"
					( Origin gPackager )
				)
				( attribute "CDS_SEC" "1"
					( Origin gPackager )
				)
				( attribute "LOCATION" "C4A1"
					( Origin gFrontEnd )
				)
				( attribute "MATERIAL" "X6S"
					( Origin gFrontEnd )
				)
				( attribute "PACK_TYPE" "0805LF"
					( Origin gFrontEnd )
				)
				( attribute "PART_NUMBER" "C95333-002"
					( Origin gFrontEnd )
				)
				( attribute "PHYS_PAGE" "222"
					( Origin gFrontEnd )
				)
				( attribute "ROOM" "VTT_DEF_PWR_VR"
					( Origin gFrontEnd )
				)
				( attribute "ROT" "0"
					( Origin gFrontEnd )
				)
				( attribute "SEC" "1"
					( Origin gFrontEnd )
				)
				( attribute "SEC_TYPE" "0805LF"
					( Origin gFrontEnd )
				)
				( attribute "TOLERANCE" "20%"
					( Origin gFrontEnd )
				)
				( attribute "VALUE" "22UF"
					( Origin gFrontEnd )
				)
				( attribute "VER" "1"
					( Origin gFrontEnd )
				)
				( attribute "VOLTAGE" "4V"
					( Units "uVoltage" "V" 1.000000)
					( Origin gFrontEnd )
				)
				( attribute "XY" "(3200,575)"
					( Origin gFrontEnd )
				)
				( attribute "CHIPS_PART_NAME" "CAP"
					( Origin gPackager )
				)
				( attribute "CDS_PART_NAME" "CAP_0805LF-22UF,4V,20%,X6S,C95A"
					( Origin gPackager )
				)
				( attribute "GROUP" "PWR_MLCC_CAP"
					( Origin gFrontEnd )
				)
				( objectStatus "C4A1" )
			)
			( gate "@baseboard_fab2_lib.baseboard_fab2(sch_1):page222_i30"
				( attribute "CDS_LIB" "mstr_misc"
					( Origin gPackager )
				)
				( attribute "CDS_LOCATION" "SH5L1"
					( Origin gPackager )
				)
				( attribute "CDS_SEC" "1"
					( Origin gPackager )
				)
				( attribute "LOCATION" "SH5L1"
					( Origin gFrontEnd )
				)
				( attribute "MATERIAL" "EMPTY"
					( Origin gFrontEnd )
				)
				( attribute "PACK_TYPE" "SH0201"
					( Origin gFrontEnd )
				)
				( attribute "PART_NUMBER" "N_A"
					( Origin gFrontEnd )
				)
				( attribute "PHYS_PAGE" "222"
					( Origin gFrontEnd )
				)
				( attribute "PIN_SHORT" "A:B"
					( Origin gFrontEnd )
				)
				( attribute "ROT" "0"
					( Origin gFrontEnd )
				)
				( attribute "SEC" "1"
					( Origin gFrontEnd )
				)
				( attribute "SEC_TYPE" "SH0201"
					( Origin gFrontEnd )
				)
				( attribute "VER" "1"
					( Origin gFrontEnd )
				)
				( attribute "XY" "(4175,-425)"
					( Origin gFrontEnd )
				)
				( attribute "CHIPS_PART_NAME" "SHUNT"
					( Origin gPackager )
				)
				( attribute "CDS_PART_NAME" "SHUNT_SH0201-EMPTY,N_A"
					( Origin gPackager )
				)
				( objectStatus "SH5L1" )
			)
			( gate "@baseboard_fab2_lib.baseboard_fab2(sch_1):page222_i31"
				( attribute "CDS_LIB" "mstr_discrete"
					( Origin gPackager )
				)
				( attribute "CDS_LOCATION" "R4A6"
					( Origin gPackager )
				)
				( attribute "CDS_SEC" "1"
					( Origin gPackager )
				)
				( attribute "LOCATION" "R4A6"
					( Origin gFrontEnd )
				)
				( attribute "MATERIAL" "CHIP"
					( Origin gFrontEnd )
				)
				( attribute "PACK_TYPE" "0402"
					( Origin gFrontEnd )
				)
				( attribute "PART_NUMBER" "G21796-074"
					( Origin gFrontEnd )
				)
				( attribute "PHYS_PAGE" "222"
					( Origin gFrontEnd )
				)
				( attribute "ROT" "0"
					( Origin gFrontEnd )
				)
				( attribute "SEC" "1"
					( Origin gFrontEnd )
				)
				( attribute "SEC_TYPE" "0402"
					( Origin gFrontEnd )
				)
				( attribute "TOLERANCE" "1%"
					( Origin gFrontEnd )
				)
				( attribute "VALUE" "33.2"
					( Origin gFrontEnd )
				)
				( attribute "VER" "1"
					( Origin gFrontEnd )
				)
				( attribute "WATTAGE" "1/16W"
					( Origin gFrontEnd )
				)
				( attribute "XY" "(3475,1375)"
					( Origin gFrontEnd )
				)
				( attribute "CHIPS_PART_NAME" "RES"
					( Origin gPackager )
				)
				( attribute "CDS_PART_NAME" "RES_0402-33.2,1%,1/16W,CHIP,G2A"
					( Origin gPackager )
				)
				( objectStatus "R4A6" )
			)
			( gate "@baseboard_fab2_lib.baseboard_fab2(sch_1):page223_i43"
				( attribute "CDS_LIB" "dev_discrete"
					( Origin gPackager )
				)
				( attribute "CDS_LOCATION" "C1G22"
					( Origin gPackager )
				)
				( attribute "CDS_SEC" "1"
					( Origin gPackager )
				)
				( attribute "LOCATION" "C1G22"
					( Origin gFrontEnd )
				)
				( attribute "MATERIAL" "X7R"
					( Origin gFrontEnd )
				)
				( attribute "PACK_TYPE" "0402V"
					( Origin gFrontEnd )
				)
				( attribute "PART_NUMBER" "A36096-030"
					( Origin gFrontEnd )
				)
				( attribute "PHYS_PAGE" "223"
					( Origin gFrontEnd )
				)
				( attribute "ROOM" "VDDQ_GHJ_PWR_VR"
					( Origin gFrontEnd )
				)
				( attribute "ROT" "0"
					( Origin gFrontEnd )
				)
				( attribute "SEC" "1"
					( Origin gFrontEnd )
				)
				( attribute "SEC_TYPE" "0402V"
					( Origin gFrontEnd )
				)
				( attribute "TOLERANCE" "10%"
					( Origin gFrontEnd )
				)
				( attribute "VALUE" "0.1UF"
					( Origin gFrontEnd )
				)
				( attribute "VER" "1"
					( Origin gFrontEnd )
				)
				( attribute "VOLTAGE" "16V"
					( Units "uVoltage" "V" 1.000000)
					( Origin gFrontEnd )
				)
				( attribute "XY" "(3375,-225)"
					( Origin gFrontEnd )
				)
				( attribute "CHIPS_PART_NAME" "CAP_A"
					( Origin gPackager )
				)
				( attribute "CDS_PART_NAME" "CAP_A_0402V-0.1UF,16V,10%,X7R,A"
					( Origin gPackager )
				)
				( objectStatus "C1G22" )
			)
			( gate "@baseboard_fab2_lib.baseboard_fab2(sch_1):page223_i40"
				( attribute "CDS_LIB" "mstr_discrete"
					( Origin gPackager )
				)
				( attribute "CDS_LOCATION" "C1G21"
					( Origin gPackager )
				)
				( attribute "CDS_SEC" "1"
					( Origin gPackager )
				)
				( attribute "LOCATION" "C1G21"
					( Origin gFrontEnd )
				)
				( attribute "MATERIAL" "X7R"
					( Origin gFrontEnd )
				)
				( attribute "PACK_TYPE" "0402LF"
					( Origin gFrontEnd )
				)
				( attribute "PART_NUMBER" "A36096-046"
					( Origin gFrontEnd )
				)
				( attribute "PHYS_PAGE" "223"
					( Origin gFrontEnd )
				)
				( attribute "ROOM" "VDDQ_GHJ_PWR_VR"
					( Origin gFrontEnd )
				)
				( attribute "ROT" "0"
					( Origin gFrontEnd )
				)
				( attribute "SEC" "1"
					( Origin gFrontEnd )
				)
				( attribute "SEC_TYPE" "0402LF"
					( Origin gFrontEnd )
				)
				( attribute "TOLERANCE" "10%"
					( Origin gFrontEnd )
				)
				( attribute "VALUE" "1000PF"
					( Origin gFrontEnd )
				)
				( attribute "VER" "1"
					( Origin gFrontEnd )
				)
				( attribute "VOLTAGE" "50V"
					( Units "uVoltage" "V" 1.000000)
					( Origin gFrontEnd )
				)
				( attribute "XY" "(3050,650)"
					( Origin gFrontEnd )
				)
				( attribute "CHIPS_PART_NAME" "CAP"
					( Origin gPackager )
				)
				( attribute "CDS_PART_NAME" "CAP_0402LF-1000PF,50V,10%,X7R,A"
					( Origin gPackager )
				)
				( objectStatus "C1G21" )
			)
			( gate "@baseboard_fab2_lib.baseboard_fab2(sch_1):page223_i35"
				( attribute "CDS_LIB" "dev_discrete"
					( Origin gPackager )
				)
				( attribute "CDS_LOCATION" "C1G25"
					( Origin gPackager )
				)
				( attribute "CDS_SEC" "1"
					( Origin gPackager )
				)
				( attribute "LOCATION" "C1G25"
					( Origin gFrontEnd )
				)
				( attribute "MATERIAL" "X7R"
					( Origin gFrontEnd )
				)
				( attribute "PACK_TYPE" "0402V"
					( Origin gFrontEnd )
				)
				( attribute "PART_NUMBER" "A36096-030"
					( Origin gFrontEnd )
				)
				( attribute "PHYS_PAGE" "223"
					( Origin gFrontEnd )
				)
				( attribute "ROOM" "VDDQ_GHJ_PWR_VR"
					( Origin gFrontEnd )
				)
				( attribute "ROT" "0"
					( Origin gFrontEnd )
				)
				( attribute "SEC" "1"
					( Origin gFrontEnd )
				)
				( attribute "SEC_TYPE" "0402V"
					( Origin gFrontEnd )
				)
				( attribute "TOLERANCE" "10%"
					( Origin gFrontEnd )
				)
				( attribute "VALUE" "0.1UF"
					( Origin gFrontEnd )
				)
				( attribute "VER" "1"
					( Origin gFrontEnd )
				)
				( attribute "VOLTAGE" "16V"
					( Units "uVoltage" "V" 1.000000)
					( Origin gFrontEnd )
				)
				( attribute "XY" "(1100,2750)"
					( Origin gFrontEnd )
				)
				( attribute "CHIPS_PART_NAME" "CAP_A"
					( Origin gPackager )
				)
				( attribute "CDS_PART_NAME" "CAP_A_0402V-0.1UF,16V,10%,X7R,A"
					( Origin gPackager )
				)
				( objectStatus "C1G25" )
			)
			( gate "@baseboard_fab2_lib.baseboard_fab2(sch_1):page223_i31"
				( attribute "BOM_COST" "SM_CONTROLLER"
					( Origin gFrontEnd )
				)
				( attribute "CDS_LIB" "mstr_discrete"
					( Origin gPackager )
				)
				( attribute "CDS_LOCATION" "R9U8"
					( Origin gPackager )
				)
				( attribute "CDS_SEC" "1"
					( Origin gPackager )
				)
				( attribute "LOCATION" "R9U8"
					( Origin gFrontEnd )
				)
				( attribute "MATERIAL" "EMPTY"
					( Origin gFrontEnd )
				)
				( attribute "PACK_TYPE" "0402"
					( Origin gFrontEnd )
				)
				( attribute "PART_NUMBER" "G21796-010"
					( Origin gFrontEnd )
				)
				( attribute "PHYS_PAGE" "223"
					( Origin gFrontEnd )
				)
				( attribute "ROOM" "BMC"
					( Origin gFrontEnd )
				)
				( attribute "ROT" "0"
					( Origin gFrontEnd )
				)
				( attribute "SEC" "1"
					( Origin gFrontEnd )
				)
				( attribute "SEC_TYPE" "0402"
					( Origin gFrontEnd )
				)
				( attribute "TOLERANCE" "1%"
					( Origin gFrontEnd )
				)
				( attribute "VALUE" "100.0K"
					( Origin gFrontEnd )
				)
				( attribute "VER" "2"
					( Origin gFrontEnd )
				)
				( attribute "WATTAGE" "1/16W"
					( Origin gFrontEnd )
				)
				( attribute "XY" "(175,3075)"
					( Origin gFrontEnd )
				)
				( attribute "CHIPS_PART_NAME" "RES"
					( Origin gPackager )
				)
				( attribute "CDS_PART_NAME" "RES_0402-100.0K,1%,1/16W,EMPTYA"
					( Origin gPackager )
				)
				( objectStatus "R9U8" )
			)
			( gate "@baseboard_fab2_lib.baseboard_fab2(sch_1):page223_i19"
				( attribute "CDS_LIB" "mstr_discrete"
					( Origin gPackager )
				)
				( attribute "CDS_LOCATION" "RF20"
					( Origin gPackager )
				)
				( attribute "CDS_SEC" "1"
					( Origin gPackager )
				)
				( attribute "LOCATION" "RF20"
					( Origin gFrontEnd )
				)
				( attribute "MATERIAL" "CHIP"
					( Origin gFrontEnd )
				)
				( attribute "PACK_TYPE" "0402"
					( Origin gFrontEnd )
				)
				( attribute "PART_NUMBER" "G85996-004"
					( Origin gFrontEnd )
				)
				( attribute "PHYS_PAGE" "223"
					( Origin gFrontEnd )
				)
				( attribute "ROOM" "SB"
					( Origin gFrontEnd )
				)
				( attribute "ROT" "0"
					( Origin gFrontEnd )
				)
				( attribute "SEC" "1"
					( Origin gFrontEnd )
				)
				( attribute "SEC_TYPE" "0402"
					( Origin gFrontEnd )
				)
				( attribute "TOLERANCE" "0.1%"
					( Origin gFrontEnd )
				)
				( attribute "VALUE" "1.0K"
					( Origin gFrontEnd )
				)
				( attribute "VER" "1"
					( Origin gFrontEnd )
				)
				( attribute "WATTAGE" "1/16W"
					( Origin gFrontEnd )
				)
				( attribute "XY" "(-225,2450)"
					( Origin gFrontEnd )
				)
				( attribute "CHIPS_PART_NAME" "RES"
					( Origin gPackager )
				)
				( attribute "CDS_PART_NAME" "RES_0402-1.0K,0.1%,1/16W,CHIP,A"
					( Origin gPackager )
				)
				( attribute "GROUP" "POWER_FAIR"
					( Origin gFrontEnd )
				)
				( attribute "BOM_SS" "NOPOP"
					( Origin gFrontEnd )
				)
				( objectStatus "RF20" )
			)
			( gate "@baseboard_fab2_lib.baseboard_fab2(sch_1):page223_i18"
				( attribute "CDS_LIB" "mstr_discrete"
					( Origin gPackager )
				)
				( attribute "CDS_LOCATION" "R1G7"
					( Origin gPackager )
				)
				( attribute "CDS_SEC" "1"
					( Origin gPackager )
				)
				( attribute "LOCATION" "R1G7"
					( Origin gFrontEnd )
				)
				( attribute "MATERIAL" "CHIP"
					( Origin gFrontEnd )
				)
				( attribute "PACK_TYPE" "0402"
					( Origin gFrontEnd )
				)
				( attribute "PART_NUMBER" "G21796-009"
					( Origin gFrontEnd )
				)
				( attribute "PHYS_PAGE" "223"
					( Origin gFrontEnd )
				)
				( attribute "ROOM" "VDDQ_GHJ_PWR_VR"
					( Origin gFrontEnd )
				)
				( attribute "ROT" "0"
					( Origin gFrontEnd )
				)
				( attribute "SEC" "1"
					( Origin gFrontEnd )
				)
				( attribute "SEC_TYPE" "0402"
					( Origin gFrontEnd )
				)
				( attribute "TOLERANCE" "1%"
					( Origin gFrontEnd )
				)
				( attribute "VALUE" "150.0"
					( Origin gFrontEnd )
				)
				( attribute "VER" "1"
					( Origin gFrontEnd )
				)
				( attribute "WATTAGE" "1/16W"
					( Origin gFrontEnd )
				)
				( attribute "XY" "(-225,2625)"
					( Origin gFrontEnd )
				)
				( attribute "CHIPS_PART_NAME" "RES"
					( Origin gPackager )
				)
				( attribute "CDS_PART_NAME" "RES_0402-150.0,1%,1/16W,CHIP,GA"
					( Origin gPackager )
				)
				( objectStatus "R1G7" )
			)
			( gate "@baseboard_fab2_lib.baseboard_fab2(sch_1):page223_i15"
				( attribute "CDS_LIB" "w_hdl"
					( Origin gPackager )
				)
				( attribute "CDS_LMAN_SYM_OUTLINE" "-50,25,50,-25"
					( Origin gPackager )
				)
				( attribute "CDS_LOCATION" "CF19"
					( Origin gPackager )
				)
				( attribute "CDS_SEC" "1"
					( Origin gPackager )
				)
				( attribute "LOCATION" "CF19"
					( Origin gFrontEnd )
				)
				( attribute "PACK_TYPE" "SMD-BCG"
					( Origin gFrontEnd )
				)
				( attribute "PART_NUMBER" "78.22034.1FL"
					( Origin gFrontEnd )
				)
				( attribute "PHYS_PAGE" "223"
					( Origin gFrontEnd )
				)
				( attribute "ROT" "1"
					( Origin gFrontEnd )
				)
				( attribute "SEC" "1"
					( Origin gPackager )
				)
				( attribute "VALUE" "SC22P50V2JN-4GP"
					( Origin gFrontEnd )
				)
				( attribute "VER" "1"
					( Origin gFrontEnd )
				)
				( attribute "XY" "(-1100,2275)"
					( Origin gFrontEnd )
				)
				( attribute "CHIPS_PART_NAME" "SC22P50V2JN-4GP"
					( Origin gPackager )
				)
				( attribute "CDS_PART_NAME" "SC22P50V2JN-4GP_SMD-BCG-SC22P5A"
					( Origin gPackager )
				)
				( attribute "ATTRIBUTE" "22PF"
					( Origin gFrontEnd )
				)
				( attribute "PACK_SIZE" "0402"
					( Origin gFrontEnd )
				)
				( attribute "RATED" "50V"
					( Origin gFrontEnd )
				)
				( attribute "TOLERANCE" "5%"
					( Origin gFrontEnd )
				)
				( attribute "TYPE" "NPO"
					( Origin gFrontEnd )
				)
				( attribute "GROUP" "POWER_FAIR"
					( Origin gFrontEnd )
				)
				( objectStatus "CF19" )
			)
			( gate "@baseboard_fab2_lib.baseboard_fab2(sch_1):page223_i12"
				( attribute "CDS_LIB" "mstr_discrete"
					( Origin gPackager )
				)
				( attribute "CDS_LOCATION" "C1G16"
					( Origin gPackager )
				)
				( attribute "CDS_SEC" "1"
					( Origin gPackager )
				)
				( attribute "LOCATION" "C1G16"
					( Origin gFrontEnd )
				)
				( attribute "MATERIAL" "X7R"
					( Origin gFrontEnd )
				)
				( attribute "NO_XNET_CONNECTION" "1"
					( Origin gFrontEnd )
				)
				( attribute "PACK_TYPE" "0402LF"
					( Origin gFrontEnd )
				)
				( attribute "PART_NUMBER" "A36096-050"
					( Origin gFrontEnd )
				)
				( attribute "PHYS_PAGE" "223"
					( Origin gFrontEnd )
				)
				( attribute "ROOM" "VDDQ_GHJ_PWR_VR"
					( Origin gFrontEnd )
				)
				( attribute "ROT" "0"
					( Origin gFrontEnd )
				)
				( attribute "SEC" "1"
					( Origin gFrontEnd )
				)
				( attribute "SEC_TYPE" "0402LF"
					( Origin gFrontEnd )
				)
				( attribute "TOLERANCE" "10%"
					( Origin gFrontEnd )
				)
				( attribute "VALUE" "220PF"
					( Origin gFrontEnd )
				)
				( attribute "VER" "1"
					( Origin gFrontEnd )
				)
				( attribute "VOLTAGE" "50V"
					( Units "uVoltage" "V" 1.000000)
					( Origin gFrontEnd )
				)
				( attribute "XY" "(-1450,575)"
					( Origin gFrontEnd )
				)
				( attribute "CHIPS_PART_NAME" "CAP"
					( Origin gPackager )
				)
				( attribute "CDS_PART_NAME" "CAP_0402LF-220PF,50V,10%,X7R,AA"
					( Origin gPackager )
				)
				( objectStatus "C1G16" )
			)
			( gate "@baseboard_fab2_lib.baseboard_fab2(sch_1):page268_i38"
				( attribute "CDS_LIB" "mstr_ttl"
					( Origin gPackager )
				)
				( attribute "CDS_LOCATION" "U25W16"
					( Origin gPackager )
				)
				( attribute "HAS_FIXED_SIZE" "4"
					( Origin gFrontEnd )
				)
				( attribute "LOCATION" "U25W16"
					( Origin gFrontEnd )
				)
				( attribute "MATERIAL" "IC"
					( Origin gFrontEnd )
				)
				( attribute "PACK_TYPE" "QFNLF"
					( Origin gFrontEnd )
				)
				( attribute "PART_NUMBER" "D18317-001"
					( Origin gFrontEnd )
				)
				( attribute "PHYS_PAGE" "255"
					( Origin gFrontEnd )
				)
				( attribute "ROOM" "DEBUG"
					( Origin gFrontEnd )
				)
				( attribute "ROT" "0"
					( Origin gFrontEnd )
				)
				( attribute "SIZE" "4"
					( Origin gFrontEnd )
				)
				( attribute "VALUE" "74CBTLV3126"
					( Origin gFrontEnd )
				)
				( attribute "VER" "3"
					( Origin gFrontEnd )
				)
				( attribute "XY" "(-2900,5000)"
					( Origin gFrontEnd )
				)
				( attribute "CHIPS_PART_NAME" "TTL3126"
					( Origin gPackager )
				)
				( attribute "CDS_PART_NAME" "TTL3126_QFNLF-74CBTLV3126,IC,DB"
					( Origin gPackager )
				)
				( objectStatus "U25W16" )
			)
			( gate "@baseboard_fab2_lib.baseboard_fab2(sch_1):page223_i13"
				( attribute "CDS_LIB" "mstr_discrete"
					( Origin gPackager )
				)
				( attribute "CDS_LOCATION" "R1G5"
					( Origin gPackager )
				)
				( attribute "CDS_SEC" "1"
					( Origin gPackager )
				)
				( attribute "LOCATION" "R1G5"
					( Origin gFrontEnd )
				)
				( attribute "MATERIAL" "CHIP"
					( Origin gFrontEnd )
				)
				( attribute "NO_XNET_CONNECTION" "1"
					( Origin gFrontEnd )
				)
				( attribute "PACK_TYPE" "0402"
					( Origin gFrontEnd )
				)
				( attribute "PART_NUMBER" "G21796-066"
					( Origin gFrontEnd )
				)
				( attribute "PHYS_PAGE" "223"
					( Origin gFrontEnd )
				)
				( attribute "ROOM" "VDDQ_GHJ_PWR_VR"
					( Origin gFrontEnd )
				)
				( attribute "ROT" "0"
					( Origin gFrontEnd )
				)
				( attribute "SEC" "1"
					( Origin gFrontEnd )
				)
				( attribute "SEC_TYPE" "0402"
					( Origin gFrontEnd )
				)
				( attribute "TOLERANCE" "1%"
					( Origin gFrontEnd )
				)
				( attribute "VALUE" "10.0"
					( Origin gFrontEnd )
				)
				( attribute "VER" "1"
					( Origin gFrontEnd )
				)
				( attribute "WATTAGE" "1/16W"
					( Origin gFrontEnd )
				)
				( attribute "XY" "(-1725,725)"
					( Origin gFrontEnd )
				)
				( attribute "CHIPS_PART_NAME" "RES"
					( Origin gPackager )
				)
				( attribute "CDS_PART_NAME" "RES_0402-10.0,1%,1/16W,CHIP,G2A"
					( Origin gPackager )
				)
				( objectStatus "R1G5" )
			)
			( gate "@baseboard_fab2_lib.baseboard_fab2(sch_1):page223_i14"
				( attribute "CDS_LIB" "mstr_discrete"
					( Origin gPackager )
				)
				( attribute "CDS_LOCATION" "R9U7"
					( Origin gPackager )
				)
				( attribute "CDS_SEC" "1"
					( Origin gPackager )
				)
				( attribute "LOCATION" "R9U7"
					( Origin gFrontEnd )
				)
				( attribute "MATERIAL" "CHIP"
					( Origin gFrontEnd )
				)
				( attribute "PACK_TYPE" "0402"
					( Origin gFrontEnd )
				)
				( attribute "PART_NUMBER" "G21497-005"
					( Origin gFrontEnd )
				)
				( attribute "PHYS_PAGE" "223"
					( Origin gFrontEnd )
				)
				( attribute "ROOM" "PVCCIN_CPU0_VR"
					( Origin gFrontEnd )
				)
				( attribute "ROT" "0"
					( Origin gFrontEnd )
				)
				( attribute "SEC" "1"
					( Origin gFrontEnd )
				)
				( attribute "TOLERANCE" "5%"
					( Origin gFrontEnd )
				)
				( attribute "VALUE" "0.0"
					( Origin gFrontEnd )
				)
				( attribute "VER" "1"
					( Origin gFrontEnd )
				)
				( attribute "WATTAGE" "1/16W"
					( Origin gFrontEnd )
				)
				( attribute "XY" "(-1500,1150)"
					( Origin gFrontEnd )
				)
				( attribute "CHIPS_PART_NAME" "RES"
					( Origin gPackager )
				)
				( attribute "CDS_PART_NAME" "RES_0402-0.0,5%,1/16W,CHIP,G21A"
					( Origin gPackager )
				)
				( attribute "SEC_TYPE" "0402"
					( Origin gFrontEnd )
				)
				( objectStatus "R9U7" )
			)
			( gate "@baseboard_fab2_lib.baseboard_fab2(sch_1):page223_i16"
				( attribute "CDS_LIB" "mstr_discrete"
					( Origin gPackager )
				)
				( attribute "CDS_LOCATION" "RF19"
					( Origin gPackager )
				)
				( attribute "CDS_SEC" "1"
					( Origin gPackager )
				)
				( attribute "LOCATION" "RF19"
					( Origin gFrontEnd )
				)
				( attribute "MATERIAL" "CHIP"
					( Origin gFrontEnd )
				)
				( attribute "PACK_TYPE" "0402"
					( Origin gFrontEnd )
				)
				( attribute "PART_NUMBER" "G85996-004"
					( Origin gFrontEnd )
				)
				( attribute "PHYS_PAGE" "223"
					( Origin gFrontEnd )
				)
				( attribute "ROOM" "SB"
					( Origin gFrontEnd )
				)
				( attribute "ROT" "0"
					( Origin gFrontEnd )
				)
				( attribute "SEC" "1"
					( Origin gFrontEnd )
				)
				( attribute "SEC_TYPE" "0402"
					( Origin gFrontEnd )
				)
				( attribute "TOLERANCE" "0.1%"
					( Origin gFrontEnd )
				)
				( attribute "VALUE" "1.0K"
					( Origin gFrontEnd )
				)
				( attribute "VER" "1"
					( Origin gFrontEnd )
				)
				( attribute "WATTAGE" "1/16W"
					( Origin gFrontEnd )
				)
				( attribute "XY" "(-1100,2450)"
					( Origin gFrontEnd )
				)
				( attribute "CHIPS_PART_NAME" "RES"
					( Origin gPackager )
				)
				( attribute "CDS_PART_NAME" "RES_0402-1.0K,0.1%,1/16W,CHIP,A"
					( Origin gPackager )
				)
				( attribute "GROUP" "POWER_FAIR"
					( Origin gFrontEnd )
				)
				( attribute "FAIR_SS" "064.9530D.M001"
					( Origin gFrontEnd )
				)
				( objectStatus "RF19" )
			)
			( gate "@baseboard_fab2_lib.baseboard_fab2(sch_1):page223_i17"
				( attribute "CDS_LIB" "w_hdl"
					( Origin gPackager )
				)
				( attribute "CDS_LMAN_SYM_OUTLINE" "-50,25,50,-25"
					( Origin gPackager )
				)
				( attribute "CDS_LOCATION" "CF20"
					( Origin gPackager )
				)
				( attribute "CDS_SEC" "1"
					( Origin gPackager )
				)
				( attribute "LOCATION" "CF20"
					( Origin gFrontEnd )
				)
				( attribute "PACK_TYPE" "SMD-BCG"
					( Origin gFrontEnd )
				)
				( attribute "PART_NUMBER" "78.22034.1FL"
					( Origin gFrontEnd )
				)
				( attribute "PHYS_PAGE" "223"
					( Origin gFrontEnd )
				)
				( attribute "ROT" "1"
					( Origin gFrontEnd )
				)
				( attribute "SEC" "1"
					( Origin gPackager )
				)
				( attribute "VALUE" "SC22P50V2JN-4GP"
					( Origin gFrontEnd )
				)
				( attribute "VER" "1"
					( Origin gFrontEnd )
				)
				( attribute "XY" "(-225,2275)"
					( Origin gFrontEnd )
				)
				( attribute "CHIPS_PART_NAME" "SC22P50V2JN-4GP"
					( Origin gPackager )
				)
				( attribute "CDS_PART_NAME" "SC22P50V2JN-4GP_SMD-BCG-SC22P5A"
					( Origin gPackager )
				)
				( attribute "ATTRIBUTE" "22PF"
					( Origin gFrontEnd )
				)
				( attribute "PACK_SIZE" "0402"
					( Origin gFrontEnd )
				)
				( attribute "RATED" "50V"
					( Origin gFrontEnd )
				)
				( attribute "TOLERANCE" "5%"
					( Origin gFrontEnd )
				)
				( attribute "TYPE" "NPO"
					( Origin gFrontEnd )
				)
				( attribute "GROUP" "POWER_FAIR"
					( Origin gFrontEnd )
				)
				( attribute "BOM_SS" "NOPOP"
					( Origin gFrontEnd )
				)
				( objectStatus "CF20" )
			)
			( gate "@baseboard_fab2_lib.baseboard_fab2(sch_1):page226_i55"
				( attribute "CDS_LIB" "mstr_discrete"
					( Origin gPackager )
				)
				( attribute "CDS_LOCATION" "R1B5"
					( Origin gPackager )
				)
				( attribute "CDS_SEC" "1"
					( Origin gPackager )
				)
				( attribute "LOCATION" "R1B5"
					( Origin gFrontEnd )
				)
				( attribute "MATERIAL" "CHIP"
					( Origin gFrontEnd )
				)
				( attribute "PACK_TYPE" "0402"
					( Origin gFrontEnd )
				)
				( attribute "PART_NUMBER" "G21796-250"
					( Origin gFrontEnd )
				)
				( attribute "PHYS_PAGE" "226"
					( Origin gFrontEnd )
				)
				( attribute "ROOM" "VDDQ_KLM_PWR_VR"
					( Origin gFrontEnd )
				)
				( attribute "ROT" "0"
					( Origin gFrontEnd )
				)
				( attribute "SEC" "1"
					( Origin gFrontEnd )
				)
				( attribute "SEC_TYPE" "0402"
					( Origin gFrontEnd )
				)
				( attribute "TOLERANCE" "1.0%"
					( Origin gFrontEnd )
				)
				( attribute "VALUE" "22.1"
					( Origin gFrontEnd )
				)
				( attribute "VER" "1"
					( Origin gFrontEnd )
				)
				( attribute "WATTAGE" "1/16W"
					( Origin gFrontEnd )
				)
				( attribute "XY" "(3025,1825)"
					( Origin gFrontEnd )
				)
				( attribute "CHIPS_PART_NAME" "RES"
					( Origin gPackager )
				)
				( attribute "CDS_PART_NAME" "RES_0402-22.1,1.0%,1/16W,CHIP,A"
					( Origin gPackager )
				)
				( attribute "POP" "NOPOP"
					( Origin gFrontEnd )
				)
				( objectStatus "R1B5" )
			)
			( gate "@baseboard_fab2_lib.baseboard_fab2(sch_1):page226_i54"
				( attribute "CDS_LIB" "mstr_discrete"
					( Origin gPackager )
				)
				( attribute "CDS_LOCATION" "R1B4"
					( Origin gPackager )
				)
				( attribute "CDS_SEC" "1"
					( Origin gPackager )
				)
				( attribute "LOCATION" "R1B4"
					( Origin gFrontEnd )
				)
				( attribute "MATERIAL" "CHIP"
					( Origin gFrontEnd )
				)
				( attribute "PACK_TYPE" "0402"
					( Origin gFrontEnd )
				)
				( attribute "PART_NUMBER" "G21796-074"
					( Origin gFrontEnd )
				)
				( attribute "PHYS_PAGE" "226"
					( Origin gFrontEnd )
				)
				( attribute "ROT" "0"
					( Origin gFrontEnd )
				)
				( attribute "SEC" "1"
					( Origin gFrontEnd )
				)
				( attribute "SEC_TYPE" "0402"
					( Origin gFrontEnd )
				)
				( attribute "TOLERANCE" "1%"
					( Origin gFrontEnd )
				)
				( attribute "VALUE" "33.2"
					( Origin gFrontEnd )
				)
				( attribute "VER" "1"
					( Origin gFrontEnd )
				)
				( attribute "WATTAGE" "1/16W"
					( Origin gFrontEnd )
				)
				( attribute "XY" "(3025,1725)"
					( Origin gFrontEnd )
				)
				( attribute "CHIPS_PART_NAME" "RES"
					( Origin gPackager )
				)
				( attribute "CDS_PART_NAME" "RES_0402-33.2,1%,1/16W,CHIP,G2A"
					( Origin gPackager )
				)
				( objectStatus "R1B4" )
			)
			( gate "@baseboard_fab2_lib.baseboard_fab2(sch_1):page229_i37"
				( attribute "BOM_COST" "MEM_VRD_VTT_GHJ"
					( Origin gFrontEnd )
				)
				( attribute "CDS_LIB" "mstr_vreg"
					( Origin gPackager )
				)
				( attribute "CDS_LMAN_SYM_OUTLINE" "-250,350,250,-350"
					( Origin gPackager )
				)
				( attribute "CDS_LOCATION" "EU4G2"
					( Origin gPackager )
				)
				( attribute "CDS_SEC" "1"
					( Origin gPackager )
				)
				( attribute "LOCATION" "EU4G2"
					( Origin gFrontEnd )
				)
				( attribute "MATERIAL" "IC"
					( Origin gFrontEnd )
				)
				( attribute "PACK_TYPE" "DFN"
					( Origin gFrontEnd )
				)
				( attribute "PART_NUMBER" "H55101-001"
					( Origin gFrontEnd )
				)
				( attribute "PHYS_PAGE" "229"
					( Origin gFrontEnd )
				)
				( attribute "ROOM" "VTT_GHJ_PWR_VR"
					( Origin gFrontEnd )
				)
				( attribute "ROT" "0"
					( Origin gFrontEnd )
				)
				( attribute "SEC" "1"
					( Origin gFrontEnd )
				)
				( attribute "SEC_TYPE" "DFN"
					( Origin gFrontEnd )
				)
				( attribute "VER" "1"
					( Origin gFrontEnd )
				)
				( attribute "XY" "(1425,900)"
					( Origin gFrontEnd )
				)
				( attribute "CHIPS_PART_NAME" "MIC5166"
					( Origin gPackager )
				)
				( attribute "CDS_PART_NAME" "MIC5166_DFN-IC,H55101-001"
					( Origin gPackager )
				)
				( objectStatus "EU4G2" )
			)
			( gate "@baseboard_fab2_lib.baseboard_fab2(sch_1):page223_i27"
				( attribute "CDS_LIB" "mstr_discrete"
					( Origin gPackager )
				)
				( attribute "CDS_LOCATION" "C1G24"
					( Origin gPackager )
				)
				( attribute "CDS_SEC" "1"
					( Origin gPackager )
				)
				( attribute "LOCATION" "C1G24"
					( Origin gFrontEnd )
				)
				( attribute "MATERIAL" "X7R"
					( Origin gFrontEnd )
				)
				( attribute "PACK_TYPE" "0402LF"
					( Origin gFrontEnd )
				)
				( attribute "PART_NUMBER" "A36096-050"
					( Origin gFrontEnd )
				)
				( attribute "PHYS_PAGE" "223"
					( Origin gFrontEnd )
				)
				( attribute "ROOM" "VDDQ_GHJ_PWR_VR"
					( Origin gFrontEnd )
				)
				( attribute "ROT" "2"
					( Origin gFrontEnd )
				)
				( attribute "SEC" "1"
					( Origin gFrontEnd )
				)
				( attribute "SEC_TYPE" "0402LF"
					( Origin gFrontEnd )
				)
				( attribute "TOLERANCE" "10%"
					( Origin gFrontEnd )
				)
				( attribute "VALUE" "220PF"
					( Origin gFrontEnd )
				)
				( attribute "VER" "1"
					( Origin gFrontEnd )
				)
				( attribute "VOLTAGE" "50V"
					( Units "uVoltage" "V" 1.000000)
					( Origin gFrontEnd )
				)
				( attribute "XY" "(100,400)"
					( Origin gFrontEnd )
				)
				( attribute "CHIPS_PART_NAME" "CAP"
					( Origin gPackager )
				)
				( attribute "CDS_PART_NAME" "CAP_0402LF-220PF,50V,10%,X7R,AA"
					( Origin gPackager )
				)
				( objectStatus "C1G24" )
			)
			( gate "@baseboard_fab2_lib.baseboard_fab2(sch_1):page223_i32"
				( attribute "CDS_LIB" "mstr_discrete"
					( Origin gPackager )
				)
				( attribute "CDS_LOCATION" "R9U10"
					( Origin gPackager )
				)
				( attribute "CDS_SEC" "1"
					( Origin gPackager )
				)
				( attribute "LOCATION" "R9U10"
					( Origin gFrontEnd )
				)
				( attribute "MATERIAL" "CHIP"
					( Origin gFrontEnd )
				)
				( attribute "PACK_TYPE" "0402"
					( Origin gFrontEnd )
				)
				( attribute "PART_NUMBER" "G21497-005"
					( Origin gFrontEnd )
				)
				( attribute "PHYS_PAGE" "223"
					( Origin gFrontEnd )
				)
				( attribute "ROOM" "VDDQ_GHJ_PWR_VR"
					( Origin gFrontEnd )
				)
				( attribute "ROT" "0"
					( Origin gFrontEnd )
				)
				( attribute "SEC" "1"
					( Origin gFrontEnd )
				)
				( attribute "SEC_TYPE" "0402"
					( Origin gFrontEnd )
				)
				( attribute "TOLERANCE" "5%"
					( Origin gFrontEnd )
				)
				( attribute "VALUE" "0.0"
					( Origin gFrontEnd )
				)
				( attribute "VER" "2"
					( Origin gFrontEnd )
				)
				( attribute "WATTAGE" "1/16W"
					( Origin gFrontEnd )
				)
				( attribute "XY" "(900,3100)"
					( Origin gFrontEnd )
				)
				( attribute "CHIPS_PART_NAME" "RES"
					( Origin gPackager )
				)
				( attribute "CDS_PART_NAME" "RES_0402-0.0,5%,1/16W,CHIP,G21A"
					( Origin gPackager )
				)
				( objectStatus "R9U10" )
			)
			( gate "@baseboard_fab2_lib.baseboard_fab2(sch_1):page223_i36"
				( attribute "CDS_LIB" "dev_discrete"
					( Origin gPackager )
				)
				( attribute "CDS_LOCATION" "C1G27"
					( Origin gPackager )
				)
				( attribute "CDS_SEC" "1"
					( Origin gPackager )
				)
				( attribute "LOCATION" "C1G27"
					( Origin gFrontEnd )
				)
				( attribute "MATERIAL" "X6S"
					( Origin gFrontEnd )
				)
				( attribute "PACK_TYPE" "0402V"
					( Origin gFrontEnd )
				)
				( attribute "PART_NUMBER" "D97712-004"
					( Origin gFrontEnd )
				)
				( attribute "PHYS_PAGE" "223"
					( Origin gFrontEnd )
				)
				( attribute "ROOM" "VDDQ_GHJ_PWR_VR"
					( Origin gFrontEnd )
				)
				( attribute "ROT" "0"
					( Origin gFrontEnd )
				)
				( attribute "SEC" "1"
					( Origin gFrontEnd )
				)
				( attribute "SEC_TYPE" "0402V"
					( Origin gFrontEnd )
				)
				( attribute "TOLERANCE" "10%"
					( Origin gFrontEnd )
				)
				( attribute "VALUE" "1.0UF"
					( Origin gFrontEnd )
				)
				( attribute "VER" "1"
					( Origin gFrontEnd )
				)
				( attribute "VOLTAGE" "6.3V"
					( Units "uVoltage" "V" 1.000000)
					( Origin gFrontEnd )
				)
				( attribute "XY" "(1600,2750)"
					( Origin gFrontEnd )
				)
				( attribute "CHIPS_PART_NAME" "CAP_A"
					( Origin gPackager )
				)
				( attribute "CDS_PART_NAME" "CAP_A_0402V-1.0UF,6.3V,10%,X6SA"
					( Origin gPackager )
				)
				( objectStatus "C1G27" )
			)
			( gate "@baseboard_fab2_lib.baseboard_fab2(sch_1):page230_i43"
				( attribute "BOM_COST" "MEM_VRD_PVDDQ_CD"
					( Origin gFrontEnd )
				)
				( attribute "CDS_LIB" "mstr_discrete"
					( Origin gPackager )
				)
				( attribute "CDS_LOCATION" "C6W13"
					( Origin gPackager )
				)
				( attribute "CDS_SEC" "1"
					( Origin gPackager )
				)
				( attribute "LOCATION" "C6W13"
					( Origin gFrontEnd )
				)
				( attribute "MATERIAL" "X5R"
					( Origin gFrontEnd )
				)
				( attribute "NEW_MATERIAL" "X6S"
					( Origin gFrontEnd )
				)
				( attribute "PACK_TYPE" "0805"
					( Origin gFrontEnd )
				)
				( attribute "PART_NUMBER" "602433-112"
					( Origin gFrontEnd )
				)
				( attribute "PHYS_PAGE" "230"
					( Origin gFrontEnd )
				)
				( attribute "ROOM" "VDDQ_ABC_PWR_VR"
					( Origin gFrontEnd )
				)
				( attribute "ROT" "0"
					( Origin gFrontEnd )
				)
				( attribute "SEC" "1"
					( Origin gFrontEnd )
				)
				( attribute "SEC_TYPE" "0805"
					( Origin gFrontEnd )
				)
				( attribute "TOLERANCE" "20%"
					( Origin gFrontEnd )
				)
				( attribute "VALUE" "100UF"
					( Origin gFrontEnd )
				)
				( attribute "VER" "1"
					( Origin gFrontEnd )
				)
				( attribute "VOLTAGE" "4V"
					( Units "uVoltage" "V" 1.000000)
					( Origin gFrontEnd )
				)
				( attribute "XY" "(3125,325)"
					( Origin gFrontEnd )
				)
				( attribute "CHIPS_PART_NAME" "CAP"
					( Origin gPackager )
				)
				( attribute "CDS_PART_NAME" "CAP_0805-100UF,4V,20%,X5R,6024A"
					( Origin gPackager )
				)
				( attribute "GROUP" "PWR_MLCC_CAP"
					( Origin gFrontEnd )
				)
				( attribute "NEW_PN" "078.1071T.M002"
					( Origin gFrontEnd )
				)
				( objectStatus "C6W13" )
			)
			( gate "@baseboard_fab2_lib.baseboard_fab2(sch_1):page223_i41"
				( attribute "CDS_LIB" "mstr_discrete"
					( Origin gPackager )
				)
				( attribute "CDS_LOCATION" "R1G10"
					( Origin gPackager )
				)
				( attribute "CDS_SEC" "1"
					( Origin gPackager )
				)
				( attribute "LOCATION" "R1G10"
					( Origin gFrontEnd )
				)
				( attribute "MATERIAL" "CHIP"
					( Origin gFrontEnd )
				)
				( attribute "PACK_TYPE" "0402"
					( Origin gFrontEnd )
				)
				( attribute "PART_NUMBER" "G21497-005"
					( Origin gFrontEnd )
				)
				( attribute "PHYS_PAGE" "223"
					( Origin gFrontEnd )
				)
				( attribute "ROOM" "VDDQ_GHJ_PWR_VR"
					( Origin gFrontEnd )
				)
				( attribute "ROT" "0"
					( Origin gFrontEnd )
				)
				( attribute "SEC" "1"
					( Origin gFrontEnd )
				)
				( attribute "SEC_TYPE" "0402"
					( Origin gFrontEnd )
				)
				( attribute "TOLERANCE" "5%"
					( Origin gFrontEnd )
				)
				( attribute "VALUE" "0.0"
					( Origin gFrontEnd )
				)
				( attribute "VER" "1"
					( Origin gFrontEnd )
				)
				( attribute "WATTAGE" "1/16W"
					( Origin gFrontEnd )
				)
				( attribute "XY" "(2850,1350)"
					( Origin gFrontEnd )
				)
				( attribute "CHIPS_PART_NAME" "RES"
					( Origin gPackager )
				)
				( attribute "CDS_PART_NAME" "RES_0402-0.0,5%,1/16W,CHIP,G21A"
					( Origin gPackager )
				)
				( objectStatus "R1G10" )
			)
			( gate "@baseboard_fab2_lib.baseboard_fab2(sch_1):page223_i44"
				( attribute "CDS_LIB" "dev_discrete"
					( Origin gPackager )
				)
				( attribute "CDS_LOCATION" "C1G23"
					( Origin gPackager )
				)
				( attribute "CDS_SEC" "1"
					( Origin gPackager )
				)
				( attribute "LOCATION" "C1G23"
					( Origin gFrontEnd )
				)
				( attribute "MATERIAL" "X6S"
					( Origin gFrontEnd )
				)
				( attribute "PACK_TYPE" "0402V"
					( Origin gFrontEnd )
				)
				( attribute "PART_NUMBER" "D97712-004"
					( Origin gFrontEnd )
				)
				( attribute "PHYS_PAGE" "223"
					( Origin gFrontEnd )
				)
				( attribute "ROOM" "VDDQ_GHJ_PWR_VR"
					( Origin gFrontEnd )
				)
				( attribute "ROT" "0"
					( Origin gFrontEnd )
				)
				( attribute "SEC" "1"
					( Origin gFrontEnd )
				)
				( attribute "SEC_TYPE" "0402V"
					( Origin gFrontEnd )
				)
				( attribute "TOLERANCE" "10%"
					( Origin gFrontEnd )
				)
				( attribute "VALUE" "1.0UF"
					( Origin gFrontEnd )
				)
				( attribute "VER" "1"
					( Origin gFrontEnd )
				)
				( attribute "VOLTAGE" "6.3V"
					( Units "uVoltage" "V" 1.000000)
					( Origin gFrontEnd )
				)
				( attribute "XY" "(4025,-225)"
					( Origin gFrontEnd )
				)
				( attribute "CHIPS_PART_NAME" "CAP_A"
					( Origin gPackager )
				)
				( attribute "CDS_PART_NAME" "CAP_A_0402V-1.0UF,6.3V,10%,X6SA"
					( Origin gPackager )
				)
				( objectStatus "C1G23" )
			)
			( gate "@baseboard_fab2_lib.baseboard_fab2(sch_1):page223_i50"
				( attribute "CDS_LIB" "mstr_discrete"
					( Origin gPackager )
				)
				( attribute "CDS_LOCATION" "R1G9"
					( Origin gPackager )
				)
				( attribute "CDS_SEC" "1"
					( Origin gPackager )
				)
				( attribute "LOCATION" "R1G9"
					( Origin gFrontEnd )
				)
				( attribute "MATERIAL" "CHIP"
					( Origin gFrontEnd )
				)
				( attribute "PACK_TYPE" "0402"
					( Origin gFrontEnd )
				)
				( attribute "PART_NUMBER" "G21497-005"
					( Origin gFrontEnd )
				)
				( attribute "PHYS_PAGE" "223"
					( Origin gFrontEnd )
				)
				( attribute "ROOM" "VDDQ_GHJ_PWR_VR"
					( Origin gFrontEnd )
				)
				( attribute "ROT" "0"
					( Origin gFrontEnd )
				)
				( attribute "SEC" "1"
					( Origin gFrontEnd )
				)
				( attribute "SEC_TYPE" "0402"
					( Origin gFrontEnd )
				)
				( attribute "TOLERANCE" "5%"
					( Origin gFrontEnd )
				)
				( attribute "VALUE" "0.0"
					( Origin gFrontEnd )
				)
				( attribute "VER" "1"
					( Origin gFrontEnd )
				)
				( attribute "WATTAGE" "1/16W"
					( Origin gFrontEnd )
				)
				( attribute "XY" "(2875,2050)"
					( Origin gFrontEnd )
				)
				( attribute "CHIPS_PART_NAME" "RES"
					( Origin gPackager )
				)
				( attribute "CDS_PART_NAME" "RES_0402-0.0,5%,1/16W,CHIP,G21A"
					( Origin gPackager )
				)
				( objectStatus "R1G9" )
			)
			( gate "@baseboard_fab2_lib.baseboard_fab2(sch_1):page223_i53"
				( attribute "CDS_LIB" "mstr_discrete"
					( Origin gPackager )
				)
				( attribute "CDS_LOCATION" "R12W33"
					( Origin gPackager )
				)
				( attribute "CDS_SEC" "1"
					( Origin gPackager )
				)
				( attribute "LOCATION" "R12W33"
					( Origin gFrontEnd )
				)
				( attribute "MATERIAL" "EMPTY"
					( Origin gFrontEnd )
				)
				( attribute "PACK_TYPE" "0402"
					( Origin gFrontEnd )
				)
				( attribute "PART_NUMBER" "G21497-005"
					( Origin gFrontEnd )
				)
				( attribute "PHYS_PAGE" "223"
					( Origin gFrontEnd )
				)
				( attribute "ROOM" "NV_DIMM"
					( Origin gFrontEnd )
				)
				( attribute "ROT" "0"
					( Origin gFrontEnd )
				)
				( attribute "SEC" "1"
					( Origin gFrontEnd )
				)
				( attribute "SEC_TYPE" "0402"
					( Origin gFrontEnd )
				)
				( attribute "TOLERANCE" "5%"
					( Origin gFrontEnd )
				)
				( attribute "VALUE" "0.0"
					( Origin gFrontEnd )
				)
				( attribute "VER" "1"
					( Origin gFrontEnd )
				)
				( attribute "WATTAGE" "1/16W"
					( Origin gFrontEnd )
				)
				( attribute "XY" "(3250,1900)"
					( Origin gFrontEnd )
				)
				( attribute "CHIPS_PART_NAME" "RES"
					( Origin gPackager )
				)
				( attribute "CDS_PART_NAME" "RES_0402-0.0,5%,1/16W,EMPTY,G2A"
					( Origin gPackager )
				)
				( attribute "BOM_COST" "MEM_NV"
					( Origin gFrontEnd )
				)
				( objectStatus "R12W33" )
			)
			( gate "@baseboard_fab2_lib.baseboard_fab2(sch_1):page229_i28"
				( attribute "CDS_LIB" "dev_discrete"
					( Origin gPackager )
				)
				( attribute "CDS_LOCATION" "C2F2"
					( Origin gPackager )
				)
				( attribute "CDS_SEC" "1"
					( Origin gPackager )
				)
				( attribute "LOCATION" "C2F2"
					( Origin gFrontEnd )
				)
				( attribute "MATERIAL" "X5R"
					( Origin gFrontEnd )
				)
				( attribute "PACK_TYPE" "0603V"
					( Origin gFrontEnd )
				)
				( attribute "PART_NUMBER" "602433-106"
					( Origin gFrontEnd )
				)
				( attribute "PHYS_PAGE" "229"
					( Origin gFrontEnd )
				)
				( attribute "ROT" "0"
					( Origin gFrontEnd )
				)
				( attribute "SEC" "1"
					( Origin gFrontEnd )
				)
				( attribute "SEC_TYPE" "0603V"
					( Origin gFrontEnd )
				)
				( attribute "TOLERANCE" "20%"
					( Origin gFrontEnd )
				)
				( attribute "VALUE" "47UF"
					( Origin gFrontEnd )
				)
				( attribute "VER" "1"
					( Origin gFrontEnd )
				)
				( attribute "VOLTAGE" "4V"
					( Units "uVoltage" "V" 1.000000)
					( Origin gFrontEnd )
				)
				( attribute "XY" "(3400,3200)"
					( Origin gFrontEnd )
				)
				( attribute "CHIPS_PART_NAME" "CAP_A"
					( Origin gPackager )
				)
				( attribute "CDS_PART_NAME" "CAP_A_0603V-47UF,4V,20%,X5R,60A"
					( Origin gPackager )
				)
				( attribute "GROUP" "PWR_MLCC_CAP"
					( Origin gFrontEnd )
				)
				( objectStatus "C2F2" )
			)
			( gate "@baseboard_fab2_lib.baseboard_fab2(sch_1):page229_i26"
				( attribute "BOM_COST" "MEM_VRD_VTT_GHJ"
					( Origin gFrontEnd )
				)
				( attribute "CDS_LIB" "mstr_discrete"
					( Origin gPackager )
				)
				( attribute "CDS_LOCATION" "C4G13"
					( Origin gPackager )
				)
				( attribute "CDS_SEC" "1"
					( Origin gPackager )
				)
				( attribute "LOCATION" "C4G13"
					( Origin gFrontEnd )
				)
				( attribute "MATERIAL" "X7R"
					( Origin gFrontEnd )
				)
				( attribute "PACK_TYPE" "0402LF"
					( Origin gFrontEnd )
				)
				( attribute "PART_NUMBER" "A36096-046"
					( Origin gFrontEnd )
				)
				( attribute "PHYS_PAGE" "229"
					( Origin gFrontEnd )
				)
				( attribute "ROOM" "VTT_GHJ_PWR_VR"
					( Origin gFrontEnd )
				)
				( attribute "ROT" "2"
					( Origin gFrontEnd )
				)
				( attribute "SEC" "1"
					( Origin gFrontEnd )
				)
				( attribute "SEC_TYPE" "0402LF"
					( Origin gFrontEnd )
				)
				( attribute "TOLERANCE" "10%"
					( Origin gFrontEnd )
				)
				( attribute "VALUE" "1000PF"
					( Origin gFrontEnd )
				)
				( attribute "VER" "1"
					( Origin gFrontEnd )
				)
				( attribute "VOLTAGE" "50V"
					( Units "uVoltage" "V" 1.000000)
					( Origin gFrontEnd )
				)
				( attribute "XY" "(3975,1450)"
					( Origin gFrontEnd )
				)
				( attribute "CHIPS_PART_NAME" "CAP"
					( Origin gPackager )
				)
				( attribute "CDS_PART_NAME" "CAP_0402LF-1000PF,50V,10%,X7R,A"
					( Origin gPackager )
				)
				( objectStatus "C4G13" )
			)
			( gate "@baseboard_fab2_lib.baseboard_fab2(sch_1):page229_i23"
				( attribute "BOM_COST" "MEM_VRD_VTT_GHJ"
					( Origin gFrontEnd )
				)
				( attribute "CDS_LIB" "mstr_discrete"
					( Origin gPackager )
				)
				( attribute "CDS_LOCATION" "C4G20"
					( Origin gPackager )
				)
				( attribute "CDS_SEC" "1"
					( Origin gPackager )
				)
				( attribute "LOCATION" "C4G20"
					( Origin gFrontEnd )
				)
				( attribute "MATERIAL" "X6S"
					( Origin gFrontEnd )
				)
				( attribute "PACK_TYPE" "0805LF"
					( Origin gFrontEnd )
				)
				( attribute "PART_NUMBER" "C95333-002"
					( Origin gFrontEnd )
				)
				( attribute "PHYS_PAGE" "229"
					( Origin gFrontEnd )
				)
				( attribute "ROOM" "VTT_GHJ_PWR_VR"
					( Origin gFrontEnd )
				)
				( attribute "ROT" "0"
					( Origin gFrontEnd )
				)
				( attribute "SEC" "1"
					( Origin gFrontEnd )
				)
				( attribute "SEC_TYPE" "0805LF"
					( Origin gFrontEnd )
				)
				( attribute "TOLERANCE" "20%"
					( Origin gFrontEnd )
				)
				( attribute "VALUE" "22UF"
					( Origin gFrontEnd )
				)
				( attribute "VER" "1"
					( Origin gFrontEnd )
				)
				( attribute "VOLTAGE" "4V"
					( Units "uVoltage" "V" 1.000000)
					( Origin gFrontEnd )
				)
				( attribute "XY" "(3850,900)"
					( Origin gFrontEnd )
				)
				( attribute "CHIPS_PART_NAME" "CAP"
					( Origin gPackager )
				)
				( attribute "CDS_PART_NAME" "CAP_0805LF-22UF,4V,20%,X6S,C95A"
					( Origin gPackager )
				)
				( attribute "GROUP" "PWR_MLCC_CAP"
					( Origin gFrontEnd )
				)
				( objectStatus "C4G20" )
			)
			( gate "@baseboard_fab2_lib.baseboard_fab2(sch_1):page229_i18"
				( attribute "BOM_COST" "MEM_VRD_VTT_GHJ"
					( Origin gFrontEnd )
				)
				( attribute "CDS_LIB" "mstr_discrete"
					( Origin gPackager )
				)
				( attribute "CDS_LOCATION" "C6U14"
					( Origin gPackager )
				)
				( attribute "CDS_SEC" "1"
					( Origin gPackager )
				)
				( attribute "LOCATION" "C6U14"
					( Origin gFrontEnd )
				)
				( attribute "MATERIAL" "X6S"
					( Origin gFrontEnd )
				)
				( attribute "PACK_TYPE" "0603LF"
					( Origin gFrontEnd )
				)
				( attribute "PART_NUMBER" "E15431-001"
					( Origin gFrontEnd )
				)
				( attribute "PHYS_PAGE" "229"
					( Origin gFrontEnd )
				)
				( attribute "ROOM" "VTT_GHJ_PWR_VR"
					( Origin gFrontEnd )
				)
				( attribute "ROT" "0"
					( Origin gFrontEnd )
				)
				( attribute "SEC" "1"
					( Origin gFrontEnd )
				)
				( attribute "SEC_TYPE" "0603LF"
					( Origin gFrontEnd )
				)
				( attribute "TOLERANCE" "20%"
					( Origin gFrontEnd )
				)
				( attribute "VALUE" "10UF"
					( Origin gFrontEnd )
				)
				( attribute "VER" "1"
					( Origin gFrontEnd )
				)
				( attribute "VOLTAGE" "4V"
					( Units "uVoltage" "V" 1.000000)
					( Origin gFrontEnd )
				)
				( attribute "XY" "(350,2200)"
					( Origin gFrontEnd )
				)
				( attribute "CHIPS_PART_NAME" "CAP"
					( Origin gPackager )
				)
				( attribute "CDS_PART_NAME" "CAP_0603LF-10UF,4V,20%,X6S,E15A"
					( Origin gPackager )
				)
				( objectStatus "C6U14" )
			)
			( gate "@baseboard_fab2_lib.baseboard_fab2(sch_1):page229_i16"
				( attribute "BOM_COST" "MEM_VRD_VTT_GHJ"
					( Origin gFrontEnd )
				)
				( attribute "CDS_LIB" "mstr_discrete"
					( Origin gPackager )
				)
				( attribute "CDS_LOCATION" "C4G18"
					( Origin gPackager )
				)
				( attribute "CDS_SEC" "1"
					( Origin gPackager )
				)
				( attribute "LOCATION" "C4G18"
					( Origin gFrontEnd )
				)
				( attribute "MATERIAL" "X6S"
					( Origin gFrontEnd )
				)
				( attribute "PACK_TYPE" "0402"
					( Origin gFrontEnd )
				)
				( attribute "PART_NUMBER" "D97712-011"
					( Origin gFrontEnd )
				)
				( attribute "PHYS_PAGE" "229"
					( Origin gFrontEnd )
				)
				( attribute "ROOM" "VTT_GHJ_PWR_VR"
					( Origin gFrontEnd )
				)
				( attribute "ROT" "0"
					( Origin gFrontEnd )
				)
				( attribute "SEC" "1"
					( Origin gFrontEnd )
				)
				( attribute "SEC_TYPE" "0402"
					( Origin gFrontEnd )
				)
				( attribute "TOLERANCE" "10%"
					( Origin gFrontEnd )
				)
				( attribute "VALUE" "1.0UF"
					( Origin gFrontEnd )
				)
				( attribute "VER" "1"
					( Origin gFrontEnd )
				)
				( attribute "VOLTAGE" "16V"
					( Units "uVoltage" "V" 1.000000)
					( Origin gFrontEnd )
				)
				( attribute "XY" "(350,1325)"
					( Origin gFrontEnd )
				)
				( attribute "CHIPS_PART_NAME" "CAP"
					( Origin gPackager )
				)
				( attribute "CDS_PART_NAME" "CAP_0402-1.0UF,16V,10%,X6S,D97A"
					( Origin gPackager )
				)
				( objectStatus "C4G18" )
			)
			( gate "@baseboard_fab2_lib.baseboard_fab2(sch_1):page229_i12"
				( attribute "CDS_LIB" "mstr_misc"
					( Origin gPackager )
				)
				( attribute "CDS_LOCATION" "SH8U1"
					( Origin gPackager )
				)
				( attribute "CDS_SEC" "1"
					( Origin gPackager )
				)
				( attribute "LOCATION" "SH8U1"
					( Origin gFrontEnd )
				)
				( attribute "MATERIAL" "EMPTY"
					( Origin gFrontEnd )
				)
				( attribute "PACK_TYPE" "SH0201"
					( Origin gFrontEnd )
				)
				( attribute "PART_NUMBER" "N_A"
					( Origin gFrontEnd )
				)
				( attribute "PHYS_PAGE" "229"
					( Origin gFrontEnd )
				)
				( attribute "PIN_SHORT" "A:B"
					( Origin gFrontEnd )
				)
				( attribute "ROT" "0"
					( Origin gFrontEnd )
				)
				( attribute "SEC" "1"
					( Origin gFrontEnd )
				)
				( attribute "SEC_TYPE" "SH0201"
					( Origin gFrontEnd )
				)
				( attribute "VER" "1"
					( Origin gFrontEnd )
				)
				( attribute "XY" "(4850,-150)"
					( Origin gFrontEnd )
				)
				( attribute "CHIPS_PART_NAME" "SHUNT"
					( Origin gPackager )
				)
				( attribute "CDS_PART_NAME" "SHUNT_SH0201-EMPTY,N_A"
					( Origin gPackager )
				)
				( objectStatus "SH8U1" )
			)
			( gate "@baseboard_fab2_lib.baseboard_fab2(sch_1):page229_i11"
				( attribute "BOM_COST" "MEM_VRD_VTT_GHJ"
					( Origin gFrontEnd )
				)
				( attribute "CDS_LIB" "mstr_discrete"
					( Origin gPackager )
				)
				( attribute "CDS_LOCATION" "C6U13"
					( Origin gPackager )
				)
				( attribute "CDS_SEC" "1"
					( Origin gPackager )
				)
				( attribute "LOCATION" "C6U13"
					( Origin gFrontEnd )
				)
				( attribute "MATERIAL" "X6S"
					( Origin gFrontEnd )
				)
				( attribute "PACK_TYPE" "0603LF"
					( Origin gFrontEnd )
				)
				( attribute "PART_NUMBER" "E15431-001"
					( Origin gFrontEnd )
				)
				( attribute "PHYS_PAGE" "229"
					( Origin gFrontEnd )
				)
				( attribute "ROOM" "VTT_GHJ_PWR_VR"
					( Origin gFrontEnd )
				)
				( attribute "ROT" "0"
					( Origin gFrontEnd )
				)
				( attribute "SEC" "1"
					( Origin gFrontEnd )
				)
				( attribute "SEC_TYPE" "0603LF"
					( Origin gFrontEnd )
				)
				( attribute "TOLERANCE" "20%"
					( Origin gFrontEnd )
				)
				( attribute "VALUE" "10UF"
					( Origin gFrontEnd )
				)
				( attribute "VER" "1"
					( Origin gFrontEnd )
				)
				( attribute "VOLTAGE" "4V"
					( Units "uVoltage" "V" 1.000000)
					( Origin gFrontEnd )
				)
				( attribute "XY" "(-75,2200)"
					( Origin gFrontEnd )
				)
				( attribute "CHIPS_PART_NAME" "CAP"
					( Origin gPackager )
				)
				( attribute "CDS_PART_NAME" "CAP_0603LF-10UF,4V,20%,X6S,E15A"
					( Origin gPackager )
				)
				( objectStatus "C6U13" )
			)
			( gate "@baseboard_fab2_lib.baseboard_fab2(sch_1):page191_i195"
				( attribute "CDS_LIB" "mstr_discrete"
					( Origin gPackager )
				)
				( attribute "CDS_LOCATION" "R4W1"
					( Origin gPackager )
				)
				( attribute "CDS_SEC" "1"
					( Origin gPackager )
				)
				( attribute "LOCATION" "R4W1"
					( Origin gFrontEnd )
				)
				( attribute "MATERIAL" "CHIP"
					( Origin gFrontEnd )
				)
				( attribute "PACK_TYPE" "0402"
					( Origin gFrontEnd )
				)
				( attribute "PART_NUMBER" "G21796-072"
					( Origin gFrontEnd )
				)
				( attribute "PHYS_PAGE" "191"
					( Origin gFrontEnd )
				)
				( attribute "ROOM" "CPLD"
					( Origin gFrontEnd )
				)
				( attribute "ROT" "0"
					( Origin gFrontEnd )
				)
				( attribute "SEC" "1"
					( Origin gFrontEnd )
				)
				( attribute "SEC_TYPE" "0402"
					( Origin gFrontEnd )
				)
				( attribute "TOLERANCE" "1%"
					( Origin gFrontEnd )
				)
				( attribute "VALUE" "4.75K"
					( Origin gFrontEnd )
				)
				( attribute "VER" "2"
					( Origin gFrontEnd )
				)
				( attribute "WATTAGE" "1/16W"
					( Origin gFrontEnd )
				)
				( attribute "XY" "(-1700,2200)"
					( Origin gFrontEnd )
				)
				( attribute "CHIPS_PART_NAME" "RES"
					( Origin gPackager )
				)
				( attribute "CDS_PART_NAME" "RES_0402-4.75K,1%,1/16W,CHIP,GA"
					( Origin gPackager )
				)
				( objectStatus "R4W1" )
			)
			( gate "@baseboard_fab2_lib.baseboard_fab2(sch_1):page229_i9"
				( attribute "BOM_COST" "MEM_VRD_VTT_GHJ"
					( Origin gFrontEnd )
				)
				( attribute "CDS_LIB" "mstr_discrete"
					( Origin gPackager )
				)
				( attribute "CDS_LOCATION" "R6U7"
					( Origin gPackager )
				)
				( attribute "CDS_SEC" "1"
					( Origin gPackager )
				)
				( attribute "LOCATION" "R6U7"
					( Origin gFrontEnd )
				)
				( attribute "MATERIAL" "CHIP"
					( Origin gFrontEnd )
				)
				( attribute "PACK_TYPE" "0402"
					( Origin gFrontEnd )
				)
				( attribute "PART_NUMBER" "G21497-005"
					( Origin gFrontEnd )
				)
				( attribute "PHYS_PAGE" "229"
					( Origin gFrontEnd )
				)
				( attribute "ROOM" "VTT_GHJ_PWR_VR"
					( Origin gFrontEnd )
				)
				( attribute "ROT" "0"
					( Origin gFrontEnd )
				)
				( attribute "SEC" "1"
					( Origin gFrontEnd )
				)
				( attribute "SEC_TYPE" "0402"
					( Origin gFrontEnd )
				)
				( attribute "TOLERANCE" "5%"
					( Origin gFrontEnd )
				)
				( attribute "VALUE" "0.0"
					( Origin gFrontEnd )
				)
				( attribute "VER" "1"
					( Origin gFrontEnd )
				)
				( attribute "WATTAGE" "1/16W"
					( Origin gFrontEnd )
				)
				( attribute "XY" "(25,1600)"
					( Origin gFrontEnd )
				)
				( attribute "CHIPS_PART_NAME" "RES"
					( Origin gPackager )
				)
				( attribute "CDS_PART_NAME" "RES_0402-0.0,5%,1/16W,CHIP,G21A"
					( Origin gPackager )
				)
				( objectStatus "R6U7" )
			)
			( gate "@baseboard_fab2_lib.baseboard_fab2(sch_1):page213_i101"
				( attribute "CDS_LIB" "mstr_discrete"
					( Origin gPackager )
				)
				( attribute "CDS_LOCATION" "C4W2"
					( Origin gPackager )
				)
				( attribute "CDS_SEC" "1"
					( Origin gPackager )
				)
				( attribute "LOCATION" "C4W2"
					( Origin gFrontEnd )
				)
				( attribute "MATERIAL" "X7R"
					( Origin gFrontEnd )
				)
				( attribute "PACK_TYPE" "0402LF"
					( Origin gFrontEnd )
				)
				( attribute "PART_NUMBER" "A36096-050"
					( Origin gFrontEnd )
				)
				( attribute "PHYS_PAGE" "213"
					( Origin gFrontEnd )
				)
				( attribute "ROOM" "PVCCIN_CPU0_VR"
					( Origin gFrontEnd )
				)
				( attribute "ROT" "0"
					( Origin gFrontEnd )
				)
				( attribute "SEC" "1"
					( Origin gFrontEnd )
				)
				( attribute "SEC_TYPE" "0402LF"
					( Origin gFrontEnd )
				)
				( attribute "TOLERANCE" "10%"
					( Origin gFrontEnd )
				)
				( attribute "VALUE" "220PF"
					( Origin gFrontEnd )
				)
				( attribute "VER" "1"
					( Origin gFrontEnd )
				)
				( attribute "VOLTAGE" "50V"
					( Units "uVoltage" "V" 1.000000)
					( Origin gFrontEnd )
				)
				( attribute "XY" "(-2100,2750)"
					( Origin gFrontEnd )
				)
				( attribute "CHIPS_PART_NAME" "CAP"
					( Origin gPackager )
				)
				( attribute "CDS_PART_NAME" "CAP_0402LF-220PF,50V,10%,X7R,AA"
					( Origin gPackager )
				)
				( objectStatus "C4W2" )
			)
			( gate "@baseboard_fab2_lib.baseboard_fab2(sch_1):page224_i6"
				( attribute "BOM_COST" "VDDQ_GHJ_PWR_VR"
					( Origin gFrontEnd )
				)
				( attribute "CDS_LIB" "mstr_discrete"
					( Origin gPackager )
				)
				( attribute "CDS_LOCATION" "C1G17"
					( Origin gPackager )
				)
				( attribute "CDS_SEC" "1"
					( Origin gPackager )
				)
				( attribute "LOCATION" "C1G17"
					( Origin gFrontEnd )
				)
				( attribute "MATERIAL" "X6S"
					( Origin gFrontEnd )
				)
				( attribute "PACK_TYPE" "0805LF"
					( Origin gFrontEnd )
				)
				( attribute "PART_NUMBER" "C95333-002"
					( Origin gFrontEnd )
				)
				( attribute "PHYS_PAGE" "224"
					( Origin gFrontEnd )
				)
				( attribute "ROOM" "VDDQ_GHJ_PWR_VR"
					( Origin gFrontEnd )
				)
				( attribute "ROT" "0"
					( Origin gFrontEnd )
				)
				( attribute "SEC" "1"
					( Origin gFrontEnd )
				)
				( attribute "SEC_TYPE" "0805LF"
					( Origin gFrontEnd )
				)
				( attribute "TOLERANCE" "20%"
					( Origin gFrontEnd )
				)
				( attribute "VALUE" "22UF"
					( Origin gFrontEnd )
				)
				( attribute "VER" "1"
					( Origin gFrontEnd )
				)
				( attribute "VOLTAGE" "4V"
					( Units "uVoltage" "V" 1.000000)
					( Origin gFrontEnd )
				)
				( attribute "XY" "(4500,1800)"
					( Origin gFrontEnd )
				)
				( attribute "CHIPS_PART_NAME" "CAP"
					( Origin gPackager )
				)
				( attribute "CDS_PART_NAME" "CAP_0805LF-22UF,4V,20%,X6S,C95A"
					( Origin gPackager )
				)
				( attribute "GROUP" "PWR_MLCC_CAP"
					( Origin gFrontEnd )
				)
				( objectStatus "C1G17" )
			)
			( gate "@baseboard_fab2_lib.baseboard_fab2(sch_1):page224_i44"
				( attribute "CDS_LIB" "mstr_discrete"
					( Origin gPackager )
				)
				( attribute "CDS_LOCATION" "C1G11"
					( Origin gPackager )
				)
				( attribute "CDS_SEC" "1"
					( Origin gPackager )
				)
				( attribute "LOCATION" "C1G11"
					( Origin gFrontEnd )
				)
				( attribute "MATERIAL" "X7R"
					( Origin gFrontEnd )
				)
				( attribute "PACK_TYPE" "0402"
					( Origin gFrontEnd )
				)
				( attribute "PART_NUMBER" "A36096-104"
					( Origin gFrontEnd )
				)
				( attribute "PHYS_PAGE" "224"
					( Origin gFrontEnd )
				)
				( attribute "ROOM" "VDDQ_GHJ_PWR_VR"
					( Origin gFrontEnd )
				)
				( attribute "ROT" "2"
					( Origin gFrontEnd )
				)
				( attribute "SEC" "1"
					( Origin gFrontEnd )
				)
				( attribute "SEC_TYPE" "0402"
					( Origin gFrontEnd )
				)
				( attribute "SPOF" "TRUE"
					( Origin gFrontEnd )
				)
				( attribute "TOLERANCE" "10%"
					( Origin gFrontEnd )
				)
				( attribute "VALUE" "0.220UF"
					( Origin gFrontEnd )
				)
				( attribute "VER" "1"
					( Origin gFrontEnd )
				)
				( attribute "VOLTAGE" "16V"
					( Units "uVoltage" "V" 1.000000)
					( Origin gFrontEnd )
				)
				( attribute "XY" "(-775,1900)"
					( Origin gFrontEnd )
				)
				( attribute "CHIPS_PART_NAME" "CAP"
					( Origin gPackager )
				)
				( attribute "CDS_PART_NAME" "CAP_0402-0.220UF,16V,10%,X7R,AA"
					( Origin gPackager )
				)
				( objectStatus "C1G11" )
			)
			( gate "@baseboard_fab2_lib.baseboard_fab2(sch_1):page224_i45"
				( attribute "CDS_LIB" "mstr_discrete"
					( Origin gPackager )
				)
				( attribute "CDS_LOCATION" "C9U6"
					( Origin gPackager )
				)
				( attribute "CDS_SEC" "1"
					( Origin gPackager )
				)
				( attribute "LOCATION" "C9U6"
					( Origin gFrontEnd )
				)
				( attribute "MATERIAL" "X6S"
					( Origin gFrontEnd )
				)
				( attribute "PACK_TYPE" "0805"
					( Origin gFrontEnd )
				)
				( attribute "PART_NUMBER" "C95333-007"
					( Origin gFrontEnd )
				)
				( attribute "PHYS_PAGE" "224"
					( Origin gFrontEnd )
				)
				( attribute "ROOM" "VDDQ_GHJ_PWR_VR"
					( Origin gFrontEnd )
				)
				( attribute "ROT" "0"
					( Origin gFrontEnd )
				)
				( attribute "SEC" "1"
					( Origin gFrontEnd )
				)
				( attribute "SEC_TYPE" "0805"
					( Origin gFrontEnd )
				)
				( attribute "TOLERANCE" "10%"
					( Origin gFrontEnd )
				)
				( attribute "VALUE" "10UF"
					( Origin gFrontEnd )
				)
				( attribute "VER" "1"
					( Origin gFrontEnd )
				)
				( attribute "VOLTAGE" "16V"
					( Units "uVoltage" "V" 1.000000)
					( Origin gFrontEnd )
				)
				( attribute "XY" "(-2150,2500)"
					( Origin gFrontEnd )
				)
				( attribute "CHIPS_PART_NAME" "CAP"
					( Origin gPackager )
				)
				( attribute "CDS_PART_NAME" "CAP_0805-10UF,16V,10%,X6S,C953A"
					( Origin gPackager )
				)
				( objectStatus "C9U6" )
			)
			( gate "@baseboard_fab2_lib.baseboard_fab2(sch_1):page224_i46"
				( attribute "CDS_LIB" "mstr_discrete"
					( Origin gPackager )
				)
				( attribute "CDS_LOCATION" "C9U4"
					( Origin gPackager )
				)
				( attribute "CDS_SEC" "1"
					( Origin gPackager )
				)
				( attribute "LOCATION" "C9U4"
					( Origin gFrontEnd )
				)
				( attribute "MATERIAL" "X6S"
					( Origin gFrontEnd )
				)
				( attribute "PACK_TYPE" "0805"
					( Origin gFrontEnd )
				)
				( attribute "PART_NUMBER" "C95333-007"
					( Origin gFrontEnd )
				)
				( attribute "PHYS_PAGE" "224"
					( Origin gFrontEnd )
				)
				( attribute "ROOM" "VDDQ_GHJ_PWR_VR"
					( Origin gFrontEnd )
				)
				( attribute "ROT" "0"
					( Origin gFrontEnd )
				)
				( attribute "SEC" "1"
					( Origin gFrontEnd )
				)
				( attribute "SEC_TYPE" "0805"
					( Origin gFrontEnd )
				)
				( attribute "TOLERANCE" "10%"
					( Origin gFrontEnd )
				)
				( attribute "VALUE" "10UF"
					( Origin gFrontEnd )
				)
				( attribute "VER" "1"
					( Origin gFrontEnd )
				)
				( attribute "VOLTAGE" "16V"
					( Units "uVoltage" "V" 1.000000)
					( Origin gFrontEnd )
				)
				( attribute "XY" "(-1900,2500)"
					( Origin gFrontEnd )
				)
				( attribute "CHIPS_PART_NAME" "CAP"
					( Origin gPackager )
				)
				( attribute "CDS_PART_NAME" "CAP_0805-10UF,16V,10%,X6S,C953A"
					( Origin gPackager )
				)
				( objectStatus "C9U4" )
			)
			( gate "@baseboard_fab2_lib.baseboard_fab2(sch_1):page224_i47"
				( attribute "CDS_LIB" "mstr_discrete"
					( Origin gPackager )
				)
				( attribute "CDS_LOCATION" "C9T4"
					( Origin gPackager )
				)
				( attribute "CDS_SEC" "1"
					( Origin gPackager )
				)
				( attribute "LOCATION" "C9T4"
					( Origin gFrontEnd )
				)
				( attribute "MATERIAL" "X6S"
					( Origin gFrontEnd )
				)
				( attribute "PACK_TYPE" "0805"
					( Origin gFrontEnd )
				)
				( attribute "PART_NUMBER" "C95333-007"
					( Origin gFrontEnd )
				)
				( attribute "PHYS_PAGE" "224"
					( Origin gFrontEnd )
				)
				( attribute "ROOM" "VDDQ_GHJ_PWR_VR"
					( Origin gFrontEnd )
				)
				( attribute "ROT" "0"
					( Origin gFrontEnd )
				)
				( attribute "SEC" "1"
					( Origin gFrontEnd )
				)
				( attribute "SEC_TYPE" "0805"
					( Origin gFrontEnd )
				)
				( attribute "TOLERANCE" "10%"
					( Origin gFrontEnd )
				)
				( attribute "VALUE" "10UF"
					( Origin gFrontEnd )
				)
				( attribute "VER" "1"
					( Origin gFrontEnd )
				)
				( attribute "VOLTAGE" "16V"
					( Units "uVoltage" "V" 1.000000)
					( Origin gFrontEnd )
				)
				( attribute "XY" "(-1650,2500)"
					( Origin gFrontEnd )
				)
				( attribute "CHIPS_PART_NAME" "CAP"
					( Origin gPackager )
				)
				( attribute "CDS_PART_NAME" "CAP_0805-10UF,16V,10%,X6S,C953A"
					( Origin gPackager )
				)
				( objectStatus "C9T4" )
			)
			( gate "@baseboard_fab2_lib.baseboard_fab2(sch_1):page224_i48"
				( attribute "CDS_LIB" "mstr_discrete"
					( Origin gPackager )
				)
				( attribute "CDS_LOCATION" "C1F27"
					( Origin gPackager )
				)
				( attribute "CDS_SEC" "1"
					( Origin gPackager )
				)
				( attribute "LOCATION" "C1F27"
					( Origin gFrontEnd )
				)
				( attribute "MATERIAL" "X6S"
					( Origin gFrontEnd )
				)
				( attribute "PACK_TYPE" "0402"
					( Origin gFrontEnd )
				)
				( attribute "PART_NUMBER" "D97712-011"
					( Origin gFrontEnd )
				)
				( attribute "PHYS_PAGE" "224"
					( Origin gFrontEnd )
				)
				( attribute "ROOM" "VDDQ_GHJ_PWR_VR"
					( Origin gFrontEnd )
				)
				( attribute "ROT" "0"
					( Origin gFrontEnd )
				)
				( attribute "SEC" "1"
					( Origin gFrontEnd )
				)
				( attribute "SEC_TYPE" "0402"
					( Origin gFrontEnd )
				)
				( attribute "TOLERANCE" "10%"
					( Origin gFrontEnd )
				)
				( attribute "VALUE" "1.0UF"
					( Origin gFrontEnd )
				)
				( attribute "VER" "1"
					( Origin gFrontEnd )
				)
				( attribute "VOLTAGE" "16V"
					( Units "uVoltage" "V" 1.000000)
					( Origin gFrontEnd )
				)
				( attribute "XY" "(-1425,2500)"
					( Origin gFrontEnd )
				)
				( attribute "CHIPS_PART_NAME" "CAP"
					( Origin gPackager )
				)
				( attribute "CDS_PART_NAME" "CAP_0402-1.0UF,16V,10%,X6S,D97A"
					( Origin gPackager )
				)
				( objectStatus "C1F27" )
			)
			( gate "@baseboard_fab2_lib.baseboard_fab2(sch_1):page224_i50"
				( attribute "CDS_LIB" "mstr_discrete"
					( Origin gPackager )
				)
				( attribute "CDS_LOCATION" "C1G6"
					( Origin gPackager )
				)
				( attribute "CDS_SEC" "1"
					( Origin gPackager )
				)
				( attribute "LOCATION" "C1G6"
					( Origin gFrontEnd )
				)
				( attribute "MATERIAL" "X6S"
					( Origin gFrontEnd )
				)
				( attribute "PACK_TYPE" "0402"
					( Origin gFrontEnd )
				)
				( attribute "PART_NUMBER" "D97712-011"
					( Origin gFrontEnd )
				)
				( attribute "PHYS_PAGE" "224"
					( Origin gFrontEnd )
				)
				( attribute "ROOM" "VDDQ_GHJ_PWR_VR"
					( Origin gFrontEnd )
				)
				( attribute "ROT" "0"
					( Origin gFrontEnd )
				)
				( attribute "SEC" "1"
					( Origin gFrontEnd )
				)
				( attribute "SEC_TYPE" "0402"
					( Origin gFrontEnd )
				)
				( attribute "TOLERANCE" "10%"
					( Origin gFrontEnd )
				)
				( attribute "VALUE" "1.0UF"
					( Origin gFrontEnd )
				)
				( attribute "VER" "1"
					( Origin gFrontEnd )
				)
				( attribute "VOLTAGE" "16V"
					( Units "uVoltage" "V" 1.000000)
					( Origin gFrontEnd )
				)
				( attribute "XY" "(-925,2500)"
					( Origin gFrontEnd )
				)
				( attribute "CHIPS_PART_NAME" "CAP"
					( Origin gPackager )
				)
				( attribute "CDS_PART_NAME" "CAP_0402-1.0UF,16V,10%,X6S,D97A"
					( Origin gPackager )
				)
				( objectStatus "C1G6" )
			)
			( gate "@baseboard_fab2_lib.baseboard_fab2(sch_1):page224_i51"
				( attribute "CDS_LIB" "dev_discrete"
					( Origin gPackager )
				)
				( attribute "CDS_LOCATION" "C1G14"
					( Origin gPackager )
				)
				( attribute "CDS_SEC" "1"
					( Origin gPackager )
				)
				( attribute "LOCATION" "C1G14"
					( Origin gFrontEnd )
				)
				( attribute "MATERIAL" "X7R"
					( Origin gFrontEnd )
				)
				( attribute "PACK_TYPE" "0402V"
					( Origin gFrontEnd )
				)
				( attribute "PART_NUMBER" "A36096-030"
					( Origin gFrontEnd )
				)
				( attribute "PHYS_PAGE" "224"
					( Origin gFrontEnd )
				)
				( attribute "ROOM" "VDDQ_GHJ_PWR_VR"
					( Origin gFrontEnd )
				)
				( attribute "ROT" "0"
					( Origin gFrontEnd )
				)
				( attribute "SEC" "1"
					( Origin gFrontEnd )
				)
				( attribute "SEC_TYPE" "0402V"
					( Origin gFrontEnd )
				)
				( attribute "TOLERANCE" "10%"
					( Origin gFrontEnd )
				)
				( attribute "VALUE" "0.1UF"
					( Origin gFrontEnd )
				)
				( attribute "VER" "1"
					( Origin gFrontEnd )
				)
				( attribute "VOLTAGE" "16V"
					( Units "uVoltage" "V" 1.000000)
					( Origin gFrontEnd )
				)
				( attribute "XY" "(-1175,2500)"
					( Origin gFrontEnd )
				)
				( attribute "CHIPS_PART_NAME" "CAP_A"
					( Origin gPackager )
				)
				( attribute "CDS_PART_NAME" "CAP_A_0402V-0.1UF,16V,10%,X7R,A"
					( Origin gPackager )
				)
				( objectStatus "C1G14" )
			)
			( gate "@baseboard_fab2_lib.baseboard_fab2(sch_1):page236_i177"
				( attribute "BOM_COST" "PROC_SIDEBAND"
					( Origin gFrontEnd )
				)
				( attribute "CDS_LIB" "mstr_discrete"
					( Origin gPackager )
				)
				( attribute "CDS_LOCATION" "R3L4"
					( Origin gPackager )
				)
				( attribute "CDS_SEC" "1"
					( Origin gPackager )
				)
				( attribute "LOCATION" "R3L4"
					( Origin gFrontEnd )
				)
				( attribute "MATERIAL" "CHIP"
					( Origin gFrontEnd )
				)
				( attribute "PACK_TYPE" "0402"
					( Origin gFrontEnd )
				)
				( attribute "PART_NUMBER" "G21497-005"
					( Origin gFrontEnd )
				)
				( attribute "PHYS_PAGE" "236"
					( Origin gFrontEnd )
				)
				( attribute "ROOM" "CPU0"
					( Origin gFrontEnd )
				)
				( attribute "ROT" "0"
					( Origin gFrontEnd )
				)
				( attribute "SEC" "1"
					( Origin gFrontEnd )
				)
				( attribute "SEC_TYPE" "0402"
					( Origin gFrontEnd )
				)
				( attribute "TOLERANCE" "5%"
					( Origin gFrontEnd )
				)
				( attribute "VALUE" "0.0"
					( Origin gFrontEnd )
				)
				( attribute "VER" "1"
					( Origin gFrontEnd )
				)
				( attribute "WATTAGE" "1/16W"
					( Origin gFrontEnd )
				)
				( attribute "XY" "(7325,3300)"
					( Origin gFrontEnd )
				)
				( attribute "CHIPS_PART_NAME" "RES"
					( Origin gPackager )
				)
				( attribute "CDS_PART_NAME" "RES_0402-0.0,5%,1/16W,CHIP,G21A"
					( Origin gPackager )
				)
				( objectStatus "R3L4" )
			)
			( gate "@baseboard_fab2_lib.baseboard_fab2(sch_1):page236_i181"
				( attribute "CDS_LIB" "w_hdl"
					( Origin gPackager )
				)
				( attribute "CDS_LMAN_SYM_OUTLINE" "-50,25,50,-25"
					( Origin gPackager )
				)
				( attribute "LOCATION" "C3L29"
					( Origin gFrontEnd )
				)
				( attribute "PACK_TYPE" "SMD-BCG6"
					( Origin gFrontEnd )
				)
				( attribute "PART_NUMBER" "78.10523.8FL"
					( Origin gFrontEnd )
				)
				( attribute "PHYS_PAGE" "236"
					( Origin gFrontEnd )
				)
				( attribute "ROT" "0"
					( Origin gFrontEnd )
				)
				( attribute "SEC" "1"
					( Origin gFrontEnd )
				)
				( attribute "SEC_TYPE" "SMD-BCG6"
					( Origin gFrontEnd )
				)
				( attribute "VALUE" "SC1U10V2KX-4-GP"
					( Origin gFrontEnd )
				)
				( attribute "VER" "1"
					( Origin gFrontEnd )
				)
				( attribute "XY" "(7625,2775)"
					( Origin gFrontEnd )
				)
				( attribute "CHIPS_PART_NAME" "SC1U10V2KX-4-GP"
					( Origin gPackager )
				)
				( attribute "CDS_PART_NAME" "SC1U10V2KX-4-GP_SMD-BCG6-SC1U1A"
					( Origin gPackager )
				)
				( attribute "CDS_LOCATION" "C3L29"
					( Origin gPackager )
				)
				( attribute "CDS_SEC" "1"
					( Origin gPackager )
				)
				( attribute "ATTRIBUTE" "1UF"
					( Origin gFrontEnd )
				)
				( attribute "PACK_SIZE" "0402"
					( Origin gFrontEnd )
				)
				( attribute "RATED" "10V"
					( Origin gFrontEnd )
				)
				( attribute "TOLERANCE" "10%"
					( Origin gFrontEnd )
				)
				( objectStatus "C3L29" )
			)
			( gate "@baseboard_fab2_lib.baseboard_fab2(sch_1):page224_i54"
				( attribute "CDS_LIB" "mstr_discrete"
					( Origin gPackager )
				)
				( attribute "CDS_LOCATION" "C1G5"
					( Origin gPackager )
				)
				( attribute "CDS_SEC" "1"
					( Origin gPackager )
				)
				( attribute "LOCATION" "C1G5"
					( Origin gFrontEnd )
				)
				( attribute "MATERIAL" "X7R"
					( Origin gFrontEnd )
				)
				( attribute "PACK_TYPE" "0402"
					( Origin gFrontEnd )
				)
				( attribute "PART_NUMBER" "A36096-155"
					( Origin gFrontEnd )
				)
				( attribute "PHYS_PAGE" "224"
					( Origin gFrontEnd )
				)
				( attribute "ROOM" "VDDQ_GHJ_PWR_VR"
					( Origin gFrontEnd )
				)
				( attribute "ROT" "0"
					( Origin gFrontEnd )
				)
				( attribute "SEC" "1"
					( Origin gFrontEnd )
				)
				( attribute "SEC_TYPE" "0402"
					( Origin gFrontEnd )
				)
				( attribute "TOLERANCE" "10%"
					( Origin gFrontEnd )
				)
				( attribute "VALUE" "0.22UF"
					( Origin gFrontEnd )
				)
				( attribute "VER" "1"
					( Origin gFrontEnd )
				)
				( attribute "VOLTAGE" "16V"
					( Units "uVoltage" "V" 1.000000)
					( Origin gFrontEnd )
				)
				( attribute "XY" "(25,2500)"
					( Origin gFrontEnd )
				)
				( attribute "CHIPS_PART_NAME" "CAP"
					( Origin gPackager )
				)
				( attribute "CDS_PART_NAME" "CAP_0402-0.22UF,16V,10%,X7R,A3A"
					( Origin gPackager )
				)
				( objectStatus "C1G5" )
			)
			( gate "@baseboard_fab2_lib.baseboard_fab2(sch_1):page227_i152"
				( attribute "ATTRIBUTE" "120NH"
					( Origin gFrontEnd )
				)
				( attribute "BOM_DS" "068.9002N.1021"
					( Origin gFrontEnd )
				)
				( attribute "BOM_SS" "068.1202N.M001"
					( Origin gFrontEnd )
				)
				( attribute "CDS_LIB" "w_hdl"
					( Origin gPackager )
				)
				( attribute "CDS_LMAN_SYM_OUTLINE" "-75,100,75,-100"
					( Origin gPackager )
				)
				( attribute "CDS_LOCATION" "L1A2"
					( Origin gPackager )
				)
				( attribute "CDS_SEC" "1"
					( Origin gPackager )
				)
				( attribute "DS_VALUE" "90NH"
					( Origin gFrontEnd )
				)
				( attribute "LOCATION" "L1A2"
					( Origin gFrontEnd )
				)
				( attribute "NEW_PACK_SIZE" "DCR=0.17MOHM"
					( Origin gFrontEnd )
				)
				( attribute "NEW_RATED" "DS_ISAT=134A@25C"
					( Origin gFrontEnd )
				)
				( attribute "NEW_TYPE" "IRMS=66A@DELTA_T<40C"
					( Origin gFrontEnd )
				)
				( attribute "PACK_SIZE" "DCR=0.17MOHM"
					( Origin gFrontEnd )
				)
				( attribute "PACK_TYPE" "DISCRET-GB2"
					( Origin gFrontEnd )
				)
				( attribute "PART_NUMBER" "068.1202N.M001"
					( Origin gFrontEnd )
				)
				( attribute "PHYS_PAGE" "227"
					( Origin gFrontEnd )
				)
				( attribute "RATED" "ISAT=94A@25C"
					( Origin gFrontEnd )
				)
				( attribute "ROT" "1"
					( Origin gFrontEnd )
				)
				( attribute "SEC" "1"
					( Origin gFrontEnd )
				)
				( attribute "SEC_TYPE" "DISCRET-GB2"
					( Origin gFrontEnd )
				)
				( attribute "SS_ISAT" "94A@25C"
					( Origin gFrontEnd )
				)
				( attribute "SS_VALUE" "120NH"
					( Origin gFrontEnd )
				)
				( attribute "TYPE" "IRMS=66A@DELTA_T<40C"
					( Origin gFrontEnd )
				)
				( attribute "VALUE" "IND-120NH-30-GP"
					( Origin gFrontEnd )
				)
				( attribute "VER" "1"
					( Origin gFrontEnd )
				)
				( attribute "XY" "(3775,1950)"
					( Origin gFrontEnd )
				)
				( attribute "CHIPS_PART_NAME" "IND-120NH-30-GP"
					( Origin gPackager )
				)
				( attribute "CDS_PART_NAME" "IND-120NH-30-GP_DISCRET-GB2-INA"
					( Origin gPackager )
				)
				( objectStatus "L1A2" )
			)
			( gate "@baseboard_fab2_lib.baseboard_fab2(sch_1):page224_i68"
				( attribute "BOM_COST" "VDDQ_GHJ_PWR_VR"
					( Origin gFrontEnd )
				)
				( attribute "CDS_LIB" "mstr_discrete"
					( Origin gPackager )
				)
				( attribute "CDS_LOCATION" "C1G20"
					( Origin gPackager )
				)
				( attribute "CDS_SEC" "1"
					( Origin gPackager )
				)
				( attribute "LOCATION" "C1G20"
					( Origin gFrontEnd )
				)
				( attribute "MATERIAL" "X6S"
					( Origin gFrontEnd )
				)
				( attribute "PACK_TYPE" "0805LF"
					( Origin gFrontEnd )
				)
				( attribute "PART_NUMBER" "C95333-002"
					( Origin gFrontEnd )
				)
				( attribute "PHYS_PAGE" "224"
					( Origin gFrontEnd )
				)
				( attribute "ROOM" "VDDQ_GHJ_PWR_VR"
					( Origin gFrontEnd )
				)
				( attribute "ROT" "0"
					( Origin gFrontEnd )
				)
				( attribute "SEC" "1"
					( Origin gFrontEnd )
				)
				( attribute "SEC_TYPE" "0805LF"
					( Origin gFrontEnd )
				)
				( attribute "TOLERANCE" "20%"
					( Origin gFrontEnd )
				)
				( attribute "VALUE" "22UF"
					( Origin gFrontEnd )
				)
				( attribute "VER" "1"
					( Origin gFrontEnd )
				)
				( attribute "VOLTAGE" "4V"
					( Units "uVoltage" "V" 1.000000)
					( Origin gFrontEnd )
				)
				( attribute "XY" "(4500,-575)"
					( Origin gFrontEnd )
				)
				( attribute "CHIPS_PART_NAME" "CAP"
					( Origin gPackager )
				)
				( attribute "CDS_PART_NAME" "CAP_0805LF-22UF,4V,20%,X6S,C95A"
					( Origin gPackager )
				)
				( attribute "GROUP" "PWR_MLCC_CAP"
					( Origin gFrontEnd )
				)
				( attribute "BOM_SS" "NOPOP"
					( Origin gFrontEnd )
				)
				( objectStatus "C1G20" )
			)
			( gate "@baseboard_fab2_lib.baseboard_fab2(sch_1):page224_i72"
				( attribute "CDS_LIB" "mstr_discrete"
					( Origin gPackager )
				)
				( attribute "CDS_LOCATION" "C1G29"
					( Origin gPackager )
				)
				( attribute "CDS_SEC" "1"
					( Origin gPackager )
				)
				( attribute "LOCATION" "C1G29"
					( Origin gFrontEnd )
				)
				( attribute "MATERIAL" "X7R"
					( Origin gFrontEnd )
				)
				( attribute "PACK_TYPE" "0402"
					( Origin gFrontEnd )
				)
				( attribute "PART_NUMBER" "A36096-155"
					( Origin gFrontEnd )
				)
				( attribute "PHYS_PAGE" "224"
					( Origin gFrontEnd )
				)
				( attribute "ROOM" "VDDQ_GHJ_PWR_VR"
					( Origin gFrontEnd )
				)
				( attribute "ROT" "0"
					( Origin gFrontEnd )
				)
				( attribute "SEC" "1"
					( Origin gFrontEnd )
				)
				( attribute "SEC_TYPE" "0402"
					( Origin gFrontEnd )
				)
				( attribute "TOLERANCE" "10%"
					( Origin gFrontEnd )
				)
				( attribute "VALUE" "0.22UF"
					( Origin gFrontEnd )
				)
				( attribute "VER" "1"
					( Origin gFrontEnd )
				)
				( attribute "VOLTAGE" "16V"
					( Units "uVoltage" "V" 1.000000)
					( Origin gFrontEnd )
				)
				( attribute "XY" "(100,150)"
					( Origin gFrontEnd )
				)
				( attribute "CHIPS_PART_NAME" "CAP"
					( Origin gPackager )
				)
				( attribute "CDS_PART_NAME" "CAP_0402-0.22UF,16V,10%,X7R,A3A"
					( Origin gPackager )
				)
				( attribute "BOM_SS" "NOPOP"
					( Origin gFrontEnd )
				)
				( objectStatus "C1G29" )
			)
			( gate "@baseboard_fab2_lib.baseboard_fab2(sch_1):page236_i180"
				( attribute "CDS_LIB" "w_hdl"
					( Origin gPackager )
				)
				( attribute "CDS_LMAN_SYM_OUTLINE" "-50,25,50,-25"
					( Origin gPackager )
				)
				( attribute "LOCATION" "C3L1"
					( Origin gFrontEnd )
				)
				( attribute "PACK_TYPE" "SMD-BCG6"
					( Origin gFrontEnd )
				)
				( attribute "PART_NUMBER" "78.10523.8FL"
					( Origin gFrontEnd )
				)
				( attribute "PHYS_PAGE" "236"
					( Origin gFrontEnd )
				)
				( attribute "ROT" "0"
					( Origin gFrontEnd )
				)
				( attribute "SEC" "1"
					( Origin gFrontEnd )
				)
				( attribute "SEC_TYPE" "SMD-BCG6"
					( Origin gFrontEnd )
				)
				( attribute "VALUE" "SC1U10V2KX-4-GP"
					( Origin gFrontEnd )
				)
				( attribute "VER" "1"
					( Origin gFrontEnd )
				)
				( attribute "XY" "(7800,4525)"
					( Origin gFrontEnd )
				)
				( attribute "CHIPS_PART_NAME" "SC1U10V2KX-4-GP"
					( Origin gPackager )
				)
				( attribute "CDS_PART_NAME" "SC1U10V2KX-4-GP_SMD-BCG6-SC1U1A"
					( Origin gPackager )
				)
				( attribute "CDS_LOCATION" "C3L1"
					( Origin gPackager )
				)
				( attribute "CDS_SEC" "1"
					( Origin gPackager )
				)
				( attribute "ATTRIBUTE" "1UF"
					( Origin gFrontEnd )
				)
				( attribute "PACK_SIZE" "0402"
					( Origin gFrontEnd )
				)
				( attribute "RATED" "10V"
					( Origin gFrontEnd )
				)
				( attribute "TOLERANCE" "10%"
					( Origin gFrontEnd )
				)
				( objectStatus "C3L1" )
			)
			( gate "@baseboard_fab2_lib.baseboard_fab2(sch_1):page224_i75"
				( attribute "CDS_LIB" "mstr_discrete"
					( Origin gPackager )
				)
				( attribute "CDS_LOCATION" "C1F26"
					( Origin gPackager )
				)
				( attribute "CDS_SEC" "1"
					( Origin gPackager )
				)
				( attribute "LOCATION" "C1F26"
					( Origin gFrontEnd )
				)
				( attribute "MATERIAL" "X7R"
					( Origin gFrontEnd )
				)
				( attribute "PACK_TYPE" "0402"
					( Origin gFrontEnd )
				)
				( attribute "PART_NUMBER" "A36096-104"
					( Origin gFrontEnd )
				)
				( attribute "PHYS_PAGE" "224"
					( Origin gFrontEnd )
				)
				( attribute "ROOM" "VDDQ_GHJ_PWR_VR"
					( Origin gFrontEnd )
				)
				( attribute "ROT" "2"
					( Origin gFrontEnd )
				)
				( attribute "SEC" "1"
					( Origin gFrontEnd )
				)
				( attribute "SEC_TYPE" "0402"
					( Origin gFrontEnd )
				)
				( attribute "SPOF" "TRUE"
					( Origin gFrontEnd )
				)
				( attribute "TOLERANCE" "10%"
					( Origin gFrontEnd )
				)
				( attribute "VALUE" "0.220UF"
					( Origin gFrontEnd )
				)
				( attribute "VER" "1"
					( Origin gFrontEnd )
				)
				( attribute "VOLTAGE" "16V"
					( Units "uVoltage" "V" 1.000000)
					( Origin gFrontEnd )
				)
				( attribute "XY" "(-625,-475)"
					( Origin gFrontEnd )
				)
				( attribute "CHIPS_PART_NAME" "CAP"
					( Origin gPackager )
				)
				( attribute "CDS_PART_NAME" "CAP_0402-0.220UF,16V,10%,X7R,AA"
					( Origin gPackager )
				)
				( attribute "BOM_SS" "NOPOP"
					( Origin gFrontEnd )
				)
				( objectStatus "C1F26" )
			)
			( gate "@baseboard_fab2_lib.baseboard_fab2(sch_1):page236_i175"
				( attribute "BOM_COST" "PROC_SIDEBAND"
					( Origin gFrontEnd )
				)
				( attribute "CDS_LIB" "mstr_discrete"
					( Origin gPackager )
				)
				( attribute "CDS_LOCATION" "R3L1"
					( Origin gPackager )
				)
				( attribute "CDS_SEC" "1"
					( Origin gPackager )
				)
				( attribute "LOCATION" "R3L1"
					( Origin gFrontEnd )
				)
				( attribute "MATERIAL" "CHIP"
					( Origin gFrontEnd )
				)
				( attribute "PACK_TYPE" "0402"
					( Origin gFrontEnd )
				)
				( attribute "PART_NUMBER" "G21497-005"
					( Origin gFrontEnd )
				)
				( attribute "PHYS_PAGE" "236"
					( Origin gFrontEnd )
				)
				( attribute "ROOM" "CPU0"
					( Origin gFrontEnd )
				)
				( attribute "ROT" "0"
					( Origin gFrontEnd )
				)
				( attribute "SEC" "1"
					( Origin gFrontEnd )
				)
				( attribute "SEC_TYPE" "0402"
					( Origin gFrontEnd )
				)
				( attribute "TOLERANCE" "5%"
					( Origin gFrontEnd )
				)
				( attribute "VALUE" "0.0"
					( Origin gFrontEnd )
				)
				( attribute "VER" "1"
					( Origin gFrontEnd )
				)
				( attribute "WATTAGE" "1/16W"
					( Origin gFrontEnd )
				)
				( attribute "XY" "(7425,5050)"
					( Origin gFrontEnd )
				)
				( attribute "CHIPS_PART_NAME" "RES"
					( Origin gPackager )
				)
				( attribute "CDS_PART_NAME" "RES_0402-0.0,5%,1/16W,CHIP,G21A"
					( Origin gPackager )
				)
				( objectStatus "R3L1" )
			)
			( gate "@baseboard_fab2_lib.baseboard_fab2(sch_1):page224_i77"
				( attribute "CDS_LIB" "mstr_discrete"
					( Origin gPackager )
				)
				( attribute "CDS_LOCATION" "C1G28"
					( Origin gPackager )
				)
				( attribute "CDS_SEC" "1"
					( Origin gPackager )
				)
				( attribute "LOCATION" "C1G28"
					( Origin gFrontEnd )
				)
				( attribute "MATERIAL" "X6S"
					( Origin gFrontEnd )
				)
				( attribute "PACK_TYPE" "0402"
					( Origin gFrontEnd )
				)
				( attribute "PART_NUMBER" "D97712-011"
					( Origin gFrontEnd )
				)
				( attribute "PHYS_PAGE" "224"
					( Origin gFrontEnd )
				)
				( attribute "ROOM" "VDDQ_GHJ_PWR_VR"
					( Origin gFrontEnd )
				)
				( attribute "ROT" "0"
					( Origin gFrontEnd )
				)
				( attribute "SEC" "1"
					( Origin gFrontEnd )
				)
				( attribute "SEC_TYPE" "0402"
					( Origin gFrontEnd )
				)
				( attribute "TOLERANCE" "10%"
					( Origin gFrontEnd )
				)
				( attribute "VALUE" "1.0UF"
					( Origin gFrontEnd )
				)
				( attribute "VER" "1"
					( Origin gFrontEnd )
				)
				( attribute "VOLTAGE" "16V"
					( Units "uVoltage" "V" 1.000000)
					( Origin gFrontEnd )
				)
				( attribute "XY" "(-800,125)"
					( Origin gFrontEnd )
				)
				( attribute "CHIPS_PART_NAME" "CAP"
					( Origin gPackager )
				)
				( attribute "CDS_PART_NAME" "CAP_0402-1.0UF,16V,10%,X6S,D97A"
					( Origin gPackager )
				)
				( attribute "BOM_SS" "NOPOP"
					( Origin gFrontEnd )
				)
				( objectStatus "C1G28" )
			)
			( gate "@baseboard_fab2_lib.baseboard_fab2(sch_1):page224_i78"
				( attribute "CDS_LIB" "dev_discrete"
					( Origin gPackager )
				)
				( attribute "CDS_LOCATION" "C1F28"
					( Origin gPackager )
				)
				( attribute "CDS_SEC" "1"
					( Origin gPackager )
				)
				( attribute "LOCATION" "C1F28"
					( Origin gFrontEnd )
				)
				( attribute "MATERIAL" "X7R"
					( Origin gFrontEnd )
				)
				( attribute "PACK_TYPE" "0402V"
					( Origin gFrontEnd )
				)
				( attribute "PART_NUMBER" "A36096-030"
					( Origin gFrontEnd )
				)
				( attribute "PHYS_PAGE" "224"
					( Origin gFrontEnd )
				)
				( attribute "ROOM" "VDDQ_GHJ_PWR_VR"
					( Origin gFrontEnd )
				)
				( attribute "ROT" "0"
					( Origin gFrontEnd )
				)
				( attribute "SEC" "1"
					( Origin gFrontEnd )
				)
				( attribute "SEC_TYPE" "0402V"
					( Origin gFrontEnd )
				)
				( attribute "TOLERANCE" "10%"
					( Origin gFrontEnd )
				)
				( attribute "VALUE" "0.1UF"
					( Origin gFrontEnd )
				)
				( attribute "VER" "1"
					( Origin gFrontEnd )
				)
				( attribute "VOLTAGE" "16V"
					( Units "uVoltage" "V" 1.000000)
					( Origin gFrontEnd )
				)
				( attribute "XY" "(-1100,125)"
					( Origin gFrontEnd )
				)
				( attribute "CHIPS_PART_NAME" "CAP_A"
					( Origin gPackager )
				)
				( attribute "CDS_PART_NAME" "CAP_A_0402V-0.1UF,16V,10%,X7R,A"
					( Origin gPackager )
				)
				( objectStatus "C1F28" )
			)
			( gate "@baseboard_fab2_lib.baseboard_fab2(sch_1):page224_i79"
				( attribute "CDS_LIB" "mstr_discrete"
					( Origin gPackager )
				)
				( attribute "CDS_LOCATION" "C1G13"
					( Origin gPackager )
				)
				( attribute "CDS_SEC" "1"
					( Origin gPackager )
				)
				( attribute "LOCATION" "C1G13"
					( Origin gFrontEnd )
				)
				( attribute "MATERIAL" "X6S"
					( Origin gFrontEnd )
				)
				( attribute "PACK_TYPE" "0402"
					( Origin gFrontEnd )
				)
				( attribute "PART_NUMBER" "D97712-011"
					( Origin gFrontEnd )
				)
				( attribute "PHYS_PAGE" "224"
					( Origin gFrontEnd )
				)
				( attribute "ROOM" "VDDQ_GHJ_PWR_VR"
					( Origin gFrontEnd )
				)
				( attribute "ROT" "0"
					( Origin gFrontEnd )
				)
				( attribute "SEC" "1"
					( Origin gFrontEnd )
				)
				( attribute "SEC_TYPE" "0402"
					( Origin gFrontEnd )
				)
				( attribute "TOLERANCE" "10%"
					( Origin gFrontEnd )
				)
				( attribute "VALUE" "1.0UF"
					( Origin gFrontEnd )
				)
				( attribute "VER" "1"
					( Origin gFrontEnd )
				)
				( attribute "VOLTAGE" "16V"
					( Units "uVoltage" "V" 1.000000)
					( Origin gFrontEnd )
				)
				( attribute "XY" "(-1375,125)"
					( Origin gFrontEnd )
				)
				( attribute "CHIPS_PART_NAME" "CAP"
					( Origin gPackager )
				)
				( attribute "CDS_PART_NAME" "CAP_0402-1.0UF,16V,10%,X6S,D97A"
					( Origin gPackager )
				)
				( objectStatus "C1G13" )
			)
			( gate "@baseboard_fab2_lib.baseboard_fab2(sch_1):page224_i80"
				( attribute "CDS_LIB" "mstr_discrete"
					( Origin gPackager )
				)
				( attribute "CDS_LOCATION" "C9U3"
					( Origin gPackager )
				)
				( attribute "CDS_SEC" "1"
					( Origin gPackager )
				)
				( attribute "LOCATION" "C9U3"
					( Origin gFrontEnd )
				)
				( attribute "MATERIAL" "X6S"
					( Origin gFrontEnd )
				)
				( attribute "PACK_TYPE" "0805"
					( Origin gFrontEnd )
				)
				( attribute "PART_NUMBER" "C95333-007"
					( Origin gFrontEnd )
				)
				( attribute "PHYS_PAGE" "224"
					( Origin gFrontEnd )
				)
				( attribute "ROOM" "VDDQ_GHJ_PWR_VR"
					( Origin gFrontEnd )
				)
				( attribute "ROT" "0"
					( Origin gFrontEnd )
				)
				( attribute "SEC" "1"
					( Origin gFrontEnd )
				)
				( attribute "SEC_TYPE" "0805"
					( Origin gFrontEnd )
				)
				( attribute "TOLERANCE" "10%"
					( Origin gFrontEnd )
				)
				( attribute "VALUE" "10UF"
					( Origin gFrontEnd )
				)
				( attribute "VER" "1"
					( Origin gFrontEnd )
				)
				( attribute "VOLTAGE" "16V"
					( Units "uVoltage" "V" 1.000000)
					( Origin gFrontEnd )
				)
				( attribute "XY" "(-1650,125)"
					( Origin gFrontEnd )
				)
				( attribute "CHIPS_PART_NAME" "CAP"
					( Origin gPackager )
				)
				( attribute "CDS_PART_NAME" "CAP_0805-10UF,16V,10%,X6S,C953A"
					( Origin gPackager )
				)
				( objectStatus "C9U3" )
			)
			( gate "@baseboard_fab2_lib.baseboard_fab2(sch_1):page224_i81"
				( attribute "CDS_LIB" "mstr_discrete"
					( Origin gPackager )
				)
				( attribute "CDS_LOCATION" "C9T6"
					( Origin gPackager )
				)
				( attribute "CDS_SEC" "1"
					( Origin gPackager )
				)
				( attribute "LOCATION" "C9T6"
					( Origin gFrontEnd )
				)
				( attribute "MATERIAL" "X6S"
					( Origin gFrontEnd )
				)
				( attribute "PACK_TYPE" "0805"
					( Origin gFrontEnd )
				)
				( attribute "PART_NUMBER" "C95333-007"
					( Origin gFrontEnd )
				)
				( attribute "PHYS_PAGE" "224"
					( Origin gFrontEnd )
				)
				( attribute "ROOM" "VDDQ_GHJ_PWR_VR"
					( Origin gFrontEnd )
				)
				( attribute "ROT" "0"
					( Origin gFrontEnd )
				)
				( attribute "SEC" "1"
					( Origin gFrontEnd )
				)
				( attribute "SEC_TYPE" "0805"
					( Origin gFrontEnd )
				)
				( attribute "TOLERANCE" "10%"
					( Origin gFrontEnd )
				)
				( attribute "VALUE" "10UF"
					( Origin gFrontEnd )
				)
				( attribute "VER" "1"
					( Origin gFrontEnd )
				)
				( attribute "VOLTAGE" "16V"
					( Units "uVoltage" "V" 1.000000)
					( Origin gFrontEnd )
				)
				( attribute "XY" "(-1925,125)"
					( Origin gFrontEnd )
				)
				( attribute "CHIPS_PART_NAME" "CAP"
					( Origin gPackager )
				)
				( attribute "CDS_PART_NAME" "CAP_0805-10UF,16V,10%,X6S,C953A"
					( Origin gPackager )
				)
				( objectStatus "C9T6" )
			)
			( gate "@baseboard_fab2_lib.baseboard_fab2(sch_1):page224_i84"
				( attribute "CDS_LIB" "mstr_discrete"
					( Origin gPackager )
				)
				( attribute "CDS_LOCATION" "C9T9"
					( Origin gPackager )
				)
				( attribute "CDS_SEC" "1"
					( Origin gPackager )
				)
				( attribute "LOCATION" "C9T9"
					( Origin gFrontEnd )
				)
				( attribute "MATERIAL" "X6S"
					( Origin gFrontEnd )
				)
				( attribute "PACK_TYPE" "0805"
					( Origin gFrontEnd )
				)
				( attribute "PART_NUMBER" "C95333-007"
					( Origin gFrontEnd )
				)
				( attribute "PHYS_PAGE" "224"
					( Origin gFrontEnd )
				)
				( attribute "ROOM" "VDDQ_GHJ_PWR_VR"
					( Origin gFrontEnd )
				)
				( attribute "ROT" "0"
					( Origin gFrontEnd )
				)
				( attribute "SEC" "1"
					( Origin gFrontEnd )
				)
				( attribute "SEC_TYPE" "0805"
					( Origin gFrontEnd )
				)
				( attribute "TOLERANCE" "10%"
					( Origin gFrontEnd )
				)
				( attribute "VALUE" "10UF"
					( Origin gFrontEnd )
				)
				( attribute "VER" "1"
					( Origin gFrontEnd )
				)
				( attribute "VOLTAGE" "16V"
					( Units "uVoltage" "V" 1.000000)
					( Origin gFrontEnd )
				)
				( attribute "XY" "(-2200,125)"
					( Origin gFrontEnd )
				)
				( attribute "CHIPS_PART_NAME" "CAP"
					( Origin gPackager )
				)
				( attribute "CDS_PART_NAME" "CAP_0805-10UF,16V,10%,X6S,C953A"
					( Origin gPackager )
				)
				( objectStatus "C9T9" )
			)
			( gate "@baseboard_fab2_lib.baseboard_fab2(sch_1):page224_i110"
				( attribute "CDS_LIB" "mstr_discrete"
					( Origin gPackager )
				)
				( attribute "CDS_LOCATION" "EU1G1"
					( Origin gPackager )
				)
				( attribute "CDS_SEC" "1"
					( Origin gPackager )
				)
				( attribute "LOCATION" "EU1G1"
					( Origin gFrontEnd )
				)
				( attribute "MATERIAL" "IC"
					( Origin gFrontEnd )
				)
				( attribute "NO_XNET_CONNECTION" "1"
					( Origin gFrontEnd )
				)
				( attribute "PACK_TYPE" "SM"
					( Origin gFrontEnd )
				)
				( attribute "PART_NUMBER" "H73688-001"
					( Origin gFrontEnd )
				)
				( attribute "PHYS_PAGE" "224"
					( Origin gFrontEnd )
				)
				( attribute "ROT" "0"
					( Origin gFrontEnd )
				)
				( attribute "SEC" "1"
					( Origin gFrontEnd )
				)
				( attribute "SEC_TYPE" "SM"
					( Origin gFrontEnd )
				)
				( attribute "VALUE" "IR35411"
					( Origin gFrontEnd )
				)
				( attribute "VER" "1"
					( Origin gFrontEnd )
				)
				( attribute "XY" "(1825,2250)"
					( Origin gFrontEnd )
				)
				( attribute "CHIPS_PART_NAME" "IR354XX"
					( Origin gPackager )
				)
				( attribute "CDS_PART_NAME" "IR354XX_SM-IR35411,IC,H73688-0A"
					( Origin gPackager )
				)
				( objectStatus "EU1G1" )
			)
			( gate "@baseboard_fab2_lib.baseboard_fab2(sch_1):page224_i111"
				( attribute "CDS_LIB" "mstr_discrete"
					( Origin gPackager )
				)
				( attribute "CDS_LOCATION" "EU1F1"
					( Origin gPackager )
				)
				( attribute "CDS_SEC" "1"
					( Origin gPackager )
				)
				( attribute "LOCATION" "EU1F1"
					( Origin gFrontEnd )
				)
				( attribute "MATERIAL" "IC"
					( Origin gFrontEnd )
				)
				( attribute "PACK_TYPE" "SM"
					( Origin gFrontEnd )
				)
				( attribute "PART_NUMBER" "H73688-001"
					( Origin gFrontEnd )
				)
				( attribute "PHYS_PAGE" "224"
					( Origin gFrontEnd )
				)
				( attribute "ROT" "0"
					( Origin gFrontEnd )
				)
				( attribute "SEC" "1"
					( Origin gFrontEnd )
				)
				( attribute "SEC_TYPE" "SM"
					( Origin gFrontEnd )
				)
				( attribute "VALUE" "IR35411"
					( Origin gFrontEnd )
				)
				( attribute "VER" "1"
					( Origin gFrontEnd )
				)
				( attribute "XY" "(1850,-125)"
					( Origin gFrontEnd )
				)
				( attribute "CHIPS_PART_NAME" "IR354XX"
					( Origin gPackager )
				)
				( attribute "CDS_PART_NAME" "IR354XX_SM-IR35411,IC,H73688-0A"
					( Origin gPackager )
				)
				( attribute "BOM_SS" "NOPOP"
					( Origin gFrontEnd )
				)
				( objectStatus "EU1F1" )
			)
			( gate "@baseboard_fab2_lib.baseboard_fab2(sch_1):page224_i112"
				( attribute "CDS_LIB" "mstr_discrete"
					( Origin gPackager )
				)
				( attribute "CDS_LOCATION" "R1G26"
					( Origin gPackager )
				)
				( attribute "LOCATION" "R1G26"
					( Origin gFrontEnd )
				)
				( attribute "MATERIAL" "EMPTY"
					( Origin gFrontEnd )
				)
				( attribute "PACK_TYPE" "0402"
					( Origin gFrontEnd )
				)
				( attribute "PART_NUMBER" "G21796-187"
					( Origin gFrontEnd )
				)
				( attribute "PHYS_PAGE" "224"
					( Origin gFrontEnd )
				)
				( attribute "ROT" "0"
					( Origin gFrontEnd )
				)
				( attribute "SEC" "1"
					( Origin gFrontEnd )
				)
				( attribute "TOLERANCE" "1%"
					( Origin gFrontEnd )
				)
				( attribute "VALUE" "68.1K"
					( Origin gFrontEnd )
				)
				( attribute "VER" "2"
					( Origin gFrontEnd )
				)
				( attribute "WATTAGE" "1/16W"
					( Origin gFrontEnd )
				)
				( attribute "XY" "(4625,2400)"
					( Origin gFrontEnd )
				)
				( attribute "CHIPS_PART_NAME" "RES"
					( Origin gPackager )
				)
				( attribute "CDS_PART_NAME" "RES_0402-68.1K,1%,1/16W,EMPTY,A"
					( Origin gPackager )
				)
				( attribute "SEC_TYPE" "0402"
					( Origin gFrontEnd )
				)
				( attribute "CDS_SEC" "1"
					( Origin gPackager )
				)
				( objectStatus "R1G26" )
			)
			( gate "@baseboard_fab2_lib.baseboard_fab2(sch_1):page224_i114"
				( attribute "CDS_LIB" "mstr_discrete"
					( Origin gPackager )
				)
				( attribute "CDS_LOCATION" "R1G25"
					( Origin gPackager )
				)
				( attribute "LOCATION" "R1G25"
					( Origin gFrontEnd )
				)
				( attribute "MATERIAL" "EMPTY"
					( Origin gFrontEnd )
				)
				( attribute "PACK_TYPE" "0402"
					( Origin gFrontEnd )
				)
				( attribute "PART_NUMBER" "G21796-187"
					( Origin gFrontEnd )
				)
				( attribute "PHYS_PAGE" "224"
					( Origin gFrontEnd )
				)
				( attribute "ROT" "0"
					( Origin gFrontEnd )
				)
				( attribute "SEC" "1"
					( Origin gFrontEnd )
				)
				( attribute "TOLERANCE" "1%"
					( Origin gFrontEnd )
				)
				( attribute "VALUE" "68.1K"
					( Origin gFrontEnd )
				)
				( attribute "VER" "2"
					( Origin gFrontEnd )
				)
				( attribute "WATTAGE" "1/16W"
					( Origin gFrontEnd )
				)
				( attribute "XY" "(4650,25)"
					( Origin gFrontEnd )
				)
				( attribute "CHIPS_PART_NAME" "RES"
					( Origin gPackager )
				)
				( attribute "CDS_PART_NAME" "RES_0402-68.1K,1%,1/16W,EMPTY,A"
					( Origin gPackager )
				)
				( attribute "SEC_TYPE" "0402"
					( Origin gFrontEnd )
				)
				( attribute "CDS_SEC" "1"
					( Origin gPackager )
				)
				( attribute "BOM_SS" "NOPOP"
					( Origin gFrontEnd )
				)
				( objectStatus "R1G25" )
			)
			( gate "@baseboard_fab2_lib.baseboard_fab2(sch_1):page225_i58"
				( attribute "BOM_COST" "MEM_VRD_PVPP_AB"
					( Origin gFrontEnd )
				)
				( attribute "CDS_LIB" "mstr_discrete"
					( Origin gPackager )
				)
				( attribute "CDS_LOCATION" "R1G20"
					( Origin gPackager )
				)
				( attribute "CDS_SEC" "1"
					( Origin gPackager )
				)
				( attribute "LOCATION" "R1G20"
					( Origin gFrontEnd )
				)
				( attribute "MATERIAL" "CHIP"
					( Origin gFrontEnd )
				)
				( attribute "PACK_TYPE" "0603"
					( Origin gFrontEnd )
				)
				( attribute "PART_NUMBER" "G22026-003"
					( Origin gFrontEnd )
				)
				( attribute "PHYS_PAGE" "225"
					( Origin gFrontEnd )
				)
				( attribute "ROOM" "VDDQ_GHJ_PWR_VR"
					( Origin gFrontEnd )
				)
				( attribute "ROT" "0"
					( Origin gFrontEnd )
				)
				( attribute "SEC" "1"
					( Origin gPackager )
				)
				( attribute "TOLERANCE" "1%"
					( Origin gFrontEnd )
				)
				( attribute "VALUE" "120.0"
					( Origin gFrontEnd )
				)
				( attribute "VER" "2"
					( Origin gFrontEnd )
				)
				( attribute "WATTAGE" "1/10W"
					( Origin gFrontEnd )
				)
				( attribute "XY" "(4450,-25)"
					( Origin gFrontEnd )
				)
				( attribute "CHIPS_PART_NAME" "RES"
					( Origin gPackager )
				)
				( attribute "CDS_PART_NAME" "RES_0603-120.0,1%,1/10W,CHIP,GA"
					( Origin gPackager )
				)
				( objectStatus "R1G20" )
			)
			( gate "@baseboard_fab2_lib.baseboard_fab2(sch_1):page225_i74"
				( attribute "CDS_LIB" "mstr_discrete"
					( Origin gPackager )
				)
				( attribute "CDS_LOCATION" "R7U2"
					( Origin gPackager )
				)
				( attribute "CDS_SEC" "1"
					( Origin gPackager )
				)
				( attribute "LOCATION" "R7U2"
					( Origin gFrontEnd )
				)
				( attribute "MATERIAL" "EMPTY"
					( Origin gFrontEnd )
				)
				( attribute "PACK_TYPE" "0402"
					( Origin gFrontEnd )
				)
				( attribute "PART_NUMBER" "G21796-017"
					( Origin gFrontEnd )
				)
				( attribute "PHYS_PAGE" "225"
					( Origin gFrontEnd )
				)
				( attribute "ROOM" "VDDQ_GHJ_PWR_VR"
					( Origin gFrontEnd )
				)
				( attribute "ROT" "0"
					( Origin gFrontEnd )
				)
				( attribute "SEC" "1"
					( Origin gFrontEnd )
				)
				( attribute "SEC_TYPE" "0402"
					( Origin gFrontEnd )
				)
				( attribute "TOLERANCE" "1%"
					( Origin gFrontEnd )
				)
				( attribute "VALUE" "100.0"
					( Origin gFrontEnd )
				)
				( attribute "VER" "2"
					( Origin gFrontEnd )
				)
				( attribute "WATTAGE" "1/16W"
					( Origin gFrontEnd )
				)
				( attribute "XY" "(-650,2075)"
					( Origin gFrontEnd )
				)
				( attribute "CHIPS_PART_NAME" "RES"
					( Origin gPackager )
				)
				( attribute "CDS_PART_NAME" "RES_0402-100.0,1%,1/16W,EMPTY,A"
					( Origin gPackager )
				)
				( objectStatus "R7U2" )
			)
			( gate "@baseboard_fab2_lib.baseboard_fab2(sch_1):page225_i75"
				( attribute "CDS_LIB" "mstr_discrete"
					( Origin gPackager )
				)
				( attribute "CDS_LOCATION" "C9T5"
					( Origin gPackager )
				)
				( attribute "CDS_SEC" "1"
					( Origin gPackager )
				)
				( attribute "LOCATION" "C9T5"
					( Origin gFrontEnd )
				)
				( attribute "MATERIAL" "ALUM"
					( Origin gFrontEnd )
				)
				( attribute "PACK_TYPE" "3018"
					( Origin gFrontEnd )
				)
				( attribute "PART_NUMBER" "699013-049"
					( Origin gFrontEnd )
				)
				( attribute "PHYS_PAGE" "225"
					( Origin gFrontEnd )
				)
				( attribute "ROOM" "VDDQ_GHJ_PWR_VR"
					( Origin gFrontEnd )
				)
				( attribute "ROT" "0"
					( Origin gFrontEnd )
				)
				( attribute "SEC" "1"
					( Origin gFrontEnd )
				)
				( attribute "SEC_TYPE" "3018"
					( Origin gFrontEnd )
				)
				( attribute "TOLERANCE" "20%"
					( Origin gFrontEnd )
				)
				( attribute "VALUE" "470UF"
					( Origin gFrontEnd )
				)
				( attribute "VER" "1"
					( Origin gFrontEnd )
				)
				( attribute "VOLTAGE" "2.5V"
					( Units "uVoltage" "V" 1.000000)
					( Origin gFrontEnd )
				)
				( attribute "XY" "(3250,-50)"
					( Origin gFrontEnd )
				)
				( attribute "CHIPS_PART_NAME" "CAPP"
					( Origin gPackager )
				)
				( attribute "CDS_PART_NAME" "CAPP_3018-470UF,2.5V,20%,ALUM,A"
					( Origin gPackager )
				)
				( attribute "GROUP" "PWR_BULK_CAP"
					( Origin gFrontEnd )
				)
				( objectStatus "C9T5" )
			)
			( gate "@baseboard_fab2_lib.baseboard_fab2(sch_1):page225_i76"
				( attribute "CDS_LIB" "mstr_discrete"
					( Origin gPackager )
				)
				( attribute "CDS_LOCATION" "C9U2"
					( Origin gPackager )
				)
				( attribute "CDS_SEC" "1"
					( Origin gPackager )
				)
				( attribute "LOCATION" "C9U2"
					( Origin gFrontEnd )
				)
				( attribute "MATERIAL" "ALUM"
					( Origin gFrontEnd )
				)
				( attribute "PACK_TYPE" "3018"
					( Origin gFrontEnd )
				)
				( attribute "PART_NUMBER" "699013-049"
					( Origin gFrontEnd )
				)
				( attribute "PHYS_PAGE" "225"
					( Origin gFrontEnd )
				)
				( attribute "ROOM" "VDDQ_GHJ_PWR_VR"
					( Origin gFrontEnd )
				)
				( attribute "ROT" "0"
					( Origin gFrontEnd )
				)
				( attribute "SEC" "1"
					( Origin gFrontEnd )
				)
				( attribute "SEC_TYPE" "3018"
					( Origin gFrontEnd )
				)
				( attribute "TOLERANCE" "20%"
					( Origin gFrontEnd )
				)
				( attribute "VALUE" "470UF"
					( Origin gFrontEnd )
				)
				( attribute "VER" "1"
					( Origin gFrontEnd )
				)
				( attribute "VOLTAGE" "2.5V"
					( Units "uVoltage" "V" 1.000000)
					( Origin gFrontEnd )
				)
				( attribute "XY" "(3550,-50)"
					( Origin gFrontEnd )
				)
				( attribute "CHIPS_PART_NAME" "CAPP"
					( Origin gPackager )
				)
				( attribute "CDS_PART_NAME" "CAPP_3018-470UF,2.5V,20%,ALUM,A"
					( Origin gPackager )
				)
				( attribute "GROUP" "PWR_BULK_CAP"
					( Origin gFrontEnd )
				)
				( objectStatus "C9U2" )
			)
			( gate "@baseboard_fab2_lib.baseboard_fab2(sch_1):page225_i77"
				( attribute "CDS_LIB" "mstr_discrete"
					( Origin gPackager )
				)
				( attribute "CDS_LOCATION" "C9U9"
					( Origin gPackager )
				)
				( attribute "CDS_SEC" "1"
					( Origin gPackager )
				)
				( attribute "LOCATION" "C9U9"
					( Origin gFrontEnd )
				)
				( attribute "MATERIAL" "ALUM"
					( Origin gFrontEnd )
				)
				( attribute "PACK_TYPE" "3018"
					( Origin gFrontEnd )
				)
				( attribute "PART_NUMBER" "699013-049"
					( Origin gFrontEnd )
				)
				( attribute "PHYS_PAGE" "225"
					( Origin gFrontEnd )
				)
				( attribute "ROOM" "VDDQ_GHJ_PWR_VR"
					( Origin gFrontEnd )
				)
				( attribute "ROT" "0"
					( Origin gFrontEnd )
				)
				( attribute "SEC" "1"
					( Origin gFrontEnd )
				)
				( attribute "SEC_TYPE" "3018"
					( Origin gFrontEnd )
				)
				( attribute "TOLERANCE" "20%"
					( Origin gFrontEnd )
				)
				( attribute "VALUE" "470UF"
					( Origin gFrontEnd )
				)
				( attribute "VER" "1"
					( Origin gFrontEnd )
				)
				( attribute "VOLTAGE" "2.5V"
					( Units "uVoltage" "V" 1.000000)
					( Origin gFrontEnd )
				)
				( attribute "XY" "(3850,-50)"
					( Origin gFrontEnd )
				)
				( attribute "CHIPS_PART_NAME" "CAPP"
					( Origin gPackager )
				)
				( attribute "CDS_PART_NAME" "CAPP_3018-470UF,2.5V,20%,ALUM,A"
					( Origin gPackager )
				)
				( attribute "GROUP" "PWR_BULK_CAP"
					( Origin gFrontEnd )
				)
				( objectStatus "C9U9" )
			)
			( gate "@baseboard_fab2_lib.baseboard_fab2(sch_1):page225_i78"
				( attribute "CDS_LIB" "mstr_discrete"
					( Origin gPackager )
				)
				( attribute "CDS_LOCATION" "C9U5"
					( Origin gPackager )
				)
				( attribute "CDS_SEC" "1"
					( Origin gPackager )
				)
				( attribute "LOCATION" "C9U5"
					( Origin gFrontEnd )
				)
				( attribute "MATERIAL" "ALUM"
					( Origin gFrontEnd )
				)
				( attribute "PACK_TYPE" "3018"
					( Origin gFrontEnd )
				)
				( attribute "PART_NUMBER" "699013-049"
					( Origin gFrontEnd )
				)
				( attribute "PHYS_PAGE" "225"
					( Origin gFrontEnd )
				)
				( attribute "ROOM" "VDDQ_GHJ_PWR_VR"
					( Origin gFrontEnd )
				)
				( attribute "ROT" "0"
					( Origin gFrontEnd )
				)
				( attribute "SEC" "1"
					( Origin gFrontEnd )
				)
				( attribute "SEC_TYPE" "3018"
					( Origin gFrontEnd )
				)
				( attribute "TOLERANCE" "20%"
					( Origin gFrontEnd )
				)
				( attribute "VALUE" "470UF"
					( Origin gFrontEnd )
				)
				( attribute "VER" "1"
					( Origin gFrontEnd )
				)
				( attribute "VOLTAGE" "2.5V"
					( Units "uVoltage" "V" 1.000000)
					( Origin gFrontEnd )
				)
				( attribute "XY" "(4150,-50)"
					( Origin gFrontEnd )
				)
				( attribute "CHIPS_PART_NAME" "CAPP"
					( Origin gPackager )
				)
				( attribute "CDS_PART_NAME" "CAPP_3018-470UF,2.5V,20%,ALUM,A"
					( Origin gPackager )
				)
				( attribute "GROUP" "PWR_BULK_CAP"
					( Origin gFrontEnd )
				)
				( objectStatus "C9U5" )
			)
			( gate "@baseboard_fab2_lib.baseboard_fab2(sch_1):page225_i320"
				( attribute "BOM_COST" "MEM_VRD_PVDDQ_CD"
					( Origin gFrontEnd )
				)
				( attribute "CDS_LIB" "mstr_discrete"
					( Origin gPackager )
				)
				( attribute "CDS_LOCATION" "C8U8"
					( Origin gPackager )
				)
				( attribute "CDS_SEC" "1"
					( Origin gPackager )
				)
				( attribute "LOCATION" "C8U8"
					( Origin gFrontEnd )
				)
				( attribute "MATERIAL" "X5R"
					( Origin gFrontEnd )
				)
				( attribute "NEW_MATERIAL" "X6S"
					( Origin gFrontEnd )
				)
				( attribute "PACK_TYPE" "0805"
					( Origin gFrontEnd )
				)
				( attribute "PART_NUMBER" "602433-112"
					( Origin gFrontEnd )
				)
				( attribute "PHYS_PAGE" "225"
					( Origin gFrontEnd )
				)
				( attribute "ROOM" "VDDQ_ABC_PWR_VR"
					( Origin gFrontEnd )
				)
				( attribute "ROT" "0"
					( Origin gFrontEnd )
				)
				( attribute "SEC" "1"
					( Origin gFrontEnd )
				)
				( attribute "SEC_TYPE" "0805"
					( Origin gFrontEnd )
				)
				( attribute "TOLERANCE" "20%"
					( Origin gFrontEnd )
				)
				( attribute "VALUE" "100UF"
					( Origin gFrontEnd )
				)
				( attribute "VER" "1"
					( Origin gFrontEnd )
				)
				( attribute "VOLTAGE" "4V"
					( Units "uVoltage" "V" 1.000000)
					( Origin gFrontEnd )
				)
				( attribute "XY" "(4600,2825)"
					( Origin gFrontEnd )
				)
				( attribute "CHIPS_PART_NAME" "CAP"
					( Origin gPackager )
				)
				( attribute "CDS_PART_NAME" "CAP_0805-100UF,4V,20%,X5R,6024A"
					( Origin gPackager )
				)
				( attribute "GROUP" "PWR_MLCC_CAP"
					( Origin gFrontEnd )
				)
				( attribute "NEW_PN" "078.1071T.M002"
					( Origin gFrontEnd )
				)
				( attribute "BOM_SS" "NOPOP"
					( Origin gFrontEnd )
				)
				( objectStatus "C8U8" )
			)
			( gate "@baseboard_fab2_lib.baseboard_fab2(sch_1):page228_i301"
				( attribute "BOM_COST" "MEM_VRD_PVDDQ_CD"
					( Origin gFrontEnd )
				)
				( attribute "CDS_LIB" "mstr_discrete"
					( Origin gPackager )
				)
				( attribute "CDS_LOCATION" "C8L1"
					( Origin gPackager )
				)
				( attribute "CDS_SEC" "1"
					( Origin gPackager )
				)
				( attribute "LOCATION" "C8L1"
					( Origin gFrontEnd )
				)
				( attribute "MATERIAL" "X5R"
					( Origin gFrontEnd )
				)
				( attribute "NEW_MATERIAL" "X6S"
					( Origin gFrontEnd )
				)
				( attribute "PACK_TYPE" "0805"
					( Origin gFrontEnd )
				)
				( attribute "PART_NUMBER" "602433-112"
					( Origin gFrontEnd )
				)
				( attribute "PHYS_PAGE" "228"
					( Origin gFrontEnd )
				)
				( attribute "ROOM" "VDDQ_ABC_PWR_VR"
					( Origin gFrontEnd )
				)
				( attribute "ROT" "0"
					( Origin gFrontEnd )
				)
				( attribute "SEC" "1"
					( Origin gFrontEnd )
				)
				( attribute "SEC_TYPE" "0805"
					( Origin gFrontEnd )
				)
				( attribute "TOLERANCE" "20%"
					( Origin gFrontEnd )
				)
				( attribute "VALUE" "100UF"
					( Origin gFrontEnd )
				)
				( attribute "VER" "1"
					( Origin gFrontEnd )
				)
				( attribute "VOLTAGE" "4V"
					( Units "uVoltage" "V" 1.000000)
					( Origin gFrontEnd )
				)
				( attribute "XY" "(2400,2825)"
					( Origin gFrontEnd )
				)
				( attribute "CHIPS_PART_NAME" "CAP"
					( Origin gPackager )
				)
				( attribute "CDS_PART_NAME" "CAP_0805-100UF,4V,20%,X5R,6024A"
					( Origin gPackager )
				)
				( attribute "GROUP" "PWR_MLCC_CAP"
					( Origin gFrontEnd )
				)
				( attribute "NEW_PN" "078.1071T.M002"
					( Origin gFrontEnd )
				)
				( attribute "BOM_SS" "NOPOP"
					( Origin gFrontEnd )
				)
				( objectStatus "C8L1" )
			)
			( gate "@baseboard_fab2_lib.baseboard_fab2(sch_1):page225_i311"
				( attribute "BOM_COST" "MEM_VRD_PVDDQ_CD"
					( Origin gFrontEnd )
				)
				( attribute "CDS_LIB" "mstr_discrete"
					( Origin gPackager )
				)
				( attribute "CDS_LOCATION" "C2G16"
					( Origin gPackager )
				)
				( attribute "CDS_SEC" "1"
					( Origin gPackager )
				)
				( attribute "LOCATION" "C2G16"
					( Origin gFrontEnd )
				)
				( attribute "MATERIAL" "X5R"
					( Origin gFrontEnd )
				)
				( attribute "NEW_MATERIAL" "X6S"
					( Origin gFrontEnd )
				)
				( attribute "PACK_TYPE" "0805"
					( Origin gFrontEnd )
				)
				( attribute "PART_NUMBER" "602433-112"
					( Origin gFrontEnd )
				)
				( attribute "PHYS_PAGE" "225"
					( Origin gFrontEnd )
				)
				( attribute "ROOM" "VDDQ_ABC_PWR_VR"
					( Origin gFrontEnd )
				)
				( attribute "ROT" "0"
					( Origin gFrontEnd )
				)
				( attribute "SEC" "1"
					( Origin gFrontEnd )
				)
				( attribute "SEC_TYPE" "0805"
					( Origin gFrontEnd )
				)
				( attribute "TOLERANCE" "20%"
					( Origin gFrontEnd )
				)
				( attribute "VALUE" "100UF"
					( Origin gFrontEnd )
				)
				( attribute "VER" "1"
					( Origin gFrontEnd )
				)
				( attribute "VOLTAGE" "4V"
					( Units "uVoltage" "V" 1.000000)
					( Origin gFrontEnd )
				)
				( attribute "XY" "(2400,2825)"
					( Origin gFrontEnd )
				)
				( attribute "CHIPS_PART_NAME" "CAP"
					( Origin gPackager )
				)
				( attribute "CDS_PART_NAME" "CAP_0805-100UF,4V,20%,X5R,6024A"
					( Origin gPackager )
				)
				( attribute "GROUP" "PWR_MLCC_CAP"
					( Origin gFrontEnd )
				)
				( attribute "NEW_PN" "078.1071T.M002"
					( Origin gFrontEnd )
				)
				( attribute "BOM_SS" "NOPOP"
					( Origin gFrontEnd )
				)
				( objectStatus "C2G16" )
			)
			( gate "@baseboard_fab2_lib.baseboard_fab2(sch_1):page225_i308"
				( attribute "BOM_COST" "MEM_VRD_PVDDQ_CD"
					( Origin gFrontEnd )
				)
				( attribute "CDS_LIB" "mstr_discrete"
					( Origin gPackager )
				)
				( attribute "CDS_LOCATION" "C7U7"
					( Origin gPackager )
				)
				( attribute "CDS_SEC" "1"
					( Origin gPackager )
				)
				( attribute "LOCATION" "C7U7"
					( Origin gFrontEnd )
				)
				( attribute "MATERIAL" "X5R"
					( Origin gFrontEnd )
				)
				( attribute "NEW_MATERIAL" "X6S"
					( Origin gFrontEnd )
				)
				( attribute "PACK_TYPE" "0805"
					( Origin gFrontEnd )
				)
				( attribute "PART_NUMBER" "602433-112"
					( Origin gFrontEnd )
				)
				( attribute "PHYS_PAGE" "225"
					( Origin gFrontEnd )
				)
				( attribute "ROOM" "VDDQ_ABC_PWR_VR"
					( Origin gFrontEnd )
				)
				( attribute "ROT" "0"
					( Origin gFrontEnd )
				)
				( attribute "SEC" "1"
					( Origin gFrontEnd )
				)
				( attribute "SEC_TYPE" "0805"
					( Origin gFrontEnd )
				)
				( attribute "TOLERANCE" "20%"
					( Origin gFrontEnd )
				)
				( attribute "VALUE" "100UF"
					( Origin gFrontEnd )
				)
				( attribute "VER" "1"
					( Origin gFrontEnd )
				)
				( attribute "VOLTAGE" "4V"
					( Units "uVoltage" "V" 1.000000)
					( Origin gFrontEnd )
				)
				( attribute "XY" "(3150,2825)"
					( Origin gFrontEnd )
				)
				( attribute "CHIPS_PART_NAME" "CAP"
					( Origin gPackager )
				)
				( attribute "CDS_PART_NAME" "CAP_0805-100UF,4V,20%,X5R,6024A"
					( Origin gPackager )
				)
				( attribute "GROUP" "PWR_MLCC_CAP"
					( Origin gFrontEnd )
				)
				( attribute "NEW_PN" "078.1071T.M002"
					( Origin gFrontEnd )
				)
				( attribute "BOM_SS" "NOPOP"
					( Origin gFrontEnd )
				)
				( objectStatus "C7U7" )
			)
			( gate "@baseboard_fab2_lib.baseboard_fab2(sch_1):page228_i302"
				( attribute "BOM_COST" "MEM_VRD_PVDDQ_CD"
					( Origin gFrontEnd )
				)
				( attribute "CDS_LIB" "mstr_discrete"
					( Origin gPackager )
				)
				( attribute "CDS_LOCATION" "C8L11"
					( Origin gPackager )
				)
				( attribute "CDS_SEC" "1"
					( Origin gPackager )
				)
				( attribute "LOCATION" "C8L11"
					( Origin gFrontEnd )
				)
				( attribute "MATERIAL" "X5R"
					( Origin gFrontEnd )
				)
				( attribute "NEW_MATERIAL" "X6S"
					( Origin gFrontEnd )
				)
				( attribute "PACK_TYPE" "0805"
					( Origin gFrontEnd )
				)
				( attribute "PART_NUMBER" "602433-112"
					( Origin gFrontEnd )
				)
				( attribute "PHYS_PAGE" "228"
					( Origin gFrontEnd )
				)
				( attribute "ROOM" "VDDQ_ABC_PWR_VR"
					( Origin gFrontEnd )
				)
				( attribute "ROT" "0"
					( Origin gFrontEnd )
				)
				( attribute "SEC" "1"
					( Origin gFrontEnd )
				)
				( attribute "SEC_TYPE" "0805"
					( Origin gFrontEnd )
				)
				( attribute "TOLERANCE" "20%"
					( Origin gFrontEnd )
				)
				( attribute "VALUE" "100UF"
					( Origin gFrontEnd )
				)
				( attribute "VER" "1"
					( Origin gFrontEnd )
				)
				( attribute "VOLTAGE" "4V"
					( Units "uVoltage" "V" 1.000000)
					( Origin gFrontEnd )
				)
				( attribute "XY" "(4250,2825)"
					( Origin gFrontEnd )
				)
				( attribute "CHIPS_PART_NAME" "CAP"
					( Origin gPackager )
				)
				( attribute "CDS_PART_NAME" "CAP_0805-100UF,4V,20%,X5R,6024A"
					( Origin gPackager )
				)
				( attribute "GROUP" "PWR_MLCC_CAP"
					( Origin gFrontEnd )
				)
				( attribute "NEW_PN" "078.1071T.M002"
					( Origin gFrontEnd )
				)
				( attribute "BOM_SS" "NOPOP"
					( Origin gFrontEnd )
				)
				( objectStatus "C8L11" )
			)
			( gate "@baseboard_fab2_lib.baseboard_fab2(sch_1):page225_i310"
				( attribute "BOM_COST" "MEM_VRD_PVDDQ_CD"
					( Origin gFrontEnd )
				)
				( attribute "CDS_LIB" "mstr_discrete"
					( Origin gPackager )
				)
				( attribute "CDS_LOCATION" "C8U12"
					( Origin gPackager )
				)
				( attribute "CDS_SEC" "1"
					( Origin gPackager )
				)
				( attribute "LOCATION" "C8U12"
					( Origin gFrontEnd )
				)
				( attribute "MATERIAL" "X5R"
					( Origin gFrontEnd )
				)
				( attribute "NEW_MATERIAL" "X6S"
					( Origin gFrontEnd )
				)
				( attribute "PACK_TYPE" "0805"
					( Origin gFrontEnd )
				)
				( attribute "PART_NUMBER" "602433-112"
					( Origin gFrontEnd )
				)
				( attribute "PHYS_PAGE" "225"
					( Origin gFrontEnd )
				)
				( attribute "ROOM" "VDDQ_ABC_PWR_VR"
					( Origin gFrontEnd )
				)
				( attribute "ROT" "0"
					( Origin gFrontEnd )
				)
				( attribute "SEC" "1"
					( Origin gFrontEnd )
				)
				( attribute "SEC_TYPE" "0805"
					( Origin gFrontEnd )
				)
				( attribute "TOLERANCE" "20%"
					( Origin gFrontEnd )
				)
				( attribute "VALUE" "100UF"
					( Origin gFrontEnd )
				)
				( attribute "VER" "1"
					( Origin gFrontEnd )
				)
				( attribute "VOLTAGE" "4V"
					( Units "uVoltage" "V" 1.000000)
					( Origin gFrontEnd )
				)
				( attribute "XY" "(4250,2825)"
					( Origin gFrontEnd )
				)
				( attribute "CHIPS_PART_NAME" "CAP"
					( Origin gPackager )
				)
				( attribute "CDS_PART_NAME" "CAP_0805-100UF,4V,20%,X5R,6024A"
					( Origin gPackager )
				)
				( attribute "GROUP" "PWR_MLCC_CAP"
					( Origin gFrontEnd )
				)
				( attribute "NEW_PN" "078.1071T.M002"
					( Origin gFrontEnd )
				)
				( attribute "BOM_SS" "NOPOP"
					( Origin gFrontEnd )
				)
				( objectStatus "C8U12" )
			)
			( gate "@baseboard_fab2_lib.baseboard_fab2(sch_1):page225_i313"
				( attribute "BOM_COST" "MEM_VRD_PVDDQ_CD"
					( Origin gFrontEnd )
				)
				( attribute "CDS_LIB" "mstr_discrete"
					( Origin gPackager )
				)
				( attribute "CDS_LOCATION" "C8P30"
					( Origin gPackager )
				)
				( attribute "CDS_SEC" "1"
					( Origin gPackager )
				)
				( attribute "LOCATION" "C8P30"
					( Origin gFrontEnd )
				)
				( attribute "MATERIAL" "X5R"
					( Origin gFrontEnd )
				)
				( attribute "NEW_MATERIAL" "X6S"
					( Origin gFrontEnd )
				)
				( attribute "PACK_TYPE" "0805"
					( Origin gFrontEnd )
				)
				( attribute "PART_NUMBER" "602433-112"
					( Origin gFrontEnd )
				)
				( attribute "PHYS_PAGE" "225"
					( Origin gFrontEnd )
				)
				( attribute "ROOM" "VDDQ_ABC_PWR_VR"
					( Origin gFrontEnd )
				)
				( attribute "ROT" "0"
					( Origin gFrontEnd )
				)
				( attribute "SEC" "1"
					( Origin gFrontEnd )
				)
				( attribute "SEC_TYPE" "0805"
					( Origin gFrontEnd )
				)
				( attribute "TOLERANCE" "20%"
					( Origin gFrontEnd )
				)
				( attribute "VALUE" "100UF"
					( Origin gFrontEnd )
				)
				( attribute "VER" "1"
					( Origin gFrontEnd )
				)
				( attribute "VOLTAGE" "4V"
					( Units "uVoltage" "V" 1.000000)
					( Origin gFrontEnd )
				)
				( attribute "XY" "(-2325,3100)"
					( Origin gFrontEnd )
				)
				( attribute "CHIPS_PART_NAME" "CAP"
					( Origin gPackager )
				)
				( attribute "CDS_PART_NAME" "CAP_0805-100UF,4V,20%,X5R,6024A"
					( Origin gPackager )
				)
				( attribute "GROUP" "PWR_MLCC_CAP"
					( Origin gFrontEnd )
				)
				( attribute "NEW_PN" "078.1071T.M002"
					( Origin gFrontEnd )
				)
				( attribute "BOM_SS" "NOPOP"
					( Origin gFrontEnd )
				)
				( objectStatus "C8P30" )
			)
			( gate "@baseboard_fab2_lib.baseboard_fab2(sch_1):page225_i312"
				( attribute "BOM_COST" "MEM_VRD_PVDDQ_CD"
					( Origin gFrontEnd )
				)
				( attribute "CDS_LIB" "mstr_discrete"
					( Origin gPackager )
				)
				( attribute "CDS_LOCATION" "C2G7"
					( Origin gPackager )
				)
				( attribute "CDS_SEC" "1"
					( Origin gPackager )
				)
				( attribute "LOCATION" "C2G7"
					( Origin gFrontEnd )
				)
				( attribute "MATERIAL" "X5R"
					( Origin gFrontEnd )
				)
				( attribute "NEW_MATERIAL" "X6S"
					( Origin gFrontEnd )
				)
				( attribute "PACK_TYPE" "0805"
					( Origin gFrontEnd )
				)
				( attribute "PART_NUMBER" "602433-112"
					( Origin gFrontEnd )
				)
				( attribute "PHYS_PAGE" "225"
					( Origin gFrontEnd )
				)
				( attribute "ROOM" "VDDQ_ABC_PWR_VR"
					( Origin gFrontEnd )
				)
				( attribute "ROT" "0"
					( Origin gFrontEnd )
				)
				( attribute "SEC" "1"
					( Origin gFrontEnd )
				)
				( attribute "SEC_TYPE" "0805"
					( Origin gFrontEnd )
				)
				( attribute "TOLERANCE" "20%"
					( Origin gFrontEnd )
				)
				( attribute "VALUE" "100UF"
					( Origin gFrontEnd )
				)
				( attribute "VER" "1"
					( Origin gFrontEnd )
				)
				( attribute "VOLTAGE" "4V"
					( Units "uVoltage" "V" 1.000000)
					( Origin gFrontEnd )
				)
				( attribute "XY" "(2750,2825)"
					( Origin gFrontEnd )
				)
				( attribute "CHIPS_PART_NAME" "CAP"
					( Origin gPackager )
				)
				( attribute "CDS_PART_NAME" "CAP_0805-100UF,4V,20%,X5R,6024A"
					( Origin gPackager )
				)
				( attribute "GROUP" "PWR_MLCC_CAP"
					( Origin gFrontEnd )
				)
				( attribute "NEW_PN" "078.1071T.M002"
					( Origin gFrontEnd )
				)
				( attribute "BOM_SS" "NOPOP"
					( Origin gFrontEnd )
				)
				( objectStatus "C2G7" )
			)
			( gate "@baseboard_fab2_lib.baseboard_fab2(sch_1):page228_i247"
				( attribute "CDS_LIB" "w_hdl"
					( Origin gPackager )
				)
				( attribute "CDS_LMAN_SYM_OUTLINE" "-75,100,75,-100"
					( Origin gPackager )
				)
				( attribute "LOCATION" "L1B1"
					( Origin gFrontEnd )
				)
				( attribute "PACK_TYPE" "DISCRET-G8"
					( Origin gFrontEnd )
				)
				( attribute "PART_NUMBER" "068.1011N.M001"
					( Origin gFrontEnd )
				)
				( attribute "PHYS_PAGE" "228"
					( Origin gFrontEnd )
				)
				( attribute "ROT" "1"
					( Origin gFrontEnd )
				)
				( attribute "SEC" "1"
					( Origin gFrontEnd )
				)
				( attribute "SEC_TYPE" "DISCRET-G8"
					( Origin gFrontEnd )
				)
				( attribute "VALUE" "IND-100NH-35-GP"
					( Origin gFrontEnd )
				)
				( attribute "VER" "1"
					( Origin gFrontEnd )
				)
				( attribute "XY" "(-1050,1125)"
					( Origin gFrontEnd )
				)
				( attribute "CHIPS_PART_NAME" "IND-100NH-35-GP"
					( Origin gPackager )
				)
				( attribute "CDS_PART_NAME" "IND-100NH-35-GP_DISCRET-G8-INDA"
					( Origin gPackager )
				)
				( attribute "CDS_LOCATION" "L1B1"
					( Origin gPackager )
				)
				( attribute "CDS_SEC" "1"
					( Origin gPackager )
				)
				( attribute "ATTRIBUTE" "100NH"
					( Origin gFrontEnd )
				)
				( attribute "PACK_SIZE" "DCR=0.16MOHM"
					( Origin gFrontEnd )
				)
				( attribute "RATED" "ISAT=16A@25C"
					( Origin gFrontEnd )
				)
				( attribute "TYPE" "IRMS=29A@DELTA_T<45C"
					( Origin gFrontEnd )
				)
				( objectStatus "L1B1" )
			)
			( gate "@baseboard_fab2_lib.baseboard_fab2(sch_1):page228_i305"
				( attribute "BOM_COST" "MEM_VRD_PVDDQ_CD"
					( Origin gFrontEnd )
				)
				( attribute "CDS_LIB" "mstr_discrete"
					( Origin gPackager )
				)
				( attribute "CDS_LOCATION" "C7P2"
					( Origin gPackager )
				)
				( attribute "CDS_SEC" "1"
					( Origin gPackager )
				)
				( attribute "LOCATION" "C7P2"
					( Origin gFrontEnd )
				)
				( attribute "MATERIAL" "X5R"
					( Origin gFrontEnd )
				)
				( attribute "NEW_MATERIAL" "X6S"
					( Origin gFrontEnd )
				)
				( attribute "PACK_TYPE" "0805"
					( Origin gFrontEnd )
				)
				( attribute "PART_NUMBER" "602433-112"
					( Origin gFrontEnd )
				)
				( attribute "PHYS_PAGE" "228"
					( Origin gFrontEnd )
				)
				( attribute "ROOM" "VDDQ_ABC_PWR_VR"
					( Origin gFrontEnd )
				)
				( attribute "ROT" "0"
					( Origin gFrontEnd )
				)
				( attribute "SEC" "1"
					( Origin gFrontEnd )
				)
				( attribute "SEC_TYPE" "0805"
					( Origin gFrontEnd )
				)
				( attribute "TOLERANCE" "20%"
					( Origin gFrontEnd )
				)
				( attribute "VALUE" "100UF"
					( Origin gFrontEnd )
				)
				( attribute "VER" "1"
					( Origin gFrontEnd )
				)
				( attribute "VOLTAGE" "4V"
					( Units "uVoltage" "V" 1.000000)
					( Origin gFrontEnd )
				)
				( attribute "XY" "(1625,2775)"
					( Origin gFrontEnd )
				)
				( attribute "CHIPS_PART_NAME" "CAP"
					( Origin gPackager )
				)
				( attribute "CDS_PART_NAME" "CAP_0805-100UF,4V,20%,X5R,6024A"
					( Origin gPackager )
				)
				( attribute "GROUP" "PWR_MLCC_CAP"
					( Origin gFrontEnd )
				)
				( attribute "NEW_PN" "078.1071T.M002"
					( Origin gFrontEnd )
				)
				( attribute "BOM_SS" "NOPOP"
					( Origin gFrontEnd )
				)
				( objectStatus "C7P2" )
			)
			( gate "@baseboard_fab2_lib.baseboard_fab2(sch_1):page225_i275"
				( attribute "CDS_LIB" "dev_discrete"
					( Origin gPackager )
				)
				( attribute "CDS_LOCATION" "C2G11"
					( Origin gPackager )
				)
				( attribute "CDS_SEC" "1"
					( Origin gPackager )
				)
				( attribute "LOCATION" "C2G11"
					( Origin gFrontEnd )
				)
				( attribute "MATERIAL" "X5R"
					( Origin gFrontEnd )
				)
				( attribute "PACK_TYPE" "0603V"
					( Origin gFrontEnd )
				)
				( attribute "PART_NUMBER" "602433-106"
					( Origin gFrontEnd )
				)
				( attribute "PHYS_PAGE" "225"
					( Origin gFrontEnd )
				)
				( attribute "ROT" "0"
					( Origin gFrontEnd )
				)
				( attribute "SEC" "1"
					( Origin gFrontEnd )
				)
				( attribute "SEC_TYPE" "0603V"
					( Origin gFrontEnd )
				)
				( attribute "TOLERANCE" "20%"
					( Origin gFrontEnd )
				)
				( attribute "VALUE" "47UF"
					( Origin gFrontEnd )
				)
				( attribute "VER" "1"
					( Origin gFrontEnd )
				)
				( attribute "VOLTAGE" "4V"
					( Units "uVoltage" "V" 1.000000)
					( Origin gFrontEnd )
				)
				( attribute "XY" "(-1975,250)"
					( Origin gFrontEnd )
				)
				( attribute "CHIPS_PART_NAME" "CAP_A"
					( Origin gPackager )
				)
				( attribute "CDS_PART_NAME" "CAP_A_0603V-47UF,4V,20%,X5R,60A"
					( Origin gPackager )
				)
				( attribute "GROUP" "PWR_MLCC_CAP"
					( Origin gFrontEnd )
				)
				( attribute "BOM_SS" "E15431-004"
					( Origin gFrontEnd )
				)
				( objectStatus "C2G11" )
			)
			( gate "@baseboard_fab2_lib.baseboard_fab2(sch_1):page225_i274"
				( attribute "CDS_LIB" "dev_discrete"
					( Origin gPackager )
				)
				( attribute "CDS_LOCATION" "C2G10"
					( Origin gPackager )
				)
				( attribute "CDS_SEC" "1"
					( Origin gPackager )
				)
				( attribute "LOCATION" "C2G10"
					( Origin gFrontEnd )
				)
				( attribute "MATERIAL" "X5R"
					( Origin gFrontEnd )
				)
				( attribute "PACK_TYPE" "0603V"
					( Origin gFrontEnd )
				)
				( attribute "PART_NUMBER" "602433-106"
					( Origin gFrontEnd )
				)
				( attribute "PHYS_PAGE" "225"
					( Origin gFrontEnd )
				)
				( attribute "ROT" "0"
					( Origin gFrontEnd )
				)
				( attribute "SEC" "1"
					( Origin gFrontEnd )
				)
				( attribute "SEC_TYPE" "0603V"
					( Origin gFrontEnd )
				)
				( attribute "TOLERANCE" "20%"
					( Origin gFrontEnd )
				)
				( attribute "VALUE" "47UF"
					( Origin gFrontEnd )
				)
				( attribute "VER" "1"
					( Origin gFrontEnd )
				)
				( attribute "VOLTAGE" "4V"
					( Units "uVoltage" "V" 1.000000)
					( Origin gFrontEnd )
				)
				( attribute "XY" "(-2275,250)"
					( Origin gFrontEnd )
				)
				( attribute "CHIPS_PART_NAME" "CAP_A"
					( Origin gPackager )
				)
				( attribute "CDS_PART_NAME" "CAP_A_0603V-47UF,4V,20%,X5R,60A"
					( Origin gPackager )
				)
				( attribute "GROUP" "PWR_MLCC_CAP"
					( Origin gFrontEnd )
				)
				( attribute "BOM_SS" "E15431-004"
					( Origin gFrontEnd )
				)
				( objectStatus "C2G10" )
			)
			( gate "@baseboard_fab2_lib.baseboard_fab2(sch_1):page188_i121"
				( attribute "CDS_LIB" "dev_discrete"
					( Origin gPackager )
				)
				( attribute "CDS_LOCATION" "C8C12"
					( Origin gPackager )
				)
				( attribute "CDS_SEC" "1"
					( Origin gPackager )
				)
				( attribute "LOCATION" "C8C12"
					( Origin gFrontEnd )
				)
				( attribute "MATERIAL" "X7R"
					( Origin gFrontEnd )
				)
				( attribute "PACK_TYPE" "0402V"
					( Origin gFrontEnd )
				)
				( attribute "PART_NUMBER" "A36096-030"
					( Origin gFrontEnd )
				)
				( attribute "PHYS_PAGE" "188"
					( Origin gFrontEnd )
				)
				( attribute "ROT" "0"
					( Origin gFrontEnd )
				)
				( attribute "SEC" "1"
					( Origin gFrontEnd )
				)
				( attribute "SEC_TYPE" "0402V"
					( Origin gFrontEnd )
				)
				( attribute "TOLERANCE" "10%"
					( Origin gFrontEnd )
				)
				( attribute "VALUE" "0.1UF"
					( Origin gFrontEnd )
				)
				( attribute "VER" "2"
					( Origin gFrontEnd )
				)
				( attribute "VOLTAGE" "16V"
					( Units "uVoltage" "V" 1.000000)
					( Origin gFrontEnd )
				)
				( attribute "XY" "(3075,3700)"
					( Origin gFrontEnd )
				)
				( attribute "CHIPS_PART_NAME" "CAP_A"
					( Origin gPackager )
				)
				( attribute "CDS_PART_NAME" "CAP_A_0402V-0.1UF,16V,10%,X7R,A"
					( Origin gPackager )
				)
				( objectStatus "C8C12" )
			)
			( gate "@baseboard_fab2_lib.baseboard_fab2(sch_1):page188_i120"
				( attribute "CDS_LIB" "dev_discrete"
					( Origin gPackager )
				)
				( attribute "CDS_LOCATION" "C8C13"
					( Origin gPackager )
				)
				( attribute "CDS_SEC" "1"
					( Origin gPackager )
				)
				( attribute "LOCATION" "C8C13"
					( Origin gFrontEnd )
				)
				( attribute "MATERIAL" "X7R"
					( Origin gFrontEnd )
				)
				( attribute "PACK_TYPE" "0402V"
					( Origin gFrontEnd )
				)
				( attribute "PART_NUMBER" "A36096-030"
					( Origin gFrontEnd )
				)
				( attribute "PHYS_PAGE" "188"
					( Origin gFrontEnd )
				)
				( attribute "ROT" "0"
					( Origin gFrontEnd )
				)
				( attribute "SEC" "1"
					( Origin gFrontEnd )
				)
				( attribute "SEC_TYPE" "0402V"
					( Origin gFrontEnd )
				)
				( attribute "TOLERANCE" "10%"
					( Origin gFrontEnd )
				)
				( attribute "VALUE" "0.1UF"
					( Origin gFrontEnd )
				)
				( attribute "VER" "2"
					( Origin gFrontEnd )
				)
				( attribute "VOLTAGE" "16V"
					( Units "uVoltage" "V" 1.000000)
					( Origin gFrontEnd )
				)
				( attribute "XY" "(3075,3375)"
					( Origin gFrontEnd )
				)
				( attribute "CHIPS_PART_NAME" "CAP_A"
					( Origin gPackager )
				)
				( attribute "CDS_PART_NAME" "CAP_A_0402V-0.1UF,16V,10%,X7R,A"
					( Origin gPackager )
				)
				( objectStatus "C8C13" )
			)
			( gate "@baseboard_fab2_lib.baseboard_fab2(sch_1):page228_i306"
				( attribute "BOM_COST" "MEM_VRD_PVDDQ_CD"
					( Origin gFrontEnd )
				)
				( attribute "CDS_LIB" "mstr_discrete"
					( Origin gPackager )
				)
				( attribute "LOCATION" "C8P3"
					( Origin gFrontEnd )
				)
				( attribute "MATERIAL" "X5R"
					( Origin gFrontEnd )
				)
				( attribute "NEW_MATERIAL" "X6S"
					( Origin gFrontEnd )
				)
				( attribute "PACK_TYPE" "0805"
					( Origin gFrontEnd )
				)
				( attribute "PART_NUMBER" "602433-112"
					( Origin gFrontEnd )
				)
				( attribute "PHYS_PAGE" "228"
					( Origin gFrontEnd )
				)
				( attribute "ROOM" "VDDQ_ABC_PWR_VR"
					( Origin gFrontEnd )
				)
				( attribute "ROT" "0"
					( Origin gFrontEnd )
				)
				( attribute "SEC" "1"
					( Origin gFrontEnd )
				)
				( attribute "SEC_TYPE" "0805"
					( Origin gFrontEnd )
				)
				( attribute "TOLERANCE" "20%"
					( Origin gFrontEnd )
				)
				( attribute "VALUE" "100UF"
					( Origin gFrontEnd )
				)
				( attribute "VER" "1"
					( Origin gFrontEnd )
				)
				( attribute "VOLTAGE" "4V"
					( Units "uVoltage" "V" 1.000000)
					( Origin gFrontEnd )
				)
				( attribute "XY" "(1125,2775)"
					( Origin gFrontEnd )
				)
				( attribute "CHIPS_PART_NAME" "CAP"
					( Origin gPackager )
				)
				( attribute "CDS_PART_NAME" "CAP_0805-100UF,4V,20%,X5R,6024A"
					( Origin gPackager )
				)
				( attribute "CDS_LOCATION" "C8P3"
					( Origin gPackager )
				)
				( attribute "CDS_SEC" "1"
					( Origin gPackager )
				)
				( attribute "GROUP" "PWR_MLCC_CAP"
					( Origin gFrontEnd )
				)
				( attribute "NEW_PN" "078.1071T.M002"
					( Origin gFrontEnd )
				)
				( attribute "BOM_SS" "NOPOP"
					( Origin gFrontEnd )
				)
				( objectStatus "C8P3" )
			)
			( gate "@baseboard_fab2_lib.baseboard_fab2(sch_1):page225_i250"
				( attribute "CDS_LIB" "w_hdl"
					( Origin gPackager )
				)
				( attribute "CDS_LMAN_SYM_OUTLINE" "-50,25,50,-25"
					( Origin gPackager )
				)
				( attribute "LOCATION" "C1G2"
					( Origin gFrontEnd )
				)
				( attribute "PACK_TYPE" "SMD-BCG5"
					( Origin gFrontEnd )
				)
				( attribute "PART_NUMBER" "078.22611.0811"
					( Origin gFrontEnd )
				)
				( attribute "PHYS_PAGE" "225"
					( Origin gFrontEnd )
				)
				( attribute "ROT" "0"
					( Origin gFrontEnd )
				)
				( attribute "SEC" "1"
					( Origin gFrontEnd )
				)
				( attribute "SEC_TYPE" "SMD-BCG5"
					( Origin gFrontEnd )
				)
				( attribute "VALUE" "SC22U16V5MX-4-GP"
					( Origin gFrontEnd )
				)
				( attribute "VER" "1"
					( Origin gFrontEnd )
				)
				( attribute "XY" "(150,1150)"
					( Origin gFrontEnd )
				)
				( attribute "CHIPS_PART_NAME" "SC22U16V5MX-4-GP"
					( Origin gPackager )
				)
				( attribute "CDS_PART_NAME" "SC22U16V5MX-4-GP_SMD-BCG5-SC22A"
					( Origin gPackager )
				)
				( attribute "CDS_LOCATION" "C1G2"
					( Origin gPackager )
				)
				( attribute "CDS_SEC" "1"
					( Origin gPackager )
				)
				( attribute "ATTRIBUTE" "22UF"
					( Origin gFrontEnd )
				)
				( attribute "PACK_SIZE" "0805"
					( Origin gFrontEnd )
				)
				( attribute "RATED" "16V"
					( Origin gFrontEnd )
				)
				( attribute "TOLERANCE" "20%"
					( Origin gFrontEnd )
				)
				( attribute "TYPE" "X6S"
					( Origin gFrontEnd )
				)
				( objectStatus "C1G2" )
			)
			( gate "@baseboard_fab2_lib.baseboard_fab2(sch_1):page225_i249"
				( attribute "CDS_LIB" "w_hdl"
					( Origin gPackager )
				)
				( attribute "CDS_LMAN_SYM_OUTLINE" "-50,25,50,-25"
					( Origin gPackager )
				)
				( attribute "LOCATION" "C22W3"
					( Origin gFrontEnd )
				)
				( attribute "PACK_TYPE" "SMD-BCG5"
					( Origin gFrontEnd )
				)
				( attribute "PART_NUMBER" "078.22611.0811"
					( Origin gFrontEnd )
				)
				( attribute "PHYS_PAGE" "225"
					( Origin gFrontEnd )
				)
				( attribute "ROT" "0"
					( Origin gFrontEnd )
				)
				( attribute "SEC" "1"
					( Origin gFrontEnd )
				)
				( attribute "SEC_TYPE" "SMD-BCG5"
					( Origin gFrontEnd )
				)
				( attribute "VALUE" "SC22U16V5MX-4-GP"
					( Origin gFrontEnd )
				)
				( attribute "VER" "1"
					( Origin gFrontEnd )
				)
				( attribute "XY" "(450,1150)"
					( Origin gFrontEnd )
				)
				( attribute "CHIPS_PART_NAME" "SC22U16V5MX-4-GP"
					( Origin gPackager )
				)
				( attribute "CDS_PART_NAME" "SC22U16V5MX-4-GP_SMD-BCG5-SC22A"
					( Origin gPackager )
				)
				( attribute "CDS_LOCATION" "C22W3"
					( Origin gPackager )
				)
				( attribute "CDS_SEC" "1"
					( Origin gPackager )
				)
				( attribute "ATTRIBUTE" "22UF"
					( Origin gFrontEnd )
				)
				( attribute "PACK_SIZE" "0805"
					( Origin gFrontEnd )
				)
				( attribute "RATED" "16V"
					( Origin gFrontEnd )
				)
				( attribute "TOLERANCE" "20%"
					( Origin gFrontEnd )
				)
				( attribute "TYPE" "X6S"
					( Origin gFrontEnd )
				)
				( objectStatus "C22W3" )
			)
			( gate "@baseboard_fab2_lib.baseboard_fab2(sch_1):page234_i223"
				( attribute "CDS_LIB" "w_hdl"
					( Origin gPackager )
				)
				( attribute "CDS_LMAN_SYM_OUTLINE" "-50,25,50,-25"
					( Origin gPackager )
				)
				( attribute "LOCATION" "C4B1"
					( Origin gFrontEnd )
				)
				( attribute "PACK_TYPE" "SMD-BCG5"
					( Origin gFrontEnd )
				)
				( attribute "PART_NUMBER" "078.22611.0811"
					( Origin gFrontEnd )
				)
				( attribute "PHYS_PAGE" "234"
					( Origin gFrontEnd )
				)
				( attribute "ROT" "0"
					( Origin gFrontEnd )
				)
				( attribute "SEC" "1"
					( Origin gFrontEnd )
				)
				( attribute "SEC_TYPE" "SMD-BCG5"
					( Origin gFrontEnd )
				)
				( attribute "VALUE" "SC22U16V5MX-4-GP"
					( Origin gFrontEnd )
				)
				( attribute "VER" "1"
					( Origin gFrontEnd )
				)
				( attribute "XY" "(-7350,4100)"
					( Origin gFrontEnd )
				)
				( attribute "CHIPS_PART_NAME" "SC22U16V5MX-4-GP"
					( Origin gPackager )
				)
				( attribute "CDS_PART_NAME" "SC22U16V5MX-4-GP_SMD-BCG5-SC22A"
					( Origin gPackager )
				)
				( attribute "CDS_LOCATION" "C4B1"
					( Origin gPackager )
				)
				( attribute "CDS_SEC" "1"
					( Origin gPackager )
				)
				( attribute "ATTRIBUTE" "22UF"
					( Origin gFrontEnd )
				)
				( attribute "PACK_SIZE" "0805"
					( Origin gFrontEnd )
				)
				( attribute "RATED" "16V"
					( Origin gFrontEnd )
				)
				( attribute "TOLERANCE" "20%"
					( Origin gFrontEnd )
				)
				( attribute "TYPE" "X6S"
					( Origin gFrontEnd )
				)
				( objectStatus "C4B1" )
			)
			( gate "@baseboard_fab2_lib.baseboard_fab2(sch_1):page234_i222"
				( attribute "CDS_LIB" "w_hdl"
					( Origin gPackager )
				)
				( attribute "CDS_LMAN_SYM_OUTLINE" "-50,25,50,-25"
					( Origin gPackager )
				)
				( attribute "LOCATION" "C22W5"
					( Origin gFrontEnd )
				)
				( attribute "PACK_TYPE" "SMD-BCG5"
					( Origin gFrontEnd )
				)
				( attribute "PART_NUMBER" "078.22611.0811"
					( Origin gFrontEnd )
				)
				( attribute "PHYS_PAGE" "234"
					( Origin gFrontEnd )
				)
				( attribute "ROT" "0"
					( Origin gFrontEnd )
				)
				( attribute "SEC" "1"
					( Origin gFrontEnd )
				)
				( attribute "SEC_TYPE" "SMD-BCG5"
					( Origin gFrontEnd )
				)
				( attribute "VALUE" "SC22U16V5MX-4-GP"
					( Origin gFrontEnd )
				)
				( attribute "VER" "1"
					( Origin gFrontEnd )
				)
				( attribute "XY" "(-7050,4100)"
					( Origin gFrontEnd )
				)
				( attribute "CHIPS_PART_NAME" "SC22U16V5MX-4-GP"
					( Origin gPackager )
				)
				( attribute "CDS_PART_NAME" "SC22U16V5MX-4-GP_SMD-BCG5-SC22A"
					( Origin gPackager )
				)
				( attribute "CDS_LOCATION" "C22W5"
					( Origin gPackager )
				)
				( attribute "CDS_SEC" "1"
					( Origin gPackager )
				)
				( attribute "ATTRIBUTE" "22UF"
					( Origin gFrontEnd )
				)
				( attribute "PACK_SIZE" "0805"
					( Origin gFrontEnd )
				)
				( attribute "RATED" "16V"
					( Origin gFrontEnd )
				)
				( attribute "TOLERANCE" "20%"
					( Origin gFrontEnd )
				)
				( attribute "TYPE" "X6S"
					( Origin gFrontEnd )
				)
				( objectStatus "C22W5" )
			)
			( gate "@baseboard_fab2_lib.baseboard_fab2(sch_1):page225_i196"
				( attribute "CDS_LIB" "dev_discrete"
					( Origin gPackager )
				)
				( attribute "CDS_LOCATION" "C8T4"
					( Origin gPackager )
				)
				( attribute "CDS_SEC" "1"
					( Origin gPackager )
				)
				( attribute "LOCATION" "C8T4"
					( Origin gFrontEnd )
				)
				( attribute "MATERIAL" "X5R"
					( Origin gFrontEnd )
				)
				( attribute "PACK_TYPE" "0603V"
					( Origin gFrontEnd )
				)
				( attribute "PART_NUMBER" "602433-106"
					( Origin gFrontEnd )
				)
				( attribute "PHYS_PAGE" "225"
					( Origin gFrontEnd )
				)
				( attribute "ROT" "0"
					( Origin gFrontEnd )
				)
				( attribute "SEC" "1"
					( Origin gFrontEnd )
				)
				( attribute "SEC_TYPE" "0603V"
					( Origin gFrontEnd )
				)
				( attribute "TOLERANCE" "20%"
					( Origin gFrontEnd )
				)
				( attribute "VALUE" "47UF"
					( Origin gFrontEnd )
				)
				( attribute "VER" "1"
					( Origin gFrontEnd )
				)
				( attribute "VOLTAGE" "4V"
					( Units "uVoltage" "V" 1.000000)
					( Origin gFrontEnd )
				)
				( attribute "XY" "(2600,975)"
					( Origin gFrontEnd )
				)
				( attribute "CHIPS_PART_NAME" "CAP_A"
					( Origin gPackager )
				)
				( attribute "CDS_PART_NAME" "CAP_A_0603V-47UF,4V,20%,X5R,60A"
					( Origin gPackager )
				)
				( attribute "GROUP" "PWR_MLCC_CAP"
					( Origin gFrontEnd )
				)
				( attribute "BOM_SS" "078.1061T.M001"
					( Origin gFrontEnd )
				)
				( objectStatus "C8T4" )
			)
			( gate "@baseboard_fab2_lib.baseboard_fab2(sch_1):page225_i197"
				( attribute "CDS_LIB" "dev_discrete"
					( Origin gPackager )
				)
				( attribute "CDS_LOCATION" "C2G8"
					( Origin gPackager )
				)
				( attribute "CDS_SEC" "1"
					( Origin gPackager )
				)
				( attribute "LOCATION" "C2G8"
					( Origin gFrontEnd )
				)
				( attribute "MATERIAL" "X5R"
					( Origin gFrontEnd )
				)
				( attribute "PACK_TYPE" "0603V"
					( Origin gFrontEnd )
				)
				( attribute "PART_NUMBER" "602433-106"
					( Origin gFrontEnd )
				)
				( attribute "PHYS_PAGE" "225"
					( Origin gFrontEnd )
				)
				( attribute "ROT" "0"
					( Origin gFrontEnd )
				)
				( attribute "SEC" "1"
					( Origin gFrontEnd )
				)
				( attribute "SEC_TYPE" "0603V"
					( Origin gFrontEnd )
				)
				( attribute "TOLERANCE" "20%"
					( Origin gFrontEnd )
				)
				( attribute "VALUE" "47UF"
					( Origin gFrontEnd )
				)
				( attribute "VER" "1"
					( Origin gFrontEnd )
				)
				( attribute "VOLTAGE" "4V"
					( Units "uVoltage" "V" 1.000000)
					( Origin gFrontEnd )
				)
				( attribute "XY" "(2950,975)"
					( Origin gFrontEnd )
				)
				( attribute "CHIPS_PART_NAME" "CAP_A"
					( Origin gPackager )
				)
				( attribute "CDS_PART_NAME" "CAP_A_0603V-47UF,4V,20%,X5R,60A"
					( Origin gPackager )
				)
				( attribute "GROUP" "PWR_MLCC_CAP"
					( Origin gFrontEnd )
				)
				( attribute "BOM_SS" "NOPOP"
					( Origin gFrontEnd )
				)
				( objectStatus "C2G8" )
			)
			( gate "@baseboard_fab2_lib.baseboard_fab2(sch_1):page225_i198"
				( attribute "CDS_LIB" "dev_discrete"
					( Origin gPackager )
				)
				( attribute "CDS_LOCATION" "C8T2"
					( Origin gPackager )
				)
				( attribute "CDS_SEC" "1"
					( Origin gPackager )
				)
				( attribute "LOCATION" "C8T2"
					( Origin gFrontEnd )
				)
				( attribute "MATERIAL" "X5R"
					( Origin gFrontEnd )
				)
				( attribute "PACK_TYPE" "0603V"
					( Origin gFrontEnd )
				)
				( attribute "PART_NUMBER" "602433-106"
					( Origin gFrontEnd )
				)
				( attribute "PHYS_PAGE" "225"
					( Origin gFrontEnd )
				)
				( attribute "ROT" "0"
					( Origin gFrontEnd )
				)
				( attribute "SEC" "1"
					( Origin gFrontEnd )
				)
				( attribute "SEC_TYPE" "0603V"
					( Origin gFrontEnd )
				)
				( attribute "TOLERANCE" "20%"
					( Origin gFrontEnd )
				)
				( attribute "VALUE" "47UF"
					( Origin gFrontEnd )
				)
				( attribute "VER" "1"
					( Origin gFrontEnd )
				)
				( attribute "VOLTAGE" "4V"
					( Units "uVoltage" "V" 1.000000)
					( Origin gFrontEnd )
				)
				( attribute "XY" "(3350,975)"
					( Origin gFrontEnd )
				)
				( attribute "CHIPS_PART_NAME" "CAP_A"
					( Origin gPackager )
				)
				( attribute "CDS_PART_NAME" "CAP_A_0603V-47UF,4V,20%,X5R,60A"
					( Origin gPackager )
				)
				( attribute "GROUP" "PWR_MLCC_CAP"
					( Origin gFrontEnd )
				)
				( attribute "BOM_SS" "NOPOP"
					( Origin gFrontEnd )
				)
				( objectStatus "C8T2" )
			)
			( gate "@baseboard_fab2_lib.baseboard_fab2(sch_1):page225_i199"
				( attribute "CDS_LIB" "dev_discrete"
					( Origin gPackager )
				)
				( attribute "CDS_LOCATION" "C8U13"
					( Origin gPackager )
				)
				( attribute "CDS_SEC" "1"
					( Origin gPackager )
				)
				( attribute "LOCATION" "C8U13"
					( Origin gFrontEnd )
				)
				( attribute "MATERIAL" "X5R"
					( Origin gFrontEnd )
				)
				( attribute "PACK_TYPE" "0603V"
					( Origin gFrontEnd )
				)
				( attribute "PART_NUMBER" "602433-106"
					( Origin gFrontEnd )
				)
				( attribute "PHYS_PAGE" "225"
					( Origin gFrontEnd )
				)
				( attribute "ROT" "0"
					( Origin gFrontEnd )
				)
				( attribute "SEC" "1"
					( Origin gFrontEnd )
				)
				( attribute "SEC_TYPE" "0603V"
					( Origin gFrontEnd )
				)
				( attribute "TOLERANCE" "20%"
					( Origin gFrontEnd )
				)
				( attribute "VALUE" "47UF"
					( Origin gFrontEnd )
				)
				( attribute "VER" "1"
					( Origin gFrontEnd )
				)
				( attribute "VOLTAGE" "4V"
					( Units "uVoltage" "V" 1.000000)
					( Origin gFrontEnd )
				)
				( attribute "XY" "(2550,1725)"
					( Origin gFrontEnd )
				)
				( attribute "CHIPS_PART_NAME" "CAP_A"
					( Origin gPackager )
				)
				( attribute "CDS_PART_NAME" "CAP_A_0603V-47UF,4V,20%,X5R,60A"
					( Origin gPackager )
				)
				( attribute "GROUP" "PWR_MLCC_CAP"
					( Origin gFrontEnd )
				)
				( attribute "BOM_SS" "NOPOP"
					( Origin gFrontEnd )
				)
				( objectStatus "C8U13" )
			)
			( gate "@baseboard_fab2_lib.baseboard_fab2(sch_1):page225_i200"
				( attribute "CDS_LIB" "dev_discrete"
					( Origin gPackager )
				)
				( attribute "CDS_LOCATION" "C2G15"
					( Origin gPackager )
				)
				( attribute "CDS_SEC" "1"
					( Origin gPackager )
				)
				( attribute "LOCATION" "C2G15"
					( Origin gFrontEnd )
				)
				( attribute "MATERIAL" "X5R"
					( Origin gFrontEnd )
				)
				( attribute "PACK_TYPE" "0603V"
					( Origin gFrontEnd )
				)
				( attribute "PART_NUMBER" "602433-106"
					( Origin gFrontEnd )
				)
				( attribute "PHYS_PAGE" "225"
					( Origin gFrontEnd )
				)
				( attribute "ROT" "0"
					( Origin gFrontEnd )
				)
				( attribute "SEC" "1"
					( Origin gFrontEnd )
				)
				( attribute "SEC_TYPE" "0603V"
					( Origin gFrontEnd )
				)
				( attribute "TOLERANCE" "20%"
					( Origin gFrontEnd )
				)
				( attribute "VALUE" "47UF"
					( Origin gFrontEnd )
				)
				( attribute "VER" "1"
					( Origin gFrontEnd )
				)
				( attribute "VOLTAGE" "4V"
					( Units "uVoltage" "V" 1.000000)
					( Origin gFrontEnd )
				)
				( attribute "XY" "(2900,1725)"
					( Origin gFrontEnd )
				)
				( attribute "CHIPS_PART_NAME" "CAP_A"
					( Origin gPackager )
				)
				( attribute "CDS_PART_NAME" "CAP_A_0603V-47UF,4V,20%,X5R,60A"
					( Origin gPackager )
				)
				( attribute "GROUP" "PWR_MLCC_CAP"
					( Origin gFrontEnd )
				)
				( attribute "BOM_SS" "NOPOP"
					( Origin gFrontEnd )
				)
				( objectStatus "C2G15" )
			)
			( gate "@baseboard_fab2_lib.baseboard_fab2(sch_1):page225_i201"
				( attribute "CDS_LIB" "dev_discrete"
					( Origin gPackager )
				)
				( attribute "CDS_LOCATION" "C2F1"
					( Origin gPackager )
				)
				( attribute "CDS_SEC" "1"
					( Origin gPackager )
				)
				( attribute "LOCATION" "C2F1"
					( Origin gFrontEnd )
				)
				( attribute "MATERIAL" "X5R"
					( Origin gFrontEnd )
				)
				( attribute "PACK_TYPE" "0603V"
					( Origin gFrontEnd )
				)
				( attribute "PART_NUMBER" "602433-106"
					( Origin gFrontEnd )
				)
				( attribute "PHYS_PAGE" "225"
					( Origin gFrontEnd )
				)
				( attribute "ROT" "0"
					( Origin gFrontEnd )
				)
				( attribute "SEC" "1"
					( Origin gFrontEnd )
				)
				( attribute "SEC_TYPE" "0603V"
					( Origin gFrontEnd )
				)
				( attribute "TOLERANCE" "20%"
					( Origin gFrontEnd )
				)
				( attribute "VALUE" "47UF"
					( Origin gFrontEnd )
				)
				( attribute "VER" "1"
					( Origin gFrontEnd )
				)
				( attribute "VOLTAGE" "4V"
					( Units "uVoltage" "V" 1.000000)
					( Origin gFrontEnd )
				)
				( attribute "XY" "(3300,1725)"
					( Origin gFrontEnd )
				)
				( attribute "CHIPS_PART_NAME" "CAP_A"
					( Origin gPackager )
				)
				( attribute "CDS_PART_NAME" "CAP_A_0603V-47UF,4V,20%,X5R,60A"
					( Origin gPackager )
				)
				( attribute "GROUP" "PWR_MLCC_CAP"
					( Origin gFrontEnd )
				)
				( attribute "BOM_SS" "NOPOP"
					( Origin gFrontEnd )
				)
				( objectStatus "C2F1" )
			)
			( gate "@baseboard_fab2_lib.baseboard_fab2(sch_1):page225_i202"
				( attribute "CDS_LIB" "dev_discrete"
					( Origin gPackager )
				)
				( attribute "CDS_LOCATION" "C8T1"
					( Origin gPackager )
				)
				( attribute "CDS_SEC" "1"
					( Origin gPackager )
				)
				( attribute "LOCATION" "C8T1"
					( Origin gFrontEnd )
				)
				( attribute "MATERIAL" "X5R"
					( Origin gFrontEnd )
				)
				( attribute "PACK_TYPE" "0603V"
					( Origin gFrontEnd )
				)
				( attribute "PART_NUMBER" "602433-106"
					( Origin gFrontEnd )
				)
				( attribute "PHYS_PAGE" "225"
					( Origin gFrontEnd )
				)
				( attribute "ROT" "0"
					( Origin gFrontEnd )
				)
				( attribute "SEC" "1"
					( Origin gFrontEnd )
				)
				( attribute "SEC_TYPE" "0603V"
					( Origin gFrontEnd )
				)
				( attribute "TOLERANCE" "20%"
					( Origin gFrontEnd )
				)
				( attribute "VALUE" "47UF"
					( Origin gFrontEnd )
				)
				( attribute "VER" "1"
					( Origin gFrontEnd )
				)
				( attribute "VOLTAGE" "4V"
					( Units "uVoltage" "V" 1.000000)
					( Origin gFrontEnd )
				)
				( attribute "XY" "(3650,1725)"
					( Origin gFrontEnd )
				)
				( attribute "CHIPS_PART_NAME" "CAP_A"
					( Origin gPackager )
				)
				( attribute "CDS_PART_NAME" "CAP_A_0603V-47UF,4V,20%,X5R,60A"
					( Origin gPackager )
				)
				( attribute "GROUP" "PWR_MLCC_CAP"
					( Origin gFrontEnd )
				)
				( attribute "BOM_SS" "NOPOP"
					( Origin gFrontEnd )
				)
				( objectStatus "C8T1" )
			)
			( gate "@baseboard_fab2_lib.baseboard_fab2(sch_1):page225_i203"
				( attribute "CDS_LIB" "dev_discrete"
					( Origin gPackager )
				)
				( attribute "CDS_LOCATION" "C8U9"
					( Origin gPackager )
				)
				( attribute "CDS_SEC" "1"
					( Origin gPackager )
				)
				( attribute "LOCATION" "C8U9"
					( Origin gFrontEnd )
				)
				( attribute "MATERIAL" "X5R"
					( Origin gFrontEnd )
				)
				( attribute "PACK_TYPE" "0603V"
					( Origin gFrontEnd )
				)
				( attribute "PART_NUMBER" "602433-106"
					( Origin gFrontEnd )
				)
				( attribute "PHYS_PAGE" "225"
					( Origin gFrontEnd )
				)
				( attribute "ROT" "0"
					( Origin gFrontEnd )
				)
				( attribute "SEC" "1"
					( Origin gFrontEnd )
				)
				( attribute "SEC_TYPE" "0603V"
					( Origin gFrontEnd )
				)
				( attribute "TOLERANCE" "20%"
					( Origin gFrontEnd )
				)
				( attribute "VALUE" "47UF"
					( Origin gFrontEnd )
				)
				( attribute "VER" "1"
					( Origin gFrontEnd )
				)
				( attribute "VOLTAGE" "4V"
					( Units "uVoltage" "V" 1.000000)
					( Origin gFrontEnd )
				)
				( attribute "XY" "(4000,1725)"
					( Origin gFrontEnd )
				)
				( attribute "CHIPS_PART_NAME" "CAP_A"
					( Origin gPackager )
				)
				( attribute "CDS_PART_NAME" "CAP_A_0603V-47UF,4V,20%,X5R,60A"
					( Origin gPackager )
				)
				( attribute "GROUP" "PWR_MLCC_CAP"
					( Origin gFrontEnd )
				)
				( attribute "BOM_SS" "NOPOP"
					( Origin gFrontEnd )
				)
				( objectStatus "C8U9" )
			)
			( gate "@baseboard_fab2_lib.baseboard_fab2(sch_1):page225_i204"
				( attribute "CDS_LIB" "dev_discrete"
					( Origin gPackager )
				)
				( attribute "CDS_LOCATION" "C8T11"
					( Origin gPackager )
				)
				( attribute "CDS_SEC" "1"
					( Origin gPackager )
				)
				( attribute "LOCATION" "C8T11"
					( Origin gFrontEnd )
				)
				( attribute "MATERIAL" "X5R"
					( Origin gFrontEnd )
				)
				( attribute "PACK_TYPE" "0603V"
					( Origin gFrontEnd )
				)
				( attribute "PART_NUMBER" "602433-106"
					( Origin gFrontEnd )
				)
				( attribute "PHYS_PAGE" "225"
					( Origin gFrontEnd )
				)
				( attribute "ROT" "0"
					( Origin gFrontEnd )
				)
				( attribute "SEC" "1"
					( Origin gFrontEnd )
				)
				( attribute "SEC_TYPE" "0603V"
					( Origin gFrontEnd )
				)
				( attribute "TOLERANCE" "20%"
					( Origin gFrontEnd )
				)
				( attribute "VALUE" "47UF"
					( Origin gFrontEnd )
				)
				( attribute "VER" "1"
					( Origin gFrontEnd )
				)
				( attribute "VOLTAGE" "4V"
					( Units "uVoltage" "V" 1.000000)
					( Origin gFrontEnd )
				)
				( attribute "XY" "(4400,1725)"
					( Origin gFrontEnd )
				)
				( attribute "CHIPS_PART_NAME" "CAP_A"
					( Origin gPackager )
				)
				( attribute "CDS_PART_NAME" "CAP_A_0603V-47UF,4V,20%,X5R,60A"
					( Origin gPackager )
				)
				( attribute "GROUP" "PWR_MLCC_CAP"
					( Origin gFrontEnd )
				)
				( attribute "BOM_SS" "NOPOP"
					( Origin gFrontEnd )
				)
				( objectStatus "C8T11" )
			)
			( gate "@baseboard_fab2_lib.baseboard_fab2(sch_1):page228_i283"
				( attribute "CDS_LIB" "dev_discrete"
					( Origin gPackager )
				)
				( attribute "CDS_LOCATION" "C2A2"
					( Origin gPackager )
				)
				( attribute "CDS_SEC" "1"
					( Origin gPackager )
				)
				( attribute "LOCATION" "C2A2"
					( Origin gFrontEnd )
				)
				( attribute "MATERIAL" "X5R"
					( Origin gFrontEnd )
				)
				( attribute "PACK_TYPE" "0603V"
					( Origin gFrontEnd )
				)
				( attribute "PART_NUMBER" "602433-106"
					( Origin gFrontEnd )
				)
				( attribute "PHYS_PAGE" "228"
					( Origin gFrontEnd )
				)
				( attribute "ROT" "0"
					( Origin gFrontEnd )
				)
				( attribute "SEC" "1"
					( Origin gFrontEnd )
				)
				( attribute "SEC_TYPE" "0603V"
					( Origin gFrontEnd )
				)
				( attribute "TOLERANCE" "20%"
					( Origin gFrontEnd )
				)
				( attribute "VALUE" "47UF"
					( Origin gFrontEnd )
				)
				( attribute "VER" "1"
					( Origin gFrontEnd )
				)
				( attribute "VOLTAGE" "4V"
					( Units "uVoltage" "V" 1.000000)
					( Origin gFrontEnd )
				)
				( attribute "XY" "(2125,-75)"
					( Origin gFrontEnd )
				)
				( attribute "CHIPS_PART_NAME" "CAP_A"
					( Origin gPackager )
				)
				( attribute "CDS_PART_NAME" "CAP_A_0603V-47UF,4V,20%,X5R,60A"
					( Origin gPackager )
				)
				( attribute "GROUP" "PWR_MLCC_CAP"
					( Origin gFrontEnd )
				)
				( attribute "BOM_SS" "E15431-004"
					( Origin gFrontEnd )
				)
				( objectStatus "C2A2" )
			)
			( gate "@baseboard_fab2_lib.baseboard_fab2(sch_1):page228_i282"
				( attribute "CDS_LIB" "dev_discrete"
					( Origin gPackager )
				)
				( attribute "CDS_LOCATION" "C2A1"
					( Origin gPackager )
				)
				( attribute "CDS_SEC" "1"
					( Origin gPackager )
				)
				( attribute "LOCATION" "C2A1"
					( Origin gFrontEnd )
				)
				( attribute "MATERIAL" "X5R"
					( Origin gFrontEnd )
				)
				( attribute "PACK_TYPE" "0603V"
					( Origin gFrontEnd )
				)
				( attribute "PART_NUMBER" "602433-106"
					( Origin gFrontEnd )
				)
				( attribute "PHYS_PAGE" "228"
					( Origin gFrontEnd )
				)
				( attribute "ROT" "0"
					( Origin gFrontEnd )
				)
				( attribute "SEC" "1"
					( Origin gFrontEnd )
				)
				( attribute "SEC_TYPE" "0603V"
					( Origin gFrontEnd )
				)
				( attribute "TOLERANCE" "20%"
					( Origin gFrontEnd )
				)
				( attribute "VALUE" "47UF"
					( Origin gFrontEnd )
				)
				( attribute "VER" "1"
					( Origin gFrontEnd )
				)
				( attribute "VOLTAGE" "4V"
					( Units "uVoltage" "V" 1.000000)
					( Origin gFrontEnd )
				)
				( attribute "XY" "(1850,-75)"
					( Origin gFrontEnd )
				)
				( attribute "CHIPS_PART_NAME" "CAP_A"
					( Origin gPackager )
				)
				( attribute "CDS_PART_NAME" "CAP_A_0603V-47UF,4V,20%,X5R,60A"
					( Origin gPackager )
				)
				( attribute "GROUP" "PWR_MLCC_CAP"
					( Origin gFrontEnd )
				)
				( attribute "BOM_SS" "E15431-004"
					( Origin gFrontEnd )
				)
				( objectStatus "C2A1" )
			)
			( gate "@baseboard_fab2_lib.baseboard_fab2(sch_1):page228_i281"
				( attribute "CDS_LIB" "dev_discrete"
					( Origin gPackager )
				)
				( attribute "CDS_LOCATION" "C2A12"
					( Origin gPackager )
				)
				( attribute "CDS_SEC" "1"
					( Origin gPackager )
				)
				( attribute "LOCATION" "C2A12"
					( Origin gFrontEnd )
				)
				( attribute "MATERIAL" "X5R"
					( Origin gFrontEnd )
				)
				( attribute "PACK_TYPE" "0603V"
					( Origin gFrontEnd )
				)
				( attribute "PART_NUMBER" "602433-106"
					( Origin gFrontEnd )
				)
				( attribute "PHYS_PAGE" "228"
					( Origin gFrontEnd )
				)
				( attribute "ROT" "0"
					( Origin gFrontEnd )
				)
				( attribute "SEC" "1"
					( Origin gFrontEnd )
				)
				( attribute "SEC_TYPE" "0603V"
					( Origin gFrontEnd )
				)
				( attribute "TOLERANCE" "20%"
					( Origin gFrontEnd )
				)
				( attribute "VALUE" "47UF"
					( Origin gFrontEnd )
				)
				( attribute "VER" "1"
					( Origin gFrontEnd )
				)
				( attribute "VOLTAGE" "4V"
					( Units "uVoltage" "V" 1.000000)
					( Origin gFrontEnd )
				)
				( attribute "XY" "(1550,-75)"
					( Origin gFrontEnd )
				)
				( attribute "CHIPS_PART_NAME" "CAP_A"
					( Origin gPackager )
				)
				( attribute "CDS_PART_NAME" "CAP_A_0603V-47UF,4V,20%,X5R,60A"
					( Origin gPackager )
				)
				( attribute "GROUP" "PWR_MLCC_CAP"
					( Origin gFrontEnd )
				)
				( attribute "BOM_SS" "E15431-004"
					( Origin gFrontEnd )
				)
				( objectStatus "C2A12" )
			)
			( gate "@baseboard_fab2_lib.baseboard_fab2(sch_1):page228_i280"
				( attribute "CDS_LIB" "dev_discrete"
					( Origin gPackager )
				)
				( attribute "CDS_LOCATION" "C2A13"
					( Origin gPackager )
				)
				( attribute "CDS_SEC" "1"
					( Origin gPackager )
				)
				( attribute "LOCATION" "C2A13"
					( Origin gFrontEnd )
				)
				( attribute "MATERIAL" "X5R"
					( Origin gFrontEnd )
				)
				( attribute "PACK_TYPE" "0603V"
					( Origin gFrontEnd )
				)
				( attribute "PART_NUMBER" "602433-106"
					( Origin gFrontEnd )
				)
				( attribute "PHYS_PAGE" "228"
					( Origin gFrontEnd )
				)
				( attribute "ROT" "0"
					( Origin gFrontEnd )
				)
				( attribute "SEC" "1"
					( Origin gFrontEnd )
				)
				( attribute "SEC_TYPE" "0603V"
					( Origin gFrontEnd )
				)
				( attribute "TOLERANCE" "20%"
					( Origin gFrontEnd )
				)
				( attribute "VALUE" "47UF"
					( Origin gFrontEnd )
				)
				( attribute "VER" "1"
					( Origin gFrontEnd )
				)
				( attribute "VOLTAGE" "4V"
					( Units "uVoltage" "V" 1.000000)
					( Origin gFrontEnd )
				)
				( attribute "XY" "(1250,-75)"
					( Origin gFrontEnd )
				)
				( attribute "CHIPS_PART_NAME" "CAP_A"
					( Origin gPackager )
				)
				( attribute "CDS_PART_NAME" "CAP_A_0603V-47UF,4V,20%,X5R,60A"
					( Origin gPackager )
				)
				( attribute "GROUP" "PWR_MLCC_CAP"
					( Origin gFrontEnd )
				)
				( attribute "BOM_SS" "E15431-004"
					( Origin gFrontEnd )
				)
				( objectStatus "C2A13" )
			)
			( gate "@baseboard_fab2_lib.baseboard_fab2(sch_1):page228_i279"
				( attribute "CDS_LIB" "dev_discrete"
					( Origin gPackager )
				)
				( attribute "CDS_LOCATION" "C2A11"
					( Origin gPackager )
				)
				( attribute "CDS_SEC" "1"
					( Origin gPackager )
				)
				( attribute "LOCATION" "C2A11"
					( Origin gFrontEnd )
				)
				( attribute "MATERIAL" "X5R"
					( Origin gFrontEnd )
				)
				( attribute "PACK_TYPE" "0603V"
					( Origin gFrontEnd )
				)
				( attribute "PART_NUMBER" "602433-106"
					( Origin gFrontEnd )
				)
				( attribute "PHYS_PAGE" "228"
					( Origin gFrontEnd )
				)
				( attribute "ROT" "0"
					( Origin gFrontEnd )
				)
				( attribute "SEC" "1"
					( Origin gFrontEnd )
				)
				( attribute "SEC_TYPE" "0603V"
					( Origin gFrontEnd )
				)
				( attribute "TOLERANCE" "20%"
					( Origin gFrontEnd )
				)
				( attribute "VALUE" "47UF"
					( Origin gFrontEnd )
				)
				( attribute "VER" "1"
					( Origin gFrontEnd )
				)
				( attribute "VOLTAGE" "4V"
					( Units "uVoltage" "V" 1.000000)
					( Origin gFrontEnd )
				)
				( attribute "XY" "(975,-75)"
					( Origin gFrontEnd )
				)
				( attribute "CHIPS_PART_NAME" "CAP_A"
					( Origin gPackager )
				)
				( attribute "CDS_PART_NAME" "CAP_A_0603V-47UF,4V,20%,X5R,60A"
					( Origin gPackager )
				)
				( attribute "GROUP" "PWR_MLCC_CAP"
					( Origin gFrontEnd )
				)
				( attribute "BOM_SS" "E15431-004"
					( Origin gFrontEnd )
				)
				( objectStatus "C2A11" )
			)
			( gate "@baseboard_fab2_lib.baseboard_fab2(sch_1):page228_i278"
				( attribute "CDS_LIB" "dev_discrete"
					( Origin gPackager )
				)
				( attribute "CDS_LOCATION" "C2A10"
					( Origin gPackager )
				)
				( attribute "CDS_SEC" "1"
					( Origin gPackager )
				)
				( attribute "LOCATION" "C2A10"
					( Origin gFrontEnd )
				)
				( attribute "MATERIAL" "X5R"
					( Origin gFrontEnd )
				)
				( attribute "PACK_TYPE" "0603V"
					( Origin gFrontEnd )
				)
				( attribute "PART_NUMBER" "602433-106"
					( Origin gFrontEnd )
				)
				( attribute "PHYS_PAGE" "228"
					( Origin gFrontEnd )
				)
				( attribute "ROT" "0"
					( Origin gFrontEnd )
				)
				( attribute "SEC" "1"
					( Origin gFrontEnd )
				)
				( attribute "SEC_TYPE" "0603V"
					( Origin gFrontEnd )
				)
				( attribute "TOLERANCE" "20%"
					( Origin gFrontEnd )
				)
				( attribute "VALUE" "47UF"
					( Origin gFrontEnd )
				)
				( attribute "VER" "1"
					( Origin gFrontEnd )
				)
				( attribute "VOLTAGE" "4V"
					( Units "uVoltage" "V" 1.000000)
					( Origin gFrontEnd )
				)
				( attribute "XY" "(700,-75)"
					( Origin gFrontEnd )
				)
				( attribute "CHIPS_PART_NAME" "CAP_A"
					( Origin gPackager )
				)
				( attribute "CDS_PART_NAME" "CAP_A_0603V-47UF,4V,20%,X5R,60A"
					( Origin gPackager )
				)
				( attribute "GROUP" "PWR_MLCC_CAP"
					( Origin gFrontEnd )
				)
				( attribute "BOM_SS" "E15431-004"
					( Origin gFrontEnd )
				)
				( objectStatus "C2A10" )
			)
			( gate "@baseboard_fab2_lib.baseboard_fab2(sch_1):page228_i277"
				( attribute "CDS_LIB" "dev_discrete"
					( Origin gPackager )
				)
				( attribute "CDS_LOCATION" "C2A9"
					( Origin gPackager )
				)
				( attribute "CDS_SEC" "1"
					( Origin gPackager )
				)
				( attribute "LOCATION" "C2A9"
					( Origin gFrontEnd )
				)
				( attribute "MATERIAL" "X5R"
					( Origin gFrontEnd )
				)
				( attribute "PACK_TYPE" "0603V"
					( Origin gFrontEnd )
				)
				( attribute "PART_NUMBER" "602433-106"
					( Origin gFrontEnd )
				)
				( attribute "PHYS_PAGE" "228"
					( Origin gFrontEnd )
				)
				( attribute "ROT" "0"
					( Origin gFrontEnd )
				)
				( attribute "SEC" "1"
					( Origin gFrontEnd )
				)
				( attribute "SEC_TYPE" "0603V"
					( Origin gFrontEnd )
				)
				( attribute "TOLERANCE" "20%"
					( Origin gFrontEnd )
				)
				( attribute "VALUE" "47UF"
					( Origin gFrontEnd )
				)
				( attribute "VER" "1"
					( Origin gFrontEnd )
				)
				( attribute "VOLTAGE" "4V"
					( Units "uVoltage" "V" 1.000000)
					( Origin gFrontEnd )
				)
				( attribute "XY" "(400,-75)"
					( Origin gFrontEnd )
				)
				( attribute "CHIPS_PART_NAME" "CAP_A"
					( Origin gPackager )
				)
				( attribute "CDS_PART_NAME" "CAP_A_0603V-47UF,4V,20%,X5R,60A"
					( Origin gPackager )
				)
				( attribute "GROUP" "PWR_MLCC_CAP"
					( Origin gFrontEnd )
				)
				( attribute "BOM_SS" "E15431-004"
					( Origin gFrontEnd )
				)
				( objectStatus "C2A9" )
			)
			( gate "@baseboard_fab2_lib.baseboard_fab2(sch_1):page228_i276"
				( attribute "CDS_LIB" "dev_discrete"
					( Origin gPackager )
				)
				( attribute "CDS_LOCATION" "C3A2"
					( Origin gPackager )
				)
				( attribute "CDS_SEC" "1"
					( Origin gPackager )
				)
				( attribute "LOCATION" "C3A2"
					( Origin gFrontEnd )
				)
				( attribute "MATERIAL" "X5R"
					( Origin gFrontEnd )
				)
				( attribute "PACK_TYPE" "0603V"
					( Origin gFrontEnd )
				)
				( attribute "PART_NUMBER" "602433-106"
					( Origin gFrontEnd )
				)
				( attribute "PHYS_PAGE" "228"
					( Origin gFrontEnd )
				)
				( attribute "ROT" "0"
					( Origin gFrontEnd )
				)
				( attribute "SEC" "1"
					( Origin gFrontEnd )
				)
				( attribute "SEC_TYPE" "0603V"
					( Origin gFrontEnd )
				)
				( attribute "TOLERANCE" "20%"
					( Origin gFrontEnd )
				)
				( attribute "VALUE" "47UF"
					( Origin gFrontEnd )
				)
				( attribute "VER" "1"
					( Origin gFrontEnd )
				)
				( attribute "VOLTAGE" "4V"
					( Units "uVoltage" "V" 1.000000)
					( Origin gFrontEnd )
				)
				( attribute "XY" "(100,-75)"
					( Origin gFrontEnd )
				)
				( attribute "CHIPS_PART_NAME" "CAP_A"
					( Origin gPackager )
				)
				( attribute "CDS_PART_NAME" "CAP_A_0603V-47UF,4V,20%,X5R,60A"
					( Origin gPackager )
				)
				( attribute "GROUP" "PWR_MLCC_CAP"
					( Origin gFrontEnd )
				)
				( attribute "BOM_SS" "E15431-004"
					( Origin gFrontEnd )
				)
				( objectStatus "C3A2" )
			)
			( gate "@baseboard_fab2_lib.baseboard_fab2(sch_1):page228_i275"
				( attribute "CDS_LIB" "dev_discrete"
					( Origin gPackager )
				)
				( attribute "CDS_LOCATION" "C3A1"
					( Origin gPackager )
				)
				( attribute "CDS_SEC" "1"
					( Origin gPackager )
				)
				( attribute "LOCATION" "C3A1"
					( Origin gFrontEnd )
				)
				( attribute "MATERIAL" "X5R"
					( Origin gFrontEnd )
				)
				( attribute "PACK_TYPE" "0603V"
					( Origin gFrontEnd )
				)
				( attribute "PART_NUMBER" "602433-106"
					( Origin gFrontEnd )
				)
				( attribute "PHYS_PAGE" "228"
					( Origin gFrontEnd )
				)
				( attribute "ROT" "0"
					( Origin gFrontEnd )
				)
				( attribute "SEC" "1"
					( Origin gFrontEnd )
				)
				( attribute "SEC_TYPE" "0603V"
					( Origin gFrontEnd )
				)
				( attribute "TOLERANCE" "20%"
					( Origin gFrontEnd )
				)
				( attribute "VALUE" "47UF"
					( Origin gFrontEnd )
				)
				( attribute "VER" "1"
					( Origin gFrontEnd )
				)
				( attribute "VOLTAGE" "4V"
					( Units "uVoltage" "V" 1.000000)
					( Origin gFrontEnd )
				)
				( attribute "XY" "(-225,-75)"
					( Origin gFrontEnd )
				)
				( attribute "CHIPS_PART_NAME" "CAP_A"
					( Origin gPackager )
				)
				( attribute "CDS_PART_NAME" "CAP_A_0603V-47UF,4V,20%,X5R,60A"
					( Origin gPackager )
				)
				( attribute "GROUP" "PWR_MLCC_CAP"
					( Origin gFrontEnd )
				)
				( attribute "BOM_SS" "E15431-004"
					( Origin gFrontEnd )
				)
				( objectStatus "C3A1" )
			)
			( gate "@baseboard_fab2_lib.baseboard_fab2(sch_1):page228_i274"
				( attribute "CDS_LIB" "dev_discrete"
					( Origin gPackager )
				)
				( attribute "CDS_LOCATION" "C2A7"
					( Origin gPackager )
				)
				( attribute "CDS_SEC" "1"
					( Origin gPackager )
				)
				( attribute "LOCATION" "C2A7"
					( Origin gFrontEnd )
				)
				( attribute "MATERIAL" "X5R"
					( Origin gFrontEnd )
				)
				( attribute "PACK_TYPE" "0603V"
					( Origin gFrontEnd )
				)
				( attribute "PART_NUMBER" "602433-106"
					( Origin gFrontEnd )
				)
				( attribute "PHYS_PAGE" "228"
					( Origin gFrontEnd )
				)
				( attribute "ROT" "0"
					( Origin gFrontEnd )
				)
				( attribute "SEC" "1"
					( Origin gFrontEnd )
				)
				( attribute "SEC_TYPE" "0603V"
					( Origin gFrontEnd )
				)
				( attribute "TOLERANCE" "20%"
					( Origin gFrontEnd )
				)
				( attribute "VALUE" "47UF"
					( Origin gFrontEnd )
				)
				( attribute "VER" "1"
					( Origin gFrontEnd )
				)
				( attribute "VOLTAGE" "4V"
					( Units "uVoltage" "V" 1.000000)
					( Origin gFrontEnd )
				)
				( attribute "XY" "(-500,-75)"
					( Origin gFrontEnd )
				)
				( attribute "CHIPS_PART_NAME" "CAP_A"
					( Origin gPackager )
				)
				( attribute "CDS_PART_NAME" "CAP_A_0603V-47UF,4V,20%,X5R,60A"
					( Origin gPackager )
				)
				( attribute "GROUP" "PWR_MLCC_CAP"
					( Origin gFrontEnd )
				)
				( attribute "BOM_SS" "E15431-004"
					( Origin gFrontEnd )
				)
				( objectStatus "C2A7" )
			)
			( gate "@baseboard_fab2_lib.baseboard_fab2(sch_1):page228_i273"
				( attribute "CDS_LIB" "dev_discrete"
					( Origin gPackager )
				)
				( attribute "CDS_LOCATION" "C2A6"
					( Origin gPackager )
				)
				( attribute "CDS_SEC" "1"
					( Origin gPackager )
				)
				( attribute "LOCATION" "C2A6"
					( Origin gFrontEnd )
				)
				( attribute "MATERIAL" "X5R"
					( Origin gFrontEnd )
				)
				( attribute "PACK_TYPE" "0603V"
					( Origin gFrontEnd )
				)
				( attribute "PART_NUMBER" "602433-106"
					( Origin gFrontEnd )
				)
				( attribute "PHYS_PAGE" "228"
					( Origin gFrontEnd )
				)
				( attribute "ROT" "0"
					( Origin gFrontEnd )
				)
				( attribute "SEC" "1"
					( Origin gFrontEnd )
				)
				( attribute "SEC_TYPE" "0603V"
					( Origin gFrontEnd )
				)
				( attribute "TOLERANCE" "20%"
					( Origin gFrontEnd )
				)
				( attribute "VALUE" "47UF"
					( Origin gFrontEnd )
				)
				( attribute "VER" "1"
					( Origin gFrontEnd )
				)
				( attribute "VOLTAGE" "4V"
					( Units "uVoltage" "V" 1.000000)
					( Origin gFrontEnd )
				)
				( attribute "XY" "(-800,-75)"
					( Origin gFrontEnd )
				)
				( attribute "CHIPS_PART_NAME" "CAP_A"
					( Origin gPackager )
				)
				( attribute "CDS_PART_NAME" "CAP_A_0603V-47UF,4V,20%,X5R,60A"
					( Origin gPackager )
				)
				( attribute "GROUP" "PWR_MLCC_CAP"
					( Origin gFrontEnd )
				)
				( attribute "BOM_SS" "E15431-004"
					( Origin gFrontEnd )
				)
				( objectStatus "C2A6" )
			)
			( gate "@baseboard_fab2_lib.baseboard_fab2(sch_1):page228_i272"
				( attribute "CDS_LIB" "dev_discrete"
					( Origin gPackager )
				)
				( attribute "CDS_LOCATION" "C2A14"
					( Origin gPackager )
				)
				( attribute "CDS_SEC" "1"
					( Origin gPackager )
				)
				( attribute "LOCATION" "C2A14"
					( Origin gFrontEnd )
				)
				( attribute "MATERIAL" "X5R"
					( Origin gFrontEnd )
				)
				( attribute "PACK_TYPE" "0603V"
					( Origin gFrontEnd )
				)
				( attribute "PART_NUMBER" "602433-106"
					( Origin gFrontEnd )
				)
				( attribute "PHYS_PAGE" "228"
					( Origin gFrontEnd )
				)
				( attribute "ROT" "0"
					( Origin gFrontEnd )
				)
				( attribute "SEC" "1"
					( Origin gFrontEnd )
				)
				( attribute "SEC_TYPE" "0603V"
					( Origin gFrontEnd )
				)
				( attribute "TOLERANCE" "20%"
					( Origin gFrontEnd )
				)
				( attribute "VALUE" "47UF"
					( Origin gFrontEnd )
				)
				( attribute "VER" "1"
					( Origin gFrontEnd )
				)
				( attribute "VOLTAGE" "4V"
					( Units "uVoltage" "V" 1.000000)
					( Origin gFrontEnd )
				)
				( attribute "XY" "(-1100,-75)"
					( Origin gFrontEnd )
				)
				( attribute "CHIPS_PART_NAME" "CAP_A"
					( Origin gPackager )
				)
				( attribute "CDS_PART_NAME" "CAP_A_0603V-47UF,4V,20%,X5R,60A"
					( Origin gPackager )
				)
				( attribute "GROUP" "PWR_MLCC_CAP"
					( Origin gFrontEnd )
				)
				( attribute "BOM_SS" "E15431-004"
					( Origin gFrontEnd )
				)
				( objectStatus "C2A14" )
			)
			( gate "@baseboard_fab2_lib.baseboard_fab2(sch_1):page228_i267"
				( attribute "BOM_COST" "PROC_SOCKET"
					( Origin gFrontEnd )
				)
				( attribute "CDS_LIB" "dev_discrete"
					( Origin gPackager )
				)
				( attribute "CDS_LOCATION" "C2D6"
					( Origin gPackager )
				)
				( attribute "CDS_SEC" "1"
					( Origin gPackager )
				)
				( attribute "LOCATION" "C2D6"
					( Origin gFrontEnd )
				)
				( attribute "MATERIAL" "X6S"
					( Origin gFrontEnd )
				)
				( attribute "PACK_TYPE" "0603V"
					( Origin gFrontEnd )
				)
				( attribute "PART_NUMBER" "E15431-004"
					( Origin gFrontEnd )
				)
				( attribute "PHYS_PAGE" "228"
					( Origin gFrontEnd )
				)
				( attribute "ROOM" "PVCCIN_CPU0_DECAP_VR"
					( Origin gFrontEnd )
				)
				( attribute "ROT" "0"
					( Origin gFrontEnd )
				)
				( attribute "SEC" "1"
					( Origin gPackager )
				)
				( attribute "TOLERANCE" "20%"
					( Origin gFrontEnd )
				)
				( attribute "VALUE" "22.0UF"
					( Origin gFrontEnd )
				)
				( attribute "VER" "1"
					( Origin gFrontEnd )
				)
				( attribute "VOLTAGE" "4V"
					( Units "uVoltage" "V" 1.000000)
					( Origin gFrontEnd )
				)
				( attribute "XY" "(-250,2975)"
					( Origin gFrontEnd )
				)
				( attribute "CHIPS_PART_NAME" "CAP_A"
					( Origin gPackager )
				)
				( attribute "CDS_PART_NAME" "CAP_A_0603V-22.0UF,4V,20%,X6S,A"
					( Origin gPackager )
				)
				( attribute "GROUP" "PWR_MLCC_CAP"
					( Origin gFrontEnd )
				)
				( objectStatus "C2D6" )
			)
			( gate "@baseboard_fab2_lib.baseboard_fab2(sch_1):page228_i266"
				( attribute "BOM_COST" "PROC_SOCKET"
					( Origin gFrontEnd )
				)
				( attribute "CDS_LIB" "dev_discrete"
					( Origin gPackager )
				)
				( attribute "CDS_LOCATION" "C2D5"
					( Origin gPackager )
				)
				( attribute "CDS_SEC" "1"
					( Origin gPackager )
				)
				( attribute "LOCATION" "C2D5"
					( Origin gFrontEnd )
				)
				( attribute "MATERIAL" "X6S"
					( Origin gFrontEnd )
				)
				( attribute "PACK_TYPE" "0603V"
					( Origin gFrontEnd )
				)
				( attribute "PART_NUMBER" "E15431-004"
					( Origin gFrontEnd )
				)
				( attribute "PHYS_PAGE" "228"
					( Origin gFrontEnd )
				)
				( attribute "ROOM" "PVCCIN_CPU0_DECAP_VR"
					( Origin gFrontEnd )
				)
				( attribute "ROT" "0"
					( Origin gFrontEnd )
				)
				( attribute "SEC" "1"
					( Origin gPackager )
				)
				( attribute "TOLERANCE" "20%"
					( Origin gFrontEnd )
				)
				( attribute "VALUE" "22.0UF"
					( Origin gFrontEnd )
				)
				( attribute "VER" "1"
					( Origin gFrontEnd )
				)
				( attribute "VOLTAGE" "4V"
					( Units "uVoltage" "V" 1.000000)
					( Origin gFrontEnd )
				)
				( attribute "XY" "(-600,2975)"
					( Origin gFrontEnd )
				)
				( attribute "CHIPS_PART_NAME" "CAP_A"
					( Origin gPackager )
				)
				( attribute "CDS_PART_NAME" "CAP_A_0603V-22.0UF,4V,20%,X6S,A"
					( Origin gPackager )
				)
				( attribute "GROUP" "PWR_MLCC_CAP"
					( Origin gFrontEnd )
				)
				( objectStatus "C2D5" )
			)
			( gate "@baseboard_fab2_lib.baseboard_fab2(sch_1):page228_i265"
				( attribute "BOM_COST" "PROC_SOCKET"
					( Origin gFrontEnd )
				)
				( attribute "CDS_LIB" "dev_discrete"
					( Origin gPackager )
				)
				( attribute "CDS_LOCATION" "C2D4"
					( Origin gPackager )
				)
				( attribute "CDS_SEC" "1"
					( Origin gPackager )
				)
				( attribute "LOCATION" "C2D4"
					( Origin gFrontEnd )
				)
				( attribute "MATERIAL" "X6S"
					( Origin gFrontEnd )
				)
				( attribute "PACK_TYPE" "0603V"
					( Origin gFrontEnd )
				)
				( attribute "PART_NUMBER" "E15431-004"
					( Origin gFrontEnd )
				)
				( attribute "PHYS_PAGE" "228"
					( Origin gFrontEnd )
				)
				( attribute "ROOM" "PVCCIN_CPU0_DECAP_VR"
					( Origin gFrontEnd )
				)
				( attribute "ROT" "0"
					( Origin gFrontEnd )
				)
				( attribute "SEC" "1"
					( Origin gPackager )
				)
				( attribute "TOLERANCE" "20%"
					( Origin gFrontEnd )
				)
				( attribute "VALUE" "22.0UF"
					( Origin gFrontEnd )
				)
				( attribute "VER" "1"
					( Origin gFrontEnd )
				)
				( attribute "VOLTAGE" "4V"
					( Units "uVoltage" "V" 1.000000)
					( Origin gFrontEnd )
				)
				( attribute "XY" "(-950,2975)"
					( Origin gFrontEnd )
				)
				( attribute "CHIPS_PART_NAME" "CAP_A"
					( Origin gPackager )
				)
				( attribute "CDS_PART_NAME" "CAP_A_0603V-22.0UF,4V,20%,X6S,A"
					( Origin gPackager )
				)
				( attribute "GROUP" "PWR_MLCC_CAP"
					( Origin gFrontEnd )
				)
				( objectStatus "C2D4" )
			)
			( gate "@baseboard_fab2_lib.baseboard_fab2(sch_1):page228_i264"
				( attribute "BOM_COST" "PROC_SOCKET"
					( Origin gFrontEnd )
				)
				( attribute "CDS_LIB" "dev_discrete"
					( Origin gPackager )
				)
				( attribute "CDS_LOCATION" "C2D7"
					( Origin gPackager )
				)
				( attribute "CDS_SEC" "1"
					( Origin gPackager )
				)
				( attribute "LOCATION" "C2D7"
					( Origin gFrontEnd )
				)
				( attribute "MATERIAL" "X6S"
					( Origin gFrontEnd )
				)
				( attribute "PACK_TYPE" "0603V"
					( Origin gFrontEnd )
				)
				( attribute "PART_NUMBER" "E15431-004"
					( Origin gFrontEnd )
				)
				( attribute "PHYS_PAGE" "228"
					( Origin gFrontEnd )
				)
				( attribute "ROOM" "PVCCIN_CPU0_DECAP_VR"
					( Origin gFrontEnd )
				)
				( attribute "ROT" "0"
					( Origin gFrontEnd )
				)
				( attribute "SEC" "1"
					( Origin gPackager )
				)
				( attribute "TOLERANCE" "20%"
					( Origin gFrontEnd )
				)
				( attribute "VALUE" "22.0UF"
					( Origin gFrontEnd )
				)
				( attribute "VER" "1"
					( Origin gFrontEnd )
				)
				( attribute "VOLTAGE" "4V"
					( Units "uVoltage" "V" 1.000000)
					( Origin gFrontEnd )
				)
				( attribute "XY" "(-1300,2975)"
					( Origin gFrontEnd )
				)
				( attribute "CHIPS_PART_NAME" "CAP_A"
					( Origin gPackager )
				)
				( attribute "CDS_PART_NAME" "CAP_A_0603V-22.0UF,4V,20%,X6S,A"
					( Origin gPackager )
				)
				( attribute "GROUP" "PWR_MLCC_CAP"
					( Origin gFrontEnd )
				)
				( objectStatus "C2D7" )
			)
			( gate "@baseboard_fab2_lib.baseboard_fab2(sch_1):page225_i243"
				( attribute "CDS_LIB" "mstr_misc"
					( Origin gPackager )
				)
				( attribute "CDS_LOCATION" "SH7U1"
					( Origin gPackager )
				)
				( attribute "CDS_SEC" "1"
					( Origin gPackager )
				)
				( attribute "LOCATION" "SH7U1"
					( Origin gFrontEnd )
				)
				( attribute "MATERIAL" "EMPTY"
					( Origin gFrontEnd )
				)
				( attribute "PACK_TYPE" "SH0201"
					( Origin gFrontEnd )
				)
				( attribute "PART_NUMBER" "N_A"
					( Origin gFrontEnd )
				)
				( attribute "PHYS_PAGE" "225"
					( Origin gFrontEnd )
				)
				( attribute "PIN_SHORT" "A:B"
					( Origin gFrontEnd )
				)
				( attribute "ROT" "0"
					( Origin gFrontEnd )
				)
				( attribute "SEC" "1"
					( Origin gFrontEnd )
				)
				( attribute "SEC_TYPE" "SH0201"
					( Origin gFrontEnd )
				)
				( attribute "VER" "1"
					( Origin gFrontEnd )
				)
				( attribute "XY" "(-250,2325)"
					( Origin gFrontEnd )
				)
				( attribute "CHIPS_PART_NAME" "SHUNT"
					( Origin gPackager )
				)
				( attribute "CDS_PART_NAME" "SHUNT_SH0201-EMPTY,N_A"
					( Origin gPackager )
				)
				( objectStatus "SH7U1" )
			)
			( gate "@baseboard_fab2_lib.baseboard_fab2(sch_1):page225_i244"
				( attribute "CDS_LIB" "mstr_misc"
					( Origin gPackager )
				)
				( attribute "CDS_LOCATION" "SH7U2"
					( Origin gPackager )
				)
				( attribute "CDS_SEC" "1"
					( Origin gPackager )
				)
				( attribute "LOCATION" "SH7U2"
					( Origin gFrontEnd )
				)
				( attribute "MATERIAL" "EMPTY"
					( Origin gFrontEnd )
				)
				( attribute "PACK_TYPE" "SH0201"
					( Origin gFrontEnd )
				)
				( attribute "PART_NUMBER" "N_A"
					( Origin gFrontEnd )
				)
				( attribute "PHYS_PAGE" "225"
					( Origin gFrontEnd )
				)
				( attribute "PIN_SHORT" "A:B"
					( Origin gFrontEnd )
				)
				( attribute "ROT" "0"
					( Origin gFrontEnd )
				)
				( attribute "SEC" "1"
					( Origin gFrontEnd )
				)
				( attribute "SEC_TYPE" "SH0201"
					( Origin gFrontEnd )
				)
				( attribute "VER" "1"
					( Origin gFrontEnd )
				)
				( attribute "XY" "(-275,1875)"
					( Origin gFrontEnd )
				)
				( attribute "CHIPS_PART_NAME" "SHUNT"
					( Origin gPackager )
				)
				( attribute "CDS_PART_NAME" "SHUNT_SH0201-EMPTY,N_A"
					( Origin gPackager )
				)
				( objectStatus "SH7U2" )
			)
			( gate "@baseboard_fab2_lib.baseboard_fab2(sch_1):page197_i114"
				( attribute "ATTRIBUTE" "4.02OHM"
					( Origin gFrontEnd )
				)
				( attribute "CDS_LIB" "w_hdl"
					( Origin gPackager )
				)
				( attribute "CDS_LMAN_SYM_OUTLINE" "-50,75,50,-75"
					( Origin gPackager )
				)
				( attribute "LOCATION" "R12W18"
					( Origin gFrontEnd )
				)
				( attribute "PACK_TYPE" "SMD-RG2"
					( Origin gFrontEnd )
				)
				( attribute "PART_NUMBER" "64.4R025.6DL"
					( Origin gFrontEnd )
				)
				( attribute "PHYS_PAGE" "197"
					( Origin gFrontEnd )
				)
				( attribute "RATED" "1/16W"
					( Origin gFrontEnd )
				)
				( attribute "ROT" "1"
					( Origin gFrontEnd )
				)
				( attribute "SEC" "1"
					( Origin gFrontEnd )
				)
				( attribute "SEC_TYPE" "SMD-RG2"
					( Origin gFrontEnd )
				)
				( attribute "TOLERANCE" "1%"
					( Origin gFrontEnd )
				)
				( attribute "VALUE" "4D02R2F-GP"
					( Origin gFrontEnd )
				)
				( attribute "VER" "1"
					( Origin gFrontEnd )
				)
				( attribute "XY" "(-1700,2450)"
					( Origin gFrontEnd )
				)
				( attribute "CHIPS_PART_NAME" "4D02R2F-GP"
					( Origin gPackager )
				)
				( attribute "CDS_PART_NAME" "4D02R2F-GP_SMD-RG2-4D02R2F-GP,A"
					( Origin gPackager )
				)
				( attribute "PACK_SIZE" "0402"
					( Origin gFrontEnd )
				)
				( attribute "CDS_LOCATION" "R12W18"
					( Origin gPackager )
				)
				( attribute "CDS_SEC" "1"
					( Origin gPackager )
				)
				( objectStatus "R12W18" )
			)
			( gate "@baseboard_fab2_lib.baseboard_fab2(sch_1):page226_i13"
				( attribute "CDS_LIB" "mstr_discrete"
					( Origin gPackager )
				)
				( attribute "CDS_LOCATION" "R1B16"
					( Origin gPackager )
				)
				( attribute "CDS_SEC" "1"
					( Origin gPackager )
				)
				( attribute "LOCATION" "R1B16"
					( Origin gFrontEnd )
				)
				( attribute "MATERIAL" "CHIP"
					( Origin gFrontEnd )
				)
				( attribute "NO_XNET_CONNECTION" "1"
					( Origin gFrontEnd )
				)
				( attribute "PACK_TYPE" "0402"
					( Origin gFrontEnd )
				)
				( attribute "PART_NUMBER" "G21796-066"
					( Origin gFrontEnd )
				)
				( attribute "PHYS_PAGE" "226"
					( Origin gFrontEnd )
				)
				( attribute "ROOM" "VDDQ_KLM_PWR_VR"
					( Origin gFrontEnd )
				)
				( attribute "ROT" "0"
					( Origin gFrontEnd )
				)
				( attribute "SEC" "1"
					( Origin gFrontEnd )
				)
				( attribute "SEC_TYPE" "0402"
					( Origin gFrontEnd )
				)
				( attribute "TOLERANCE" "1%"
					( Origin gFrontEnd )
				)
				( attribute "VALUE" "10.0"
					( Origin gFrontEnd )
				)
				( attribute "VER" "1"
					( Origin gFrontEnd )
				)
				( attribute "WATTAGE" "1/16W"
					( Origin gFrontEnd )
				)
				( attribute "XY" "(-1925,475)"
					( Origin gFrontEnd )
				)
				( attribute "CHIPS_PART_NAME" "RES"
					( Origin gPackager )
				)
				( attribute "CDS_PART_NAME" "RES_0402-10.0,1%,1/16W,CHIP,G2A"
					( Origin gPackager )
				)
				( objectStatus "R1B16" )
			)
			( gate "@baseboard_fab2_lib.baseboard_fab2(sch_1):page226_i14"
				( attribute "CDS_LIB" "mstr_discrete"
					( Origin gPackager )
				)
				( attribute "CDS_LOCATION" "R9M9"
					( Origin gPackager )
				)
				( attribute "CDS_SEC" "1"
					( Origin gPackager )
				)
				( attribute "LOCATION" "R9M9"
					( Origin gFrontEnd )
				)
				( attribute "MATERIAL" "CHIP"
					( Origin gFrontEnd )
				)
				( attribute "PACK_TYPE" "0402"
					( Origin gFrontEnd )
				)
				( attribute "PART_NUMBER" "G21497-005"
					( Origin gFrontEnd )
				)
				( attribute "PHYS_PAGE" "226"
					( Origin gFrontEnd )
				)
				( attribute "ROOM" "PVCCIN_CPU0_VR"
					( Origin gFrontEnd )
				)
				( attribute "ROT" "0"
					( Origin gFrontEnd )
				)
				( attribute "SEC" "1"
					( Origin gPackager )
				)
				( attribute "TOLERANCE" "5%"
					( Origin gFrontEnd )
				)
				( attribute "VALUE" "0.0"
					( Origin gFrontEnd )
				)
				( attribute "VER" "1"
					( Origin gFrontEnd )
				)
				( attribute "WATTAGE" "1/16W"
					( Origin gFrontEnd )
				)
				( attribute "XY" "(-1800,775)"
					( Origin gFrontEnd )
				)
				( attribute "CHIPS_PART_NAME" "RES"
					( Origin gPackager )
				)
				( attribute "CDS_PART_NAME" "RES_0402-0.0,5%,1/16W,CHIP,G21A"
					( Origin gPackager )
				)
				( objectStatus "R9M9" )
			)
			( gate "@baseboard_fab2_lib.baseboard_fab2(sch_1):page226_i16"
				( attribute "CDS_LIB" "mstr_discrete"
					( Origin gPackager )
				)
				( attribute "CDS_LOCATION" "RF21"
					( Origin gPackager )
				)
				( attribute "CDS_SEC" "1"
					( Origin gPackager )
				)
				( attribute "LOCATION" "RF21"
					( Origin gFrontEnd )
				)
				( attribute "MATERIAL" "CHIP"
					( Origin gFrontEnd )
				)
				( attribute "PACK_TYPE" "0402"
					( Origin gFrontEnd )
				)
				( attribute "PART_NUMBER" "G85996-004"
					( Origin gFrontEnd )
				)
				( attribute "PHYS_PAGE" "226"
					( Origin gFrontEnd )
				)
				( attribute "ROOM" "SB"
					( Origin gFrontEnd )
				)
				( attribute "ROT" "0"
					( Origin gFrontEnd )
				)
				( attribute "SEC" "1"
					( Origin gFrontEnd )
				)
				( attribute "SEC_TYPE" "0402"
					( Origin gFrontEnd )
				)
				( attribute "TOLERANCE" "0.1%"
					( Origin gFrontEnd )
				)
				( attribute "VALUE" "1.0K"
					( Origin gFrontEnd )
				)
				( attribute "VER" "1"
					( Origin gFrontEnd )
				)
				( attribute "WATTAGE" "1/16W"
					( Origin gFrontEnd )
				)
				( attribute "XY" "(-1550,2025)"
					( Origin gFrontEnd )
				)
				( attribute "CHIPS_PART_NAME" "RES"
					( Origin gPackager )
				)
				( attribute "CDS_PART_NAME" "RES_0402-1.0K,0.1%,1/16W,CHIP,A"
					( Origin gPackager )
				)
				( attribute "GROUP" "POWER_FAIR"
					( Origin gFrontEnd )
				)
				( attribute "FAIR_SS" "064.9090D.M001"
					( Origin gFrontEnd )
				)
				( objectStatus "RF21" )
			)
			( gate "@baseboard_fab2_lib.baseboard_fab2(sch_1):page226_i17"
				( attribute "CDS_LIB" "w_hdl"
					( Origin gPackager )
				)
				( attribute "CDS_LMAN_SYM_OUTLINE" "-50,25,50,-25"
					( Origin gPackager )
				)
				( attribute "CDS_LOCATION" "CF22"
					( Origin gPackager )
				)
				( attribute "CDS_SEC" "1"
					( Origin gPackager )
				)
				( attribute "LOCATION" "CF22"
					( Origin gFrontEnd )
				)
				( attribute "PACK_TYPE" "SMD-BCG"
					( Origin gFrontEnd )
				)
				( attribute "PART_NUMBER" "78.22034.1FL"
					( Origin gFrontEnd )
				)
				( attribute "PHYS_PAGE" "226"
					( Origin gFrontEnd )
				)
				( attribute "ROT" "1"
					( Origin gFrontEnd )
				)
				( attribute "SEC" "1"
					( Origin gPackager )
				)
				( attribute "VALUE" "SC22P50V2JN-4GP"
					( Origin gFrontEnd )
				)
				( attribute "VER" "1"
					( Origin gFrontEnd )
				)
				( attribute "XY" "(-750,1850)"
					( Origin gFrontEnd )
				)
				( attribute "CHIPS_PART_NAME" "SC22P50V2JN-4GP"
					( Origin gPackager )
				)
				( attribute "CDS_PART_NAME" "SC22P50V2JN-4GP_SMD-BCG-SC22P5A"
					( Origin gPackager )
				)
				( attribute "ATTRIBUTE" "22PF"
					( Origin gFrontEnd )
				)
				( attribute "PACK_SIZE" "0402"
					( Origin gFrontEnd )
				)
				( attribute "RATED" "50V"
					( Origin gFrontEnd )
				)
				( attribute "TOLERANCE" "5%"
					( Origin gFrontEnd )
				)
				( attribute "TYPE" "NPO"
					( Origin gFrontEnd )
				)
				( attribute "GROUP" "POWER_FAIR"
					( Origin gFrontEnd )
				)
				( attribute "BOM_SS" "NOPOP"
					( Origin gFrontEnd )
				)
				( objectStatus "CF22" )
			)
			( gate "@baseboard_fab2_lib.baseboard_fab2(sch_1):page197_i21"
				( attribute "BOM_COST" "PROC_SOCKET"
					( Origin gFrontEnd )
				)
				( attribute "CDS_LIB" "mstr_discrete"
					( Origin gPackager )
				)
				( attribute "CDS_LOCATION" "R12W9"
					( Origin gPackager )
				)
				( attribute "CDS_SEC" "1"
					( Origin gPackager )
				)
				( attribute "LOCATION" "R12W9"
					( Origin gFrontEnd )
				)
				( attribute "MATERIAL" "CHIP"
					( Origin gFrontEnd )
				)
				( attribute "PACK_TYPE" "0603"
					( Origin gFrontEnd )
				)
				( attribute "PART_NUMBER" "G22026-050"
					( Origin gFrontEnd )
				)
				( attribute "PHYS_PAGE" "197"
					( Origin gFrontEnd )
				)
				( attribute "ROOM" "CPU0"
					( Origin gFrontEnd )
				)
				( attribute "ROT" "0"
					( Origin gFrontEnd )
				)
				( attribute "SEC" "1"
					( Origin gFrontEnd )
				)
				( attribute "SEC_TYPE" "0603"
					( Origin gFrontEnd )
				)
				( attribute "TOLERANCE" "1%"
					( Origin gFrontEnd )
				)
				( attribute "VALUE" "100.0K"
					( Origin gFrontEnd )
				)
				( attribute "VER" "2"
					( Origin gFrontEnd )
				)
				( attribute "WATTAGE" "1/10W"
					( Origin gFrontEnd )
				)
				( attribute "XY" "(-2725,2400)"
					( Origin gFrontEnd )
				)
				( attribute "CHIPS_PART_NAME" "RES"
					( Origin gPackager )
				)
				( attribute "CDS_PART_NAME" "RES_0603-100.0K,1%,1/10W,CHIP,A"
					( Origin gPackager )
				)
				( objectStatus "R12W9" )
			)
			( gate "@baseboard_fab2_lib.baseboard_fab2(sch_1):page226_i23"
				( attribute "CDS_LIB" "mstr_discrete"
					( Origin gPackager )
				)
				( attribute "CDS_LOCATION" "C1B11"
					( Origin gPackager )
				)
				( attribute "CDS_SEC" "1"
					( Origin gPackager )
				)
				( attribute "LOCATION" "C1B11"
					( Origin gFrontEnd )
				)
				( attribute "MATERIAL" "X7R"
					( Origin gFrontEnd )
				)
				( attribute "PACK_TYPE" "0402LF"
					( Origin gFrontEnd )
				)
				( attribute "PART_NUMBER" "A36096-050"
					( Origin gFrontEnd )
				)
				( attribute "PHYS_PAGE" "226"
					( Origin gFrontEnd )
				)
				( attribute "ROOM" "VDDQ_KLM_PWR_VR"
					( Origin gFrontEnd )
				)
				( attribute "ROT" "2"
					( Origin gFrontEnd )
				)
				( attribute "SEC" "1"
					( Origin gFrontEnd )
				)
				( attribute "SEC_TYPE" "0402LF"
					( Origin gFrontEnd )
				)
				( attribute "TOLERANCE" "10%"
					( Origin gFrontEnd )
				)
				( attribute "VALUE" "220PF"
					( Origin gFrontEnd )
				)
				( attribute "VER" "1"
					( Origin gFrontEnd )
				)
				( attribute "VOLTAGE" "50V"
					( Units "uVoltage" "V" 1.000000)
					( Origin gFrontEnd )
				)
				( attribute "XY" "(-225,25)"
					( Origin gFrontEnd )
				)
				( attribute "CHIPS_PART_NAME" "CAP"
					( Origin gPackager )
				)
				( attribute "CDS_PART_NAME" "CAP_0402LF-220PF,50V,10%,X7R,AA"
					( Origin gPackager )
				)
				( objectStatus "C1B11" )
			)
			( gate "@baseboard_fab2_lib.baseboard_fab2(sch_1):page197_i19"
				( attribute "CDS_LIB" "w_hdl"
					( Origin gPackager )
				)
				( attribute "CDS_LMAN_SYM_OUTLINE" "-125,250,125,-250"
					( Origin gPackager )
				)
				( attribute "CDS_LOCATION" "Q12W2"
					( Origin gPackager )
				)
				( attribute "CDS_SEC" "1"
					( Origin gPackager )
				)
				( attribute "LOCATION" "Q12W2"
					( Origin gFrontEnd )
				)
				( attribute "PACK_TYPE" "DISCRET-GB1"
					( Origin gFrontEnd )
				)
				( attribute "PART_NUMBER" "075.00308.007C"
					( Origin gFrontEnd )
				)
				( attribute "PHYS_PAGE" "197"
					( Origin gFrontEnd )
				)
				( attribute "ROT" "0"
					( Origin gFrontEnd )
				)
				( attribute "SEC" "1"
					( Origin gFrontEnd )
				)
				( attribute "SEC_TYPE" "DISCRET-GB1"
					( Origin gFrontEnd )
				)
				( attribute "VALUE" "BSL308C-H6327-GP"
					( Origin gFrontEnd )
				)
				( attribute "VER" "1"
					( Origin gFrontEnd )
				)
				( attribute "XY" "(-3250,2000)"
					( Origin gFrontEnd )
				)
				( attribute "CHIPS_PART_NAME" "BSL308C-H6327-GP"
					( Origin gPackager )
				)
				( attribute "CDS_PART_NAME" "BSL308C-H6327-GP_DISCRET-GB1-BA"
					( Origin gPackager )
				)
				( objectStatus "Q12W2" )
			)
			( gate "@baseboard_fab2_lib.baseboard_fab2(sch_1):page235_i254"
				( attribute "CDS_LIB" "mstr_discrete"
					( Origin gPackager )
				)
				( attribute "CDS_LOCATION" "R2L9"
					( Origin gPackager )
				)
				( attribute "CDS_SEC" "1"
					( Origin gPackager )
				)
				( attribute "LOCATION" "R2L9"
					( Origin gFrontEnd )
				)
				( attribute "MATERIAL" "CHIP"
					( Origin gFrontEnd )
				)
				( attribute "PACK_TYPE" "0402"
					( Origin gFrontEnd )
				)
				( attribute "PART_NUMBER" "G21796-082"
					( Origin gFrontEnd )
				)
				( attribute "PHYS_PAGE" "235"
					( Origin gFrontEnd )
				)
				( attribute "ROOM" "PVCCIN_CPU0_VR"
					( Origin gFrontEnd )
				)
				( attribute "ROT" "0"
					( Origin gFrontEnd )
				)
				( attribute "SEC" "1"
					( Origin gFrontEnd )
				)
				( attribute "SEC_TYPE" "0402"
					( Origin gFrontEnd )
				)
				( attribute "TOLERANCE" "1%"
					( Origin gFrontEnd )
				)
				( attribute "VALUE" "4.02K"
					( Origin gFrontEnd )
				)
				( attribute "VER" "2"
					( Origin gFrontEnd )
				)
				( attribute "WATTAGE" "1/16W"
					( Origin gFrontEnd )
				)
				( attribute "XY" "(-10750,2150)"
					( Origin gFrontEnd )
				)
				( attribute "CHIPS_PART_NAME" "RES"
					( Origin gPackager )
				)
				( attribute "CDS_PART_NAME" "RES_0402-4.02K,1%,1/16W,CHIP,GA"
					( Origin gPackager )
				)
				( objectStatus "R2L9" )
			)
			( gate "@baseboard_fab2_lib.baseboard_fab2(sch_1):page226_i32"
				( attribute "CDS_LIB" "dev_discrete"
					( Origin gPackager )
				)
				( attribute "CDS_LOCATION" "C1B5"
					( Origin gPackager )
				)
				( attribute "CDS_SEC" "1"
					( Origin gPackager )
				)
				( attribute "LOCATION" "C1B5"
					( Origin gFrontEnd )
				)
				( attribute "MATERIAL" "X7R"
					( Origin gFrontEnd )
				)
				( attribute "PACK_TYPE" "0402V"
					( Origin gFrontEnd )
				)
				( attribute "PART_NUMBER" "A36096-030"
					( Origin gFrontEnd )
				)
				( attribute "PHYS_PAGE" "226"
					( Origin gFrontEnd )
				)
				( attribute "ROOM" "VDDQ_KLM_PWR_VR"
					( Origin gFrontEnd )
				)
				( attribute "ROT" "0"
					( Origin gFrontEnd )
				)
				( attribute "SEC" "1"
					( Origin gFrontEnd )
				)
				( attribute "SEC_TYPE" "0402V"
					( Origin gFrontEnd )
				)
				( attribute "TOLERANCE" "10%"
					( Origin gFrontEnd )
				)
				( attribute "VALUE" "0.1UF"
					( Origin gFrontEnd )
				)
				( attribute "VER" "1"
					( Origin gFrontEnd )
				)
				( attribute "VOLTAGE" "16V"
					( Units "uVoltage" "V" 1.000000)
					( Origin gFrontEnd )
				)
				( attribute "XY" "(675,2375)"
					( Origin gFrontEnd )
				)
				( attribute "CHIPS_PART_NAME" "CAP_A"
					( Origin gPackager )
				)
				( attribute "CDS_PART_NAME" "CAP_A_0402V-0.1UF,16V,10%,X7R,A"
					( Origin gPackager )
				)
				( objectStatus "C1B5" )
			)
			( gate "@baseboard_fab2_lib.baseboard_fab2(sch_1):page226_i36"
				( attribute "CDS_LIB" "mstr_discrete"
					( Origin gPackager )
				)
				( attribute "CDS_LOCATION" "R9M3"
					( Origin gPackager )
				)
				( attribute "CDS_SEC" "1"
					( Origin gPackager )
				)
				( attribute "LOCATION" "R9M3"
					( Origin gFrontEnd )
				)
				( attribute "MATERIAL" "CHIP"
					( Origin gFrontEnd )
				)
				( attribute "PACK_TYPE" "0402"
					( Origin gFrontEnd )
				)
				( attribute "PART_NUMBER" "G21497-005"
					( Origin gFrontEnd )
				)
				( attribute "PHYS_PAGE" "226"
					( Origin gFrontEnd )
				)
				( attribute "ROOM" "VDDQ_KLM_PWR_VR"
					( Origin gFrontEnd )
				)
				( attribute "ROT" "0"
					( Origin gFrontEnd )
				)
				( attribute "SEC" "1"
					( Origin gFrontEnd )
				)
				( attribute "SEC_TYPE" "0402"
					( Origin gFrontEnd )
				)
				( attribute "TOLERANCE" "5%"
					( Origin gFrontEnd )
				)
				( attribute "VALUE" "0.0"
					( Origin gFrontEnd )
				)
				( attribute "VER" "2"
					( Origin gFrontEnd )
				)
				( attribute "WATTAGE" "1/16W"
					( Origin gFrontEnd )
				)
				( attribute "XY" "(575,2825)"
					( Origin gFrontEnd )
				)
				( attribute "CHIPS_PART_NAME" "RES"
					( Origin gPackager )
				)
				( attribute "CDS_PART_NAME" "RES_0402-0.0,5%,1/16W,CHIP,G21A"
					( Origin gPackager )
				)
				( objectStatus "R9M3" )
			)
			( gate "@baseboard_fab2_lib.baseboard_fab2(sch_1):page197_i18"
				( attribute "BOM_COST" "SM_HM"
					( Origin gFrontEnd )
				)
				( attribute "CDS_LIB" "mstr_discrete"
					( Origin gPackager )
				)
				( attribute "CDS_LOCATION" "C12W4"
					( Origin gPackager )
				)
				( attribute "CDS_SEC" "1"
					( Origin gPackager )
				)
				( attribute "LOCATION" "C12W4"
					( Origin gFrontEnd )
				)
				( attribute "MATERIAL" "COG"
					( Origin gFrontEnd )
				)
				( attribute "PACK_TYPE" "0402LF"
					( Origin gFrontEnd )
				)
				( attribute "PART_NUMBER" "A36095-025"
					( Origin gFrontEnd )
				)
				( attribute "PHYS_PAGE" "197"
					( Origin gFrontEnd )
				)
				( attribute "ROOM" "BMC_VOLT_MONITOR"
					( Origin gFrontEnd )
				)
				( attribute "ROT" "1"
					( Origin gFrontEnd )
				)
				( attribute "SEC" "1"
					( Origin gFrontEnd )
				)
				( attribute "SEC_TYPE" "0402LF"
					( Origin gFrontEnd )
				)
				( attribute "TOLERANCE" "5%"
					( Origin gFrontEnd )
				)
				( attribute "VALUE" "47.0PF"
					( Origin gFrontEnd )
				)
				( attribute "VER" "1"
					( Origin gFrontEnd )
				)
				( attribute "VOLTAGE" "50V"
					( Units "uVoltage" "V" 1.000000)
					( Origin gFrontEnd )
				)
				( attribute "XY" "(-1725,1450)"
					( Origin gFrontEnd )
				)
				( attribute "CHIPS_PART_NAME" "CAP"
					( Origin gPackager )
				)
				( attribute "CDS_PART_NAME" "CAP_0402LF-47.0PF,50V,5%,COG,AA"
					( Origin gPackager )
				)
				( objectStatus "C12W4" )
			)
			( gate "@baseboard_fab2_lib.baseboard_fab2(sch_1):page226_i41"
				( attribute "CDS_LIB" "mstr_discrete"
					( Origin gPackager )
				)
				( attribute "CDS_LOCATION" "R1B10"
					( Origin gPackager )
				)
				( attribute "CDS_SEC" "1"
					( Origin gPackager )
				)
				( attribute "LOCATION" "R1B10"
					( Origin gFrontEnd )
				)
				( attribute "MATERIAL" "CHIP"
					( Origin gFrontEnd )
				)
				( attribute "PACK_TYPE" "0402"
					( Origin gFrontEnd )
				)
				( attribute "PART_NUMBER" "G21497-005"
					( Origin gFrontEnd )
				)
				( attribute "PHYS_PAGE" "226"
					( Origin gFrontEnd )
				)
				( attribute "ROOM" "VDDQ_KLM_PWR_VR"
					( Origin gFrontEnd )
				)
				( attribute "ROT" "0"
					( Origin gFrontEnd )
				)
				( attribute "SEC" "1"
					( Origin gFrontEnd )
				)
				( attribute "SEC_TYPE" "0402"
					( Origin gFrontEnd )
				)
				( attribute "TOLERANCE" "5%"
					( Origin gFrontEnd )
				)
				( attribute "VALUE" "0.0"
					( Origin gFrontEnd )
				)
				( attribute "VER" "1"
					( Origin gFrontEnd )
				)
				( attribute "WATTAGE" "1/16W"
					( Origin gFrontEnd )
				)
				( attribute "XY" "(2525,975)"
					( Origin gFrontEnd )
				)
				( attribute "CHIPS_PART_NAME" "RES"
					( Origin gPackager )
				)
				( attribute "CDS_PART_NAME" "RES_0402-0.0,5%,1/16W,CHIP,G21A"
					( Origin gPackager )
				)
				( objectStatus "R1B10" )
			)
			( gate "@baseboard_fab2_lib.baseboard_fab2(sch_1):page226_i44"
				( attribute "CDS_LIB" "dev_discrete"
					( Origin gPackager )
				)
				( attribute "CDS_LOCATION" "C1B2"
					( Origin gPackager )
				)
				( attribute "CDS_SEC" "1"
					( Origin gPackager )
				)
				( attribute "LOCATION" "C1B2"
					( Origin gFrontEnd )
				)
				( attribute "MATERIAL" "X7R"
					( Origin gFrontEnd )
				)
				( attribute "PACK_TYPE" "0402V"
					( Origin gFrontEnd )
				)
				( attribute "PART_NUMBER" "A36096-030"
					( Origin gFrontEnd )
				)
				( attribute "PHYS_PAGE" "226"
					( Origin gFrontEnd )
				)
				( attribute "ROOM" "VDDQ_KLM_PWR_VR"
					( Origin gFrontEnd )
				)
				( attribute "ROT" "0"
					( Origin gFrontEnd )
				)
				( attribute "SEC" "1"
					( Origin gFrontEnd )
				)
				( attribute "SEC_TYPE" "0402V"
					( Origin gFrontEnd )
				)
				( attribute "TOLERANCE" "10%"
					( Origin gFrontEnd )
				)
				( attribute "VALUE" "0.1UF"
					( Origin gFrontEnd )
				)
				( attribute "VER" "1"
					( Origin gFrontEnd )
				)
				( attribute "VOLTAGE" "16V"
					( Units "uVoltage" "V" 1.000000)
					( Origin gFrontEnd )
				)
				( attribute "XY" "(3100,-525)"
					( Origin gFrontEnd )
				)
				( attribute "CHIPS_PART_NAME" "CAP_A"
					( Origin gPackager )
				)
				( attribute "CDS_PART_NAME" "CAP_A_0402V-0.1UF,16V,10%,X7R,A"
					( Origin gPackager )
				)
				( objectStatus "C1B2" )
			)
			( gate "@baseboard_fab2_lib.baseboard_fab2(sch_1):page226_i50"
				( attribute "CDS_LIB" "mstr_discrete"
					( Origin gPackager )
				)
				( attribute "CDS_LOCATION" "R1B2"
					( Origin gPackager )
				)
				( attribute "CDS_SEC" "1"
					( Origin gPackager )
				)
				( attribute "LOCATION" "R1B2"
					( Origin gFrontEnd )
				)
				( attribute "MATERIAL" "CHIP"
					( Origin gFrontEnd )
				)
				( attribute "PACK_TYPE" "0402"
					( Origin gFrontEnd )
				)
				( attribute "PART_NUMBER" "G21796-026"
					( Origin gFrontEnd )
				)
				( attribute "PHYS_PAGE" "226"
					( Origin gFrontEnd )
				)
				( attribute "ROOM" "VDDQ_KLM_PWR_VR"
					( Origin gFrontEnd )
				)
				( attribute "ROT" "0"
					( Origin gFrontEnd )
				)
				( attribute "SEC" "1"
					( Origin gFrontEnd )
				)
				( attribute "SEC_TYPE" "0402"
					( Origin gFrontEnd )
				)
				( attribute "TOLERANCE" "1%"
					( Origin gFrontEnd )
				)
				( attribute "VALUE" "1.00K"
					( Origin gFrontEnd )
				)
				( attribute "VER" "2"
					( Origin gFrontEnd )
				)
				( attribute "WATTAGE" "1/16W"
					( Origin gFrontEnd )
				)
				( attribute "XY" "(2100,2350)"
					( Origin gFrontEnd )
				)
				( attribute "CHIPS_PART_NAME" "RES"
					( Origin gPackager )
				)
				( attribute "CDS_PART_NAME" "RES_0402-1.00K,1%,1/16W,CHIP,GA"
					( Origin gPackager )
				)
				( objectStatus "R1B2" )
			)
			( gate "@baseboard_fab2_lib.baseboard_fab2(sch_1):page226_i53"
				( attribute "CDS_LIB" "mstr_discrete"
					( Origin gPackager )
				)
				( attribute "CDS_LOCATION" "R12W36"
					( Origin gPackager )
				)
				( attribute "CDS_SEC" "1"
					( Origin gPackager )
				)
				( attribute "LOCATION" "R12W36"
					( Origin gFrontEnd )
				)
				( attribute "MATERIAL" "EMPTY"
					( Origin gFrontEnd )
				)
				( attribute "PACK_TYPE" "0402"
					( Origin gFrontEnd )
				)
				( attribute "PART_NUMBER" "G21497-005"
					( Origin gFrontEnd )
				)
				( attribute "PHYS_PAGE" "226"
					( Origin gFrontEnd )
				)
				( attribute "ROOM" "NV_DIMM"
					( Origin gFrontEnd )
				)
				( attribute "ROT" "0"
					( Origin gFrontEnd )
				)
				( attribute "SEC" "1"
					( Origin gFrontEnd )
				)
				( attribute "SEC_TYPE" "0402"
					( Origin gFrontEnd )
				)
				( attribute "TOLERANCE" "5%"
					( Origin gFrontEnd )
				)
				( attribute "VALUE" "0.0"
					( Origin gFrontEnd )
				)
				( attribute "VER" "1"
					( Origin gFrontEnd )
				)
				( attribute "WATTAGE" "1/16W"
					( Origin gFrontEnd )
				)
				( attribute "XY" "(2950,1525)"
					( Origin gFrontEnd )
				)
				( attribute "CHIPS_PART_NAME" "RES"
					( Origin gPackager )
				)
				( attribute "CDS_PART_NAME" "RES_0402-0.0,5%,1/16W,EMPTY,G2A"
					( Origin gPackager )
				)
				( attribute "BOM_COST" "MEM_NV"
					( Origin gFrontEnd )
				)
				( objectStatus "R12W36" )
			)
			( gate "@baseboard_fab2_lib.baseboard_fab2(sch_1):page197_i14"
				( attribute "BOM_COST" "PVDDQ_ABC_VR"
					( Origin gFrontEnd )
				)
				( attribute "CDS_LIB" "mstr_discrete"
					( Origin gPackager )
				)
				( attribute "CDS_LOCATION" "R4F2"
					( Origin gPackager )
				)
				( attribute "CDS_SEC" "1"
					( Origin gPackager )
				)
				( attribute "LOCATION" "R4F2"
					( Origin gFrontEnd )
				)
				( attribute "MATERIAL" "CHIP"
					( Origin gFrontEnd )
				)
				( attribute "PACK_TYPE" "1206"
					( Origin gFrontEnd )
				)
				( attribute "PART_NUMBER" "G52199-004"
					( Origin gFrontEnd )
				)
				( attribute "PHYS_PAGE" "197"
					( Origin gFrontEnd )
				)
				( attribute "ROOM" "PVDDQ_ABC_PWR_VR"
					( Origin gFrontEnd )
				)
				( attribute "ROT" "0"
					( Origin gFrontEnd )
				)
				( attribute "SEC" "1"
					( Origin gFrontEnd )
				)
				( attribute "SEC_TYPE" "1206"
					( Origin gFrontEnd )
				)
				( attribute "TOLERANCE" "1%"
					( Origin gFrontEnd )
				)
				( attribute "VALUE" "0.002"
					( Origin gFrontEnd )
				)
				( attribute "VER" "1"
					( Origin gFrontEnd )
				)
				( attribute "WATTAGE" "1W"
					( Origin gFrontEnd )
				)
				( attribute "XY" "(-4275,4800)"
					( Origin gFrontEnd )
				)
				( attribute "CHIPS_PART_NAME" "RES"
					( Origin gPackager )
				)
				( attribute "CDS_PART_NAME" "RES_1206-0.002,1%,1W,CHIP,G521A"
					( Origin gPackager )
				)
				( attribute "CONFIG" "064.R0045.0711"
					( Origin gFrontEnd )
				)
				( attribute "NEW_VALUE" "0.004 OHM"
					( Origin gFrontEnd )
				)
				( objectStatus "R4F2" )
			)
			( gate "@baseboard_fab2_lib.baseboard_fab2(sch_1):page197_i115"
				( attribute "ATTRIBUTE" "4.02OHM"
					( Origin gFrontEnd )
				)
				( attribute "CDS_LIB" "w_hdl"
					( Origin gPackager )
				)
				( attribute "CDS_LMAN_SYM_OUTLINE" "-50,75,50,-75"
					( Origin gPackager )
				)
				( attribute "LOCATION" "R12W3"
					( Origin gFrontEnd )
				)
				( attribute "PACK_TYPE" "SMD-RG2"
					( Origin gFrontEnd )
				)
				( attribute "PART_NUMBER" "64.4R025.6DL"
					( Origin gFrontEnd )
				)
				( attribute "PHYS_PAGE" "197"
					( Origin gFrontEnd )
				)
				( attribute "RATED" "1/16W"
					( Origin gFrontEnd )
				)
				( attribute "ROT" "1"
					( Origin gFrontEnd )
				)
				( attribute "SEC" "1"
					( Origin gFrontEnd )
				)
				( attribute "SEC_TYPE" "SMD-RG2"
					( Origin gFrontEnd )
				)
				( attribute "TOLERANCE" "1%"
					( Origin gFrontEnd )
				)
				( attribute "VALUE" "4D02R2F-GP"
					( Origin gFrontEnd )
				)
				( attribute "VER" "1"
					( Origin gFrontEnd )
				)
				( attribute "XY" "(-4250,4550)"
					( Origin gFrontEnd )
				)
				( attribute "CHIPS_PART_NAME" "4D02R2F-GP"
					( Origin gPackager )
				)
				( attribute "CDS_PART_NAME" "4D02R2F-GP_SMD-RG2-4D02R2F-GP,A"
					( Origin gPackager )
				)
				( attribute "PACK_SIZE" "0402"
					( Origin gFrontEnd )
				)
				( attribute "CDS_LOCATION" "R12W3"
					( Origin gPackager )
				)
				( attribute "CDS_SEC" "1"
					( Origin gPackager )
				)
				( objectStatus "R12W3" )
			)
			( gate "@baseboard_fab2_lib.baseboard_fab2(sch_1):page197_i8"
				( attribute "BOM_COST" "SM_HM"
					( Origin gFrontEnd )
				)
				( attribute "CDS_LIB" "mstr_discrete"
					( Origin gPackager )
				)
				( attribute "CDS_LOCATION" "C12W1"
					( Origin gPackager )
				)
				( attribute "CDS_SEC" "1"
					( Origin gPackager )
				)
				( attribute "LOCATION" "C12W1"
					( Origin gFrontEnd )
				)
				( attribute "MATERIAL" "COG"
					( Origin gFrontEnd )
				)
				( attribute "PACK_TYPE" "0402LF"
					( Origin gFrontEnd )
				)
				( attribute "PART_NUMBER" "A36095-025"
					( Origin gFrontEnd )
				)
				( attribute "PHYS_PAGE" "197"
					( Origin gFrontEnd )
				)
				( attribute "ROOM" "BMC_VOLT_MONITOR"
					( Origin gFrontEnd )
				)
				( attribute "ROT" "1"
					( Origin gFrontEnd )
				)
				( attribute "SEC" "1"
					( Origin gFrontEnd )
				)
				( attribute "SEC_TYPE" "0402LF"
					( Origin gFrontEnd )
				)
				( attribute "TOLERANCE" "5%"
					( Origin gFrontEnd )
				)
				( attribute "VALUE" "47.0PF"
					( Origin gFrontEnd )
				)
				( attribute "VER" "1"
					( Origin gFrontEnd )
				)
				( attribute "VOLTAGE" "50V"
					( Units "uVoltage" "V" 1.000000)
					( Origin gFrontEnd )
				)
				( attribute "XY" "(-4275,3550)"
					( Origin gFrontEnd )
				)
				( attribute "CHIPS_PART_NAME" "CAP"
					( Origin gPackager )
				)
				( attribute "CDS_PART_NAME" "CAP_0402LF-47.0PF,50V,5%,COG,AA"
					( Origin gPackager )
				)
				( objectStatus "C12W1" )
			)
			( gate "@baseboard_fab2_lib.baseboard_fab2(sch_1):page197_i6"
				( attribute "BOM_COST" "PVDDQ_ABC_VR"
					( Origin gFrontEnd )
				)
				( attribute "CDS_LIB" "mstr_discrete"
					( Origin gPackager )
				)
				( attribute "CDS_LOCATION" "R4B12"
					( Origin gPackager )
				)
				( attribute "CDS_SEC" "1"
					( Origin gPackager )
				)
				( attribute "LOCATION" "R4B12"
					( Origin gFrontEnd )
				)
				( attribute "MATERIAL" "CHIP"
					( Origin gFrontEnd )
				)
				( attribute "PACK_TYPE" "1206"
					( Origin gFrontEnd )
				)
				( attribute "PART_NUMBER" "G52199-004"
					( Origin gFrontEnd )
				)
				( attribute "PHYS_PAGE" "197"
					( Origin gFrontEnd )
				)
				( attribute "ROOM" "PVDDQ_ABC_PWR_VR"
					( Origin gFrontEnd )
				)
				( attribute "ROT" "0"
					( Origin gFrontEnd )
				)
				( attribute "SEC" "1"
					( Origin gFrontEnd )
				)
				( attribute "SEC_TYPE" "1206"
					( Origin gFrontEnd )
				)
				( attribute "TOLERANCE" "1%"
					( Origin gFrontEnd )
				)
				( attribute "VALUE" "0.002"
					( Origin gFrontEnd )
				)
				( attribute "VER" "1"
					( Origin gFrontEnd )
				)
				( attribute "WATTAGE" "1W"
					( Origin gFrontEnd )
				)
				( attribute "XY" "(-4275,2700)"
					( Origin gFrontEnd )
				)
				( attribute "CHIPS_PART_NAME" "RES"
					( Origin gPackager )
				)
				( attribute "CDS_PART_NAME" "RES_1206-0.002,1%,1W,CHIP,G521A"
					( Origin gPackager )
				)
				( attribute "CONFIG" "064.R0045.0711"
					( Origin gFrontEnd )
				)
				( attribute "NEW_VALUE" "0.004 OHM"
					( Origin gFrontEnd )
				)
				( objectStatus "R4B12" )
			)
			( gate "@baseboard_fab2_lib.baseboard_fab2(sch_1):page211_i97"
				( attribute "CDS_LIB" "mstr_discrete"
					( Origin gPackager )
				)
				( attribute "CDS_LOCATION" "C4W1"
					( Origin gPackager )
				)
				( attribute "CDS_SEC" "1"
					( Origin gPackager )
				)
				( attribute "LOCATION" "C4W1"
					( Origin gFrontEnd )
				)
				( attribute "MATERIAL" "X7R"
					( Origin gFrontEnd )
				)
				( attribute "PACK_TYPE" "0402LF"
					( Origin gFrontEnd )
				)
				( attribute "PART_NUMBER" "A36096-050"
					( Origin gFrontEnd )
				)
				( attribute "PHYS_PAGE" "211"
					( Origin gFrontEnd )
				)
				( attribute "ROOM" "PVCCIN_CPU0_VR"
					( Origin gFrontEnd )
				)
				( attribute "ROT" "0"
					( Origin gFrontEnd )
				)
				( attribute "SEC" "1"
					( Origin gFrontEnd )
				)
				( attribute "SEC_TYPE" "0402LF"
					( Origin gFrontEnd )
				)
				( attribute "TOLERANCE" "10%"
					( Origin gFrontEnd )
				)
				( attribute "VALUE" "220PF"
					( Origin gFrontEnd )
				)
				( attribute "VER" "1"
					( Origin gFrontEnd )
				)
				( attribute "VOLTAGE" "50V"
					( Units "uVoltage" "V" 1.000000)
					( Origin gFrontEnd )
				)
				( attribute "XY" "(-2250,2750)"
					( Origin gFrontEnd )
				)
				( attribute "CHIPS_PART_NAME" "CAP"
					( Origin gPackager )
				)
				( attribute "CDS_PART_NAME" "CAP_0402LF-220PF,50V,10%,X7R,AA"
					( Origin gPackager )
				)
				( objectStatus "C4W1" )
			)
			( gate "@baseboard_fab2_lib.baseboard_fab2(sch_1):page227_i6"
				( attribute "BOM_COST" "VDDQ_KLM_PWR_VR"
					( Origin gFrontEnd )
				)
				( attribute "CDS_LIB" "mstr_discrete"
					( Origin gPackager )
				)
				( attribute "CDS_LOCATION" "C1A12"
					( Origin gPackager )
				)
				( attribute "CDS_SEC" "1"
					( Origin gPackager )
				)
				( attribute "LOCATION" "C1A12"
					( Origin gFrontEnd )
				)
				( attribute "MATERIAL" "X6S"
					( Origin gFrontEnd )
				)
				( attribute "PACK_TYPE" "0805LF"
					( Origin gFrontEnd )
				)
				( attribute "PART_NUMBER" "C95333-002"
					( Origin gFrontEnd )
				)
				( attribute "PHYS_PAGE" "227"
					( Origin gFrontEnd )
				)
				( attribute "ROOM" "VDDQ_KLM_PWR_VR"
					( Origin gFrontEnd )
				)
				( attribute "ROT" "0"
					( Origin gFrontEnd )
				)
				( attribute "SEC" "1"
					( Origin gFrontEnd )
				)
				( attribute "SEC_TYPE" "0805LF"
					( Origin gFrontEnd )
				)
				( attribute "TOLERANCE" "20%"
					( Origin gFrontEnd )
				)
				( attribute "VALUE" "22UF"
					( Origin gFrontEnd )
				)
				( attribute "VER" "1"
					( Origin gFrontEnd )
				)
				( attribute "VOLTAGE" "4V"
					( Units "uVoltage" "V" 1.000000)
					( Origin gFrontEnd )
				)
				( attribute "XY" "(4350,1775)"
					( Origin gFrontEnd )
				)
				( attribute "CHIPS_PART_NAME" "CAP"
					( Origin gPackager )
				)
				( attribute "CDS_PART_NAME" "CAP_0805LF-22UF,4V,20%,X6S,C95A"
					( Origin gPackager )
				)
				( attribute "GROUP" "PWR_MLCC_CAP"
					( Origin gFrontEnd )
				)
				( objectStatus "C1A12" )
			)
			( gate "@baseboard_fab2_lib.baseboard_fab2(sch_1):page227_i44"
				( attribute "CDS_LIB" "mstr_discrete"
					( Origin gPackager )
				)
				( attribute "CDS_LOCATION" "C1A18"
					( Origin gPackager )
				)
				( attribute "CDS_SEC" "1"
					( Origin gPackager )
				)
				( attribute "LOCATION" "C1A18"
					( Origin gFrontEnd )
				)
				( attribute "MATERIAL" "X7R"
					( Origin gFrontEnd )
				)
				( attribute "PACK_TYPE" "0402"
					( Origin gFrontEnd )
				)
				( attribute "PART_NUMBER" "A36096-104"
					( Origin gFrontEnd )
				)
				( attribute "PHYS_PAGE" "227"
					( Origin gFrontEnd )
				)
				( attribute "ROOM" "VDDQ_KLM_PWR_VR"
					( Origin gFrontEnd )
				)
				( attribute "ROT" "2"
					( Origin gFrontEnd )
				)
				( attribute "SEC" "1"
					( Origin gFrontEnd )
				)
				( attribute "SEC_TYPE" "0402"
					( Origin gFrontEnd )
				)
				( attribute "SPOF" "TRUE"
					( Origin gFrontEnd )
				)
				( attribute "TOLERANCE" "10%"
					( Origin gFrontEnd )
				)
				( attribute "VALUE" "0.220UF"
					( Origin gFrontEnd )
				)
				( attribute "VER" "1"
					( Origin gFrontEnd )
				)
				( attribute "VOLTAGE" "16V"
					( Units "uVoltage" "V" 1.000000)
					( Origin gFrontEnd )
				)
				( attribute "XY" "(-825,1925)"
					( Origin gFrontEnd )
				)
				( attribute "CHIPS_PART_NAME" "CAP"
					( Origin gPackager )
				)
				( attribute "CDS_PART_NAME" "CAP_0402-0.220UF,16V,10%,X7R,AA"
					( Origin gPackager )
				)
				( objectStatus "C1A18" )
			)
			( gate "@baseboard_fab2_lib.baseboard_fab2(sch_1):page227_i45"
				( attribute "CDS_LIB" "mstr_discrete"
					( Origin gPackager )
				)
				( attribute "CDS_LOCATION" "C9L11"
					( Origin gPackager )
				)
				( attribute "CDS_SEC" "1"
					( Origin gPackager )
				)
				( attribute "LOCATION" "C9L11"
					( Origin gFrontEnd )
				)
				( attribute "MATERIAL" "X6S"
					( Origin gFrontEnd )
				)
				( attribute "PACK_TYPE" "0805"
					( Origin gFrontEnd )
				)
				( attribute "PART_NUMBER" "C95333-007"
					( Origin gFrontEnd )
				)
				( attribute "PHYS_PAGE" "227"
					( Origin gFrontEnd )
				)
				( attribute "ROOM" "VDDQ_KLM_PWR_VR"
					( Origin gFrontEnd )
				)
				( attribute "ROT" "0"
					( Origin gFrontEnd )
				)
				( attribute "SEC" "1"
					( Origin gFrontEnd )
				)
				( attribute "SEC_TYPE" "0805"
					( Origin gFrontEnd )
				)
				( attribute "TOLERANCE" "10%"
					( Origin gFrontEnd )
				)
				( attribute "VALUE" "10UF"
					( Origin gFrontEnd )
				)
				( attribute "VER" "1"
					( Origin gFrontEnd )
				)
				( attribute "VOLTAGE" "16V"
					( Units "uVoltage" "V" 1.000000)
					( Origin gFrontEnd )
				)
				( attribute "XY" "(-2250,2500)"
					( Origin gFrontEnd )
				)
				( attribute "CHIPS_PART_NAME" "CAP"
					( Origin gPackager )
				)
				( attribute "CDS_PART_NAME" "CAP_0805-10UF,16V,10%,X6S,C953A"
					( Origin gPackager )
				)
				( objectStatus "C9L11" )
			)
			( gate "@baseboard_fab2_lib.baseboard_fab2(sch_1):page227_i46"
				( attribute "CDS_LIB" "mstr_discrete"
					( Origin gPackager )
				)
				( attribute "CDS_LOCATION" "C9L10"
					( Origin gPackager )
				)
				( attribute "CDS_SEC" "1"
					( Origin gPackager )
				)
				( attribute "LOCATION" "C9L10"
					( Origin gFrontEnd )
				)
				( attribute "MATERIAL" "X6S"
					( Origin gFrontEnd )
				)
				( attribute "PACK_TYPE" "0805"
					( Origin gFrontEnd )
				)
				( attribute "PART_NUMBER" "C95333-007"
					( Origin gFrontEnd )
				)
				( attribute "PHYS_PAGE" "227"
					( Origin gFrontEnd )
				)
				( attribute "ROOM" "VDDQ_KLM_PWR_VR"
					( Origin gFrontEnd )
				)
				( attribute "ROT" "0"
					( Origin gFrontEnd )
				)
				( attribute "SEC" "1"
					( Origin gFrontEnd )
				)
				( attribute "SEC_TYPE" "0805"
					( Origin gFrontEnd )
				)
				( attribute "TOLERANCE" "10%"
					( Origin gFrontEnd )
				)
				( attribute "VALUE" "10UF"
					( Origin gFrontEnd )
				)
				( attribute "VER" "1"
					( Origin gFrontEnd )
				)
				( attribute "VOLTAGE" "16V"
					( Units "uVoltage" "V" 1.000000)
					( Origin gFrontEnd )
				)
				( attribute "XY" "(-1975,2500)"
					( Origin gFrontEnd )
				)
				( attribute "CHIPS_PART_NAME" "CAP"
					( Origin gPackager )
				)
				( attribute "CDS_PART_NAME" "CAP_0805-10UF,16V,10%,X6S,C953A"
					( Origin gPackager )
				)
				( objectStatus "C9L10" )
			)
			( gate "@baseboard_fab2_lib.baseboard_fab2(sch_1):page227_i47"
				( attribute "CDS_LIB" "mstr_discrete"
					( Origin gPackager )
				)
				( attribute "CDS_LOCATION" "C9L6"
					( Origin gPackager )
				)
				( attribute "CDS_SEC" "1"
					( Origin gPackager )
				)
				( attribute "LOCATION" "C9L6"
					( Origin gFrontEnd )
				)
				( attribute "MATERIAL" "X6S"
					( Origin gFrontEnd )
				)
				( attribute "PACK_TYPE" "0805"
					( Origin gFrontEnd )
				)
				( attribute "PART_NUMBER" "C95333-007"
					( Origin gFrontEnd )
				)
				( attribute "PHYS_PAGE" "227"
					( Origin gFrontEnd )
				)
				( attribute "ROOM" "VDDQ_KLM_PWR_VR"
					( Origin gFrontEnd )
				)
				( attribute "ROT" "0"
					( Origin gFrontEnd )
				)
				( attribute "SEC" "1"
					( Origin gFrontEnd )
				)
				( attribute "SEC_TYPE" "0805"
					( Origin gFrontEnd )
				)
				( attribute "TOLERANCE" "10%"
					( Origin gFrontEnd )
				)
				( attribute "VALUE" "10UF"
					( Origin gFrontEnd )
				)
				( attribute "VER" "1"
					( Origin gFrontEnd )
				)
				( attribute "VOLTAGE" "16V"
					( Units "uVoltage" "V" 1.000000)
					( Origin gFrontEnd )
				)
				( attribute "XY" "(-1700,2500)"
					( Origin gFrontEnd )
				)
				( attribute "CHIPS_PART_NAME" "CAP"
					( Origin gPackager )
				)
				( attribute "CDS_PART_NAME" "CAP_0805-10UF,16V,10%,X6S,C953A"
					( Origin gPackager )
				)
				( objectStatus "C9L6" )
			)
			( gate "@baseboard_fab2_lib.baseboard_fab2(sch_1):page227_i48"
				( attribute "CDS_LIB" "mstr_discrete"
					( Origin gPackager )
				)
				( attribute "CDS_LOCATION" "C1A19"
					( Origin gPackager )
				)
				( attribute "CDS_SEC" "1"
					( Origin gPackager )
				)
				( attribute "LOCATION" "C1A19"
					( Origin gFrontEnd )
				)
				( attribute "MATERIAL" "X6S"
					( Origin gFrontEnd )
				)
				( attribute "PACK_TYPE" "0402"
					( Origin gFrontEnd )
				)
				( attribute "PART_NUMBER" "D97712-011"
					( Origin gFrontEnd )
				)
				( attribute "PHYS_PAGE" "227"
					( Origin gFrontEnd )
				)
				( attribute "ROOM" "VDDQ_KLM_PWR_VR"
					( Origin gFrontEnd )
				)
				( attribute "ROT" "0"
					( Origin gFrontEnd )
				)
				( attribute "SEC" "1"
					( Origin gFrontEnd )
				)
				( attribute "SEC_TYPE" "0402"
					( Origin gFrontEnd )
				)
				( attribute "TOLERANCE" "10%"
					( Origin gFrontEnd )
				)
				( attribute "VALUE" "1.0UF"
					( Origin gFrontEnd )
				)
				( attribute "VER" "1"
					( Origin gFrontEnd )
				)
				( attribute "VOLTAGE" "16V"
					( Units "uVoltage" "V" 1.000000)
					( Origin gFrontEnd )
				)
				( attribute "XY" "(-1425,2475)"
					( Origin gFrontEnd )
				)
				( attribute "CHIPS_PART_NAME" "CAP"
					( Origin gPackager )
				)
				( attribute "CDS_PART_NAME" "CAP_0402-1.0UF,16V,10%,X6S,D97A"
					( Origin gPackager )
				)
				( objectStatus "C1A19" )
			)
			( gate "@baseboard_fab2_lib.baseboard_fab2(sch_1):page227_i50"
				( attribute "CDS_LIB" "mstr_discrete"
					( Origin gPackager )
				)
				( attribute "CDS_LOCATION" "C1B20"
					( Origin gPackager )
				)
				( attribute "CDS_SEC" "1"
					( Origin gPackager )
				)
				( attribute "LOCATION" "C1B20"
					( Origin gFrontEnd )
				)
				( attribute "MATERIAL" "X6S"
					( Origin gFrontEnd )
				)
				( attribute "PACK_TYPE" "0402"
					( Origin gFrontEnd )
				)
				( attribute "PART_NUMBER" "D97712-011"
					( Origin gFrontEnd )
				)
				( attribute "PHYS_PAGE" "227"
					( Origin gFrontEnd )
				)
				( attribute "ROOM" "VDDQ_KLM_PWR_VR"
					( Origin gFrontEnd )
				)
				( attribute "ROT" "0"
					( Origin gFrontEnd )
				)
				( attribute "SEC" "1"
					( Origin gFrontEnd )
				)
				( attribute "SEC_TYPE" "0402"
					( Origin gFrontEnd )
				)
				( attribute "TOLERANCE" "10%"
					( Origin gFrontEnd )
				)
				( attribute "VALUE" "1.0UF"
					( Origin gFrontEnd )
				)
				( attribute "VER" "1"
					( Origin gFrontEnd )
				)
				( attribute "VOLTAGE" "16V"
					( Units "uVoltage" "V" 1.000000)
					( Origin gFrontEnd )
				)
				( attribute "XY" "(-900,2500)"
					( Origin gFrontEnd )
				)
				( attribute "CHIPS_PART_NAME" "CAP"
					( Origin gPackager )
				)
				( attribute "CDS_PART_NAME" "CAP_0402-1.0UF,16V,10%,X6S,D97A"
					( Origin gPackager )
				)
				( objectStatus "C1B20" )
			)
			( gate "@baseboard_fab2_lib.baseboard_fab2(sch_1):page227_i51"
				( attribute "CDS_LIB" "dev_discrete"
					( Origin gPackager )
				)
				( attribute "CDS_LOCATION" "C1A10"
					( Origin gPackager )
				)
				( attribute "CDS_SEC" "1"
					( Origin gPackager )
				)
				( attribute "LOCATION" "C1A10"
					( Origin gFrontEnd )
				)
				( attribute "MATERIAL" "X7R"
					( Origin gFrontEnd )
				)
				( attribute "PACK_TYPE" "0402V"
					( Origin gFrontEnd )
				)
				( attribute "PART_NUMBER" "A36096-030"
					( Origin gFrontEnd )
				)
				( attribute "PHYS_PAGE" "227"
					( Origin gFrontEnd )
				)
				( attribute "ROOM" "VDDQ_KLM_PWR_VR"
					( Origin gFrontEnd )
				)
				( attribute "ROT" "0"
					( Origin gFrontEnd )
				)
				( attribute "SEC" "1"
					( Origin gFrontEnd )
				)
				( attribute "SEC_TYPE" "0402V"
					( Origin gFrontEnd )
				)
				( attribute "TOLERANCE" "10%"
					( Origin gFrontEnd )
				)
				( attribute "VALUE" "0.1UF"
					( Origin gFrontEnd )
				)
				( attribute "VER" "1"
					( Origin gFrontEnd )
				)
				( attribute "VOLTAGE" "16V"
					( Units "uVoltage" "V" 1.000000)
					( Origin gFrontEnd )
				)
				( attribute "XY" "(-1175,2475)"
					( Origin gFrontEnd )
				)
				( attribute "CHIPS_PART_NAME" "CAP_A"
					( Origin gPackager )
				)
				( attribute "CDS_PART_NAME" "CAP_A_0402V-0.1UF,16V,10%,X7R,A"
					( Origin gPackager )
				)
				( objectStatus "C1A10" )
			)
			( gate "@baseboard_fab2_lib.baseboard_fab2(sch_1):page208_i119"
				( attribute "CDS_LIB" "w_hdl"
					( Origin gPackager )
				)
				( attribute "CDS_LMAN_SYM_OUTLINE" "-50,25,50,-25"
					( Origin gPackager )
				)
				( attribute "LOCATION" "C1D5"
					( Origin gFrontEnd )
				)
				( attribute "PACK_TYPE" "SMD-BCG6"
					( Origin gFrontEnd )
				)
				( attribute "PART_NUMBER" "78.10523.8FL"
					( Origin gFrontEnd )
				)
				( attribute "PHYS_PAGE" "208"
					( Origin gFrontEnd )
				)
				( attribute "ROT" "0"
					( Origin gFrontEnd )
				)
				( attribute "SEC" "1"
					( Origin gFrontEnd )
				)
				( attribute "SEC_TYPE" "SMD-BCG6"
					( Origin gFrontEnd )
				)
				( attribute "VALUE" "SC1U10V2KX-4-GP"
					( Origin gFrontEnd )
				)
				( attribute "VER" "1"
					( Origin gFrontEnd )
				)
				( attribute "XY" "(-5200,1550)"
					( Origin gFrontEnd )
				)
				( attribute "CHIPS_PART_NAME" "SC1U10V2KX-4-GP"
					( Origin gPackager )
				)
				( attribute "CDS_PART_NAME" "SC1U10V2KX-4-GP_SMD-BCG6-SC1U1A"
					( Origin gPackager )
				)
				( attribute "CDS_LOCATION" "C1D5"
					( Origin gPackager )
				)
				( attribute "CDS_SEC" "1"
					( Origin gPackager )
				)
				( attribute "ATTRIBUTE" "1UF"
					( Origin gFrontEnd )
				)
				( attribute "PACK_SIZE" "0402"
					( Origin gFrontEnd )
				)
				( attribute "RATED" "10V"
					( Origin gFrontEnd )
				)
				( attribute "TOLERANCE" "10%"
					( Origin gFrontEnd )
				)
				( objectStatus "C1D5" )
			)
			( gate "@baseboard_fab2_lib.baseboard_fab2(sch_1):page227_i54"
				( attribute "CDS_LIB" "mstr_discrete"
					( Origin gPackager )
				)
				( attribute "CDS_LOCATION" "C1B21"
					( Origin gPackager )
				)
				( attribute "CDS_SEC" "1"
					( Origin gPackager )
				)
				( attribute "LOCATION" "C1B21"
					( Origin gFrontEnd )
				)
				( attribute "MATERIAL" "X7R"
					( Origin gFrontEnd )
				)
				( attribute "PACK_TYPE" "0402"
					( Origin gFrontEnd )
				)
				( attribute "PART_NUMBER" "A36096-155"
					( Origin gFrontEnd )
				)
				( attribute "PHYS_PAGE" "227"
					( Origin gFrontEnd )
				)
				( attribute "ROOM" "VDDQ_KLM_PWR_VR"
					( Origin gFrontEnd )
				)
				( attribute "ROT" "0"
					( Origin gFrontEnd )
				)
				( attribute "SEC" "1"
					( Origin gFrontEnd )
				)
				( attribute "SEC_TYPE" "0402"
					( Origin gFrontEnd )
				)
				( attribute "TOLERANCE" "10%"
					( Origin gFrontEnd )
				)
				( attribute "VALUE" "0.22UF"
					( Origin gFrontEnd )
				)
				( attribute "VER" "1"
					( Origin gFrontEnd )
				)
				( attribute "VOLTAGE" "16V"
					( Units "uVoltage" "V" 1.000000)
					( Origin gFrontEnd )
				)
				( attribute "XY" "(-100,2475)"
					( Origin gFrontEnd )
				)
				( attribute "CHIPS_PART_NAME" "CAP"
					( Origin gPackager )
				)
				( attribute "CDS_PART_NAME" "CAP_0402-0.22UF,16V,10%,X7R,A3A"
					( Origin gPackager )
				)
				( objectStatus "C1B21" )
			)
			( gate "@baseboard_fab2_lib.baseboard_fab2(sch_1):page212_i142"
				( attribute "CDS_LIB" "w_hdl"
					( Origin gPackager )
				)
				( attribute "CDS_LMAN_SYM_OUTLINE" "-75,100,75,-100"
					( Origin gPackager )
				)
				( attribute "LOCATION" "L7C1"
					( Origin gFrontEnd )
				)
				( attribute "PACK_TYPE" "DISCRET-G8"
					( Origin gFrontEnd )
				)
				( attribute "PART_NUMBER" "068.1011N.M001"
					( Origin gFrontEnd )
				)
				( attribute "PHYS_PAGE" "212"
					( Origin gFrontEnd )
				)
				( attribute "ROT" "1"
					( Origin gFrontEnd )
				)
				( attribute "SEC" "1"
					( Origin gFrontEnd )
				)
				( attribute "SEC_TYPE" "DISCRET-G8"
					( Origin gFrontEnd )
				)
				( attribute "VALUE" "IND-100NH-35-GP"
					( Origin gFrontEnd )
				)
				( attribute "VER" "1"
					( Origin gFrontEnd )
				)
				( attribute "XY" "(225,2475)"
					( Origin gFrontEnd )
				)
				( attribute "CHIPS_PART_NAME" "IND-100NH-35-GP"
					( Origin gPackager )
				)
				( attribute "CDS_PART_NAME" "IND-100NH-35-GP_DISCRET-G8-INDA"
					( Origin gPackager )
				)
				( attribute "CDS_LOCATION" "L7C1"
					( Origin gPackager )
				)
				( attribute "CDS_SEC" "1"
					( Origin gPackager )
				)
				( attribute "ATTRIBUTE" "100NH"
					( Origin gFrontEnd )
				)
				( attribute "PACK_SIZE" "DCR=0.16MOHM"
					( Origin gFrontEnd )
				)
				( attribute "RATED" "ISAT=16A@25C"
					( Origin gFrontEnd )
				)
				( attribute "TYPE" "IRMS=29A@DELTA_T<45C"
					( Origin gFrontEnd )
				)
				( objectStatus "L7C1" )
			)
			( gate "@baseboard_fab2_lib.baseboard_fab2(sch_1):page212_i141"
				( attribute "CDS_LIB" "w_hdl"
					( Origin gPackager )
				)
				( attribute "CDS_LMAN_SYM_OUTLINE" "-75,100,75,-100"
					( Origin gPackager )
				)
				( attribute "LOCATION" "L7C2"
					( Origin gFrontEnd )
				)
				( attribute "PACK_TYPE" "DISCRET-GA1"
					( Origin gFrontEnd )
				)
				( attribute "PART_NUMBER" "068.1512N.M001"
					( Origin gFrontEnd )
				)
				( attribute "PHYS_PAGE" "212"
					( Origin gFrontEnd )
				)
				( attribute "ROT" "1"
					( Origin gFrontEnd )
				)
				( attribute "SEC" "1"
					( Origin gFrontEnd )
				)
				( attribute "SEC_TYPE" "DISCRET-GA1"
					( Origin gFrontEnd )
				)
				( attribute "VALUE" "IND-150NH-56-GP"
					( Origin gFrontEnd )
				)
				( attribute "VER" "1"
					( Origin gFrontEnd )
				)
				( attribute "XY" "(3075,3675)"
					( Origin gFrontEnd )
				)
				( attribute "CHIPS_PART_NAME" "IND-150NH-56-GP"
					( Origin gPackager )
				)
				( attribute "CDS_PART_NAME" "IND-150NH-56-GP_DISCRET-GA1-INA"
					( Origin gPackager )
				)
				( attribute "CDS_LOCATION" "L7C2"
					( Origin gPackager )
				)
				( attribute "CDS_SEC" "1"
					( Origin gPackager )
				)
				( attribute "ATTRIBUTE" "150NH"
					( Origin gFrontEnd )
				)
				( attribute "PACK_SIZE" "DCR=0.17MOHM"
					( Origin gFrontEnd )
				)
				( attribute "RATED" "ISAT=75A@25C"
					( Origin gFrontEnd )
				)
				( attribute "TYPE" "IRMS=66A@DELTA_T<40C"
					( Origin gFrontEnd )
				)
				( objectStatus "L7C2" )
			)
			( gate "@baseboard_fab2_lib.baseboard_fab2(sch_1):page227_i68"
				( attribute "BOM_COST" "VDDQ_KLM_PWR_VR"
					( Origin gFrontEnd )
				)
				( attribute "CDS_LIB" "mstr_discrete"
					( Origin gPackager )
				)
				( attribute "CDS_LOCATION" "C1A1"
					( Origin gPackager )
				)
				( attribute "CDS_SEC" "1"
					( Origin gPackager )
				)
				( attribute "LOCATION" "C1A1"
					( Origin gFrontEnd )
				)
				( attribute "MATERIAL" "X6S"
					( Origin gFrontEnd )
				)
				( attribute "PACK_TYPE" "0805LF"
					( Origin gFrontEnd )
				)
				( attribute "PART_NUMBER" "C95333-002"
					( Origin gFrontEnd )
				)
				( attribute "PHYS_PAGE" "227"
					( Origin gFrontEnd )
				)
				( attribute "ROOM" "VDDQ_KLM_PWR_VR"
					( Origin gFrontEnd )
				)
				( attribute "ROT" "0"
					( Origin gFrontEnd )
				)
				( attribute "SEC" "1"
					( Origin gFrontEnd )
				)
				( attribute "SEC_TYPE" "0805LF"
					( Origin gFrontEnd )
				)
				( attribute "TOLERANCE" "20%"
					( Origin gFrontEnd )
				)
				( attribute "VALUE" "22UF"
					( Origin gFrontEnd )
				)
				( attribute "VER" "1"
					( Origin gFrontEnd )
				)
				( attribute "VOLTAGE" "4V"
					( Units "uVoltage" "V" 1.000000)
					( Origin gFrontEnd )
				)
				( attribute "XY" "(4375,-475)"
					( Origin gFrontEnd )
				)
				( attribute "CHIPS_PART_NAME" "CAP"
					( Origin gPackager )
				)
				( attribute "CDS_PART_NAME" "CAP_0805LF-22UF,4V,20%,X6S,C95A"
					( Origin gPackager )
				)
				( attribute "GROUP" "PWR_MLCC_CAP"
					( Origin gFrontEnd )
				)
				( attribute "BOM_SS" "NOPOP"
					( Origin gFrontEnd )
				)
				( objectStatus "C1A1" )
			)
			( gate "@baseboard_fab2_lib.baseboard_fab2(sch_1):page227_i72"
				( attribute "CDS_LIB" "mstr_discrete"
					( Origin gPackager )
				)
				( attribute "CDS_LOCATION" "C1A13"
					( Origin gPackager )
				)
				( attribute "CDS_SEC" "1"
					( Origin gPackager )
				)
				( attribute "LOCATION" "C1A13"
					( Origin gFrontEnd )
				)
				( attribute "MATERIAL" "X7R"
					( Origin gFrontEnd )
				)
				( attribute "PACK_TYPE" "0402"
					( Origin gFrontEnd )
				)
				( attribute "PART_NUMBER" "A36096-155"
					( Origin gFrontEnd )
				)
				( attribute "PHYS_PAGE" "227"
					( Origin gFrontEnd )
				)
				( attribute "ROOM" "VDDQ_KLM_PWR_VR"
					( Origin gFrontEnd )
				)
				( attribute "ROT" "0"
					( Origin gFrontEnd )
				)
				( attribute "SEC" "1"
					( Origin gFrontEnd )
				)
				( attribute "SEC_TYPE" "0402"
					( Origin gFrontEnd )
				)
				( attribute "TOLERANCE" "10%"
					( Origin gFrontEnd )
				)
				( attribute "VALUE" "0.22UF"
					( Origin gFrontEnd )
				)
				( attribute "VER" "1"
					( Origin gFrontEnd )
				)
				( attribute "VOLTAGE" "16V"
					( Units "uVoltage" "V" 1.000000)
					( Origin gFrontEnd )
				)
				( attribute "XY" "(-75,250)"
					( Origin gFrontEnd )
				)
				( attribute "CHIPS_PART_NAME" "CAP"
					( Origin gPackager )
				)
				( attribute "CDS_PART_NAME" "CAP_0402-0.22UF,16V,10%,X7R,A3A"
					( Origin gPackager )
				)
				( attribute "BOM_SS" "NOPOP"
					( Origin gFrontEnd )
				)
				( objectStatus "C1A13" )
			)
			( gate "@baseboard_fab2_lib.baseboard_fab2(sch_1):page210_i73"
				( attribute "CDS_LIB" "w_hdl"
					( Origin gPackager )
				)
				( attribute "CDS_LMAN_SYM_OUTLINE" "-50,25,50,-25"
					( Origin gPackager )
				)
				( attribute "LOCATION" "C1C3"
					( Origin gFrontEnd )
				)
				( attribute "PACK_TYPE" "SMD-BCG6"
					( Origin gFrontEnd )
				)
				( attribute "PART_NUMBER" "78.10523.8FL"
					( Origin gFrontEnd )
				)
				( attribute "PHYS_PAGE" "210"
					( Origin gFrontEnd )
				)
				( attribute "ROT" "0"
					( Origin gFrontEnd )
				)
				( attribute "SEC" "1"
					( Origin gFrontEnd )
				)
				( attribute "SEC_TYPE" "SMD-BCG6"
					( Origin gFrontEnd )
				)
				( attribute "VALUE" "SC1U10V2KX-4-GP"
					( Origin gFrontEnd )
				)
				( attribute "VER" "1"
					( Origin gFrontEnd )
				)
				( attribute "XY" "(-5475,3850)"
					( Origin gFrontEnd )
				)
				( attribute "CHIPS_PART_NAME" "SC1U10V2KX-4-GP"
					( Origin gPackager )
				)
				( attribute "CDS_PART_NAME" "SC1U10V2KX-4-GP_SMD-BCG6-SC1U1A"
					( Origin gPackager )
				)
				( attribute "CDS_LOCATION" "C1C3"
					( Origin gPackager )
				)
				( attribute "CDS_SEC" "1"
					( Origin gPackager )
				)
				( attribute "ATTRIBUTE" "1UF"
					( Origin gFrontEnd )
				)
				( attribute "PACK_SIZE" "0402"
					( Origin gFrontEnd )
				)
				( attribute "RATED" "10V"
					( Origin gFrontEnd )
				)
				( attribute "TOLERANCE" "10%"
					( Origin gFrontEnd )
				)
				( objectStatus "C1C3" )
			)
			( gate "@baseboard_fab2_lib.baseboard_fab2(sch_1):page227_i75"
				( attribute "CDS_LIB" "mstr_discrete"
					( Origin gPackager )
				)
				( attribute "CDS_LOCATION" "C1A8"
					( Origin gPackager )
				)
				( attribute "CDS_SEC" "1"
					( Origin gPackager )
				)
				( attribute "LOCATION" "C1A8"
					( Origin gFrontEnd )
				)
				( attribute "MATERIAL" "X7R"
					( Origin gFrontEnd )
				)
				( attribute "PACK_TYPE" "0402"
					( Origin gFrontEnd )
				)
				( attribute "PART_NUMBER" "A36096-104"
					( Origin gFrontEnd )
				)
				( attribute "PHYS_PAGE" "227"
					( Origin gFrontEnd )
				)
				( attribute "ROOM" "VDDQ_KLM_PWR_VR"
					( Origin gFrontEnd )
				)
				( attribute "ROT" "2"
					( Origin gFrontEnd )
				)
				( attribute "SEC" "1"
					( Origin gFrontEnd )
				)
				( attribute "SEC_TYPE" "0402"
					( Origin gFrontEnd )
				)
				( attribute "SPOF" "TRUE"
					( Origin gFrontEnd )
				)
				( attribute "TOLERANCE" "10%"
					( Origin gFrontEnd )
				)
				( attribute "VALUE" "0.220UF"
					( Origin gFrontEnd )
				)
				( attribute "VER" "1"
					( Origin gFrontEnd )
				)
				( attribute "VOLTAGE" "16V"
					( Units "uVoltage" "V" 1.000000)
					( Origin gFrontEnd )
				)
				( attribute "XY" "(-775,-350)"
					( Origin gFrontEnd )
				)
				( attribute "CHIPS_PART_NAME" "CAP"
					( Origin gPackager )
				)
				( attribute "CDS_PART_NAME" "CAP_0402-0.220UF,16V,10%,X7R,AA"
					( Origin gPackager )
				)
				( attribute "BOM_SS" "NOPOP"
					( Origin gFrontEnd )
				)
				( objectStatus "C1A8" )
			)
			( gate "@baseboard_fab2_lib.baseboard_fab2(sch_1):page227_i77"
				( attribute "CDS_LIB" "mstr_discrete"
					( Origin gPackager )
				)
				( attribute "CDS_LOCATION" "C1A6"
					( Origin gPackager )
				)
				( attribute "CDS_SEC" "1"
					( Origin gPackager )
				)
				( attribute "LOCATION" "C1A6"
					( Origin gFrontEnd )
				)
				( attribute "MATERIAL" "X6S"
					( Origin gFrontEnd )
				)
				( attribute "PACK_TYPE" "0402"
					( Origin gFrontEnd )
				)
				( attribute "PART_NUMBER" "D97712-011"
					( Origin gFrontEnd )
				)
				( attribute "PHYS_PAGE" "227"
					( Origin gFrontEnd )
				)
				( attribute "ROOM" "VDDQ_KLM_PWR_VR"
					( Origin gFrontEnd )
				)
				( attribute "ROT" "0"
					( Origin gFrontEnd )
				)
				( attribute "SEC" "1"
					( Origin gFrontEnd )
				)
				( attribute "SEC_TYPE" "0402"
					( Origin gFrontEnd )
				)
				( attribute "TOLERANCE" "10%"
					( Origin gFrontEnd )
				)
				( attribute "VALUE" "1.0UF"
					( Origin gFrontEnd )
				)
				( attribute "VER" "1"
					( Origin gFrontEnd )
				)
				( attribute "VOLTAGE" "16V"
					( Units "uVoltage" "V" 1.000000)
					( Origin gFrontEnd )
				)
				( attribute "XY" "(-825,250)"
					( Origin gFrontEnd )
				)
				( attribute "CHIPS_PART_NAME" "CAP"
					( Origin gPackager )
				)
				( attribute "CDS_PART_NAME" "CAP_0402-1.0UF,16V,10%,X6S,D97A"
					( Origin gPackager )
				)
				( attribute "BOM_SS" "NOPOP"
					( Origin gFrontEnd )
				)
				( objectStatus "C1A6" )
			)
			( gate "@baseboard_fab2_lib.baseboard_fab2(sch_1):page227_i78"
				( attribute "CDS_LIB" "dev_discrete"
					( Origin gPackager )
				)
				( attribute "CDS_LOCATION" "C1A20"
					( Origin gPackager )
				)
				( attribute "CDS_SEC" "1"
					( Origin gPackager )
				)
				( attribute "LOCATION" "C1A20"
					( Origin gFrontEnd )
				)
				( attribute "MATERIAL" "X7R"
					( Origin gFrontEnd )
				)
				( attribute "PACK_TYPE" "0402V"
					( Origin gFrontEnd )
				)
				( attribute "PART_NUMBER" "A36096-030"
					( Origin gFrontEnd )
				)
				( attribute "PHYS_PAGE" "227"
					( Origin gFrontEnd )
				)
				( attribute "ROOM" "VDDQ_KLM_PWR_VR"
					( Origin gFrontEnd )
				)
				( attribute "ROT" "0"
					( Origin gFrontEnd )
				)
				( attribute "SEC" "1"
					( Origin gFrontEnd )
				)
				( attribute "SEC_TYPE" "0402V"
					( Origin gFrontEnd )
				)
				( attribute "TOLERANCE" "10%"
					( Origin gFrontEnd )
				)
				( attribute "VALUE" "0.1UF"
					( Origin gFrontEnd )
				)
				( attribute "VER" "1"
					( Origin gFrontEnd )
				)
				( attribute "VOLTAGE" "16V"
					( Units "uVoltage" "V" 1.000000)
					( Origin gFrontEnd )
				)
				( attribute "XY" "(-1075,250)"
					( Origin gFrontEnd )
				)
				( attribute "CHIPS_PART_NAME" "CAP_A"
					( Origin gPackager )
				)
				( attribute "CDS_PART_NAME" "CAP_A_0402V-0.1UF,16V,10%,X7R,A"
					( Origin gPackager )
				)
				( objectStatus "C1A20" )
			)
			( gate "@baseboard_fab2_lib.baseboard_fab2(sch_1):page227_i79"
				( attribute "CDS_LIB" "mstr_discrete"
					( Origin gPackager )
				)
				( attribute "CDS_LOCATION" "C1A9"
					( Origin gPackager )
				)
				( attribute "CDS_SEC" "1"
					( Origin gPackager )
				)
				( attribute "LOCATION" "C1A9"
					( Origin gFrontEnd )
				)
				( attribute "MATERIAL" "X6S"
					( Origin gFrontEnd )
				)
				( attribute "PACK_TYPE" "0402"
					( Origin gFrontEnd )
				)
				( attribute "PART_NUMBER" "D97712-011"
					( Origin gFrontEnd )
				)
				( attribute "PHYS_PAGE" "227"
					( Origin gFrontEnd )
				)
				( attribute "ROOM" "VDDQ_KLM_PWR_VR"
					( Origin gFrontEnd )
				)
				( attribute "ROT" "0"
					( Origin gFrontEnd )
				)
				( attribute "SEC" "1"
					( Origin gFrontEnd )
				)
				( attribute "SEC_TYPE" "0402"
					( Origin gFrontEnd )
				)
				( attribute "TOLERANCE" "10%"
					( Origin gFrontEnd )
				)
				( attribute "VALUE" "1.0UF"
					( Origin gFrontEnd )
				)
				( attribute "VER" "1"
					( Origin gFrontEnd )
				)
				( attribute "VOLTAGE" "16V"
					( Units "uVoltage" "V" 1.000000)
					( Origin gFrontEnd )
				)
				( attribute "XY" "(-1350,250)"
					( Origin gFrontEnd )
				)
				( attribute "CHIPS_PART_NAME" "CAP"
					( Origin gPackager )
				)
				( attribute "CDS_PART_NAME" "CAP_0402-1.0UF,16V,10%,X6S,D97A"
					( Origin gPackager )
				)
				( objectStatus "C1A9" )
			)
			( gate "@baseboard_fab2_lib.baseboard_fab2(sch_1):page227_i80"
				( attribute "CDS_LIB" "mstr_discrete"
					( Origin gPackager )
				)
				( attribute "CDS_LOCATION" "C9L5"
					( Origin gPackager )
				)
				( attribute "CDS_SEC" "1"
					( Origin gPackager )
				)
				( attribute "LOCATION" "C9L5"
					( Origin gFrontEnd )
				)
				( attribute "MATERIAL" "X6S"
					( Origin gFrontEnd )
				)
				( attribute "PACK_TYPE" "0805"
					( Origin gFrontEnd )
				)
				( attribute "PART_NUMBER" "C95333-007"
					( Origin gFrontEnd )
				)
				( attribute "PHYS_PAGE" "227"
					( Origin gFrontEnd )
				)
				( attribute "ROOM" "VDDQ_KLM_PWR_VR"
					( Origin gFrontEnd )
				)
				( attribute "ROT" "0"
					( Origin gFrontEnd )
				)
				( attribute "SEC" "1"
					( Origin gFrontEnd )
				)
				( attribute "SEC_TYPE" "0805"
					( Origin gFrontEnd )
				)
				( attribute "TOLERANCE" "10%"
					( Origin gFrontEnd )
				)
				( attribute "VALUE" "10UF"
					( Origin gFrontEnd )
				)
				( attribute "VER" "1"
					( Origin gFrontEnd )
				)
				( attribute "VOLTAGE" "16V"
					( Units "uVoltage" "V" 1.000000)
					( Origin gFrontEnd )
				)
				( attribute "XY" "(-1625,250)"
					( Origin gFrontEnd )
				)
				( attribute "CHIPS_PART_NAME" "CAP"
					( Origin gPackager )
				)
				( attribute "CDS_PART_NAME" "CAP_0805-10UF,16V,10%,X6S,C953A"
					( Origin gPackager )
				)
				( objectStatus "C9L5" )
			)
			( gate "@baseboard_fab2_lib.baseboard_fab2(sch_1):page227_i81"
				( attribute "CDS_LIB" "mstr_discrete"
					( Origin gPackager )
				)
				( attribute "CDS_LOCATION" "C9L13"
					( Origin gPackager )
				)
				( attribute "CDS_SEC" "1"
					( Origin gPackager )
				)
				( attribute "LOCATION" "C9L13"
					( Origin gFrontEnd )
				)
				( attribute "MATERIAL" "X6S"
					( Origin gFrontEnd )
				)
				( attribute "PACK_TYPE" "0805"
					( Origin gFrontEnd )
				)
				( attribute "PART_NUMBER" "C95333-007"
					( Origin gFrontEnd )
				)
				( attribute "PHYS_PAGE" "227"
					( Origin gFrontEnd )
				)
				( attribute "ROOM" "VDDQ_KLM_PWR_VR"
					( Origin gFrontEnd )
				)
				( attribute "ROT" "0"
					( Origin gFrontEnd )
				)
				( attribute "SEC" "1"
					( Origin gFrontEnd )
				)
				( attribute "SEC_TYPE" "0805"
					( Origin gFrontEnd )
				)
				( attribute "TOLERANCE" "10%"
					( Origin gFrontEnd )
				)
				( attribute "VALUE" "10UF"
					( Origin gFrontEnd )
				)
				( attribute "VER" "1"
					( Origin gFrontEnd )
				)
				( attribute "VOLTAGE" "16V"
					( Units "uVoltage" "V" 1.000000)
					( Origin gFrontEnd )
				)
				( attribute "XY" "(-1900,250)"
					( Origin gFrontEnd )
				)
				( attribute "CHIPS_PART_NAME" "CAP"
					( Origin gPackager )
				)
				( attribute "CDS_PART_NAME" "CAP_0805-10UF,16V,10%,X6S,C953A"
					( Origin gPackager )
				)
				( objectStatus "C9L13" )
			)
			( gate "@baseboard_fab2_lib.baseboard_fab2(sch_1):page227_i84"
				( attribute "CDS_LIB" "mstr_discrete"
					( Origin gPackager )
				)
				( attribute "CDS_LOCATION" "C9L14"
					( Origin gPackager )
				)
				( attribute "CDS_SEC" "1"
					( Origin gPackager )
				)
				( attribute "LOCATION" "C9L14"
					( Origin gFrontEnd )
				)
				( attribute "MATERIAL" "X6S"
					( Origin gFrontEnd )
				)
				( attribute "PACK_TYPE" "0805"
					( Origin gFrontEnd )
				)
				( attribute "PART_NUMBER" "C95333-007"
					( Origin gFrontEnd )
				)
				( attribute "PHYS_PAGE" "227"
					( Origin gFrontEnd )
				)
				( attribute "ROOM" "VDDQ_KLM_PWR_VR"
					( Origin gFrontEnd )
				)
				( attribute "ROT" "0"
					( Origin gFrontEnd )
				)
				( attribute "SEC" "1"
					( Origin gFrontEnd )
				)
				( attribute "SEC_TYPE" "0805"
					( Origin gFrontEnd )
				)
				( attribute "TOLERANCE" "10%"
					( Origin gFrontEnd )
				)
				( attribute "VALUE" "10UF"
					( Origin gFrontEnd )
				)
				( attribute "VER" "1"
					( Origin gFrontEnd )
				)
				( attribute "VOLTAGE" "16V"
					( Units "uVoltage" "V" 1.000000)
					( Origin gFrontEnd )
				)
				( attribute "XY" "(-2175,250)"
					( Origin gFrontEnd )
				)
				( attribute "CHIPS_PART_NAME" "CAP"
					( Origin gPackager )
				)
				( attribute "CDS_PART_NAME" "CAP_0805-10UF,16V,10%,X6S,C953A"
					( Origin gPackager )
				)
				( objectStatus "C9L14" )
			)
			( gate "@baseboard_fab2_lib.baseboard_fab2(sch_1):page227_i101"
				( attribute "CDS_LIB" "mstr_discrete"
					( Origin gPackager )
				)
				( attribute "CDS_LOCATION" "EU1A2"
					( Origin gPackager )
				)
				( attribute "CDS_SEC" "1"
					( Origin gPackager )
				)
				( attribute "LOCATION" "EU1A2"
					( Origin gFrontEnd )
				)
				( attribute "MATERIAL" "IC"
					( Origin gFrontEnd )
				)
				( attribute "NO_XNET_CONNECTION" "1"
					( Origin gFrontEnd )
				)
				( attribute "PACK_TYPE" "SM"
					( Origin gFrontEnd )
				)
				( attribute "PART_NUMBER" "H73688-001"
					( Origin gFrontEnd )
				)
				( attribute "PHYS_PAGE" "227"
					( Origin gFrontEnd )
				)
				( attribute "ROT" "0"
					( Origin gFrontEnd )
				)
				( attribute "SEC" "1"
					( Origin gFrontEnd )
				)
				( attribute "SEC_TYPE" "SM"
					( Origin gFrontEnd )
				)
				( attribute "VALUE" "IR35411"
					( Origin gFrontEnd )
				)
				( attribute "VER" "1"
					( Origin gFrontEnd )
				)
				( attribute "XY" "(1825,2225)"
					( Origin gFrontEnd )
				)
				( attribute "CHIPS_PART_NAME" "IR354XX"
					( Origin gPackager )
				)
				( attribute "CDS_PART_NAME" "IR354XX_SM-IR35411,IC,H73688-0A"
					( Origin gPackager )
				)
				( objectStatus "EU1A2" )
			)
			( gate "@baseboard_fab2_lib.baseboard_fab2(sch_1):page227_i102"
				( attribute "CDS_LIB" "mstr_discrete"
					( Origin gPackager )
				)
				( attribute "CDS_LOCATION" "EU1A1"
					( Origin gPackager )
				)
				( attribute "CDS_SEC" "1"
					( Origin gPackager )
				)
				( attribute "LOCATION" "EU1A1"
					( Origin gFrontEnd )
				)
				( attribute "MATERIAL" "IC"
					( Origin gFrontEnd )
				)
				( attribute "NO_XNET_CONNECTION" "1"
					( Origin gFrontEnd )
				)
				( attribute "PACK_TYPE" "SM"
					( Origin gFrontEnd )
				)
				( attribute "PART_NUMBER" "H73688-001"
					( Origin gFrontEnd )
				)
				( attribute "PHYS_PAGE" "227"
					( Origin gFrontEnd )
				)
				( attribute "ROT" "0"
					( Origin gFrontEnd )
				)
				( attribute "SEC" "1"
					( Origin gFrontEnd )
				)
				( attribute "SEC_TYPE" "SM"
					( Origin gFrontEnd )
				)
				( attribute "VALUE" "IR35411"
					( Origin gFrontEnd )
				)
				( attribute "VER" "1"
					( Origin gFrontEnd )
				)
				( attribute "XY" "(1825,-25)"
					( Origin gFrontEnd )
				)
				( attribute "CHIPS_PART_NAME" "IR354XX"
					( Origin gPackager )
				)
				( attribute "CDS_PART_NAME" "IR354XX_SM-IR35411,IC,H73688-0A"
					( Origin gPackager )
				)
				( attribute "BOM_SS" "NOPOP"
					( Origin gFrontEnd )
				)
				( objectStatus "EU1A1" )
			)
			( gate "@baseboard_fab2_lib.baseboard_fab2(sch_1):page227_i103"
				( attribute "CDS_LIB" "mstr_discrete"
					( Origin gPackager )
				)
				( attribute "CDS_LOCATION" "R1A3"
					( Origin gPackager )
				)
				( attribute "CDS_SEC" "1"
					( Origin gPackager )
				)
				( attribute "LOCATION" "R1A3"
					( Origin gFrontEnd )
				)
				( attribute "MATERIAL" "EMPTY"
					( Origin gFrontEnd )
				)
				( attribute "PACK_TYPE" "0402"
					( Origin gFrontEnd )
				)
				( attribute "PART_NUMBER" "G21796-187"
					( Origin gFrontEnd )
				)
				( attribute "PHYS_PAGE" "227"
					( Origin gFrontEnd )
				)
				( attribute "ROT" "0"
					( Origin gFrontEnd )
				)
				( attribute "SEC" "1"
					( Origin gFrontEnd )
				)
				( attribute "SEC_TYPE" "0402"
					( Origin gFrontEnd )
				)
				( attribute "TOLERANCE" "1%"
					( Origin gFrontEnd )
				)
				( attribute "VALUE" "68.1K"
					( Origin gFrontEnd )
				)
				( attribute "VER" "2"
					( Origin gFrontEnd )
				)
				( attribute "WATTAGE" "1/16W"
					( Origin gFrontEnd )
				)
				( attribute "XY" "(4650,2400)"
					( Origin gFrontEnd )
				)
				( attribute "CHIPS_PART_NAME" "RES"
					( Origin gPackager )
				)
				( attribute "CDS_PART_NAME" "RES_0402-68.1K,1%,1/16W,EMPTY,A"
					( Origin gPackager )
				)
				( objectStatus "R1A3" )
			)
			( gate "@baseboard_fab2_lib.baseboard_fab2(sch_1):page227_i105"
				( attribute "CDS_LIB" "mstr_discrete"
					( Origin gPackager )
				)
				( attribute "CDS_LOCATION" "R1A2"
					( Origin gPackager )
				)
				( attribute "CDS_SEC" "1"
					( Origin gPackager )
				)
				( attribute "LOCATION" "R1A2"
					( Origin gFrontEnd )
				)
				( attribute "MATERIAL" "EMPTY"
					( Origin gFrontEnd )
				)
				( attribute "PACK_TYPE" "0402"
					( Origin gFrontEnd )
				)
				( attribute "PART_NUMBER" "G21796-187"
					( Origin gFrontEnd )
				)
				( attribute "PHYS_PAGE" "227"
					( Origin gFrontEnd )
				)
				( attribute "ROT" "0"
					( Origin gFrontEnd )
				)
				( attribute "SEC" "1"
					( Origin gFrontEnd )
				)
				( attribute "SEC_TYPE" "0402"
					( Origin gFrontEnd )
				)
				( attribute "TOLERANCE" "1%"
					( Origin gFrontEnd )
				)
				( attribute "VALUE" "68.1K"
					( Origin gFrontEnd )
				)
				( attribute "VER" "2"
					( Origin gFrontEnd )
				)
				( attribute "WATTAGE" "1/16W"
					( Origin gFrontEnd )
				)
				( attribute "XY" "(4650,150)"
					( Origin gFrontEnd )
				)
				( attribute "CHIPS_PART_NAME" "RES"
					( Origin gPackager )
				)
				( attribute "CDS_PART_NAME" "RES_0402-68.1K,1%,1/16W,EMPTY,A"
					( Origin gPackager )
				)
				( attribute "BOM_SS" "NOPOP"
					( Origin gFrontEnd )
				)
				( objectStatus "R1A2" )
			)
			( gate "@baseboard_fab2_lib.baseboard_fab2(sch_1):page228_i58"
				( attribute "BOM_COST" "MEM_VRD_PVPP_AB"
					( Origin gFrontEnd )
				)
				( attribute "CDS_LIB" "mstr_discrete"
					( Origin gPackager )
				)
				( attribute "CDS_LOCATION" "R1A1"
					( Origin gPackager )
				)
				( attribute "CDS_SEC" "1"
					( Origin gPackager )
				)
				( attribute "LOCATION" "R1A1"
					( Origin gFrontEnd )
				)
				( attribute "MATERIAL" "CHIP"
					( Origin gFrontEnd )
				)
				( attribute "PACK_TYPE" "0603"
					( Origin gFrontEnd )
				)
				( attribute "PART_NUMBER" "G22026-003"
					( Origin gFrontEnd )
				)
				( attribute "PHYS_PAGE" "228"
					( Origin gFrontEnd )
				)
				( attribute "ROOM" "VDDQ_KLM_PWR_VR"
					( Origin gFrontEnd )
				)
				( attribute "ROT" "0"
					( Origin gFrontEnd )
				)
				( attribute "SEC" "1"
					( Origin gPackager )
				)
				( attribute "TOLERANCE" "1%"
					( Origin gFrontEnd )
				)
				( attribute "VALUE" "120.0"
					( Origin gFrontEnd )
				)
				( attribute "VER" "2"
					( Origin gFrontEnd )
				)
				( attribute "WATTAGE" "1/10W"
					( Origin gFrontEnd )
				)
				( attribute "XY" "(4100,-500)"
					( Origin gFrontEnd )
				)
				( attribute "CHIPS_PART_NAME" "RES"
					( Origin gPackager )
				)
				( attribute "CDS_PART_NAME" "RES_0603-120.0,1%,1/10W,CHIP,GA"
					( Origin gPackager )
				)
				( objectStatus "R1A1" )
			)
			( gate "@baseboard_fab2_lib.baseboard_fab2(sch_1):page228_i74"
				( attribute "CDS_LIB" "mstr_discrete"
					( Origin gPackager )
				)
				( attribute "CDS_LOCATION" "R7L2"
					( Origin gPackager )
				)
				( attribute "CDS_SEC" "1"
					( Origin gPackager )
				)
				( attribute "LOCATION" "R7L2"
					( Origin gFrontEnd )
				)
				( attribute "MATERIAL" "EMPTY"
					( Origin gFrontEnd )
				)
				( attribute "PACK_TYPE" "0402"
					( Origin gFrontEnd )
				)
				( attribute "PART_NUMBER" "G21796-017"
					( Origin gFrontEnd )
				)
				( attribute "PHYS_PAGE" "228"
					( Origin gFrontEnd )
				)
				( attribute "ROOM" "VDDQ_KLM_PWR_VR"
					( Origin gFrontEnd )
				)
				( attribute "ROT" "0"
					( Origin gFrontEnd )
				)
				( attribute "SEC" "1"
					( Origin gFrontEnd )
				)
				( attribute "SEC_TYPE" "0402"
					( Origin gFrontEnd )
				)
				( attribute "TOLERANCE" "1%"
					( Origin gFrontEnd )
				)
				( attribute "VALUE" "100.0"
					( Origin gFrontEnd )
				)
				( attribute "VER" "2"
					( Origin gFrontEnd )
				)
				( attribute "WATTAGE" "1/16W"
					( Origin gFrontEnd )
				)
				( attribute "XY" "(-375,1925)"
					( Origin gFrontEnd )
				)
				( attribute "CHIPS_PART_NAME" "RES"
					( Origin gPackager )
				)
				( attribute "CDS_PART_NAME" "RES_0402-100.0,1%,1/16W,EMPTY,A"
					( Origin gPackager )
				)
				( objectStatus "R7L2" )
			)
			( gate "@baseboard_fab2_lib.baseboard_fab2(sch_1):page228_i75"
				( attribute "CDS_LIB" "mstr_discrete"
					( Origin gPackager )
				)
				( attribute "CDS_LOCATION" "C9L9"
					( Origin gPackager )
				)
				( attribute "CDS_SEC" "1"
					( Origin gPackager )
				)
				( attribute "LOCATION" "C9L9"
					( Origin gFrontEnd )
				)
				( attribute "MATERIAL" "ALUM"
					( Origin gFrontEnd )
				)
				( attribute "PACK_TYPE" "3018"
					( Origin gFrontEnd )
				)
				( attribute "PART_NUMBER" "699013-049"
					( Origin gFrontEnd )
				)
				( attribute "PHYS_PAGE" "228"
					( Origin gFrontEnd )
				)
				( attribute "ROOM" "VDDQ_KLM_PWR_VR"
					( Origin gFrontEnd )
				)
				( attribute "ROT" "0"
					( Origin gFrontEnd )
				)
				( attribute "SEC" "1"
					( Origin gFrontEnd )
				)
				( attribute "SEC_TYPE" "3018"
					( Origin gFrontEnd )
				)
				( attribute "TOLERANCE" "20%"
					( Origin gFrontEnd )
				)
				( attribute "VALUE" "470UF"
					( Origin gFrontEnd )
				)
				( attribute "VER" "1"
					( Origin gFrontEnd )
				)
				( attribute "VOLTAGE" "2.5V"
					( Units "uVoltage" "V" 1.000000)
					( Origin gFrontEnd )
				)
				( attribute "XY" "(2900,-500)"
					( Origin gFrontEnd )
				)
				( attribute "CHIPS_PART_NAME" "CAPP"
					( Origin gPackager )
				)
				( attribute "CDS_PART_NAME" "CAPP_3018-470UF,2.5V,20%,ALUM,A"
					( Origin gPackager )
				)
				( attribute "GROUP" "PWR_BULK_CAP"
					( Origin gFrontEnd )
				)
				( objectStatus "C9L9" )
			)
			( gate "@baseboard_fab2_lib.baseboard_fab2(sch_1):page228_i76"
				( attribute "CDS_LIB" "mstr_discrete"
					( Origin gPackager )
				)
				( attribute "CDS_LOCATION" "C9L12"
					( Origin gPackager )
				)
				( attribute "CDS_SEC" "1"
					( Origin gPackager )
				)
				( attribute "LOCATION" "C9L12"
					( Origin gFrontEnd )
				)
				( attribute "MATERIAL" "ALUM"
					( Origin gFrontEnd )
				)
				( attribute "PACK_TYPE" "3018"
					( Origin gFrontEnd )
				)
				( attribute "PART_NUMBER" "699013-049"
					( Origin gFrontEnd )
				)
				( attribute "PHYS_PAGE" "228"
					( Origin gFrontEnd )
				)
				( attribute "ROOM" "VDDQ_KLM_PWR_VR"
					( Origin gFrontEnd )
				)
				( attribute "ROT" "0"
					( Origin gFrontEnd )
				)
				( attribute "SEC" "1"
					( Origin gFrontEnd )
				)
				( attribute "SEC_TYPE" "3018"
					( Origin gFrontEnd )
				)
				( attribute "TOLERANCE" "20%"
					( Origin gFrontEnd )
				)
				( attribute "VALUE" "470UF"
					( Origin gFrontEnd )
				)
				( attribute "VER" "1"
					( Origin gFrontEnd )
				)
				( attribute "VOLTAGE" "2.5V"
					( Units "uVoltage" "V" 1.000000)
					( Origin gFrontEnd )
				)
				( attribute "XY" "(3200,-500)"
					( Origin gFrontEnd )
				)
				( attribute "CHIPS_PART_NAME" "CAPP"
					( Origin gPackager )
				)
				( attribute "CDS_PART_NAME" "CAPP_3018-470UF,2.5V,20%,ALUM,A"
					( Origin gPackager )
				)
				( attribute "GROUP" "PWR_BULK_CAP"
					( Origin gFrontEnd )
				)
				( objectStatus "C9L12" )
			)
			( gate "@baseboard_fab2_lib.baseboard_fab2(sch_1):page228_i77"
				( attribute "CDS_LIB" "mstr_discrete"
					( Origin gPackager )
				)
				( attribute "CDS_LOCATION" "C9L4"
					( Origin gPackager )
				)
				( attribute "CDS_SEC" "1"
					( Origin gPackager )
				)
				( attribute "LOCATION" "C9L4"
					( Origin gFrontEnd )
				)
				( attribute "MATERIAL" "ALUM"
					( Origin gFrontEnd )
				)
				( attribute "PACK_TYPE" "3018"
					( Origin gFrontEnd )
				)
				( attribute "PART_NUMBER" "699013-049"
					( Origin gFrontEnd )
				)
				( attribute "PHYS_PAGE" "228"
					( Origin gFrontEnd )
				)
				( attribute "ROOM" "VDDQ_KLM_PWR_VR"
					( Origin gFrontEnd )
				)
				( attribute "ROT" "0"
					( Origin gFrontEnd )
				)
				( attribute "SEC" "1"
					( Origin gFrontEnd )
				)
				( attribute "SEC_TYPE" "3018"
					( Origin gFrontEnd )
				)
				( attribute "TOLERANCE" "20%"
					( Origin gFrontEnd )
				)
				( attribute "VALUE" "470UF"
					( Origin gFrontEnd )
				)
				( attribute "VER" "1"
					( Origin gFrontEnd )
				)
				( attribute "VOLTAGE" "2.5V"
					( Units "uVoltage" "V" 1.000000)
					( Origin gFrontEnd )
				)
				( attribute "XY" "(3500,-500)"
					( Origin gFrontEnd )
				)
				( attribute "CHIPS_PART_NAME" "CAPP"
					( Origin gPackager )
				)
				( attribute "CDS_PART_NAME" "CAPP_3018-470UF,2.5V,20%,ALUM,A"
					( Origin gPackager )
				)
				( attribute "GROUP" "PWR_BULK_CAP"
					( Origin gFrontEnd )
				)
				( objectStatus "C9L4" )
			)
			( gate "@baseboard_fab2_lib.baseboard_fab2(sch_1):page228_i78"
				( attribute "CDS_LIB" "mstr_discrete"
					( Origin gPackager )
				)
				( attribute "CDS_LOCATION" "C9L2"
					( Origin gPackager )
				)
				( attribute "CDS_SEC" "1"
					( Origin gPackager )
				)
				( attribute "LOCATION" "C9L2"
					( Origin gFrontEnd )
				)
				( attribute "MATERIAL" "ALUM"
					( Origin gFrontEnd )
				)
				( attribute "PACK_TYPE" "3018"
					( Origin gFrontEnd )
				)
				( attribute "PART_NUMBER" "699013-049"
					( Origin gFrontEnd )
				)
				( attribute "PHYS_PAGE" "228"
					( Origin gFrontEnd )
				)
				( attribute "ROOM" "VDDQ_KLM_PWR_VR"
					( Origin gFrontEnd )
				)
				( attribute "ROT" "0"
					( Origin gFrontEnd )
				)
				( attribute "SEC" "1"
					( Origin gFrontEnd )
				)
				( attribute "SEC_TYPE" "3018"
					( Origin gFrontEnd )
				)
				( attribute "TOLERANCE" "20%"
					( Origin gFrontEnd )
				)
				( attribute "VALUE" "470UF"
					( Origin gFrontEnd )
				)
				( attribute "VER" "1"
					( Origin gFrontEnd )
				)
				( attribute "VOLTAGE" "2.5V"
					( Units "uVoltage" "V" 1.000000)
					( Origin gFrontEnd )
				)
				( attribute "XY" "(3800,-500)"
					( Origin gFrontEnd )
				)
				( attribute "CHIPS_PART_NAME" "CAPP"
					( Origin gPackager )
				)
				( attribute "CDS_PART_NAME" "CAPP_3018-470UF,2.5V,20%,ALUM,A"
					( Origin gPackager )
				)
				( attribute "GROUP" "PWR_BULK_CAP"
					( Origin gFrontEnd )
				)
				( objectStatus "C9L2" )
			)
			( gate "@baseboard_fab2_lib.baseboard_fab2(sch_1):page228_i310"
				( attribute "BOM_COST" "MEM_VRD_PVDDQ_CD"
					( Origin gFrontEnd )
				)
				( attribute "CDS_LIB" "mstr_discrete"
					( Origin gPackager )
				)
				( attribute "CDS_LOCATION" "C8L2"
					( Origin gPackager )
				)
				( attribute "CDS_SEC" "1"
					( Origin gPackager )
				)
				( attribute "LOCATION" "C8L2"
					( Origin gFrontEnd )
				)
				( attribute "MATERIAL" "X5R"
					( Origin gFrontEnd )
				)
				( attribute "NEW_MATERIAL" "X6S"
					( Origin gFrontEnd )
				)
				( attribute "PACK_TYPE" "0805"
					( Origin gFrontEnd )
				)
				( attribute "PART_NUMBER" "602433-112"
					( Origin gFrontEnd )
				)
				( attribute "PHYS_PAGE" "228"
					( Origin gFrontEnd )
				)
				( attribute "ROOM" "VDDQ_ABC_PWR_VR"
					( Origin gFrontEnd )
				)
				( attribute "ROT" "0"
					( Origin gFrontEnd )
				)
				( attribute "SEC" "1"
					( Origin gFrontEnd )
				)
				( attribute "SEC_TYPE" "0805"
					( Origin gFrontEnd )
				)
				( attribute "TOLERANCE" "20%"
					( Origin gFrontEnd )
				)
				( attribute "VALUE" "100UF"
					( Origin gFrontEnd )
				)
				( attribute "VER" "1"
					( Origin gFrontEnd )
				)
				( attribute "VOLTAGE" "4V"
					( Units "uVoltage" "V" 1.000000)
					( Origin gFrontEnd )
				)
				( attribute "XY" "(4600,2825)"
					( Origin gFrontEnd )
				)
				( attribute "CHIPS_PART_NAME" "CAP"
					( Origin gPackager )
				)
				( attribute "CDS_PART_NAME" "CAP_0805-100UF,4V,20%,X5R,6024A"
					( Origin gPackager )
				)
				( attribute "GROUP" "PWR_MLCC_CAP"
					( Origin gFrontEnd )
				)
				( attribute "NEW_PN" "078.1071T.M002"
					( Origin gFrontEnd )
				)
				( attribute "BOM_SS" "NOPOP"
					( Origin gFrontEnd )
				)
				( objectStatus "C8L2" )
			)
			( gate "@baseboard_fab2_lib.baseboard_fab2(sch_1):page228_i311"
				( attribute "BOM_COST" "MEM_VRD_PVDDQ_CD"
					( Origin gFrontEnd )
				)
				( attribute "CDS_LIB" "mstr_discrete"
					( Origin gPackager )
				)
				( attribute "CDS_LOCATION" "C8M11"
					( Origin gPackager )
				)
				( attribute "CDS_SEC" "1"
					( Origin gPackager )
				)
				( attribute "LOCATION" "C8M11"
					( Origin gFrontEnd )
				)
				( attribute "MATERIAL" "X5R"
					( Origin gFrontEnd )
				)
				( attribute "NEW_MATERIAL" "X6S"
					( Origin gFrontEnd )
				)
				( attribute "PACK_TYPE" "0805"
					( Origin gFrontEnd )
				)
				( attribute "PART_NUMBER" "602433-112"
					( Origin gFrontEnd )
				)
				( attribute "PHYS_PAGE" "228"
					( Origin gFrontEnd )
				)
				( attribute "ROOM" "VDDQ_ABC_PWR_VR"
					( Origin gFrontEnd )
				)
				( attribute "ROT" "0"
					( Origin gFrontEnd )
				)
				( attribute "SEC" "1"
					( Origin gFrontEnd )
				)
				( attribute "SEC_TYPE" "0805"
					( Origin gFrontEnd )
				)
				( attribute "TOLERANCE" "20%"
					( Origin gFrontEnd )
				)
				( attribute "VALUE" "100UF"
					( Origin gFrontEnd )
				)
				( attribute "VER" "1"
					( Origin gFrontEnd )
				)
				( attribute "VOLTAGE" "4V"
					( Units "uVoltage" "V" 1.000000)
					( Origin gFrontEnd )
				)
				( attribute "XY" "(3150,2825)"
					( Origin gFrontEnd )
				)
				( attribute "CHIPS_PART_NAME" "CAP"
					( Origin gPackager )
				)
				( attribute "CDS_PART_NAME" "CAP_0805-100UF,4V,20%,X5R,6024A"
					( Origin gPackager )
				)
				( attribute "GROUP" "PWR_MLCC_CAP"
					( Origin gFrontEnd )
				)
				( attribute "NEW_PN" "078.1071T.M002"
					( Origin gFrontEnd )
				)
				( attribute "BOM_SS" "NOPOP"
					( Origin gFrontEnd )
				)
				( objectStatus "C8M11" )
			)
			( gate "@baseboard_fab2_lib.baseboard_fab2(sch_1):page229_i42"
				( attribute "BOM_COST" "MEM_VRD_PVDDQ_CD"
					( Origin gFrontEnd )
				)
				( attribute "CDS_LIB" "mstr_discrete"
					( Origin gPackager )
				)
				( attribute "CDS_LOCATION" "C8U10"
					( Origin gPackager )
				)
				( attribute "CDS_SEC" "1"
					( Origin gPackager )
				)
				( attribute "LOCATION" "C8U10"
					( Origin gFrontEnd )
				)
				( attribute "MATERIAL" "X5R"
					( Origin gFrontEnd )
				)
				( attribute "NEW_MATERIAL" "X6S"
					( Origin gFrontEnd )
				)
				( attribute "PACK_TYPE" "0805"
					( Origin gFrontEnd )
				)
				( attribute "PART_NUMBER" "602433-112"
					( Origin gFrontEnd )
				)
				( attribute "PHYS_PAGE" "229"
					( Origin gFrontEnd )
				)
				( attribute "ROOM" "VDDQ_ABC_PWR_VR"
					( Origin gFrontEnd )
				)
				( attribute "ROT" "0"
					( Origin gFrontEnd )
				)
				( attribute "SEC" "1"
					( Origin gFrontEnd )
				)
				( attribute "SEC_TYPE" "0805"
					( Origin gFrontEnd )
				)
				( attribute "TOLERANCE" "20%"
					( Origin gFrontEnd )
				)
				( attribute "VALUE" "100UF"
					( Origin gFrontEnd )
				)
				( attribute "VER" "1"
					( Origin gFrontEnd )
				)
				( attribute "VOLTAGE" "4V"
					( Units "uVoltage" "V" 1.000000)
					( Origin gFrontEnd )
				)
				( attribute "XY" "(4150,3200)"
					( Origin gFrontEnd )
				)
				( attribute "CHIPS_PART_NAME" "CAP"
					( Origin gPackager )
				)
				( attribute "CDS_PART_NAME" "CAP_0805-100UF,4V,20%,X5R,6024A"
					( Origin gPackager )
				)
				( attribute "GROUP" "PWR_MLCC_CAP"
					( Origin gFrontEnd )
				)
				( attribute "NEW_PN" "078.1071T.M002"
					( Origin gFrontEnd )
				)
				( objectStatus "C8U10" )
			)
			( gate "@baseboard_fab2_lib.baseboard_fab2(sch_1):page228_i314"
				( attribute "BOM_COST" "MEM_VRD_PVDDQ_CD"
					( Origin gFrontEnd )
				)
				( attribute "CDS_LIB" "mstr_discrete"
					( Origin gPackager )
				)
				( attribute "CDS_LOCATION" "C7L1"
					( Origin gPackager )
				)
				( attribute "CDS_SEC" "1"
					( Origin gPackager )
				)
				( attribute "LOCATION" "C7L1"
					( Origin gFrontEnd )
				)
				( attribute "MATERIAL" "X5R"
					( Origin gFrontEnd )
				)
				( attribute "NEW_MATERIAL" "X6S"
					( Origin gFrontEnd )
				)
				( attribute "PACK_TYPE" "0805"
					( Origin gFrontEnd )
				)
				( attribute "PART_NUMBER" "602433-112"
					( Origin gFrontEnd )
				)
				( attribute "PHYS_PAGE" "228"
					( Origin gFrontEnd )
				)
				( attribute "ROOM" "VDDQ_ABC_PWR_VR"
					( Origin gFrontEnd )
				)
				( attribute "ROT" "0"
					( Origin gFrontEnd )
				)
				( attribute "SEC" "1"
					( Origin gFrontEnd )
				)
				( attribute "SEC_TYPE" "0805"
					( Origin gFrontEnd )
				)
				( attribute "TOLERANCE" "20%"
					( Origin gFrontEnd )
				)
				( attribute "VALUE" "100UF"
					( Origin gFrontEnd )
				)
				( attribute "VER" "1"
					( Origin gFrontEnd )
				)
				( attribute "VOLTAGE" "4V"
					( Units "uVoltage" "V" 1.000000)
					( Origin gFrontEnd )
				)
				( attribute "XY" "(2750,2825)"
					( Origin gFrontEnd )
				)
				( attribute "CHIPS_PART_NAME" "CAP"
					( Origin gPackager )
				)
				( attribute "CDS_PART_NAME" "CAP_0805-100UF,4V,20%,X5R,6024A"
					( Origin gPackager )
				)
				( attribute "GROUP" "PWR_MLCC_CAP"
					( Origin gFrontEnd )
				)
				( attribute "NEW_PN" "078.1071T.M002"
					( Origin gFrontEnd )
				)
				( attribute "BOM_SS" "NOPOP"
					( Origin gFrontEnd )
				)
				( objectStatus "C7L1" )
			)
			( gate "@baseboard_fab2_lib.baseboard_fab2(sch_1):page229_i41"
				( attribute "BOM_COST" "MEM_VRD_PVDDQ_CD"
					( Origin gFrontEnd )
				)
				( attribute "CDS_LIB" "mstr_discrete"
					( Origin gPackager )
				)
				( attribute "CDS_LOCATION" "C8T3"
					( Origin gPackager )
				)
				( attribute "CDS_SEC" "1"
					( Origin gPackager )
				)
				( attribute "LOCATION" "C8T3"
					( Origin gFrontEnd )
				)
				( attribute "MATERIAL" "X5R"
					( Origin gFrontEnd )
				)
				( attribute "NEW_MATERIAL" "X6S"
					( Origin gFrontEnd )
				)
				( attribute "PACK_TYPE" "0805"
					( Origin gFrontEnd )
				)
				( attribute "PART_NUMBER" "602433-112"
					( Origin gFrontEnd )
				)
				( attribute "PHYS_PAGE" "229"
					( Origin gFrontEnd )
				)
				( attribute "ROOM" "VDDQ_ABC_PWR_VR"
					( Origin gFrontEnd )
				)
				( attribute "ROT" "0"
					( Origin gFrontEnd )
				)
				( attribute "SEC" "1"
					( Origin gFrontEnd )
				)
				( attribute "SEC_TYPE" "0805"
					( Origin gFrontEnd )
				)
				( attribute "TOLERANCE" "20%"
					( Origin gFrontEnd )
				)
				( attribute "VALUE" "100UF"
					( Origin gFrontEnd )
				)
				( attribute "VER" "1"
					( Origin gFrontEnd )
				)
				( attribute "VOLTAGE" "4V"
					( Units "uVoltage" "V" 1.000000)
					( Origin gFrontEnd )
				)
				( attribute "XY" "(3800,3200)"
					( Origin gFrontEnd )
				)
				( attribute "CHIPS_PART_NAME" "CAP"
					( Origin gPackager )
				)
				( attribute "CDS_PART_NAME" "CAP_0805-100UF,4V,20%,X5R,6024A"
					( Origin gPackager )
				)
				( attribute "GROUP" "PWR_MLCC_CAP"
					( Origin gFrontEnd )
				)
				( attribute "NEW_PN" "078.1071T.M002"
					( Origin gFrontEnd )
				)
				( objectStatus "C8T3" )
			)
			( gate "@baseboard_fab2_lib.baseboard_fab2(sch_1):page228_i307"
				( attribute "BOM_COST" "MEM_VRD_PVDDQ_CD"
					( Origin gFrontEnd )
				)
				( attribute "CDS_LIB" "mstr_discrete"
					( Origin gPackager )
				)
				( attribute "LOCATION" "C8P4"
					( Origin gFrontEnd )
				)
				( attribute "MATERIAL" "X5R"
					( Origin gFrontEnd )
				)
				( attribute "NEW_MATERIAL" "X6S"
					( Origin gFrontEnd )
				)
				( attribute "PACK_TYPE" "0805"
					( Origin gFrontEnd )
				)
				( attribute "PART_NUMBER" "602433-112"
					( Origin gFrontEnd )
				)
				( attribute "PHYS_PAGE" "228"
					( Origin gFrontEnd )
				)
				( attribute "ROOM" "VDDQ_ABC_PWR_VR"
					( Origin gFrontEnd )
				)
				( attribute "ROT" "0"
					( Origin gFrontEnd )
				)
				( attribute "SEC" "1"
					( Origin gFrontEnd )
				)
				( attribute "SEC_TYPE" "0805"
					( Origin gFrontEnd )
				)
				( attribute "TOLERANCE" "20%"
					( Origin gFrontEnd )
				)
				( attribute "VALUE" "100UF"
					( Origin gFrontEnd )
				)
				( attribute "VER" "1"
					( Origin gFrontEnd )
				)
				( attribute "VOLTAGE" "4V"
					( Units "uVoltage" "V" 1.000000)
					( Origin gFrontEnd )
				)
				( attribute "XY" "(650,2775)"
					( Origin gFrontEnd )
				)
				( attribute "CHIPS_PART_NAME" "CAP"
					( Origin gPackager )
				)
				( attribute "CDS_PART_NAME" "CAP_0805-100UF,4V,20%,X5R,6024A"
					( Origin gPackager )
				)
				( attribute "CDS_LOCATION" "C8P4"
					( Origin gPackager )
				)
				( attribute "CDS_SEC" "1"
					( Origin gPackager )
				)
				( attribute "GROUP" "PWR_MLCC_CAP"
					( Origin gFrontEnd )
				)
				( attribute "NEW_PN" "078.1071T.M002"
					( Origin gFrontEnd )
				)
				( attribute "BOM_SS" "NOPOP"
					( Origin gFrontEnd )
				)
				( objectStatus "C8P4" )
			)
			( gate "@baseboard_fab2_lib.baseboard_fab2(sch_1):page228_i175"
				( attribute "CDS_LIB" "mstr_discrete"
					( Origin gPackager )
				)
				( attribute "CDS_LOCATION" "C1B10"
					( Origin gPackager )
				)
				( attribute "CDS_SEC" "1"
					( Origin gPackager )
				)
				( attribute "LOCATION" "C1B10"
					( Origin gFrontEnd )
				)
				( attribute "MATERIAL" "OSCON"
					( Origin gFrontEnd )
				)
				( attribute "PACK_TYPE" "2626"
					( Origin gFrontEnd )
				)
				( attribute "PART_NUMBER" "A31228-047"
					( Origin gFrontEnd )
				)
				( attribute "PHYS_PAGE" "228"
					( Origin gFrontEnd )
				)
				( attribute "ROOM" "VDDQ_KLM_PWR_VR"
					( Origin gFrontEnd )
				)
				( attribute "ROT" "0"
					( Origin gFrontEnd )
				)
				( attribute "SEC" "1"
					( Origin gFrontEnd )
				)
				( attribute "SEC_TYPE" "2626"
					( Origin gFrontEnd )
				)
				( attribute "TOLERANCE" "20%"
					( Origin gFrontEnd )
				)
				( attribute "VALUE" "270UF"
					( Origin gFrontEnd )
				)
				( attribute "VER" "1"
					( Origin gFrontEnd )
				)
				( attribute "VOLTAGE" "16V"
					( Units "uVoltage" "V" 1.000000)
					( Origin gFrontEnd )
				)
				( attribute "XY" "(-675,900)"
					( Origin gFrontEnd )
				)
				( attribute "CHIPS_PART_NAME" "CAPP"
					( Origin gPackager )
				)
				( attribute "CDS_PART_NAME" "CAPP_2626-270UF,16V,20%,OSCON,A"
					( Origin gPackager )
				)
				( objectStatus "C1B10" )
			)
			( gate "@baseboard_fab2_lib.baseboard_fab2(sch_1):page228_i312"
				( attribute "BOM_COST" "MEM_VRD_PVDDQ_CD"
					( Origin gFrontEnd )
				)
				( attribute "CDS_LIB" "mstr_discrete"
					( Origin gPackager )
				)
				( attribute "CDS_LOCATION" "C8M7"
					( Origin gPackager )
				)
				( attribute "CDS_SEC" "1"
					( Origin gPackager )
				)
				( attribute "LOCATION" "C8M7"
					( Origin gFrontEnd )
				)
				( attribute "MATERIAL" "X5R"
					( Origin gFrontEnd )
				)
				( attribute "NEW_MATERIAL" "X6S"
					( Origin gFrontEnd )
				)
				( attribute "PACK_TYPE" "0805"
					( Origin gFrontEnd )
				)
				( attribute "PART_NUMBER" "602433-112"
					( Origin gFrontEnd )
				)
				( attribute "PHYS_PAGE" "228"
					( Origin gFrontEnd )
				)
				( attribute "ROOM" "VDDQ_ABC_PWR_VR"
					( Origin gFrontEnd )
				)
				( attribute "ROT" "0"
					( Origin gFrontEnd )
				)
				( attribute "SEC" "1"
					( Origin gFrontEnd )
				)
				( attribute "SEC_TYPE" "0805"
					( Origin gFrontEnd )
				)
				( attribute "TOLERANCE" "20%"
					( Origin gFrontEnd )
				)
				( attribute "VALUE" "100UF"
					( Origin gFrontEnd )
				)
				( attribute "VER" "1"
					( Origin gFrontEnd )
				)
				( attribute "VOLTAGE" "4V"
					( Units "uVoltage" "V" 1.000000)
					( Origin gFrontEnd )
				)
				( attribute "XY" "(3500,2825)"
					( Origin gFrontEnd )
				)
				( attribute "CHIPS_PART_NAME" "CAP"
					( Origin gPackager )
				)
				( attribute "CDS_PART_NAME" "CAP_0805-100UF,4V,20%,X5R,6024A"
					( Origin gPackager )
				)
				( attribute "GROUP" "PWR_MLCC_CAP"
					( Origin gFrontEnd )
				)
				( attribute "NEW_PN" "078.1071T.M002"
					( Origin gFrontEnd )
				)
				( attribute "BOM_SS" "NOPOP"
					( Origin gFrontEnd )
				)
				( objectStatus "C8M7" )
			)
			( gate "@baseboard_fab2_lib.baseboard_fab2(sch_1):page228_i308"
				( attribute "BOM_COST" "MEM_VRD_PVDDQ_CD"
					( Origin gFrontEnd )
				)
				( attribute "CDS_LIB" "mstr_discrete"
					( Origin gPackager )
				)
				( attribute "CDS_LOCATION" "C7P1"
					( Origin gPackager )
				)
				( attribute "CDS_SEC" "1"
					( Origin gPackager )
				)
				( attribute "LOCATION" "C7P1"
					( Origin gFrontEnd )
				)
				( attribute "MATERIAL" "X5R"
					( Origin gFrontEnd )
				)
				( attribute "NEW_MATERIAL" "X6S"
					( Origin gFrontEnd )
				)
				( attribute "PACK_TYPE" "0805"
					( Origin gFrontEnd )
				)
				( attribute "PART_NUMBER" "602433-112"
					( Origin gFrontEnd )
				)
				( attribute "PHYS_PAGE" "228"
					( Origin gFrontEnd )
				)
				( attribute "ROOM" "VDDQ_ABC_PWR_VR"
					( Origin gFrontEnd )
				)
				( attribute "ROT" "0"
					( Origin gFrontEnd )
				)
				( attribute "SEC" "1"
					( Origin gFrontEnd )
				)
				( attribute "SEC_TYPE" "0805"
					( Origin gFrontEnd )
				)
				( attribute "TOLERANCE" "20%"
					( Origin gFrontEnd )
				)
				( attribute "VALUE" "100UF"
					( Origin gFrontEnd )
				)
				( attribute "VER" "1"
					( Origin gFrontEnd )
				)
				( attribute "VOLTAGE" "4V"
					( Units "uVoltage" "V" 1.000000)
					( Origin gFrontEnd )
				)
				( attribute "XY" "(525,725)"
					( Origin gFrontEnd )
				)
				( attribute "CHIPS_PART_NAME" "CAP"
					( Origin gPackager )
				)
				( attribute "CDS_PART_NAME" "CAP_0805-100UF,4V,20%,X5R,6024A"
					( Origin gPackager )
				)
				( attribute "GROUP" "PWR_MLCC_CAP"
					( Origin gFrontEnd )
				)
				( attribute "NEW_PN" "078.1071T.M002"
					( Origin gFrontEnd )
				)
				( attribute "BOM_SS" "NOPOP"
					( Origin gFrontEnd )
				)
				( objectStatus "C7P1" )
			)
			( gate "@baseboard_fab2_lib.baseboard_fab2(sch_1):page228_i271"
				( attribute "CDS_LIB" "dev_discrete"
					( Origin gPackager )
				)
				( attribute "CDS_LOCATION" "C2A15"
					( Origin gPackager )
				)
				( attribute "CDS_SEC" "1"
					( Origin gPackager )
				)
				( attribute "LOCATION" "C2A15"
					( Origin gFrontEnd )
				)
				( attribute "MATERIAL" "X5R"
					( Origin gFrontEnd )
				)
				( attribute "PACK_TYPE" "0603V"
					( Origin gFrontEnd )
				)
				( attribute "PART_NUMBER" "602433-106"
					( Origin gFrontEnd )
				)
				( attribute "PHYS_PAGE" "228"
					( Origin gFrontEnd )
				)
				( attribute "ROT" "0"
					( Origin gFrontEnd )
				)
				( attribute "SEC" "1"
					( Origin gFrontEnd )
				)
				( attribute "SEC_TYPE" "0603V"
					( Origin gFrontEnd )
				)
				( attribute "TOLERANCE" "20%"
					( Origin gFrontEnd )
				)
				( attribute "VALUE" "47UF"
					( Origin gFrontEnd )
				)
				( attribute "VER" "1"
					( Origin gFrontEnd )
				)
				( attribute "VOLTAGE" "4V"
					( Units "uVoltage" "V" 1.000000)
					( Origin gFrontEnd )
				)
				( attribute "XY" "(-1375,-75)"
					( Origin gFrontEnd )
				)
				( attribute "CHIPS_PART_NAME" "CAP_A"
					( Origin gPackager )
				)
				( attribute "CDS_PART_NAME" "CAP_A_0603V-47UF,4V,20%,X5R,60A"
					( Origin gPackager )
				)
				( attribute "GROUP" "PWR_MLCC_CAP"
					( Origin gFrontEnd )
				)
				( attribute "BOM_SS" "E15431-004"
					( Origin gFrontEnd )
				)
				( objectStatus "C2A15" )
			)
			( gate "@baseboard_fab2_lib.baseboard_fab2(sch_1):page228_i270"
				( attribute "CDS_LIB" "dev_discrete"
					( Origin gPackager )
				)
				( attribute "CDS_LOCATION" "C3A5"
					( Origin gPackager )
				)
				( attribute "CDS_SEC" "1"
					( Origin gPackager )
				)
				( attribute "LOCATION" "C3A5"
					( Origin gFrontEnd )
				)
				( attribute "MATERIAL" "X5R"
					( Origin gFrontEnd )
				)
				( attribute "PACK_TYPE" "0603V"
					( Origin gFrontEnd )
				)
				( attribute "PART_NUMBER" "602433-106"
					( Origin gFrontEnd )
				)
				( attribute "PHYS_PAGE" "228"
					( Origin gFrontEnd )
				)
				( attribute "ROT" "0"
					( Origin gFrontEnd )
				)
				( attribute "SEC" "1"
					( Origin gFrontEnd )
				)
				( attribute "SEC_TYPE" "0603V"
					( Origin gFrontEnd )
				)
				( attribute "TOLERANCE" "20%"
					( Origin gFrontEnd )
				)
				( attribute "VALUE" "47UF"
					( Origin gFrontEnd )
				)
				( attribute "VER" "1"
					( Origin gFrontEnd )
				)
				( attribute "VOLTAGE" "4V"
					( Units "uVoltage" "V" 1.000000)
					( Origin gFrontEnd )
				)
				( attribute "XY" "(-1650,-75)"
					( Origin gFrontEnd )
				)
				( attribute "CHIPS_PART_NAME" "CAP_A"
					( Origin gPackager )
				)
				( attribute "CDS_PART_NAME" "CAP_A_0603V-47UF,4V,20%,X5R,60A"
					( Origin gPackager )
				)
				( attribute "GROUP" "PWR_MLCC_CAP"
					( Origin gFrontEnd )
				)
				( attribute "BOM_SS" "E15431-004"
					( Origin gFrontEnd )
				)
				( objectStatus "C3A5" )
			)
			( gate "@baseboard_fab2_lib.baseboard_fab2(sch_1):page228_i269"
				( attribute "CDS_LIB" "dev_discrete"
					( Origin gPackager )
				)
				( attribute "CDS_LOCATION" "C3A6"
					( Origin gPackager )
				)
				( attribute "CDS_SEC" "1"
					( Origin gPackager )
				)
				( attribute "LOCATION" "C3A6"
					( Origin gFrontEnd )
				)
				( attribute "MATERIAL" "X5R"
					( Origin gFrontEnd )
				)
				( attribute "PACK_TYPE" "0603V"
					( Origin gFrontEnd )
				)
				( attribute "PART_NUMBER" "602433-106"
					( Origin gFrontEnd )
				)
				( attribute "PHYS_PAGE" "228"
					( Origin gFrontEnd )
				)
				( attribute "ROT" "0"
					( Origin gFrontEnd )
				)
				( attribute "SEC" "1"
					( Origin gFrontEnd )
				)
				( attribute "SEC_TYPE" "0603V"
					( Origin gFrontEnd )
				)
				( attribute "TOLERANCE" "20%"
					( Origin gFrontEnd )
				)
				( attribute "VALUE" "47UF"
					( Origin gFrontEnd )
				)
				( attribute "VER" "1"
					( Origin gFrontEnd )
				)
				( attribute "VOLTAGE" "4V"
					( Units "uVoltage" "V" 1.000000)
					( Origin gFrontEnd )
				)
				( attribute "XY" "(-1950,-75)"
					( Origin gFrontEnd )
				)
				( attribute "CHIPS_PART_NAME" "CAP_A"
					( Origin gPackager )
				)
				( attribute "CDS_PART_NAME" "CAP_A_0603V-47UF,4V,20%,X5R,60A"
					( Origin gPackager )
				)
				( attribute "GROUP" "PWR_MLCC_CAP"
					( Origin gFrontEnd )
				)
				( attribute "BOM_SS" "E15431-004"
					( Origin gFrontEnd )
				)
				( objectStatus "C3A6" )
			)
			( gate "@baseboard_fab2_lib.baseboard_fab2(sch_1):page228_i268"
				( attribute "CDS_LIB" "dev_discrete"
					( Origin gPackager )
				)
				( attribute "CDS_LOCATION" "C7L5"
					( Origin gPackager )
				)
				( attribute "CDS_SEC" "1"
					( Origin gPackager )
				)
				( attribute "LOCATION" "C7L5"
					( Origin gFrontEnd )
				)
				( attribute "MATERIAL" "X5R"
					( Origin gFrontEnd )
				)
				( attribute "PACK_TYPE" "0603V"
					( Origin gFrontEnd )
				)
				( attribute "PART_NUMBER" "602433-106"
					( Origin gFrontEnd )
				)
				( attribute "PHYS_PAGE" "228"
					( Origin gFrontEnd )
				)
				( attribute "ROT" "0"
					( Origin gFrontEnd )
				)
				( attribute "SEC" "1"
					( Origin gFrontEnd )
				)
				( attribute "SEC_TYPE" "0603V"
					( Origin gFrontEnd )
				)
				( attribute "TOLERANCE" "20%"
					( Origin gFrontEnd )
				)
				( attribute "VALUE" "47UF"
					( Origin gFrontEnd )
				)
				( attribute "VER" "1"
					( Origin gFrontEnd )
				)
				( attribute "VOLTAGE" "4V"
					( Units "uVoltage" "V" 1.000000)
					( Origin gFrontEnd )
				)
				( attribute "XY" "(-2250,-75)"
					( Origin gFrontEnd )
				)
				( attribute "CHIPS_PART_NAME" "CAP_A"
					( Origin gPackager )
				)
				( attribute "CDS_PART_NAME" "CAP_A_0603V-47UF,4V,20%,X5R,60A"
					( Origin gPackager )
				)
				( attribute "GROUP" "PWR_MLCC_CAP"
					( Origin gFrontEnd )
				)
				( attribute "BOM_SS" "E15431-004"
					( Origin gFrontEnd )
				)
				( objectStatus "C7L5" )
			)
			( gate "@baseboard_fab2_lib.baseboard_fab2(sch_1):page228_i198"
				( attribute "CDS_LIB" "dev_discrete"
					( Origin gPackager )
				)
				( attribute "CDS_LOCATION" "C8M8"
					( Origin gPackager )
				)
				( attribute "CDS_SEC" "1"
					( Origin gPackager )
				)
				( attribute "LOCATION" "C8M8"
					( Origin gFrontEnd )
				)
				( attribute "MATERIAL" "X5R"
					( Origin gFrontEnd )
				)
				( attribute "PACK_TYPE" "0603V"
					( Origin gFrontEnd )
				)
				( attribute "PART_NUMBER" "602433-106"
					( Origin gFrontEnd )
				)
				( attribute "PHYS_PAGE" "228"
					( Origin gFrontEnd )
				)
				( attribute "ROT" "0"
					( Origin gFrontEnd )
				)
				( attribute "SEC" "1"
					( Origin gFrontEnd )
				)
				( attribute "SEC_TYPE" "0603V"
					( Origin gFrontEnd )
				)
				( attribute "TOLERANCE" "20%"
					( Origin gFrontEnd )
				)
				( attribute "VALUE" "47UF"
					( Origin gFrontEnd )
				)
				( attribute "VER" "1"
					( Origin gFrontEnd )
				)
				( attribute "VOLTAGE" "4V"
					( Units "uVoltage" "V" 1.000000)
					( Origin gFrontEnd )
				)
				( attribute "XY" "(2550,725)"
					( Origin gFrontEnd )
				)
				( attribute "CHIPS_PART_NAME" "CAP_A"
					( Origin gPackager )
				)
				( attribute "CDS_PART_NAME" "CAP_A_0603V-47UF,4V,20%,X5R,60A"
					( Origin gPackager )
				)
				( attribute "GROUP" "PWR_MLCC_CAP"
					( Origin gFrontEnd )
				)
				( attribute "BOM_SS" "NOPOP"
					( Origin gFrontEnd )
				)
				( objectStatus "C8M8" )
			)
			( gate "@baseboard_fab2_lib.baseboard_fab2(sch_1):page228_i199"
				( attribute "CDS_LIB" "dev_discrete"
					( Origin gPackager )
				)
				( attribute "CDS_LOCATION" "C2A5"
					( Origin gPackager )
				)
				( attribute "CDS_SEC" "1"
					( Origin gPackager )
				)
				( attribute "LOCATION" "C2A5"
					( Origin gFrontEnd )
				)
				( attribute "MATERIAL" "X5R"
					( Origin gFrontEnd )
				)
				( attribute "PACK_TYPE" "0603V"
					( Origin gFrontEnd )
				)
				( attribute "PART_NUMBER" "602433-106"
					( Origin gFrontEnd )
				)
				( attribute "PHYS_PAGE" "228"
					( Origin gFrontEnd )
				)
				( attribute "ROT" "0"
					( Origin gFrontEnd )
				)
				( attribute "SEC" "1"
					( Origin gFrontEnd )
				)
				( attribute "SEC_TYPE" "0603V"
					( Origin gFrontEnd )
				)
				( attribute "TOLERANCE" "20%"
					( Origin gFrontEnd )
				)
				( attribute "VALUE" "47UF"
					( Origin gFrontEnd )
				)
				( attribute "VER" "1"
					( Origin gFrontEnd )
				)
				( attribute "VOLTAGE" "4V"
					( Units "uVoltage" "V" 1.000000)
					( Origin gFrontEnd )
				)
				( attribute "XY" "(2900,725)"
					( Origin gFrontEnd )
				)
				( attribute "CHIPS_PART_NAME" "CAP_A"
					( Origin gPackager )
				)
				( attribute "CDS_PART_NAME" "CAP_A_0603V-47UF,4V,20%,X5R,60A"
					( Origin gPackager )
				)
				( attribute "GROUP" "PWR_MLCC_CAP"
					( Origin gFrontEnd )
				)
				( attribute "BOM_SS" "NOPOP"
					( Origin gFrontEnd )
				)
				( objectStatus "C2A5" )
			)
			( gate "@baseboard_fab2_lib.baseboard_fab2(sch_1):page228_i200"
				( attribute "CDS_LIB" "dev_discrete"
					( Origin gPackager )
				)
				( attribute "CDS_LOCATION" "C2B1"
					( Origin gPackager )
				)
				( attribute "CDS_SEC" "1"
					( Origin gPackager )
				)
				( attribute "LOCATION" "C2B1"
					( Origin gFrontEnd )
				)
				( attribute "MATERIAL" "X5R"
					( Origin gFrontEnd )
				)
				( attribute "PACK_TYPE" "0603V"
					( Origin gFrontEnd )
				)
				( attribute "PART_NUMBER" "602433-106"
					( Origin gFrontEnd )
				)
				( attribute "PHYS_PAGE" "228"
					( Origin gFrontEnd )
				)
				( attribute "ROT" "0"
					( Origin gFrontEnd )
				)
				( attribute "SEC" "1"
					( Origin gFrontEnd )
				)
				( attribute "SEC_TYPE" "0603V"
					( Origin gFrontEnd )
				)
				( attribute "TOLERANCE" "20%"
					( Origin gFrontEnd )
				)
				( attribute "VALUE" "47UF"
					( Origin gFrontEnd )
				)
				( attribute "VER" "1"
					( Origin gFrontEnd )
				)
				( attribute "VOLTAGE" "4V"
					( Units "uVoltage" "V" 1.000000)
					( Origin gFrontEnd )
				)
				( attribute "XY" "(3300,725)"
					( Origin gFrontEnd )
				)
				( attribute "CHIPS_PART_NAME" "CAP_A"
					( Origin gPackager )
				)
				( attribute "CDS_PART_NAME" "CAP_A_0603V-47UF,4V,20%,X5R,60A"
					( Origin gPackager )
				)
				( attribute "GROUP" "PWR_MLCC_CAP"
					( Origin gFrontEnd )
				)
				( attribute "BOM_SS" "NOPOP"
					( Origin gFrontEnd )
				)
				( objectStatus "C2B1" )
			)
			( gate "@baseboard_fab2_lib.baseboard_fab2(sch_1):page228_i201"
				( attribute "CDS_LIB" "dev_discrete"
					( Origin gPackager )
				)
				( attribute "CDS_LOCATION" "C8L12"
					( Origin gPackager )
				)
				( attribute "CDS_SEC" "1"
					( Origin gPackager )
				)
				( attribute "LOCATION" "C8L12"
					( Origin gFrontEnd )
				)
				( attribute "MATERIAL" "X5R"
					( Origin gFrontEnd )
				)
				( attribute "PACK_TYPE" "0603V"
					( Origin gFrontEnd )
				)
				( attribute "PART_NUMBER" "602433-106"
					( Origin gFrontEnd )
				)
				( attribute "PHYS_PAGE" "228"
					( Origin gFrontEnd )
				)
				( attribute "ROT" "0"
					( Origin gFrontEnd )
				)
				( attribute "SEC" "1"
					( Origin gFrontEnd )
				)
				( attribute "SEC_TYPE" "0603V"
					( Origin gFrontEnd )
				)
				( attribute "TOLERANCE" "20%"
					( Origin gFrontEnd )
				)
				( attribute "VALUE" "47UF"
					( Origin gFrontEnd )
				)
				( attribute "VER" "1"
					( Origin gFrontEnd )
				)
				( attribute "VOLTAGE" "4V"
					( Units "uVoltage" "V" 1.000000)
					( Origin gFrontEnd )
				)
				( attribute "XY" "(2525,1425)"
					( Origin gFrontEnd )
				)
				( attribute "CHIPS_PART_NAME" "CAP_A"
					( Origin gPackager )
				)
				( attribute "CDS_PART_NAME" "CAP_A_0603V-47UF,4V,20%,X5R,60A"
					( Origin gPackager )
				)
				( attribute "GROUP" "PWR_MLCC_CAP"
					( Origin gFrontEnd )
				)
				( attribute "BOM_SS" "NOPOP"
					( Origin gFrontEnd )
				)
				( objectStatus "C8L12" )
			)
			( gate "@baseboard_fab2_lib.baseboard_fab2(sch_1):page228_i202"
				( attribute "CDS_LIB" "dev_discrete"
					( Origin gPackager )
				)
				( attribute "CDS_LOCATION" "C7M5"
					( Origin gPackager )
				)
				( attribute "CDS_SEC" "1"
					( Origin gPackager )
				)
				( attribute "LOCATION" "C7M5"
					( Origin gFrontEnd )
				)
				( attribute "MATERIAL" "X5R"
					( Origin gFrontEnd )
				)
				( attribute "PACK_TYPE" "0603V"
					( Origin gFrontEnd )
				)
				( attribute "PART_NUMBER" "602433-106"
					( Origin gFrontEnd )
				)
				( attribute "PHYS_PAGE" "228"
					( Origin gFrontEnd )
				)
				( attribute "ROT" "0"
					( Origin gFrontEnd )
				)
				( attribute "SEC" "1"
					( Origin gFrontEnd )
				)
				( attribute "SEC_TYPE" "0603V"
					( Origin gFrontEnd )
				)
				( attribute "TOLERANCE" "20%"
					( Origin gFrontEnd )
				)
				( attribute "VALUE" "47UF"
					( Origin gFrontEnd )
				)
				( attribute "VER" "1"
					( Origin gFrontEnd )
				)
				( attribute "VOLTAGE" "4V"
					( Units "uVoltage" "V" 1.000000)
					( Origin gFrontEnd )
				)
				( attribute "XY" "(2875,1425)"
					( Origin gFrontEnd )
				)
				( attribute "CHIPS_PART_NAME" "CAP_A"
					( Origin gPackager )
				)
				( attribute "CDS_PART_NAME" "CAP_A_0603V-47UF,4V,20%,X5R,60A"
					( Origin gPackager )
				)
				( attribute "GROUP" "PWR_MLCC_CAP"
					( Origin gFrontEnd )
				)
				( attribute "BOM_SS" "NOPOP"
					( Origin gFrontEnd )
				)
				( objectStatus "C7M5" )
			)
			( gate "@baseboard_fab2_lib.baseboard_fab2(sch_1):page228_i203"
				( attribute "CDS_LIB" "dev_discrete"
					( Origin gPackager )
				)
				( attribute "CDS_LOCATION" "C8M10"
					( Origin gPackager )
				)
				( attribute "CDS_SEC" "1"
					( Origin gPackager )
				)
				( attribute "LOCATION" "C8M10"
					( Origin gFrontEnd )
				)
				( attribute "MATERIAL" "X5R"
					( Origin gFrontEnd )
				)
				( attribute "PACK_TYPE" "0603V"
					( Origin gFrontEnd )
				)
				( attribute "PART_NUMBER" "602433-106"
					( Origin gFrontEnd )
				)
				( attribute "PHYS_PAGE" "228"
					( Origin gFrontEnd )
				)
				( attribute "ROT" "0"
					( Origin gFrontEnd )
				)
				( attribute "SEC" "1"
					( Origin gFrontEnd )
				)
				( attribute "SEC_TYPE" "0603V"
					( Origin gFrontEnd )
				)
				( attribute "TOLERANCE" "20%"
					( Origin gFrontEnd )
				)
				( attribute "VALUE" "47UF"
					( Origin gFrontEnd )
				)
				( attribute "VER" "1"
					( Origin gFrontEnd )
				)
				( attribute "VOLTAGE" "4V"
					( Units "uVoltage" "V" 1.000000)
					( Origin gFrontEnd )
				)
				( attribute "XY" "(3275,1425)"
					( Origin gFrontEnd )
				)
				( attribute "CHIPS_PART_NAME" "CAP_A"
					( Origin gPackager )
				)
				( attribute "CDS_PART_NAME" "CAP_A_0603V-47UF,4V,20%,X5R,60A"
					( Origin gPackager )
				)
				( attribute "GROUP" "PWR_MLCC_CAP"
					( Origin gFrontEnd )
				)
				( attribute "BOM_SS" "078.1061T.M001"
					( Origin gFrontEnd )
				)
				( objectStatus "C8M10" )
			)
			( gate "@baseboard_fab2_lib.baseboard_fab2(sch_1):page228_i204"
				( attribute "CDS_LIB" "dev_discrete"
					( Origin gPackager )
				)
				( attribute "CDS_LOCATION" "C2B2"
					( Origin gPackager )
				)
				( attribute "CDS_SEC" "1"
					( Origin gPackager )
				)
				( attribute "LOCATION" "C2B2"
					( Origin gFrontEnd )
				)
				( attribute "MATERIAL" "X5R"
					( Origin gFrontEnd )
				)
				( attribute "PACK_TYPE" "0603V"
					( Origin gFrontEnd )
				)
				( attribute "PART_NUMBER" "602433-106"
					( Origin gFrontEnd )
				)
				( attribute "PHYS_PAGE" "228"
					( Origin gFrontEnd )
				)
				( attribute "ROT" "0"
					( Origin gFrontEnd )
				)
				( attribute "SEC" "1"
					( Origin gFrontEnd )
				)
				( attribute "SEC_TYPE" "0603V"
					( Origin gFrontEnd )
				)
				( attribute "TOLERANCE" "20%"
					( Origin gFrontEnd )
				)
				( attribute "VALUE" "47UF"
					( Origin gFrontEnd )
				)
				( attribute "VER" "1"
					( Origin gFrontEnd )
				)
				( attribute "VOLTAGE" "4V"
					( Units "uVoltage" "V" 1.000000)
					( Origin gFrontEnd )
				)
				( attribute "XY" "(3625,1425)"
					( Origin gFrontEnd )
				)
				( attribute "CHIPS_PART_NAME" "CAP_A"
					( Origin gPackager )
				)
				( attribute "CDS_PART_NAME" "CAP_A_0603V-47UF,4V,20%,X5R,60A"
					( Origin gPackager )
				)
				( attribute "GROUP" "PWR_MLCC_CAP"
					( Origin gFrontEnd )
				)
				( attribute "BOM_SS" "NOPOP"
					( Origin gFrontEnd )
				)
				( objectStatus "C2B2" )
			)
			( gate "@baseboard_fab2_lib.baseboard_fab2(sch_1):page228_i205"
				( attribute "CDS_LIB" "dev_discrete"
					( Origin gPackager )
				)
				( attribute "CDS_LOCATION" "C8M9"
					( Origin gPackager )
				)
				( attribute "CDS_SEC" "1"
					( Origin gPackager )
				)
				( attribute "LOCATION" "C8M9"
					( Origin gFrontEnd )
				)
				( attribute "MATERIAL" "X5R"
					( Origin gFrontEnd )
				)
				( attribute "PACK_TYPE" "0603V"
					( Origin gFrontEnd )
				)
				( attribute "PART_NUMBER" "602433-106"
					( Origin gFrontEnd )
				)
				( attribute "PHYS_PAGE" "228"
					( Origin gFrontEnd )
				)
				( attribute "ROT" "0"
					( Origin gFrontEnd )
				)
				( attribute "SEC" "1"
					( Origin gFrontEnd )
				)
				( attribute "SEC_TYPE" "0603V"
					( Origin gFrontEnd )
				)
				( attribute "TOLERANCE" "20%"
					( Origin gFrontEnd )
				)
				( attribute "VALUE" "47UF"
					( Origin gFrontEnd )
				)
				( attribute "VER" "1"
					( Origin gFrontEnd )
				)
				( attribute "VOLTAGE" "4V"
					( Units "uVoltage" "V" 1.000000)
					( Origin gFrontEnd )
				)
				( attribute "XY" "(3975,1425)"
					( Origin gFrontEnd )
				)
				( attribute "CHIPS_PART_NAME" "CAP_A"
					( Origin gPackager )
				)
				( attribute "CDS_PART_NAME" "CAP_A_0603V-47UF,4V,20%,X5R,60A"
					( Origin gPackager )
				)
				( attribute "GROUP" "PWR_MLCC_CAP"
					( Origin gFrontEnd )
				)
				( attribute "BOM_SS" "NOPOP"
					( Origin gFrontEnd )
				)
				( objectStatus "C8M9" )
			)
			( gate "@baseboard_fab2_lib.baseboard_fab2(sch_1):page228_i206"
				( attribute "CDS_LIB" "dev_discrete"
					( Origin gPackager )
				)
				( attribute "CDS_LOCATION" "C8M2"
					( Origin gPackager )
				)
				( attribute "CDS_SEC" "1"
					( Origin gPackager )
				)
				( attribute "LOCATION" "C8M2"
					( Origin gFrontEnd )
				)
				( attribute "MATERIAL" "X5R"
					( Origin gFrontEnd )
				)
				( attribute "PACK_TYPE" "0603V"
					( Origin gFrontEnd )
				)
				( attribute "PART_NUMBER" "602433-106"
					( Origin gFrontEnd )
				)
				( attribute "PHYS_PAGE" "228"
					( Origin gFrontEnd )
				)
				( attribute "ROT" "0"
					( Origin gFrontEnd )
				)
				( attribute "SEC" "1"
					( Origin gFrontEnd )
				)
				( attribute "SEC_TYPE" "0603V"
					( Origin gFrontEnd )
				)
				( attribute "TOLERANCE" "20%"
					( Origin gFrontEnd )
				)
				( attribute "VALUE" "47UF"
					( Origin gFrontEnd )
				)
				( attribute "VER" "1"
					( Origin gFrontEnd )
				)
				( attribute "VOLTAGE" "4V"
					( Units "uVoltage" "V" 1.000000)
					( Origin gFrontEnd )
				)
				( attribute "XY" "(4375,1425)"
					( Origin gFrontEnd )
				)
				( attribute "CHIPS_PART_NAME" "CAP_A"
					( Origin gPackager )
				)
				( attribute "CDS_PART_NAME" "CAP_A_0603V-47UF,4V,20%,X5R,60A"
					( Origin gPackager )
				)
				( attribute "GROUP" "PWR_MLCC_CAP"
					( Origin gFrontEnd )
				)
				( attribute "BOM_SS" "NOPOP"
					( Origin gFrontEnd )
				)
				( objectStatus "C8M2" )
			)
			( gate "@baseboard_fab2_lib.baseboard_fab2(sch_1):page228_i299"
				( attribute "CDS_LIB" "dev_discrete"
					( Origin gPackager )
				)
				( attribute "CDS_LOCATION" "C8M3"
					( Origin gPackager )
				)
				( attribute "CDS_SEC" "1"
					( Origin gPackager )
				)
				( attribute "LOCATION" "C8M3"
					( Origin gFrontEnd )
				)
				( attribute "MATERIAL" "X5R"
					( Origin gFrontEnd )
				)
				( attribute "PACK_TYPE" "0603V"
					( Origin gFrontEnd )
				)
				( attribute "PART_NUMBER" "602433-106"
					( Origin gFrontEnd )
				)
				( attribute "PHYS_PAGE" "228"
					( Origin gFrontEnd )
				)
				( attribute "ROT" "0"
					( Origin gFrontEnd )
				)
				( attribute "SEC" "1"
					( Origin gFrontEnd )
				)
				( attribute "SEC_TYPE" "0603V"
					( Origin gFrontEnd )
				)
				( attribute "TOLERANCE" "20%"
					( Origin gFrontEnd )
				)
				( attribute "VALUE" "47UF"
					( Origin gFrontEnd )
				)
				( attribute "VER" "1"
					( Origin gFrontEnd )
				)
				( attribute "VOLTAGE" "4V"
					( Units "uVoltage" "V" 1.000000)
					( Origin gFrontEnd )
				)
				( attribute "XY" "(2150,-775)"
					( Origin gFrontEnd )
				)
				( attribute "CHIPS_PART_NAME" "CAP_A"
					( Origin gPackager )
				)
				( attribute "CDS_PART_NAME" "CAP_A_0603V-47UF,4V,20%,X5R,60A"
					( Origin gPackager )
				)
				( attribute "GROUP" "PWR_MLCC_CAP"
					( Origin gFrontEnd )
				)
				( attribute "BOM_SS" "E15431-004"
					( Origin gFrontEnd )
				)
				( objectStatus "C8M3" )
			)
			( gate "@baseboard_fab2_lib.baseboard_fab2(sch_1):page228_i298"
				( attribute "CDS_LIB" "dev_discrete"
					( Origin gPackager )
				)
				( attribute "CDS_LOCATION" "C8M5"
					( Origin gPackager )
				)
				( attribute "CDS_SEC" "1"
					( Origin gPackager )
				)
				( attribute "LOCATION" "C8M5"
					( Origin gFrontEnd )
				)
				( attribute "MATERIAL" "X5R"
					( Origin gFrontEnd )
				)
				( attribute "PACK_TYPE" "0603V"
					( Origin gFrontEnd )
				)
				( attribute "PART_NUMBER" "602433-106"
					( Origin gFrontEnd )
				)
				( attribute "PHYS_PAGE" "228"
					( Origin gFrontEnd )
				)
				( attribute "ROT" "0"
					( Origin gFrontEnd )
				)
				( attribute "SEC" "1"
					( Origin gFrontEnd )
				)
				( attribute "SEC_TYPE" "0603V"
					( Origin gFrontEnd )
				)
				( attribute "TOLERANCE" "20%"
					( Origin gFrontEnd )
				)
				( attribute "VALUE" "47UF"
					( Origin gFrontEnd )
				)
				( attribute "VER" "1"
					( Origin gFrontEnd )
				)
				( attribute "VOLTAGE" "4V"
					( Units "uVoltage" "V" 1.000000)
					( Origin gFrontEnd )
				)
				( attribute "XY" "(1875,-775)"
					( Origin gFrontEnd )
				)
				( attribute "CHIPS_PART_NAME" "CAP_A"
					( Origin gPackager )
				)
				( attribute "CDS_PART_NAME" "CAP_A_0603V-47UF,4V,20%,X5R,60A"
					( Origin gPackager )
				)
				( attribute "GROUP" "PWR_MLCC_CAP"
					( Origin gFrontEnd )
				)
				( attribute "BOM_SS" "E15431-004"
					( Origin gFrontEnd )
				)
				( objectStatus "C8M5" )
			)
			( gate "@baseboard_fab2_lib.baseboard_fab2(sch_1):page228_i297"
				( attribute "CDS_LIB" "dev_discrete"
					( Origin gPackager )
				)
				( attribute "CDS_LOCATION" "C8L10"
					( Origin gPackager )
				)
				( attribute "CDS_SEC" "1"
					( Origin gPackager )
				)
				( attribute "LOCATION" "C8L10"
					( Origin gFrontEnd )
				)
				( attribute "MATERIAL" "X5R"
					( Origin gFrontEnd )
				)
				( attribute "PACK_TYPE" "0603V"
					( Origin gFrontEnd )
				)
				( attribute "PART_NUMBER" "602433-106"
					( Origin gFrontEnd )
				)
				( attribute "PHYS_PAGE" "228"
					( Origin gFrontEnd )
				)
				( attribute "ROT" "0"
					( Origin gFrontEnd )
				)
				( attribute "SEC" "1"
					( Origin gFrontEnd )
				)
				( attribute "SEC_TYPE" "0603V"
					( Origin gFrontEnd )
				)
				( attribute "TOLERANCE" "20%"
					( Origin gFrontEnd )
				)
				( attribute "VALUE" "47UF"
					( Origin gFrontEnd )
				)
				( attribute "VER" "1"
					( Origin gFrontEnd )
				)
				( attribute "VOLTAGE" "4V"
					( Units "uVoltage" "V" 1.000000)
					( Origin gFrontEnd )
				)
				( attribute "XY" "(1575,-775)"
					( Origin gFrontEnd )
				)
				( attribute "CHIPS_PART_NAME" "CAP_A"
					( Origin gPackager )
				)
				( attribute "CDS_PART_NAME" "CAP_A_0603V-47UF,4V,20%,X5R,60A"
					( Origin gPackager )
				)
				( attribute "GROUP" "PWR_MLCC_CAP"
					( Origin gFrontEnd )
				)
				( attribute "BOM_SS" "E15431-004"
					( Origin gFrontEnd )
				)
				( objectStatus "C8L10" )
			)
			( gate "@baseboard_fab2_lib.baseboard_fab2(sch_1):page228_i296"
				( attribute "CDS_LIB" "dev_discrete"
					( Origin gPackager )
				)
				( attribute "CDS_LOCATION" "C2A3"
					( Origin gPackager )
				)
				( attribute "CDS_SEC" "1"
					( Origin gPackager )
				)
				( attribute "LOCATION" "C2A3"
					( Origin gFrontEnd )
				)
				( attribute "MATERIAL" "X5R"
					( Origin gFrontEnd )
				)
				( attribute "PACK_TYPE" "0603V"
					( Origin gFrontEnd )
				)
				( attribute "PART_NUMBER" "602433-106"
					( Origin gFrontEnd )
				)
				( attribute "PHYS_PAGE" "228"
					( Origin gFrontEnd )
				)
				( attribute "ROT" "0"
					( Origin gFrontEnd )
				)
				( attribute "SEC" "1"
					( Origin gFrontEnd )
				)
				( attribute "SEC_TYPE" "0603V"
					( Origin gFrontEnd )
				)
				( attribute "TOLERANCE" "20%"
					( Origin gFrontEnd )
				)
				( attribute "VALUE" "47UF"
					( Origin gFrontEnd )
				)
				( attribute "VER" "1"
					( Origin gFrontEnd )
				)
				( attribute "VOLTAGE" "4V"
					( Units "uVoltage" "V" 1.000000)
					( Origin gFrontEnd )
				)
				( attribute "XY" "(1275,-775)"
					( Origin gFrontEnd )
				)
				( attribute "CHIPS_PART_NAME" "CAP_A"
					( Origin gPackager )
				)
				( attribute "CDS_PART_NAME" "CAP_A_0603V-47UF,4V,20%,X5R,60A"
					( Origin gPackager )
				)
				( attribute "GROUP" "PWR_MLCC_CAP"
					( Origin gFrontEnd )
				)
				( attribute "BOM_SS" "E15431-004"
					( Origin gFrontEnd )
				)
				( objectStatus "C2A3" )
			)
			( gate "@baseboard_fab2_lib.baseboard_fab2(sch_1):page228_i295"
				( attribute "CDS_LIB" "dev_discrete"
					( Origin gPackager )
				)
				( attribute "CDS_LOCATION" "C7M1"
					( Origin gPackager )
				)
				( attribute "CDS_SEC" "1"
					( Origin gPackager )
				)
				( attribute "LOCATION" "C7M1"
					( Origin gFrontEnd )
				)
				( attribute "MATERIAL" "X5R"
					( Origin gFrontEnd )
				)
				( attribute "PACK_TYPE" "0603V"
					( Origin gFrontEnd )
				)
				( attribute "PART_NUMBER" "602433-106"
					( Origin gFrontEnd )
				)
				( attribute "PHYS_PAGE" "228"
					( Origin gFrontEnd )
				)
				( attribute "ROT" "0"
					( Origin gFrontEnd )
				)
				( attribute "SEC" "1"
					( Origin gFrontEnd )
				)
				( attribute "SEC_TYPE" "0603V"
					( Origin gFrontEnd )
				)
				( attribute "TOLERANCE" "20%"
					( Origin gFrontEnd )
				)
				( attribute "VALUE" "47UF"
					( Origin gFrontEnd )
				)
				( attribute "VER" "1"
					( Origin gFrontEnd )
				)
				( attribute "VOLTAGE" "4V"
					( Units "uVoltage" "V" 1.000000)
					( Origin gFrontEnd )
				)
				( attribute "XY" "(1000,-775)"
					( Origin gFrontEnd )
				)
				( attribute "CHIPS_PART_NAME" "CAP_A"
					( Origin gPackager )
				)
				( attribute "CDS_PART_NAME" "CAP_A_0603V-47UF,4V,20%,X5R,60A"
					( Origin gPackager )
				)
				( attribute "GROUP" "PWR_MLCC_CAP"
					( Origin gFrontEnd )
				)
				( attribute "BOM_SS" "E15431-004"
					( Origin gFrontEnd )
				)
				( objectStatus "C7M1" )
			)
			( gate "@baseboard_fab2_lib.baseboard_fab2(sch_1):page228_i294"
				( attribute "CDS_LIB" "dev_discrete"
					( Origin gPackager )
				)
				( attribute "CDS_LOCATION" "C7M2"
					( Origin gPackager )
				)
				( attribute "CDS_SEC" "1"
					( Origin gPackager )
				)
				( attribute "LOCATION" "C7M2"
					( Origin gFrontEnd )
				)
				( attribute "MATERIAL" "X5R"
					( Origin gFrontEnd )
				)
				( attribute "PACK_TYPE" "0603V"
					( Origin gFrontEnd )
				)
				( attribute "PART_NUMBER" "602433-106"
					( Origin gFrontEnd )
				)
				( attribute "PHYS_PAGE" "228"
					( Origin gFrontEnd )
				)
				( attribute "ROT" "0"
					( Origin gFrontEnd )
				)
				( attribute "SEC" "1"
					( Origin gFrontEnd )
				)
				( attribute "SEC_TYPE" "0603V"
					( Origin gFrontEnd )
				)
				( attribute "TOLERANCE" "20%"
					( Origin gFrontEnd )
				)
				( attribute "VALUE" "47UF"
					( Origin gFrontEnd )
				)
				( attribute "VER" "1"
					( Origin gFrontEnd )
				)
				( attribute "VOLTAGE" "4V"
					( Units "uVoltage" "V" 1.000000)
					( Origin gFrontEnd )
				)
				( attribute "XY" "(725,-775)"
					( Origin gFrontEnd )
				)
				( attribute "CHIPS_PART_NAME" "CAP_A"
					( Origin gPackager )
				)
				( attribute "CDS_PART_NAME" "CAP_A_0603V-47UF,4V,20%,X5R,60A"
					( Origin gPackager )
				)
				( attribute "GROUP" "PWR_MLCC_CAP"
					( Origin gFrontEnd )
				)
				( attribute "BOM_SS" "E15431-004"
					( Origin gFrontEnd )
				)
				( objectStatus "C7M2" )
			)
			( gate "@baseboard_fab2_lib.baseboard_fab2(sch_1):page228_i293"
				( attribute "CDS_LIB" "dev_discrete"
					( Origin gPackager )
				)
				( attribute "CDS_LOCATION" "C8M4"
					( Origin gPackager )
				)
				( attribute "CDS_SEC" "1"
					( Origin gPackager )
				)
				( attribute "LOCATION" "C8M4"
					( Origin gFrontEnd )
				)
				( attribute "MATERIAL" "X5R"
					( Origin gFrontEnd )
				)
				( attribute "PACK_TYPE" "0603V"
					( Origin gFrontEnd )
				)
				( attribute "PART_NUMBER" "602433-106"
					( Origin gFrontEnd )
				)
				( attribute "PHYS_PAGE" "228"
					( Origin gFrontEnd )
				)
				( attribute "ROT" "0"
					( Origin gFrontEnd )
				)
				( attribute "SEC" "1"
					( Origin gFrontEnd )
				)
				( attribute "SEC_TYPE" "0603V"
					( Origin gFrontEnd )
				)
				( attribute "TOLERANCE" "20%"
					( Origin gFrontEnd )
				)
				( attribute "VALUE" "47UF"
					( Origin gFrontEnd )
				)
				( attribute "VER" "1"
					( Origin gFrontEnd )
				)
				( attribute "VOLTAGE" "4V"
					( Units "uVoltage" "V" 1.000000)
					( Origin gFrontEnd )
				)
				( attribute "XY" "(425,-775)"
					( Origin gFrontEnd )
				)
				( attribute "CHIPS_PART_NAME" "CAP_A"
					( Origin gPackager )
				)
				( attribute "CDS_PART_NAME" "CAP_A_0603V-47UF,4V,20%,X5R,60A"
					( Origin gPackager )
				)
				( attribute "GROUP" "PWR_MLCC_CAP"
					( Origin gFrontEnd )
				)
				( attribute "BOM_SS" "E15431-004"
					( Origin gFrontEnd )
				)
				( objectStatus "C8M4" )
			)
			( gate "@baseboard_fab2_lib.baseboard_fab2(sch_1):page228_i292"
				( attribute "CDS_LIB" "dev_discrete"
					( Origin gPackager )
				)
				( attribute "CDS_LOCATION" "C2A4"
					( Origin gPackager )
				)
				( attribute "CDS_SEC" "1"
					( Origin gPackager )
				)
				( attribute "LOCATION" "C2A4"
					( Origin gFrontEnd )
				)
				( attribute "MATERIAL" "X5R"
					( Origin gFrontEnd )
				)
				( attribute "PACK_TYPE" "0603V"
					( Origin gFrontEnd )
				)
				( attribute "PART_NUMBER" "602433-106"
					( Origin gFrontEnd )
				)
				( attribute "PHYS_PAGE" "228"
					( Origin gFrontEnd )
				)
				( attribute "ROT" "0"
					( Origin gFrontEnd )
				)
				( attribute "SEC" "1"
					( Origin gFrontEnd )
				)
				( attribute "SEC_TYPE" "0603V"
					( Origin gFrontEnd )
				)
				( attribute "TOLERANCE" "20%"
					( Origin gFrontEnd )
				)
				( attribute "VALUE" "47UF"
					( Origin gFrontEnd )
				)
				( attribute "VER" "1"
					( Origin gFrontEnd )
				)
				( attribute "VOLTAGE" "4V"
					( Units "uVoltage" "V" 1.000000)
					( Origin gFrontEnd )
				)
				( attribute "XY" "(125,-775)"
					( Origin gFrontEnd )
				)
				( attribute "CHIPS_PART_NAME" "CAP_A"
					( Origin gPackager )
				)
				( attribute "CDS_PART_NAME" "CAP_A_0603V-47UF,4V,20%,X5R,60A"
					( Origin gPackager )
				)
				( attribute "GROUP" "PWR_MLCC_CAP"
					( Origin gFrontEnd )
				)
				( attribute "BOM_SS" "E15431-004"
					( Origin gFrontEnd )
				)
				( objectStatus "C2A4" )
			)
			( gate "@baseboard_fab2_lib.baseboard_fab2(sch_1):page228_i291"
				( attribute "CDS_LIB" "dev_discrete"
					( Origin gPackager )
				)
				( attribute "CDS_LOCATION" "C8M6"
					( Origin gPackager )
				)
				( attribute "CDS_SEC" "1"
					( Origin gPackager )
				)
				( attribute "LOCATION" "C8M6"
					( Origin gFrontEnd )
				)
				( attribute "MATERIAL" "X5R"
					( Origin gFrontEnd )
				)
				( attribute "PACK_TYPE" "0603V"
					( Origin gFrontEnd )
				)
				( attribute "PART_NUMBER" "602433-106"
					( Origin gFrontEnd )
				)
				( attribute "PHYS_PAGE" "228"
					( Origin gFrontEnd )
				)
				( attribute "ROT" "0"
					( Origin gFrontEnd )
				)
				( attribute "SEC" "1"
					( Origin gFrontEnd )
				)
				( attribute "SEC_TYPE" "0603V"
					( Origin gFrontEnd )
				)
				( attribute "TOLERANCE" "20%"
					( Origin gFrontEnd )
				)
				( attribute "VALUE" "47UF"
					( Origin gFrontEnd )
				)
				( attribute "VER" "1"
					( Origin gFrontEnd )
				)
				( attribute "VOLTAGE" "4V"
					( Units "uVoltage" "V" 1.000000)
					( Origin gFrontEnd )
				)
				( attribute "XY" "(-200,-775)"
					( Origin gFrontEnd )
				)
				( attribute "CHIPS_PART_NAME" "CAP_A"
					( Origin gPackager )
				)
				( attribute "CDS_PART_NAME" "CAP_A_0603V-47UF,4V,20%,X5R,60A"
					( Origin gPackager )
				)
				( attribute "GROUP" "PWR_MLCC_CAP"
					( Origin gFrontEnd )
				)
				( attribute "BOM_SS" "E15431-004"
					( Origin gFrontEnd )
				)
				( objectStatus "C8M6" )
			)
			( gate "@baseboard_fab2_lib.baseboard_fab2(sch_1):page228_i290"
				( attribute "CDS_LIB" "dev_discrete"
					( Origin gPackager )
				)
				( attribute "CDS_LOCATION" "C8L9"
					( Origin gPackager )
				)
				( attribute "CDS_SEC" "1"
					( Origin gPackager )
				)
				( attribute "LOCATION" "C8L9"
					( Origin gFrontEnd )
				)
				( attribute "MATERIAL" "X5R"
					( Origin gFrontEnd )
				)
				( attribute "PACK_TYPE" "0603V"
					( Origin gFrontEnd )
				)
				( attribute "PART_NUMBER" "602433-106"
					( Origin gFrontEnd )
				)
				( attribute "PHYS_PAGE" "228"
					( Origin gFrontEnd )
				)
				( attribute "ROT" "0"
					( Origin gFrontEnd )
				)
				( attribute "SEC" "1"
					( Origin gFrontEnd )
				)
				( attribute "SEC_TYPE" "0603V"
					( Origin gFrontEnd )
				)
				( attribute "TOLERANCE" "20%"
					( Origin gFrontEnd )
				)
				( attribute "VALUE" "47UF"
					( Origin gFrontEnd )
				)
				( attribute "VER" "1"
					( Origin gFrontEnd )
				)
				( attribute "VOLTAGE" "4V"
					( Units "uVoltage" "V" 1.000000)
					( Origin gFrontEnd )
				)
				( attribute "XY" "(-475,-775)"
					( Origin gFrontEnd )
				)
				( attribute "CHIPS_PART_NAME" "CAP_A"
					( Origin gPackager )
				)
				( attribute "CDS_PART_NAME" "CAP_A_0603V-47UF,4V,20%,X5R,60A"
					( Origin gPackager )
				)
				( attribute "GROUP" "PWR_MLCC_CAP"
					( Origin gFrontEnd )
				)
				( attribute "BOM_SS" "E15431-004"
					( Origin gFrontEnd )
				)
				( objectStatus "C8L9" )
			)
			( gate "@baseboard_fab2_lib.baseboard_fab2(sch_1):page228_i289"
				( attribute "CDS_LIB" "dev_discrete"
					( Origin gPackager )
				)
				( attribute "CDS_LOCATION" "C8L8"
					( Origin gPackager )
				)
				( attribute "CDS_SEC" "1"
					( Origin gPackager )
				)
				( attribute "LOCATION" "C8L8"
					( Origin gFrontEnd )
				)
				( attribute "MATERIAL" "X5R"
					( Origin gFrontEnd )
				)
				( attribute "PACK_TYPE" "0603V"
					( Origin gFrontEnd )
				)
				( attribute "PART_NUMBER" "602433-106"
					( Origin gFrontEnd )
				)
				( attribute "PHYS_PAGE" "228"
					( Origin gFrontEnd )
				)
				( attribute "ROT" "0"
					( Origin gFrontEnd )
				)
				( attribute "SEC" "1"
					( Origin gFrontEnd )
				)
				( attribute "SEC_TYPE" "0603V"
					( Origin gFrontEnd )
				)
				( attribute "TOLERANCE" "20%"
					( Origin gFrontEnd )
				)
				( attribute "VALUE" "47UF"
					( Origin gFrontEnd )
				)
				( attribute "VER" "1"
					( Origin gFrontEnd )
				)
				( attribute "VOLTAGE" "4V"
					( Units "uVoltage" "V" 1.000000)
					( Origin gFrontEnd )
				)
				( attribute "XY" "(-775,-775)"
					( Origin gFrontEnd )
				)
				( attribute "CHIPS_PART_NAME" "CAP_A"
					( Origin gPackager )
				)
				( attribute "CDS_PART_NAME" "CAP_A_0603V-47UF,4V,20%,X5R,60A"
					( Origin gPackager )
				)
				( attribute "GROUP" "PWR_MLCC_CAP"
					( Origin gFrontEnd )
				)
				( attribute "BOM_SS" "E15431-004"
					( Origin gFrontEnd )
				)
				( objectStatus "C8L8" )
			)
			( gate "@baseboard_fab2_lib.baseboard_fab2(sch_1):page228_i288"
				( attribute "CDS_LIB" "dev_discrete"
					( Origin gPackager )
				)
				( attribute "CDS_LOCATION" "C7L4"
					( Origin gPackager )
				)
				( attribute "CDS_SEC" "1"
					( Origin gPackager )
				)
				( attribute "LOCATION" "C7L4"
					( Origin gFrontEnd )
				)
				( attribute "MATERIAL" "X5R"
					( Origin gFrontEnd )
				)
				( attribute "PACK_TYPE" "0603V"
					( Origin gFrontEnd )
				)
				( attribute "PART_NUMBER" "602433-106"
					( Origin gFrontEnd )
				)
				( attribute "PHYS_PAGE" "228"
					( Origin gFrontEnd )
				)
				( attribute "ROT" "0"
					( Origin gFrontEnd )
				)
				( attribute "SEC" "1"
					( Origin gFrontEnd )
				)
				( attribute "SEC_TYPE" "0603V"
					( Origin gFrontEnd )
				)
				( attribute "TOLERANCE" "20%"
					( Origin gFrontEnd )
				)
				( attribute "VALUE" "47UF"
					( Origin gFrontEnd )
				)
				( attribute "VER" "1"
					( Origin gFrontEnd )
				)
				( attribute "VOLTAGE" "4V"
					( Units "uVoltage" "V" 1.000000)
					( Origin gFrontEnd )
				)
				( attribute "XY" "(-1075,-775)"
					( Origin gFrontEnd )
				)
				( attribute "CHIPS_PART_NAME" "CAP_A"
					( Origin gPackager )
				)
				( attribute "CDS_PART_NAME" "CAP_A_0603V-47UF,4V,20%,X5R,60A"
					( Origin gPackager )
				)
				( attribute "GROUP" "PWR_MLCC_CAP"
					( Origin gFrontEnd )
				)
				( attribute "BOM_SS" "E15431-004"
					( Origin gFrontEnd )
				)
				( objectStatus "C7L4" )
			)
			( gate "@baseboard_fab2_lib.baseboard_fab2(sch_1):page228_i287"
				( attribute "CDS_LIB" "dev_discrete"
					( Origin gPackager )
				)
				( attribute "CDS_LOCATION" "C8L7"
					( Origin gPackager )
				)
				( attribute "CDS_SEC" "1"
					( Origin gPackager )
				)
				( attribute "LOCATION" "C8L7"
					( Origin gFrontEnd )
				)
				( attribute "MATERIAL" "X5R"
					( Origin gFrontEnd )
				)
				( attribute "PACK_TYPE" "0603V"
					( Origin gFrontEnd )
				)
				( attribute "PART_NUMBER" "602433-106"
					( Origin gFrontEnd )
				)
				( attribute "PHYS_PAGE" "228"
					( Origin gFrontEnd )
				)
				( attribute "ROT" "0"
					( Origin gFrontEnd )
				)
				( attribute "SEC" "1"
					( Origin gFrontEnd )
				)
				( attribute "SEC_TYPE" "0603V"
					( Origin gFrontEnd )
				)
				( attribute "TOLERANCE" "20%"
					( Origin gFrontEnd )
				)
				( attribute "VALUE" "47UF"
					( Origin gFrontEnd )
				)
				( attribute "VER" "1"
					( Origin gFrontEnd )
				)
				( attribute "VOLTAGE" "4V"
					( Units "uVoltage" "V" 1.000000)
					( Origin gFrontEnd )
				)
				( attribute "XY" "(-1350,-775)"
					( Origin gFrontEnd )
				)
				( attribute "CHIPS_PART_NAME" "CAP_A"
					( Origin gPackager )
				)
				( attribute "CDS_PART_NAME" "CAP_A_0603V-47UF,4V,20%,X5R,60A"
					( Origin gPackager )
				)
				( attribute "GROUP" "PWR_MLCC_CAP"
					( Origin gFrontEnd )
				)
				( attribute "BOM_SS" "E15431-004"
					( Origin gFrontEnd )
				)
				( objectStatus "C8L7" )
			)
			( gate "@baseboard_fab2_lib.baseboard_fab2(sch_1):page228_i286"
				( attribute "CDS_LIB" "dev_discrete"
					( Origin gPackager )
				)
				( attribute "CDS_LOCATION" "C8L6"
					( Origin gPackager )
				)
				( attribute "CDS_SEC" "1"
					( Origin gPackager )
				)
				( attribute "LOCATION" "C8L6"
					( Origin gFrontEnd )
				)
				( attribute "MATERIAL" "X5R"
					( Origin gFrontEnd )
				)
				( attribute "PACK_TYPE" "0603V"
					( Origin gFrontEnd )
				)
				( attribute "PART_NUMBER" "602433-106"
					( Origin gFrontEnd )
				)
				( attribute "PHYS_PAGE" "228"
					( Origin gFrontEnd )
				)
				( attribute "ROT" "0"
					( Origin gFrontEnd )
				)
				( attribute "SEC" "1"
					( Origin gFrontEnd )
				)
				( attribute "SEC_TYPE" "0603V"
					( Origin gFrontEnd )
				)
				( attribute "TOLERANCE" "20%"
					( Origin gFrontEnd )
				)
				( attribute "VALUE" "47UF"
					( Origin gFrontEnd )
				)
				( attribute "VER" "1"
					( Origin gFrontEnd )
				)
				( attribute "VOLTAGE" "4V"
					( Units "uVoltage" "V" 1.000000)
					( Origin gFrontEnd )
				)
				( attribute "XY" "(-1625,-775)"
					( Origin gFrontEnd )
				)
				( attribute "CHIPS_PART_NAME" "CAP_A"
					( Origin gPackager )
				)
				( attribute "CDS_PART_NAME" "CAP_A_0603V-47UF,4V,20%,X5R,60A"
					( Origin gPackager )
				)
				( attribute "GROUP" "PWR_MLCC_CAP"
					( Origin gFrontEnd )
				)
				( attribute "BOM_SS" "E15431-004"
					( Origin gFrontEnd )
				)
				( objectStatus "C8L6" )
			)
			( gate "@baseboard_fab2_lib.baseboard_fab2(sch_1):page228_i285"
				( attribute "CDS_LIB" "dev_discrete"
					( Origin gPackager )
				)
				( attribute "CDS_LOCATION" "C8L5"
					( Origin gPackager )
				)
				( attribute "CDS_SEC" "1"
					( Origin gPackager )
				)
				( attribute "LOCATION" "C8L5"
					( Origin gFrontEnd )
				)
				( attribute "MATERIAL" "X5R"
					( Origin gFrontEnd )
				)
				( attribute "PACK_TYPE" "0603V"
					( Origin gFrontEnd )
				)
				( attribute "PART_NUMBER" "602433-106"
					( Origin gFrontEnd )
				)
				( attribute "PHYS_PAGE" "228"
					( Origin gFrontEnd )
				)
				( attribute "ROT" "0"
					( Origin gFrontEnd )
				)
				( attribute "SEC" "1"
					( Origin gFrontEnd )
				)
				( attribute "SEC_TYPE" "0603V"
					( Origin gFrontEnd )
				)
				( attribute "TOLERANCE" "20%"
					( Origin gFrontEnd )
				)
				( attribute "VALUE" "47UF"
					( Origin gFrontEnd )
				)
				( attribute "VER" "1"
					( Origin gFrontEnd )
				)
				( attribute "VOLTAGE" "4V"
					( Units "uVoltage" "V" 1.000000)
					( Origin gFrontEnd )
				)
				( attribute "XY" "(-1925,-775)"
					( Origin gFrontEnd )
				)
				( attribute "CHIPS_PART_NAME" "CAP_A"
					( Origin gPackager )
				)
				( attribute "CDS_PART_NAME" "CAP_A_0603V-47UF,4V,20%,X5R,60A"
					( Origin gPackager )
				)
				( attribute "GROUP" "PWR_MLCC_CAP"
					( Origin gFrontEnd )
				)
				( attribute "BOM_SS" "E15431-004"
					( Origin gFrontEnd )
				)
				( objectStatus "C8L5" )
			)
			( gate "@baseboard_fab2_lib.baseboard_fab2(sch_1):page228_i284"
				( attribute "CDS_LIB" "dev_discrete"
					( Origin gPackager )
				)
				( attribute "CDS_LOCATION" "C8M1"
					( Origin gPackager )
				)
				( attribute "CDS_SEC" "1"
					( Origin gPackager )
				)
				( attribute "LOCATION" "C8M1"
					( Origin gFrontEnd )
				)
				( attribute "MATERIAL" "X5R"
					( Origin gFrontEnd )
				)
				( attribute "PACK_TYPE" "0603V"
					( Origin gFrontEnd )
				)
				( attribute "PART_NUMBER" "602433-106"
					( Origin gFrontEnd )
				)
				( attribute "PHYS_PAGE" "228"
					( Origin gFrontEnd )
				)
				( attribute "ROT" "0"
					( Origin gFrontEnd )
				)
				( attribute "SEC" "1"
					( Origin gFrontEnd )
				)
				( attribute "SEC_TYPE" "0603V"
					( Origin gFrontEnd )
				)
				( attribute "TOLERANCE" "20%"
					( Origin gFrontEnd )
				)
				( attribute "VALUE" "47UF"
					( Origin gFrontEnd )
				)
				( attribute "VER" "1"
					( Origin gFrontEnd )
				)
				( attribute "VOLTAGE" "4V"
					( Units "uVoltage" "V" 1.000000)
					( Origin gFrontEnd )
				)
				( attribute "XY" "(-2225,-775)"
					( Origin gFrontEnd )
				)
				( attribute "CHIPS_PART_NAME" "CAP_A"
					( Origin gPackager )
				)
				( attribute "CDS_PART_NAME" "CAP_A_0603V-47UF,4V,20%,X5R,60A"
					( Origin gPackager )
				)
				( attribute "GROUP" "PWR_MLCC_CAP"
					( Origin gFrontEnd )
				)
				( attribute "BOM_SS" "E15431-004"
					( Origin gFrontEnd )
				)
				( objectStatus "C8M1" )
			)
			( gate "@baseboard_fab2_lib.baseboard_fab2(sch_1):page228_i245"
				( attribute "CDS_LIB" "mstr_misc"
					( Origin gPackager )
				)
				( attribute "CDS_LOCATION" "SH7L2"
					( Origin gPackager )
				)
				( attribute "CDS_SEC" "1"
					( Origin gPackager )
				)
				( attribute "LOCATION" "SH7L2"
					( Origin gFrontEnd )
				)
				( attribute "MATERIAL" "EMPTY"
					( Origin gFrontEnd )
				)
				( attribute "PACK_TYPE" "SH0201"
					( Origin gFrontEnd )
				)
				( attribute "PART_NUMBER" "N_A"
					( Origin gFrontEnd )
				)
				( attribute "PHYS_PAGE" "228"
					( Origin gFrontEnd )
				)
				( attribute "PIN_SHORT" "A:B"
					( Origin gFrontEnd )
				)
				( attribute "ROT" "0"
					( Origin gFrontEnd )
				)
				( attribute "SEC" "1"
					( Origin gFrontEnd )
				)
				( attribute "SEC_TYPE" "SH0201"
					( Origin gFrontEnd )
				)
				( attribute "VER" "1"
					( Origin gFrontEnd )
				)
				( attribute "XY" "(75,2175)"
					( Origin gFrontEnd )
				)
				( attribute "CHIPS_PART_NAME" "SHUNT"
					( Origin gPackager )
				)
				( attribute "CDS_PART_NAME" "SHUNT_SH0201-EMPTY,N_A"
					( Origin gPackager )
				)
				( objectStatus "SH7L2" )
			)
			( gate "@baseboard_fab2_lib.baseboard_fab2(sch_1):page228_i246"
				( attribute "CDS_LIB" "mstr_misc"
					( Origin gPackager )
				)
				( attribute "CDS_LOCATION" "SH7L1"
					( Origin gPackager )
				)
				( attribute "CDS_SEC" "1"
					( Origin gPackager )
				)
				( attribute "LOCATION" "SH7L1"
					( Origin gFrontEnd )
				)
				( attribute "MATERIAL" "EMPTY"
					( Origin gFrontEnd )
				)
				( attribute "PACK_TYPE" "SH0201"
					( Origin gFrontEnd )
				)
				( attribute "PART_NUMBER" "N_A"
					( Origin gFrontEnd )
				)
				( attribute "PHYS_PAGE" "228"
					( Origin gFrontEnd )
				)
				( attribute "PIN_SHORT" "A:B"
					( Origin gFrontEnd )
				)
				( attribute "ROT" "0"
					( Origin gFrontEnd )
				)
				( attribute "SEC" "1"
					( Origin gFrontEnd )
				)
				( attribute "SEC_TYPE" "SH0201"
					( Origin gFrontEnd )
				)
				( attribute "VER" "1"
					( Origin gFrontEnd )
				)
				( attribute "XY" "(75,1725)"
					( Origin gFrontEnd )
				)
				( attribute "CHIPS_PART_NAME" "SHUNT"
					( Origin gPackager )
				)
				( attribute "CDS_PART_NAME" "SHUNT_SH0201-EMPTY,N_A"
					( Origin gPackager )
				)
				( objectStatus "SH7L1" )
			)
			( gate "@baseboard_fab2_lib.baseboard_fab2(sch_1):page229_i14"
				( attribute "CDS_LIB" "mstr_discrete"
					( Origin gPackager )
				)
				( attribute "CDS_LOCATION" "C6U11"
					( Origin gPackager )
				)
				( attribute "CDS_SEC" "1"
					( Origin gPackager )
				)
				( attribute "LOCATION" "C6U11"
					( Origin gFrontEnd )
				)
				( attribute "MATERIAL" "X6S"
					( Origin gFrontEnd )
				)
				( attribute "PACK_TYPE" "0603"
					( Origin gFrontEnd )
				)
				( attribute "PART_NUMBER" "E15431-003"
					( Origin gFrontEnd )
				)
				( attribute "PHYS_PAGE" "229"
					( Origin gFrontEnd )
				)
				( attribute "ROOM" "VTT_GHJ_PWR_VR"
					( Origin gFrontEnd )
				)
				( attribute "ROT" "0"
					( Origin gFrontEnd )
				)
				( attribute "SEC" "1"
					( Origin gFrontEnd )
				)
				( attribute "SEC_TYPE" "0603"
					( Origin gFrontEnd )
				)
				( attribute "TOLERANCE" "10%"
					( Origin gFrontEnd )
				)
				( attribute "VALUE" "4.7UF"
					( Origin gFrontEnd )
				)
				( attribute "VER" "1"
					( Origin gFrontEnd )
				)
				( attribute "VOLTAGE" "6.3V"
					( Units "uVoltage" "V" 1.000000)
					( Origin gFrontEnd )
				)
				( attribute "XY" "(200,825)"
					( Origin gFrontEnd )
				)
				( attribute "CHIPS_PART_NAME" "CAP"
					( Origin gPackager )
				)
				( attribute "CDS_PART_NAME" "CAP_0603-4.7UF,6.3V,10%,X6S,E1A"
					( Origin gPackager )
				)
				( objectStatus "C6U11" )
			)
			( gate "@baseboard_fab2_lib.baseboard_fab2(sch_1):page226_i49"
				( attribute "CDS_LIB" "mstr_discrete"
					( Origin gPackager )
				)
				( attribute "CDS_LOCATION" "R1B1"
					( Origin gPackager )
				)
				( attribute "CDS_SEC" "1"
					( Origin gPackager )
				)
				( attribute "LOCATION" "R1B1"
					( Origin gFrontEnd )
				)
				( attribute "MATERIAL" "CHIP"
					( Origin gFrontEnd )
				)
				( attribute "PACK_TYPE" "0402"
					( Origin gFrontEnd )
				)
				( attribute "PART_NUMBER" "G21796-026"
					( Origin gFrontEnd )
				)
				( attribute "PHYS_PAGE" "226"
					( Origin gFrontEnd )
				)
				( attribute "ROOM" "RQ_PVDDQ_KLM_VRHOT_LVT3_N"
					( Origin gFrontEnd )
				)
				( attribute "ROT" "0"
					( Origin gFrontEnd )
				)
				( attribute "SEC" "1"
					( Origin gFrontEnd )
				)
				( attribute "SEC_TYPE" "0402"
					( Origin gFrontEnd )
				)
				( attribute "TOLERANCE" "1%"
					( Origin gFrontEnd )
				)
				( attribute "VALUE" "1.00K"
					( Origin gFrontEnd )
				)
				( attribute "VER" "2"
					( Origin gFrontEnd )
				)
				( attribute "WATTAGE" "1/16W"
					( Origin gFrontEnd )
				)
				( attribute "XY" "(1825,2350)"
					( Origin gFrontEnd )
				)
				( attribute "CHIPS_PART_NAME" "RES"
					( Origin gPackager )
				)
				( attribute "CDS_PART_NAME" "RES_0402-1.00K,1%,1/16W,CHIP,GA"
					( Origin gPackager )
				)
				( objectStatus "R1B1" )
			)
			( gate "@baseboard_fab2_lib.baseboard_fab2(sch_1):page226_i48"
				( attribute "CDS_LIB" "mstr_discrete"
					( Origin gPackager )
				)
				( attribute "CDS_LOCATION" "R1B11"
					( Origin gPackager )
				)
				( attribute "CDS_SEC" "1"
					( Origin gPackager )
				)
				( attribute "LOCATION" "R1B11"
					( Origin gFrontEnd )
				)
				( attribute "MATERIAL" "CHIP"
					( Origin gFrontEnd )
				)
				( attribute "PACK_TYPE" "0402"
					( Origin gFrontEnd )
				)
				( attribute "PART_NUMBER" "G21497-005"
					( Origin gFrontEnd )
				)
				( attribute "PHYS_PAGE" "226"
					( Origin gFrontEnd )
				)
				( attribute "ROOM" "VDDQ_KLM_PWR_VR"
					( Origin gFrontEnd )
				)
				( attribute "ROT" "0"
					( Origin gFrontEnd )
				)
				( attribute "SEC" "1"
					( Origin gFrontEnd )
				)
				( attribute "SEC_TYPE" "0402"
					( Origin gFrontEnd )
				)
				( attribute "TOLERANCE" "5%"
					( Origin gFrontEnd )
				)
				( attribute "VALUE" "0.0"
					( Origin gFrontEnd )
				)
				( attribute "VER" "1"
					( Origin gFrontEnd )
				)
				( attribute "WATTAGE" "1/16W"
					( Origin gFrontEnd )
				)
				( attribute "XY" "(2325,1675)"
					( Origin gFrontEnd )
				)
				( attribute "CHIPS_PART_NAME" "RES"
					( Origin gPackager )
				)
				( attribute "CDS_PART_NAME" "RES_0402-0.0,5%,1/16W,CHIP,G21A"
					( Origin gPackager )
				)
				( objectStatus "R1B11" )
			)
			( gate "@baseboard_fab2_lib.baseboard_fab2(sch_1):page229_i21"
				( attribute "BOM_COST" "MEM_VRD_VTT_GHJ"
					( Origin gFrontEnd )
				)
				( attribute "CDS_LIB" "mstr_discrete"
					( Origin gPackager )
				)
				( attribute "CDS_LOCATION" "C4G21"
					( Origin gPackager )
				)
				( attribute "CDS_SEC" "1"
					( Origin gPackager )
				)
				( attribute "LOCATION" "C4G21"
					( Origin gFrontEnd )
				)
				( attribute "MATERIAL" "X6S"
					( Origin gFrontEnd )
				)
				( attribute "PACK_TYPE" "0402"
					( Origin gFrontEnd )
				)
				( attribute "PART_NUMBER" "D97712-011"
					( Origin gFrontEnd )
				)
				( attribute "PHYS_PAGE" "229"
					( Origin gFrontEnd )
				)
				( attribute "ROOM" "VTT_GHJ_PWR_VR"
					( Origin gFrontEnd )
				)
				( attribute "ROT" "0"
					( Origin gFrontEnd )
				)
				( attribute "SEC" "1"
					( Origin gFrontEnd )
				)
				( attribute "SEC_TYPE" "0402"
					( Origin gFrontEnd )
				)
				( attribute "TOLERANCE" "10%"
					( Origin gFrontEnd )
				)
				( attribute "VALUE" "1.0UF"
					( Origin gFrontEnd )
				)
				( attribute "VER" "1"
					( Origin gFrontEnd )
				)
				( attribute "VOLTAGE" "16V"
					( Units "uVoltage" "V" 1.000000)
					( Origin gFrontEnd )
				)
				( attribute "XY" "(2200,675)"
					( Origin gFrontEnd )
				)
				( attribute "CHIPS_PART_NAME" "CAP"
					( Origin gPackager )
				)
				( attribute "CDS_PART_NAME" "CAP_0402-1.0UF,16V,10%,X6S,D97A"
					( Origin gPackager )
				)
				( objectStatus "C4G21" )
			)
			( gate "@baseboard_fab2_lib.baseboard_fab2(sch_1):page229_i24"
				( attribute "BOM_COST" "MEM_VRD_VTT_GHJ"
					( Origin gFrontEnd )
				)
				( attribute "CDS_LIB" "mstr_discrete"
					( Origin gPackager )
				)
				( attribute "CDS_LOCATION" "R4G17"
					( Origin gPackager )
				)
				( attribute "CDS_SEC" "1"
					( Origin gPackager )
				)
				( attribute "LOCATION" "R4G17"
					( Origin gFrontEnd )
				)
				( attribute "MATERIAL" "CHIP"
					( Origin gFrontEnd )
				)
				( attribute "PACK_TYPE" "0402"
					( Origin gFrontEnd )
				)
				( attribute "PART_NUMBER" "G21796-016"
					( Origin gFrontEnd )
				)
				( attribute "PHYS_PAGE" "229"
					( Origin gFrontEnd )
				)
				( attribute "ROOM" "VTT_GHJ_PWR_VR"
					( Origin gFrontEnd )
				)
				( attribute "ROT" "0"
					( Origin gFrontEnd )
				)
				( attribute "SEC" "1"
					( Origin gFrontEnd )
				)
				( attribute "SEC_TYPE" "0402"
					( Origin gFrontEnd )
				)
				( attribute "TOLERANCE" "1%"
					( Origin gFrontEnd )
				)
				( attribute "VALUE" "10.0K"
					( Origin gFrontEnd )
				)
				( attribute "VER" "2"
					( Origin gFrontEnd )
				)
				( attribute "WATTAGE" "1/16W"
					( Origin gFrontEnd )
				)
				( attribute "XY" "(3325,1850)"
					( Origin gFrontEnd )
				)
				( attribute "CHIPS_PART_NAME" "RES"
					( Origin gPackager )
				)
				( attribute "CDS_PART_NAME" "RES_0402-10.0K,1%,1/16W,CHIP,GA"
					( Origin gPackager )
				)
				( objectStatus "R4G17" )
			)
			( gate "@baseboard_fab2_lib.baseboard_fab2(sch_1):page226_i46"
				( attribute "BOM_COST" "MEM_NV"
					( Origin gFrontEnd )
				)
				( attribute "CDS_LIB" "mstr_discrete"
					( Origin gPackager )
				)
				( attribute "CDS_LOCATION" "R12W35"
					( Origin gPackager )
				)
				( attribute "CDS_SEC" "1"
					( Origin gPackager )
				)
				( attribute "LOCATION" "R12W35"
					( Origin gFrontEnd )
				)
				( attribute "MATERIAL" "EMPTY"
					( Origin gFrontEnd )
				)
				( attribute "PACK_TYPE" "0402"
					( Origin gFrontEnd )
				)
				( attribute "PART_NUMBER" "G21497-005"
					( Origin gFrontEnd )
				)
				( attribute "PHYS_PAGE" "226"
					( Origin gFrontEnd )
				)
				( attribute "ROOM" "NV_DIMM"
					( Origin gFrontEnd )
				)
				( attribute "ROT" "0"
					( Origin gFrontEnd )
				)
				( attribute "SEC" "1"
					( Origin gFrontEnd )
				)
				( attribute "SEC_TYPE" "0402"
					( Origin gFrontEnd )
				)
				( attribute "TOLERANCE" "5%"
					( Origin gFrontEnd )
				)
				( attribute "VALUE" "0.0"
					( Origin gFrontEnd )
				)
				( attribute "VER" "1"
					( Origin gFrontEnd )
				)
				( attribute "WATTAGE" "1/16W"
					( Origin gFrontEnd )
				)
				( attribute "XY" "(2950,1125)"
					( Origin gFrontEnd )
				)
				( attribute "CHIPS_PART_NAME" "RES"
					( Origin gPackager )
				)
				( attribute "CDS_PART_NAME" "RES_0402-0.0,5%,1/16W,EMPTY,G2A"
					( Origin gPackager )
				)
				( objectStatus "R12W35" )
			)
			( gate "@baseboard_fab2_lib.baseboard_fab2(sch_1):page226_i45"
				( attribute "CDS_LIB" "dev_discrete"
					( Origin gPackager )
				)
				( attribute "CDS_LOCATION" "C1B3"
					( Origin gPackager )
				)
				( attribute "CDS_SEC" "1"
					( Origin gPackager )
				)
				( attribute "LOCATION" "C1B3"
					( Origin gFrontEnd )
				)
				( attribute "MATERIAL" "X6S"
					( Origin gFrontEnd )
				)
				( attribute "PACK_TYPE" "0402V"
					( Origin gFrontEnd )
				)
				( attribute "PART_NUMBER" "D97712-004"
					( Origin gFrontEnd )
				)
				( attribute "PHYS_PAGE" "226"
					( Origin gFrontEnd )
				)
				( attribute "ROOM" "VDDQ_KLM_PWR_VR"
					( Origin gFrontEnd )
				)
				( attribute "ROT" "0"
					( Origin gFrontEnd )
				)
				( attribute "SEC" "1"
					( Origin gFrontEnd )
				)
				( attribute "SEC_TYPE" "0402V"
					( Origin gFrontEnd )
				)
				( attribute "TOLERANCE" "10%"
					( Origin gFrontEnd )
				)
				( attribute "VALUE" "1.0UF"
					( Origin gFrontEnd )
				)
				( attribute "VER" "1"
					( Origin gFrontEnd )
				)
				( attribute "VOLTAGE" "6.3V"
					( Units "uVoltage" "V" 1.000000)
					( Origin gFrontEnd )
				)
				( attribute "XY" "(3500,-525)"
					( Origin gFrontEnd )
				)
				( attribute "CHIPS_PART_NAME" "CAP_A"
					( Origin gPackager )
				)
				( attribute "CDS_PART_NAME" "CAP_A_0402V-1.0UF,6.3V,10%,X6SA"
					( Origin gPackager )
				)
				( objectStatus "C1B3" )
			)
			( gate "@baseboard_fab2_lib.baseboard_fab2(sch_1):page229_i32"
				( attribute "CDS_LIB" "mstr_discrete"
					( Origin gPackager )
				)
				( attribute "CDS_LOCATION" "R4G15"
					( Origin gPackager )
				)
				( attribute "CDS_SEC" "1"
					( Origin gPackager )
				)
				( attribute "LOCATION" "R4G15"
					( Origin gFrontEnd )
				)
				( attribute "MATERIAL" "CHIP"
					( Origin gFrontEnd )
				)
				( attribute "PACK_TYPE" "0402"
					( Origin gFrontEnd )
				)
				( attribute "PART_NUMBER" "G21796-074"
					( Origin gFrontEnd )
				)
				( attribute "PHYS_PAGE" "229"
					( Origin gFrontEnd )
				)
				( attribute "ROT" "0"
					( Origin gFrontEnd )
				)
				( attribute "SEC" "1"
					( Origin gFrontEnd )
				)
				( attribute "SEC_TYPE" "0402"
					( Origin gFrontEnd )
				)
				( attribute "TOLERANCE" "1%"
					( Origin gFrontEnd )
				)
				( attribute "VALUE" "33.2"
					( Origin gFrontEnd )
				)
				( attribute "VER" "1"
					( Origin gFrontEnd )
				)
				( attribute "WATTAGE" "1/16W"
					( Origin gFrontEnd )
				)
				( attribute "XY" "(4250,1650)"
					( Origin gFrontEnd )
				)
				( attribute "CHIPS_PART_NAME" "RES"
					( Origin gPackager )
				)
				( attribute "CDS_PART_NAME" "RES_0402-33.2,1%,1/16W,CHIP,G2A"
					( Origin gPackager )
				)
				( objectStatus "R4G15" )
			)
			( gate "@baseboard_fab2_lib.baseboard_fab2(sch_1):page226_i40"
				( attribute "CDS_LIB" "mstr_discrete"
					( Origin gPackager )
				)
				( attribute "CDS_LOCATION" "C1B4"
					( Origin gPackager )
				)
				( attribute "CDS_SEC" "1"
					( Origin gPackager )
				)
				( attribute "LOCATION" "C1B4"
					( Origin gFrontEnd )
				)
				( attribute "MATERIAL" "X7R"
					( Origin gFrontEnd )
				)
				( attribute "PACK_TYPE" "0402LF"
					( Origin gFrontEnd )
				)
				( attribute "PART_NUMBER" "A36096-046"
					( Origin gFrontEnd )
				)
				( attribute "PHYS_PAGE" "226"
					( Origin gFrontEnd )
				)
				( attribute "ROOM" "VDDQ_KLM_PWR_VR"
					( Origin gFrontEnd )
				)
				( attribute "ROT" "0"
					( Origin gFrontEnd )
				)
				( attribute "SEC" "1"
					( Origin gFrontEnd )
				)
				( attribute "SEC_TYPE" "0402LF"
					( Origin gFrontEnd )
				)
				( attribute "TOLERANCE" "10%"
					( Origin gFrontEnd )
				)
				( attribute "VALUE" "1000PF"
					( Origin gFrontEnd )
				)
				( attribute "VER" "1"
					( Origin gFrontEnd )
				)
				( attribute "VOLTAGE" "50V"
					( Units "uVoltage" "V" 1.000000)
					( Origin gFrontEnd )
				)
				( attribute "XY" "(2650,275)"
					( Origin gFrontEnd )
				)
				( attribute "CHIPS_PART_NAME" "CAP"
					( Origin gPackager )
				)
				( attribute "CDS_PART_NAME" "CAP_0402LF-1000PF,50V,10%,X7R,A"
					( Origin gPackager )
				)
				( objectStatus "C1B4" )
			)
			( gate "@baseboard_fab2_lib.baseboard_fab2(sch_1):page226_i38"
				( attribute "CDS_LIB" "dev_discrete"
					( Origin gPackager )
				)
				( attribute "CDS_LOCATION" "C1B6"
					( Origin gPackager )
				)
				( attribute "CDS_SEC" "1"
					( Origin gPackager )
				)
				( attribute "LOCATION" "C1B6"
					( Origin gFrontEnd )
				)
				( attribute "MATERIAL" "X6S"
					( Origin gFrontEnd )
				)
				( attribute "PACK_TYPE" "0402V"
					( Origin gFrontEnd )
				)
				( attribute "PART_NUMBER" "D97712-004"
					( Origin gFrontEnd )
				)
				( attribute "PHYS_PAGE" "226"
					( Origin gFrontEnd )
				)
				( attribute "ROOM" "VDDQ_KLM_PWR_VR"
					( Origin gFrontEnd )
				)
				( attribute "ROT" "0"
					( Origin gFrontEnd )
				)
				( attribute "SEC" "1"
					( Origin gFrontEnd )
				)
				( attribute "SEC_TYPE" "0402V"
					( Origin gFrontEnd )
				)
				( attribute "TOLERANCE" "10%"
					( Origin gFrontEnd )
				)
				( attribute "VALUE" "1.0UF"
					( Origin gFrontEnd )
				)
				( attribute "VER" "1"
					( Origin gFrontEnd )
				)
				( attribute "VOLTAGE" "6.3V"
					( Units "uVoltage" "V" 1.000000)
					( Origin gFrontEnd )
				)
				( attribute "XY" "(1275,2375)"
					( Origin gFrontEnd )
				)
				( attribute "CHIPS_PART_NAME" "CAP_A"
					( Origin gPackager )
				)
				( attribute "CDS_PART_NAME" "CAP_A_0402V-1.0UF,6.3V,10%,X6SA"
					( Origin gPackager )
				)
				( objectStatus "C1B6" )
			)
			( gate "@baseboard_fab2_lib.baseboard_fab2(sch_1):page226_i34"
				( attribute "BOM_COST" "SM_CONTROLLER"
					( Origin gFrontEnd )
				)
				( attribute "CDS_LIB" "mstr_discrete"
					( Origin gPackager )
				)
				( attribute "CDS_LOCATION" "R9M5"
					( Origin gPackager )
				)
				( attribute "CDS_SEC" "1"
					( Origin gPackager )
				)
				( attribute "LOCATION" "R9M5"
					( Origin gFrontEnd )
				)
				( attribute "MATERIAL" "EMPTY"
					( Origin gFrontEnd )
				)
				( attribute "PACK_TYPE" "0402"
					( Origin gFrontEnd )
				)
				( attribute "PART_NUMBER" "G21796-010"
					( Origin gFrontEnd )
				)
				( attribute "PHYS_PAGE" "226"
					( Origin gFrontEnd )
				)
				( attribute "ROOM" "BMC"
					( Origin gFrontEnd )
				)
				( attribute "ROT" "0"
					( Origin gFrontEnd )
				)
				( attribute "SEC" "1"
					( Origin gFrontEnd )
				)
				( attribute "SEC_TYPE" "0402"
					( Origin gFrontEnd )
				)
				( attribute "TOLERANCE" "1%"
					( Origin gFrontEnd )
				)
				( attribute "VALUE" "100.0K"
					( Origin gFrontEnd )
				)
				( attribute "VER" "2"
					( Origin gFrontEnd )
				)
				( attribute "WATTAGE" "1/16W"
					( Origin gFrontEnd )
				)
				( attribute "XY" "(-175,2850)"
					( Origin gFrontEnd )
				)
				( attribute "CHIPS_PART_NAME" "RES"
					( Origin gPackager )
				)
				( attribute "CDS_PART_NAME" "RES_0402-100.0K,1%,1/16W,EMPTYA"
					( Origin gPackager )
				)
				( objectStatus "R9M5" )
			)
			( gate "@baseboard_fab2_lib.baseboard_fab2(sch_1):page223_i70"
				( attribute "CDS_LIB" "mstr_discrete"
					( Origin gPackager )
				)
				( attribute "CDS_LOCATION" "R9U4"
					( Origin gPackager )
				)
				( attribute "CDS_SEC" "1"
					( Origin gPackager )
				)
				( attribute "LOCATION" "R9U4"
					( Origin gFrontEnd )
				)
				( attribute "MATERIAL" "CHIP"
					( Origin gFrontEnd )
				)
				( attribute "PACK_TYPE" "0402"
					( Origin gFrontEnd )
				)
				( attribute "PART_NUMBER" "G21796-047"
					( Origin gFrontEnd )
				)
				( attribute "PHYS_PAGE" "223"
					( Origin gFrontEnd )
				)
				( attribute "ROOM" "VDDQ_KLM_PWR_VR"
					( Origin gFrontEnd )
				)
				( attribute "ROT" "0"
					( Origin gFrontEnd )
				)
				( attribute "SEC" "1"
					( Origin gFrontEnd )
				)
				( attribute "SEC_TYPE" "0402"
					( Origin gFrontEnd )
				)
				( attribute "TOLERANCE" "1%"
					( Origin gFrontEnd )
				)
				( attribute "VALUE" "49.9"
					( Origin gFrontEnd )
				)
				( attribute "VER" "2"
					( Origin gFrontEnd )
				)
				( attribute "WATTAGE" "1/16W"
					( Origin gFrontEnd )
				)
				( attribute "XY" "(-625,3000)"
					( Origin gFrontEnd )
				)
				( attribute "CHIPS_PART_NAME" "RES"
					( Origin gPackager )
				)
				( attribute "CDS_PART_NAME" "RES_0402-49.9,1%,1/16W,CHIP,G2A"
					( Origin gPackager )
				)
				( objectStatus "R9U4" )
			)
			( gate "@baseboard_fab2_lib.baseboard_fab2(sch_1):page226_i19"
				( attribute "CDS_LIB" "mstr_discrete"
					( Origin gPackager )
				)
				( attribute "CDS_LOCATION" "R1B8"
					( Origin gPackager )
				)
				( attribute "CDS_SEC" "1"
					( Origin gPackager )
				)
				( attribute "LOCATION" "R1B8"
					( Origin gFrontEnd )
				)
				( attribute "MATERIAL" "CHIP"
					( Origin gFrontEnd )
				)
				( attribute "PACK_TYPE" "0402"
					( Origin gFrontEnd )
				)
				( attribute "PART_NUMBER" "G21796-009"
					( Origin gFrontEnd )
				)
				( attribute "PHYS_PAGE" "226"
					( Origin gFrontEnd )
				)
				( attribute "ROOM" "VDDQ_KLM_PWR_VR"
					( Origin gFrontEnd )
				)
				( attribute "ROT" "0"
					( Origin gFrontEnd )
				)
				( attribute "SEC" "1"
					( Origin gFrontEnd )
				)
				( attribute "SEC_TYPE" "0402"
					( Origin gFrontEnd )
				)
				( attribute "TOLERANCE" "1%"
					( Origin gFrontEnd )
				)
				( attribute "VALUE" "150.0"
					( Origin gFrontEnd )
				)
				( attribute "VER" "1"
					( Origin gFrontEnd )
				)
				( attribute "WATTAGE" "1/16W"
					( Origin gFrontEnd )
				)
				( attribute "XY" "(-550,2350)"
					( Origin gFrontEnd )
				)
				( attribute "CHIPS_PART_NAME" "RES"
					( Origin gPackager )
				)
				( attribute "CDS_PART_NAME" "RES_0402-150.0,1%,1/16W,CHIP,GA"
					( Origin gPackager )
				)
				( objectStatus "R1B8" )
			)
			( gate "@baseboard_fab2_lib.baseboard_fab2(sch_1):page226_i18"
				( attribute "CDS_LIB" "mstr_discrete"
					( Origin gPackager )
				)
				( attribute "CDS_LOCATION" "RF22"
					( Origin gPackager )
				)
				( attribute "CDS_SEC" "1"
					( Origin gPackager )
				)
				( attribute "LOCATION" "RF22"
					( Origin gFrontEnd )
				)
				( attribute "MATERIAL" "CHIP"
					( Origin gFrontEnd )
				)
				( attribute "PACK_TYPE" "0402"
					( Origin gFrontEnd )
				)
				( attribute "PART_NUMBER" "G85996-004"
					( Origin gFrontEnd )
				)
				( attribute "PHYS_PAGE" "226"
					( Origin gFrontEnd )
				)
				( attribute "ROOM" "SB"
					( Origin gFrontEnd )
				)
				( attribute "ROT" "0"
					( Origin gFrontEnd )
				)
				( attribute "SEC" "1"
					( Origin gFrontEnd )
				)
				( attribute "SEC_TYPE" "0402"
					( Origin gFrontEnd )
				)
				( attribute "TOLERANCE" "0.1%"
					( Origin gFrontEnd )
				)
				( attribute "VALUE" "1.0K"
					( Origin gFrontEnd )
				)
				( attribute "VER" "1"
					( Origin gFrontEnd )
				)
				( attribute "WATTAGE" "1/16W"
					( Origin gFrontEnd )
				)
				( attribute "XY" "(-775,2025)"
					( Origin gFrontEnd )
				)
				( attribute "CHIPS_PART_NAME" "RES"
					( Origin gPackager )
				)
				( attribute "CDS_PART_NAME" "RES_0402-1.0K,0.1%,1/16W,CHIP,A"
					( Origin gPackager )
				)
				( attribute "GROUP" "POWER_FAIR"
					( Origin gFrontEnd )
				)
				( attribute "BOM_SS" "NOPOP"
					( Origin gFrontEnd )
				)
				( objectStatus "RF22" )
			)
			( gate "@baseboard_fab2_lib.baseboard_fab2(sch_1):page226_i15"
				( attribute "CDS_LIB" "w_hdl"
					( Origin gPackager )
				)
				( attribute "CDS_LMAN_SYM_OUTLINE" "-50,25,50,-25"
					( Origin gPackager )
				)
				( attribute "CDS_LOCATION" "CF21"
					( Origin gPackager )
				)
				( attribute "CDS_SEC" "1"
					( Origin gPackager )
				)
				( attribute "LOCATION" "CF21"
					( Origin gFrontEnd )
				)
				( attribute "PACK_TYPE" "SMD-BCG"
					( Origin gFrontEnd )
				)
				( attribute "PART_NUMBER" "78.22034.1FL"
					( Origin gFrontEnd )
				)
				( attribute "PHYS_PAGE" "226"
					( Origin gFrontEnd )
				)
				( attribute "ROT" "1"
					( Origin gFrontEnd )
				)
				( attribute "SEC" "1"
					( Origin gPackager )
				)
				( attribute "VALUE" "SC22P50V2JN-4GP"
					( Origin gFrontEnd )
				)
				( attribute "VER" "1"
					( Origin gFrontEnd )
				)
				( attribute "XY" "(-1550,1850)"
					( Origin gFrontEnd )
				)
				( attribute "CHIPS_PART_NAME" "SC22P50V2JN-4GP"
					( Origin gPackager )
				)
				( attribute "CDS_PART_NAME" "SC22P50V2JN-4GP_SMD-BCG-SC22P5A"
					( Origin gPackager )
				)
				( attribute "ATTRIBUTE" "22PF"
					( Origin gFrontEnd )
				)
				( attribute "PACK_SIZE" "0402"
					( Origin gFrontEnd )
				)
				( attribute "RATED" "50V"
					( Origin gFrontEnd )
				)
				( attribute "TOLERANCE" "5%"
					( Origin gFrontEnd )
				)
				( attribute "TYPE" "NPO"
					( Origin gFrontEnd )
				)
				( attribute "GROUP" "POWER_FAIR"
					( Origin gFrontEnd )
				)
				( objectStatus "CF21" )
			)
			( gate "@baseboard_fab2_lib.baseboard_fab2(sch_1):page226_i12"
				( attribute "CDS_LIB" "mstr_discrete"
					( Origin gPackager )
				)
				( attribute "CDS_LOCATION" "C1B12"
					( Origin gPackager )
				)
				( attribute "CDS_SEC" "1"
					( Origin gPackager )
				)
				( attribute "LOCATION" "C1B12"
					( Origin gFrontEnd )
				)
				( attribute "MATERIAL" "X7R"
					( Origin gFrontEnd )
				)
				( attribute "NO_XNET_CONNECTION" "1"
					( Origin gFrontEnd )
				)
				( attribute "PACK_TYPE" "0402LF"
					( Origin gFrontEnd )
				)
				( attribute "PART_NUMBER" "A36096-050"
					( Origin gFrontEnd )
				)
				( attribute "PHYS_PAGE" "226"
					( Origin gFrontEnd )
				)
				( attribute "ROOM" "VDDQ_KLM_PWR_VR"
					( Origin gFrontEnd )
				)
				( attribute "ROT" "0"
					( Origin gFrontEnd )
				)
				( attribute "SEC" "1"
					( Origin gFrontEnd )
				)
				( attribute "SEC_TYPE" "0402LF"
					( Origin gFrontEnd )
				)
				( attribute "TOLERANCE" "10%"
					( Origin gFrontEnd )
				)
				( attribute "VALUE" "220PF"
					( Origin gFrontEnd )
				)
				( attribute "VER" "1"
					( Origin gFrontEnd )
				)
				( attribute "VOLTAGE" "50V"
					( Units "uVoltage" "V" 1.000000)
					( Origin gFrontEnd )
				)
				( attribute "XY" "(-1750,325)"
					( Origin gFrontEnd )
				)
				( attribute "CHIPS_PART_NAME" "CAP"
					( Origin gPackager )
				)
				( attribute "CDS_PART_NAME" "CAP_0402LF-220PF,50V,10%,X7R,AA"
					( Origin gPackager )
				)
				( objectStatus "C1B12" )
			)
			( gate "@baseboard_fab2_lib.baseboard_fab2(sch_1):page230_i17"
				( attribute "BOM_COST" "MEM_VRD_VTT_KLM"
					( Origin gFrontEnd )
				)
				( attribute "CDS_LIB" "mstr_discrete"
					( Origin gPackager )
				)
				( attribute "CDS_LOCATION" "C4A15"
					( Origin gPackager )
				)
				( attribute "CDS_SEC" "1"
					( Origin gPackager )
				)
				( attribute "LOCATION" "C4A15"
					( Origin gFrontEnd )
				)
				( attribute "MATERIAL" "X6S"
					( Origin gFrontEnd )
				)
				( attribute "PACK_TYPE" "0603LF"
					( Origin gFrontEnd )
				)
				( attribute "PART_NUMBER" "E15431-001"
					( Origin gFrontEnd )
				)
				( attribute "PHYS_PAGE" "230"
					( Origin gFrontEnd )
				)
				( attribute "ROOM" "VTT_KLM_PWR_VR"
					( Origin gFrontEnd )
				)
				( attribute "ROT" "0"
					( Origin gFrontEnd )
				)
				( attribute "SEC" "1"
					( Origin gFrontEnd )
				)
				( attribute "SEC_TYPE" "0603LF"
					( Origin gFrontEnd )
				)
				( attribute "TOLERANCE" "20%"
					( Origin gFrontEnd )
				)
				( attribute "VALUE" "10UF"
					( Origin gFrontEnd )
				)
				( attribute "VER" "1"
					( Origin gFrontEnd )
				)
				( attribute "VOLTAGE" "4V"
					( Units "uVoltage" "V" 1.000000)
					( Origin gFrontEnd )
				)
				( attribute "XY" "(-1200,1650)"
					( Origin gFrontEnd )
				)
				( attribute "CHIPS_PART_NAME" "CAP"
					( Origin gPackager )
				)
				( attribute "CDS_PART_NAME" "CAP_0603LF-10UF,4V,20%,X6S,E15A"
					( Origin gPackager )
				)
				( objectStatus "C4A15" )
			)
			( gate "@baseboard_fab2_lib.baseboard_fab2(sch_1):page230_i21"
				( attribute "BOM_COST" "MEM_VRD_VTT_KLM"
					( Origin gFrontEnd )
				)
				( attribute "CDS_LIB" "mstr_discrete"
					( Origin gPackager )
				)
				( attribute "CDS_LOCATION" "R4A5"
					( Origin gPackager )
				)
				( attribute "CDS_SEC" "1"
					( Origin gPackager )
				)
				( attribute "LOCATION" "R4A5"
					( Origin gFrontEnd )
				)
				( attribute "MATERIAL" "CHIP"
					( Origin gFrontEnd )
				)
				( attribute "PACK_TYPE" "0402"
					( Origin gFrontEnd )
				)
				( attribute "PART_NUMBER" "G21796-016"
					( Origin gFrontEnd )
				)
				( attribute "PHYS_PAGE" "230"
					( Origin gFrontEnd )
				)
				( attribute "ROOM" "VTT_KLM_PWR_VR"
					( Origin gFrontEnd )
				)
				( attribute "ROT" "2"
					( Origin gFrontEnd )
				)
				( attribute "SEC" "1"
					( Origin gFrontEnd )
				)
				( attribute "SEC_TYPE" "0402"
					( Origin gFrontEnd )
				)
				( attribute "TOLERANCE" "1%"
					( Origin gFrontEnd )
				)
				( attribute "VALUE" "10.0K"
					( Origin gFrontEnd )
				)
				( attribute "VER" "2"
					( Origin gFrontEnd )
				)
				( attribute "WATTAGE" "1/16W"
					( Origin gFrontEnd )
				)
				( attribute "XY" "(1800,1250)"
					( Origin gFrontEnd )
				)
				( attribute "CHIPS_PART_NAME" "RES"
					( Origin gPackager )
				)
				( attribute "CDS_PART_NAME" "RES_0402-10.0K,1%,1/16W,CHIP,GA"
					( Origin gPackager )
				)
				( objectStatus "R4A5" )
			)
			( gate "@baseboard_fab2_lib.baseboard_fab2(sch_1):page230_i30"
				( attribute "CDS_LIB" "mstr_misc"
					( Origin gPackager )
				)
				( attribute "CDS_LOCATION" "SH8L1"
					( Origin gPackager )
				)
				( attribute "CDS_SEC" "1"
					( Origin gPackager )
				)
				( attribute "LOCATION" "SH8L1"
					( Origin gFrontEnd )
				)
				( attribute "MATERIAL" "EMPTY"
					( Origin gFrontEnd )
				)
				( attribute "PACK_TYPE" "SH0201"
					( Origin gFrontEnd )
				)
				( attribute "PART_NUMBER" "N_A"
					( Origin gFrontEnd )
				)
				( attribute "PHYS_PAGE" "230"
					( Origin gFrontEnd )
				)
				( attribute "PIN_SHORT" "A:B"
					( Origin gFrontEnd )
				)
				( attribute "ROT" "0"
					( Origin gFrontEnd )
				)
				( attribute "SEC" "1"
					( Origin gFrontEnd )
				)
				( attribute "SEC_TYPE" "SH0201"
					( Origin gFrontEnd )
				)
				( attribute "VER" "1"
					( Origin gFrontEnd )
				)
				( attribute "XY" "(3300,-700)"
					( Origin gFrontEnd )
				)
				( attribute "CHIPS_PART_NAME" "SHUNT"
					( Origin gPackager )
				)
				( attribute "CDS_PART_NAME" "SHUNT_SH0201-EMPTY,N_A"
					( Origin gPackager )
				)
				( objectStatus "SH8L1" )
			)
			( gate "@baseboard_fab2_lib.baseboard_fab2(sch_1):page221_i45"
				( attribute "BOM_COST" "MEM_VRD_PVDDQ_CD"
					( Origin gFrontEnd )
				)
				( attribute "CDS_LIB" "mstr_discrete"
					( Origin gPackager )
				)
				( attribute "CDS_LOCATION" "C5U12"
					( Origin gPackager )
				)
				( attribute "CDS_SEC" "1"
					( Origin gPackager )
				)
				( attribute "LOCATION" "C5U12"
					( Origin gFrontEnd )
				)
				( attribute "MATERIAL" "X5R"
					( Origin gFrontEnd )
				)
				( attribute "NEW_MATERIAL" "X6S"
					( Origin gFrontEnd )
				)
				( attribute "PACK_TYPE" "0805"
					( Origin gFrontEnd )
				)
				( attribute "PART_NUMBER" "602433-112"
					( Origin gFrontEnd )
				)
				( attribute "PHYS_PAGE" "221"
					( Origin gFrontEnd )
				)
				( attribute "ROOM" "VDDQ_ABC_PWR_VR"
					( Origin gFrontEnd )
				)
				( attribute "ROT" "0"
					( Origin gFrontEnd )
				)
				( attribute "SEC" "1"
					( Origin gFrontEnd )
				)
				( attribute "SEC_TYPE" "0805"
					( Origin gFrontEnd )
				)
				( attribute "TOLERANCE" "20%"
					( Origin gFrontEnd )
				)
				( attribute "VALUE" "100UF"
					( Origin gFrontEnd )
				)
				( attribute "VER" "1"
					( Origin gFrontEnd )
				)
				( attribute "VOLTAGE" "4V"
					( Units "uVoltage" "V" 1.000000)
					( Origin gFrontEnd )
				)
				( attribute "XY" "(3325,3300)"
					( Origin gFrontEnd )
				)
				( attribute "CHIPS_PART_NAME" "CAP"
					( Origin gPackager )
				)
				( attribute "CDS_PART_NAME" "CAP_0805-100UF,4V,20%,X5R,6024A"
					( Origin gPackager )
				)
				( attribute "GROUP" "PWR_MLCC_CAP"
					( Origin gFrontEnd )
				)
				( attribute "NEW_PN" "078.1071T.M002"
					( Origin gFrontEnd )
				)
				( objectStatus "C5U12" )
			)
			( gate "@baseboard_fab2_lib.baseboard_fab2(sch_1):page230_i37"
				( attribute "BOM_COST" "MEM_VRD_VTT_KLM"
					( Origin gFrontEnd )
				)
				( attribute "CDS_LIB" "mstr_vreg"
					( Origin gPackager )
				)
				( attribute "CDS_LMAN_SYM_OUTLINE" "-250,350,250,-350"
					( Origin gPackager )
				)
				( attribute "CDS_LOCATION" "EU4A2"
					( Origin gPackager )
				)
				( attribute "CDS_SEC" "1"
					( Origin gPackager )
				)
				( attribute "LOCATION" "EU4A2"
					( Origin gFrontEnd )
				)
				( attribute "MATERIAL" "IC"
					( Origin gFrontEnd )
				)
				( attribute "PACK_TYPE" "DFN"
					( Origin gFrontEnd )
				)
				( attribute "PART_NUMBER" "H55101-001"
					( Origin gFrontEnd )
				)
				( attribute "PHYS_PAGE" "230"
					( Origin gFrontEnd )
				)
				( attribute "ROOM" "VTT_KLM_PWR_VR"
					( Origin gFrontEnd )
				)
				( attribute "ROT" "0"
					( Origin gFrontEnd )
				)
				( attribute "SEC" "1"
					( Origin gFrontEnd )
				)
				( attribute "SEC_TYPE" "DFN"
					( Origin gFrontEnd )
				)
				( attribute "VER" "1"
					( Origin gFrontEnd )
				)
				( attribute "XY" "(-100,325)"
					( Origin gFrontEnd )
				)
				( attribute "CHIPS_PART_NAME" "MIC5166"
					( Origin gPackager )
				)
				( attribute "CDS_PART_NAME" "MIC5166_DFN-IC,H55101-001"
					( Origin gPackager )
				)
				( objectStatus "EU4A2" )
			)
			( gate "@baseboard_fab2_lib.baseboard_fab2(sch_1):page231_i122"
				( attribute "BOM_COST" "MEM_VRD_PVPP_AB"
					( Origin gFrontEnd )
				)
				( attribute "CDS_LIB" "mstr_discrete"
					( Origin gPackager )
				)
				( attribute "CDS_LOCATION" "C6F6"
					( Origin gPackager )
				)
				( attribute "CDS_SEC" "1"
					( Origin gPackager )
				)
				( attribute "LOCATION" "C6F6"
					( Origin gFrontEnd )
				)
				( attribute "MATERIAL" "X6S"
					( Origin gFrontEnd )
				)
				( attribute "PACK_TYPE" "0603LF"
					( Origin gFrontEnd )
				)
				( attribute "PART_NUMBER" "E15431-001"
					( Origin gFrontEnd )
				)
				( attribute "PHYS_PAGE" "231"
					( Origin gFrontEnd )
				)
				( attribute "ROOM" "PVPP_KLM_VR"
					( Origin gFrontEnd )
				)
				( attribute "ROT" "0"
					( Origin gFrontEnd )
				)
				( attribute "SEC" "1"
					( Origin gPackager )
				)
				( attribute "TOLERANCE" "20%"
					( Origin gFrontEnd )
				)
				( attribute "VALUE" "10UF"
					( Origin gFrontEnd )
				)
				( attribute "VER" "1"
					( Origin gFrontEnd )
				)
				( attribute "VOLTAGE" "4V"
					( Units "uVoltage" "V" 1.000000)
					( Origin gFrontEnd )
				)
				( attribute "XY" "(-7925,1000)"
					( Origin gFrontEnd )
				)
				( attribute "CHIPS_PART_NAME" "CAP"
					( Origin gPackager )
				)
				( attribute "CDS_PART_NAME" "CAP_0603LF-10UF,4V,20%,X6S,E15A"
					( Origin gPackager )
				)
				( attribute "GROUP" "PWR_MLCC_CAP"
					( Origin gFrontEnd )
				)
				( objectStatus "C6F6" )
			)
			( gate "@baseboard_fab2_lib.baseboard_fab2(sch_1):page231_i124"
				( attribute "BOM_COST" "MEM_VRD_PVPP_AB"
					( Origin gFrontEnd )
				)
				( attribute "CDS_LIB" "mstr_discrete"
					( Origin gPackager )
				)
				( attribute "CDS_LOCATION" "C4T6"
					( Origin gPackager )
				)
				( attribute "CDS_SEC" "1"
					( Origin gPackager )
				)
				( attribute "LOCATION" "C4T6"
					( Origin gFrontEnd )
				)
				( attribute "MATERIAL" "X6S"
					( Origin gFrontEnd )
				)
				( attribute "PACK_TYPE" "0603LF"
					( Origin gFrontEnd )
				)
				( attribute "PART_NUMBER" "E15431-001"
					( Origin gFrontEnd )
				)
				( attribute "PHYS_PAGE" "231"
					( Origin gFrontEnd )
				)
				( attribute "ROOM" "PVPP_KLM_VR"
					( Origin gFrontEnd )
				)
				( attribute "ROT" "0"
					( Origin gFrontEnd )
				)
				( attribute "SEC" "1"
					( Origin gPackager )
				)
				( attribute "TOLERANCE" "20%"
					( Origin gFrontEnd )
				)
				( attribute "VALUE" "10UF"
					( Origin gFrontEnd )
				)
				( attribute "VER" "1"
					( Origin gFrontEnd )
				)
				( attribute "VOLTAGE" "4V"
					( Units "uVoltage" "V" 1.000000)
					( Origin gFrontEnd )
				)
				( attribute "XY" "(-7625,1000)"
					( Origin gFrontEnd )
				)
				( attribute "CHIPS_PART_NAME" "CAP"
					( Origin gPackager )
				)
				( attribute "CDS_PART_NAME" "CAP_0603LF-10UF,4V,20%,X6S,E15A"
					( Origin gPackager )
				)
				( attribute "GROUP" "PWR_MLCC_CAP"
					( Origin gFrontEnd )
				)
				( objectStatus "C4T6" )
			)
			( gate "@baseboard_fab2_lib.baseboard_fab2(sch_1):page231_i125"
				( attribute "BOM_COST" "MEM_VRD_PVPP_AB"
					( Origin gFrontEnd )
				)
				( attribute "CDS_LIB" "mstr_discrete"
					( Origin gPackager )
				)
				( attribute "CDS_LOCATION" "C4T5"
					( Origin gPackager )
				)
				( attribute "CDS_SEC" "1"
					( Origin gPackager )
				)
				( attribute "LOCATION" "C4T5"
					( Origin gFrontEnd )
				)
				( attribute "MATERIAL" "X6S"
					( Origin gFrontEnd )
				)
				( attribute "PACK_TYPE" "0603LF"
					( Origin gFrontEnd )
				)
				( attribute "PART_NUMBER" "E15431-001"
					( Origin gFrontEnd )
				)
				( attribute "PHYS_PAGE" "231"
					( Origin gFrontEnd )
				)
				( attribute "ROOM" "PVPP_KLM_VR"
					( Origin gFrontEnd )
				)
				( attribute "ROT" "0"
					( Origin gFrontEnd )
				)
				( attribute "SEC" "1"
					( Origin gPackager )
				)
				( attribute "TOLERANCE" "20%"
					( Origin gFrontEnd )
				)
				( attribute "VALUE" "10UF"
					( Origin gFrontEnd )
				)
				( attribute "VER" "1"
					( Origin gFrontEnd )
				)
				( attribute "VOLTAGE" "4V"
					( Units "uVoltage" "V" 1.000000)
					( Origin gFrontEnd )
				)
				( attribute "XY" "(-7350,1000)"
					( Origin gFrontEnd )
				)
				( attribute "CHIPS_PART_NAME" "CAP"
					( Origin gPackager )
				)
				( attribute "CDS_PART_NAME" "CAP_0603LF-10UF,4V,20%,X6S,E15A"
					( Origin gPackager )
				)
				( attribute "GROUP" "PWR_MLCC_CAP"
					( Origin gFrontEnd )
				)
				( objectStatus "C4T5" )
			)
			( gate "@baseboard_fab2_lib.baseboard_fab2(sch_1):page231_i126"
				( attribute "BOM_COST" "MEM_VRD_PVPP_AB"
					( Origin gFrontEnd )
				)
				( attribute "CDS_LIB" "mstr_discrete"
					( Origin gPackager )
				)
				( attribute "CDS_LOCATION" "C6G1"
					( Origin gPackager )
				)
				( attribute "CDS_SEC" "1"
					( Origin gPackager )
				)
				( attribute "LOCATION" "C6G1"
					( Origin gFrontEnd )
				)
				( attribute "MATERIAL" "X6S"
					( Origin gFrontEnd )
				)
				( attribute "PACK_TYPE" "0603LF"
					( Origin gFrontEnd )
				)
				( attribute "PART_NUMBER" "E15431-001"
					( Origin gFrontEnd )
				)
				( attribute "PHYS_PAGE" "231"
					( Origin gFrontEnd )
				)
				( attribute "ROOM" "PVPP_KLM_VR"
					( Origin gFrontEnd )
				)
				( attribute "ROT" "0"
					( Origin gFrontEnd )
				)
				( attribute "SEC" "1"
					( Origin gPackager )
				)
				( attribute "TOLERANCE" "20%"
					( Origin gFrontEnd )
				)
				( attribute "VALUE" "10UF"
					( Origin gFrontEnd )
				)
				( attribute "VER" "1"
					( Origin gFrontEnd )
				)
				( attribute "VOLTAGE" "4V"
					( Units "uVoltage" "V" 1.000000)
					( Origin gFrontEnd )
				)
				( attribute "XY" "(-7075,975)"
					( Origin gFrontEnd )
				)
				( attribute "CHIPS_PART_NAME" "CAP"
					( Origin gPackager )
				)
				( attribute "CDS_PART_NAME" "CAP_0603LF-10UF,4V,20%,X6S,E15A"
					( Origin gPackager )
				)
				( attribute "GROUP" "PWR_MLCC_CAP"
					( Origin gFrontEnd )
				)
				( objectStatus "C6G1" )
			)
			( gate "@baseboard_fab2_lib.baseboard_fab2(sch_1):page231_i128"
				( attribute "BOM_COST" "MEM_VRD_PVPP_AB"
					( Origin gFrontEnd )
				)
				( attribute "CDS_LIB" "mstr_discrete"
					( Origin gPackager )
				)
				( attribute "CDS_LOCATION" "C6G2"
					( Origin gPackager )
				)
				( attribute "CDS_SEC" "1"
					( Origin gPackager )
				)
				( attribute "LOCATION" "C6G2"
					( Origin gFrontEnd )
				)
				( attribute "MATERIAL" "X6S"
					( Origin gFrontEnd )
				)
				( attribute "PACK_TYPE" "0603LF"
					( Origin gFrontEnd )
				)
				( attribute "PART_NUMBER" "E15431-001"
					( Origin gFrontEnd )
				)
				( attribute "PHYS_PAGE" "231"
					( Origin gFrontEnd )
				)
				( attribute "ROOM" "PVPP_KLM_VR"
					( Origin gFrontEnd )
				)
				( attribute "ROT" "0"
					( Origin gFrontEnd )
				)
				( attribute "SEC" "1"
					( Origin gPackager )
				)
				( attribute "TOLERANCE" "20%"
					( Origin gFrontEnd )
				)
				( attribute "VALUE" "10UF"
					( Origin gFrontEnd )
				)
				( attribute "VER" "1"
					( Origin gFrontEnd )
				)
				( attribute "VOLTAGE" "4V"
					( Units "uVoltage" "V" 1.000000)
					( Origin gFrontEnd )
				)
				( attribute "XY" "(-6800,1000)"
					( Origin gFrontEnd )
				)
				( attribute "CHIPS_PART_NAME" "CAP"
					( Origin gPackager )
				)
				( attribute "CDS_PART_NAME" "CAP_0603LF-10UF,4V,20%,X6S,E15A"
					( Origin gPackager )
				)
				( attribute "GROUP" "PWR_MLCC_CAP"
					( Origin gFrontEnd )
				)
				( objectStatus "C6G2" )
			)
			( gate "@baseboard_fab2_lib.baseboard_fab2(sch_1):page231_i129"
				( attribute "BOM_COST" "MEM_VRD_PVPP_AB"
					( Origin gFrontEnd )
				)
				( attribute "CDS_LIB" "mstr_discrete"
					( Origin gPackager )
				)
				( attribute "CDS_LOCATION" "C4U2"
					( Origin gPackager )
				)
				( attribute "CDS_SEC" "1"
					( Origin gPackager )
				)
				( attribute "LOCATION" "C4U2"
					( Origin gFrontEnd )
				)
				( attribute "MATERIAL" "X6S"
					( Origin gFrontEnd )
				)
				( attribute "PACK_TYPE" "0603LF"
					( Origin gFrontEnd )
				)
				( attribute "PART_NUMBER" "E15431-001"
					( Origin gFrontEnd )
				)
				( attribute "PHYS_PAGE" "231"
					( Origin gFrontEnd )
				)
				( attribute "ROOM" "PVPP_KLM_VR"
					( Origin gFrontEnd )
				)
				( attribute "ROT" "0"
					( Origin gFrontEnd )
				)
				( attribute "SEC" "1"
					( Origin gPackager )
				)
				( attribute "TOLERANCE" "20%"
					( Origin gFrontEnd )
				)
				( attribute "VALUE" "10UF"
					( Origin gFrontEnd )
				)
				( attribute "VER" "1"
					( Origin gFrontEnd )
				)
				( attribute "VOLTAGE" "4V"
					( Units "uVoltage" "V" 1.000000)
					( Origin gFrontEnd )
				)
				( attribute "XY" "(-6500,1000)"
					( Origin gFrontEnd )
				)
				( attribute "CHIPS_PART_NAME" "CAP"
					( Origin gPackager )
				)
				( attribute "CDS_PART_NAME" "CAP_0603LF-10UF,4V,20%,X6S,E15A"
					( Origin gPackager )
				)
				( attribute "GROUP" "PWR_MLCC_CAP"
					( Origin gFrontEnd )
				)
				( objectStatus "C4U2" )
			)
			( gate "@baseboard_fab2_lib.baseboard_fab2(sch_1):page231_i130"
				( attribute "BOM_COST" "MEM_VRD_PVPP_AB"
					( Origin gFrontEnd )
				)
				( attribute "CDS_LIB" "mstr_discrete"
					( Origin gPackager )
				)
				( attribute "CDS_LOCATION" "C4U1"
					( Origin gPackager )
				)
				( attribute "CDS_SEC" "1"
					( Origin gPackager )
				)
				( attribute "LOCATION" "C4U1"
					( Origin gFrontEnd )
				)
				( attribute "MATERIAL" "X6S"
					( Origin gFrontEnd )
				)
				( attribute "PACK_TYPE" "0603LF"
					( Origin gFrontEnd )
				)
				( attribute "PART_NUMBER" "E15431-001"
					( Origin gFrontEnd )
				)
				( attribute "PHYS_PAGE" "231"
					( Origin gFrontEnd )
				)
				( attribute "ROOM" "PVPP_KLM_VR"
					( Origin gFrontEnd )
				)
				( attribute "ROT" "0"
					( Origin gFrontEnd )
				)
				( attribute "SEC" "1"
					( Origin gPackager )
				)
				( attribute "TOLERANCE" "20%"
					( Origin gFrontEnd )
				)
				( attribute "VALUE" "10UF"
					( Origin gFrontEnd )
				)
				( attribute "VER" "1"
					( Origin gFrontEnd )
				)
				( attribute "VOLTAGE" "4V"
					( Units "uVoltage" "V" 1.000000)
					( Origin gFrontEnd )
				)
				( attribute "XY" "(-6225,1000)"
					( Origin gFrontEnd )
				)
				( attribute "CHIPS_PART_NAME" "CAP"
					( Origin gPackager )
				)
				( attribute "CDS_PART_NAME" "CAP_0603LF-10UF,4V,20%,X6S,E15A"
					( Origin gPackager )
				)
				( attribute "GROUP" "PWR_MLCC_CAP"
					( Origin gFrontEnd )
				)
				( objectStatus "C4U1" )
			)
			( gate "@baseboard_fab2_lib.baseboard_fab2(sch_1):page231_i131"
				( attribute "BOM_COST" "MEM_VRD_PVPP_AB"
					( Origin gFrontEnd )
				)
				( attribute "CDS_LIB" "mstr_discrete"
					( Origin gPackager )
				)
				( attribute "CDS_LOCATION" "C6G4"
					( Origin gPackager )
				)
				( attribute "CDS_SEC" "1"
					( Origin gPackager )
				)
				( attribute "LOCATION" "C6G4"
					( Origin gFrontEnd )
				)
				( attribute "MATERIAL" "X6S"
					( Origin gFrontEnd )
				)
				( attribute "PACK_TYPE" "0603LF"
					( Origin gFrontEnd )
				)
				( attribute "PART_NUMBER" "E15431-001"
					( Origin gFrontEnd )
				)
				( attribute "PHYS_PAGE" "231"
					( Origin gFrontEnd )
				)
				( attribute "ROOM" "PVPP_KLM_VR"
					( Origin gFrontEnd )
				)
				( attribute "ROT" "0"
					( Origin gFrontEnd )
				)
				( attribute "SEC" "1"
					( Origin gPackager )
				)
				( attribute "TOLERANCE" "20%"
					( Origin gFrontEnd )
				)
				( attribute "VALUE" "10UF"
					( Origin gFrontEnd )
				)
				( attribute "VER" "1"
					( Origin gFrontEnd )
				)
				( attribute "VOLTAGE" "4V"
					( Units "uVoltage" "V" 1.000000)
					( Origin gFrontEnd )
				)
				( attribute "XY" "(-5925,1000)"
					( Origin gFrontEnd )
				)
				( attribute "CHIPS_PART_NAME" "CAP"
					( Origin gPackager )
				)
				( attribute "CDS_PART_NAME" "CAP_0603LF-10UF,4V,20%,X6S,E15A"
					( Origin gPackager )
				)
				( attribute "GROUP" "PWR_MLCC_CAP"
					( Origin gFrontEnd )
				)
				( objectStatus "C6G4" )
			)
			( gate "@baseboard_fab2_lib.baseboard_fab2(sch_1):page231_i134"
				( attribute "BOM_COST" "PVPP_KLM_VR"
					( Origin gFrontEnd )
				)
				( attribute "CDS_LIB" "mstr_discrete"
					( Origin gPackager )
				)
				( attribute "CDS_LOCATION" "R7F15"
					( Origin gPackager )
				)
				( attribute "CDS_SEC" "1"
					( Origin gPackager )
				)
				( attribute "LOCATION" "R7F15"
					( Origin gFrontEnd )
				)
				( attribute "MATERIAL" "CHIP"
					( Origin gFrontEnd )
				)
				( attribute "PACK_TYPE" "0402"
					( Origin gFrontEnd )
				)
				( attribute "PART_NUMBER" "G21796-242"
					( Origin gFrontEnd )
				)
				( attribute "PHYS_PAGE" "231"
					( Origin gFrontEnd )
				)
				( attribute "ROOM" "PVPP_KLM_VR"
					( Origin gFrontEnd )
				)
				( attribute "ROT" "2"
					( Origin gFrontEnd )
				)
				( attribute "SEC" "1"
					( Origin gPackager )
				)
				( attribute "TOLERANCE" "1.0%"
					( Origin gFrontEnd )
				)
				( attribute "VALUE" "7.87K"
					( Origin gFrontEnd )
				)
				( attribute "VER" "2"
					( Origin gFrontEnd )
				)
				( attribute "WATTAGE" "1/16W"
					( Origin gFrontEnd )
				)
				( attribute "XY" "(-4400,1900)"
					( Origin gFrontEnd )
				)
				( attribute "CHIPS_PART_NAME" "RES"
					( Origin gPackager )
				)
				( attribute "CDS_PART_NAME" "RES_0402-7.87K,1.0%,1/16W,CHIPA"
					( Origin gPackager )
				)
				( attribute "CONFIG" "64.39015.6DL"
					( Origin gFrontEnd )
				)
				( attribute "NEW_VALUE" "3.9K"
					( Origin gFrontEnd )
				)
				( objectStatus "R7F15" )
			)
			( gate "@baseboard_fab2_lib.baseboard_fab2(sch_1):page231_i136"
				( attribute "BOM" "SYSB_CPLD"
					( Origin gFrontEnd )
				)
				( attribute "BOM_COST" "PVPP_KLM_VR"
					( Origin gFrontEnd )
				)
				( attribute "CDS_LIB" "mstr_discrete"
					( Origin gPackager )
				)
				( attribute "CDS_LOCATION" "R7F14"
					( Origin gPackager )
				)
				( attribute "CDS_SEC" "1"
					( Origin gPackager )
				)
				( attribute "LOCATION" "R7F14"
					( Origin gFrontEnd )
				)
				( attribute "MATERIAL" "CHIP"
					( Origin gFrontEnd )
				)
				( attribute "PACK_TYPE" "0402"
					( Origin gFrontEnd )
				)
				( attribute "PART_NUMBER" "G21796-016"
					( Origin gFrontEnd )
				)
				( attribute "PHYS_PAGE" "231"
					( Origin gFrontEnd )
				)
				( attribute "ROOM" "PVPP_KLM_VR"
					( Origin gFrontEnd )
				)
				( attribute "ROT" "0"
					( Origin gFrontEnd )
				)
				( attribute "SEC" "1"
					( Origin gPackager )
				)
				( attribute "TOLERANCE" "1%"
					( Origin gFrontEnd )
				)
				( attribute "VALUE" "10.0K"
					( Origin gFrontEnd )
				)
				( attribute "VER" "2"
					( Origin gFrontEnd )
				)
				( attribute "WATTAGE" "1/16W"
					( Origin gFrontEnd )
				)
				( attribute "XY" "(-6625,2450)"
					( Origin gFrontEnd )
				)
				( attribute "CHIPS_PART_NAME" "RES"
					( Origin gPackager )
				)
				( attribute "CDS_PART_NAME" "RES_0402-10.0K,1%,1/16W,CHIP,GA"
					( Origin gPackager )
				)
				( objectStatus "R7F14" )
			)
			( gate "@baseboard_fab2_lib.baseboard_fab2(sch_1):page231_i140"
				( attribute "BOM_COST" "PVPP_KLM_VR"
					( Origin gFrontEnd )
				)
				( attribute "CDS_LIB" "mstr_discrete"
					( Origin gPackager )
				)
				( attribute "CDS_LOCATION" "C7F8"
					( Origin gPackager )
				)
				( attribute "CDS_SEC" "1"
					( Origin gPackager )
				)
				( attribute "FIN" "VR_1P2"
					( Origin gFrontEnd )
				)
				( attribute "LOCATION" "C7F8"
					( Origin gFrontEnd )
				)
				( attribute "MATERIAL" "EMPTY"
					( Origin gFrontEnd )
				)
				( attribute "PACK_TYPE" "0402LF"
					( Origin gFrontEnd )
				)
				( attribute "PART_NUMBER" "A36096-046"
					( Origin gFrontEnd )
				)
				( attribute "PHYS_PAGE" "231"
					( Origin gFrontEnd )
				)
				( attribute "REUSE_ID" "1"
					( Origin gFrontEnd )
				)
				( attribute "ROOM" "PVPP_KLM_VR"
					( Origin gFrontEnd )
				)
				( attribute "ROT" "2"
					( Origin gFrontEnd )
				)
				( attribute "SEC" "1"
					( Origin gPackager )
				)
				( attribute "TOLERANCE" "10%"
					( Origin gFrontEnd )
				)
				( attribute "VALUE" "1000PF"
					( Origin gFrontEnd )
				)
				( attribute "VER" "1"
					( Origin gFrontEnd )
				)
				( attribute "VOLTAGE" "50V"
					( Units "uVoltage" "V" 1.000000)
					( Origin gFrontEnd )
				)
				( attribute "XY" "(-6175,2650)"
					( Origin gFrontEnd )
				)
				( attribute "CHIPS_PART_NAME" "CAP"
					( Origin gPackager )
				)
				( attribute "CDS_PART_NAME" "CAP_0402LF-1000PF,50V,10%,EMPTA"
					( Origin gPackager )
				)
				( objectStatus "C7F8" )
			)
			( gate "@baseboard_fab2_lib.baseboard_fab2(sch_1):page231_i142"
				( attribute "BOM_COST" "PVPP_KLM_VR"
					( Origin gFrontEnd )
				)
				( attribute "CDS_LIB" "mstr_discrete"
					( Origin gPackager )
				)
				( attribute "CDS_LOCATION" "C7F11"
					( Origin gPackager )
				)
				( attribute "CDS_SEC" "1"
					( Origin gPackager )
				)
				( attribute "LOCATION" "C7F11"
					( Origin gFrontEnd )
				)
				( attribute "MATERIAL" "X7R"
					( Origin gFrontEnd )
				)
				( attribute "PACK_TYPE" "0402LF"
					( Origin gFrontEnd )
				)
				( attribute "PART_NUMBER" "A36096-046"
					( Origin gFrontEnd )
				)
				( attribute "PHYS_PAGE" "231"
					( Origin gFrontEnd )
				)
				( attribute "REUSE_ID" "17"
					( Origin gFrontEnd )
				)
				( attribute "ROOM" "PVPP_KLM_VR"
					( Origin gFrontEnd )
				)
				( attribute "ROT" "0"
					( Origin gFrontEnd )
				)
				( attribute "SEC" "1"
					( Origin gPackager )
				)
				( attribute "TOLERANCE" "10%"
					( Origin gFrontEnd )
				)
				( attribute "VALUE" "1000PF"
					( Origin gFrontEnd )
				)
				( attribute "VER" "1"
					( Origin gFrontEnd )
				)
				( attribute "VOLTAGE" "50V"
					( Units "uVoltage" "V" 1.000000)
					( Origin gFrontEnd )
				)
				( attribute "XY" "(-3700,1050)"
					( Origin gFrontEnd )
				)
				( attribute "CHIPS_PART_NAME" "CAP"
					( Origin gPackager )
				)
				( attribute "CDS_PART_NAME" "CAP_0402LF-1000PF,50V,10%,X7R,A"
					( Origin gPackager )
				)
				( objectStatus "C7F11" )
			)
			( gate "@baseboard_fab2_lib.baseboard_fab2(sch_1):page231_i143"
				( attribute "BOM_COST" "PVPP_KLM_VR"
					( Origin gFrontEnd )
				)
				( attribute "CDS_LIB" "mstr_discrete"
					( Origin gPackager )
				)
				( attribute "CDS_LOCATION" "R7F19"
					( Origin gPackager )
				)
				( attribute "CDS_SEC" "1"
					( Origin gPackager )
				)
				( attribute "LOCATION" "R7F19"
					( Origin gFrontEnd )
				)
				( attribute "MATERIAL" "CHIP"
					( Origin gFrontEnd )
				)
				( attribute "PACK_TYPE" "0402"
					( Origin gFrontEnd )
				)
				( attribute "PART_NUMBER" "G21796-026"
					( Origin gFrontEnd )
				)
				( attribute "PHYS_PAGE" "231"
					( Origin gFrontEnd )
				)
				( attribute "REUSE_ID" "21"
					( Origin gFrontEnd )
				)
				( attribute "ROOM" "PVPP_KLM_VR"
					( Origin gFrontEnd )
				)
				( attribute "ROT" "0"
					( Origin gFrontEnd )
				)
				( attribute "SEC" "1"
					( Origin gFrontEnd )
				)
				( attribute "SEC_TYPE" "0402"
					( Origin gFrontEnd )
				)
				( attribute "TOLERANCE" "1%"
					( Origin gFrontEnd )
				)
				( attribute "VALUE" "1.00K"
					( Origin gFrontEnd )
				)
				( attribute "VER" "2"
					( Origin gFrontEnd )
				)
				( attribute "WATTAGE" "1/16W"
					( Origin gFrontEnd )
				)
				( attribute "XY" "(-3875,1500)"
					( Origin gFrontEnd )
				)
				( attribute "CHIPS_PART_NAME" "RES"
					( Origin gPackager )
				)
				( attribute "CDS_PART_NAME" "RES_0402-1.00K,1%,1/16W,CHIP,GA"
					( Origin gPackager )
				)
				( objectStatus "R7F19" )
			)
			( gate "@baseboard_fab2_lib.baseboard_fab2(sch_1):page231_i145"
				( attribute "BOM_COST" "MEM_VRD_PVPP_AB"
					( Origin gFrontEnd )
				)
				( attribute "CDS_LIB" "mstr_discrete"
					( Origin gPackager )
				)
				( attribute "CDS_LOCATION" "C6G5"
					( Origin gPackager )
				)
				( attribute "CDS_SEC" "1"
					( Origin gPackager )
				)
				( attribute "LOCATION" "C6G5"
					( Origin gFrontEnd )
				)
				( attribute "MATERIAL" "X6S"
					( Origin gFrontEnd )
				)
				( attribute "PACK_TYPE" "0603LF"
					( Origin gFrontEnd )
				)
				( attribute "PART_NUMBER" "E15431-001"
					( Origin gFrontEnd )
				)
				( attribute "PHYS_PAGE" "231"
					( Origin gFrontEnd )
				)
				( attribute "ROOM" "PVPP_KLM_VR"
					( Origin gFrontEnd )
				)
				( attribute "ROT" "0"
					( Origin gFrontEnd )
				)
				( attribute "SEC" "1"
					( Origin gPackager )
				)
				( attribute "TOLERANCE" "20%"
					( Origin gFrontEnd )
				)
				( attribute "VALUE" "10UF"
					( Origin gFrontEnd )
				)
				( attribute "VER" "1"
					( Origin gFrontEnd )
				)
				( attribute "VOLTAGE" "4V"
					( Units "uVoltage" "V" 1.000000)
					( Origin gFrontEnd )
				)
				( attribute "XY" "(-5625,1000)"
					( Origin gFrontEnd )
				)
				( attribute "CHIPS_PART_NAME" "CAP"
					( Origin gPackager )
				)
				( attribute "CDS_PART_NAME" "CAP_0603LF-10UF,4V,20%,X6S,E15A"
					( Origin gPackager )
				)
				( attribute "GROUP" "PWR_MLCC_CAP"
					( Origin gFrontEnd )
				)
				( objectStatus "C6G5" )
			)
			( gate "@baseboard_fab2_lib.baseboard_fab2(sch_1):page231_i146"
				( attribute "BOM_COST" "MEM_VRD_PVPP_AB"
					( Origin gFrontEnd )
				)
				( attribute "CDS_LIB" "mstr_discrete"
					( Origin gPackager )
				)
				( attribute "CDS_LOCATION" "C4U4"
					( Origin gPackager )
				)
				( attribute "CDS_SEC" "1"
					( Origin gPackager )
				)
				( attribute "LOCATION" "C4U4"
					( Origin gFrontEnd )
				)
				( attribute "MATERIAL" "X6S"
					( Origin gFrontEnd )
				)
				( attribute "PACK_TYPE" "0603LF"
					( Origin gFrontEnd )
				)
				( attribute "PART_NUMBER" "E15431-001"
					( Origin gFrontEnd )
				)
				( attribute "PHYS_PAGE" "231"
					( Origin gFrontEnd )
				)
				( attribute "ROOM" "PVPP_KLM_VR"
					( Origin gFrontEnd )
				)
				( attribute "ROT" "0"
					( Origin gFrontEnd )
				)
				( attribute "SEC" "1"
					( Origin gPackager )
				)
				( attribute "TOLERANCE" "20%"
					( Origin gFrontEnd )
				)
				( attribute "VALUE" "10UF"
					( Origin gFrontEnd )
				)
				( attribute "VER" "1"
					( Origin gFrontEnd )
				)
				( attribute "VOLTAGE" "4V"
					( Units "uVoltage" "V" 1.000000)
					( Origin gFrontEnd )
				)
				( attribute "XY" "(-5350,975)"
					( Origin gFrontEnd )
				)
				( attribute "CHIPS_PART_NAME" "CAP"
					( Origin gPackager )
				)
				( attribute "CDS_PART_NAME" "CAP_0603LF-10UF,4V,20%,X6S,E15A"
					( Origin gPackager )
				)
				( attribute "GROUP" "PWR_MLCC_CAP"
					( Origin gFrontEnd )
				)
				( objectStatus "C4U4" )
			)
			( gate "@baseboard_fab2_lib.baseboard_fab2(sch_1):page231_i148"
				( attribute "BOM_COST" "MEM_VRD_PVPP_AB"
					( Origin gFrontEnd )
				)
				( attribute "CDS_LIB" "mstr_discrete"
					( Origin gPackager )
				)
				( attribute "CDS_LOCATION" "C4U3"
					( Origin gPackager )
				)
				( attribute "CDS_SEC" "1"
					( Origin gPackager )
				)
				( attribute "LOCATION" "C4U3"
					( Origin gFrontEnd )
				)
				( attribute "MATERIAL" "X6S"
					( Origin gFrontEnd )
				)
				( attribute "PACK_TYPE" "0603LF"
					( Origin gFrontEnd )
				)
				( attribute "PART_NUMBER" "E15431-001"
					( Origin gFrontEnd )
				)
				( attribute "PHYS_PAGE" "231"
					( Origin gFrontEnd )
				)
				( attribute "ROOM" "PVPP_KLM_VR"
					( Origin gFrontEnd )
				)
				( attribute "ROT" "0"
					( Origin gFrontEnd )
				)
				( attribute "SEC" "1"
					( Origin gPackager )
				)
				( attribute "TOLERANCE" "20%"
					( Origin gFrontEnd )
				)
				( attribute "VALUE" "10UF"
					( Origin gFrontEnd )
				)
				( attribute "VER" "1"
					( Origin gFrontEnd )
				)
				( attribute "VOLTAGE" "4V"
					( Units "uVoltage" "V" 1.000000)
					( Origin gFrontEnd )
				)
				( attribute "XY" "(-5075,975)"
					( Origin gFrontEnd )
				)
				( attribute "CHIPS_PART_NAME" "CAP"
					( Origin gPackager )
				)
				( attribute "CDS_PART_NAME" "CAP_0603LF-10UF,4V,20%,X6S,E15A"
					( Origin gPackager )
				)
				( attribute "GROUP" "PWR_MLCC_CAP"
					( Origin gFrontEnd )
				)
				( objectStatus "C4U3" )
			)
			( gate "@baseboard_fab2_lib.baseboard_fab2(sch_1):page231_i149"
				( attribute "BOM_COST" "MEM_VRD_PVPP_AB"
					( Origin gFrontEnd )
				)
				( attribute "CDS_LIB" "mstr_discrete"
					( Origin gPackager )
				)
				( attribute "CDS_LOCATION" "C6F5"
					( Origin gPackager )
				)
				( attribute "CDS_SEC" "1"
					( Origin gPackager )
				)
				( attribute "LOCATION" "C6F5"
					( Origin gFrontEnd )
				)
				( attribute "MATERIAL" "X6S"
					( Origin gFrontEnd )
				)
				( attribute "PACK_TYPE" "0603LF"
					( Origin gFrontEnd )
				)
				( attribute "PART_NUMBER" "E15431-001"
					( Origin gFrontEnd )
				)
				( attribute "PHYS_PAGE" "231"
					( Origin gFrontEnd )
				)
				( attribute "ROOM" "PVPP_KLM_VR"
					( Origin gFrontEnd )
				)
				( attribute "ROT" "0"
					( Origin gFrontEnd )
				)
				( attribute "SEC" "1"
					( Origin gFrontEnd )
				)
				( attribute "SEC_TYPE" "0603LF"
					( Origin gFrontEnd )
				)
				( attribute "TOLERANCE" "20%"
					( Origin gFrontEnd )
				)
				( attribute "VALUE" "10UF"
					( Origin gFrontEnd )
				)
				( attribute "VER" "1"
					( Origin gFrontEnd )
				)
				( attribute "VOLTAGE" "4V"
					( Units "uVoltage" "V" 1.000000)
					( Origin gFrontEnd )
				)
				( attribute "XY" "(-4800,975)"
					( Origin gFrontEnd )
				)
				( attribute "CHIPS_PART_NAME" "CAP"
					( Origin gPackager )
				)
				( attribute "CDS_PART_NAME" "CAP_0603LF-10UF,4V,20%,X6S,E15A"
					( Origin gPackager )
				)
				( attribute "GROUP" "PWR_MLCC_CAP"
					( Origin gFrontEnd )
				)
				( objectStatus "C6F5" )
			)
			( gate "@baseboard_fab2_lib.baseboard_fab2(sch_1):page240_i183"
				( attribute "CDS_LIB" "w_hdl"
					( Origin gPackager )
				)
				( attribute "CDS_LMAN_SYM_OUTLINE" "-50,25,50,-25"
					( Origin gPackager )
				)
				( attribute "LOCATION" "C8E11"
					( Origin gFrontEnd )
				)
				( attribute "PACK_TYPE" "SMD-BCG5"
					( Origin gFrontEnd )
				)
				( attribute "PART_NUMBER" "078.22611.0811"
					( Origin gFrontEnd )
				)
				( attribute "PHYS_PAGE" "240"
					( Origin gFrontEnd )
				)
				( attribute "ROT" "0"
					( Origin gFrontEnd )
				)
				( attribute "SEC" "1"
					( Origin gFrontEnd )
				)
				( attribute "SEC_TYPE" "SMD-BCG5"
					( Origin gFrontEnd )
				)
				( attribute "VALUE" "SC22U16V5MX-4-GP"
					( Origin gFrontEnd )
				)
				( attribute "VER" "1"
					( Origin gFrontEnd )
				)
				( attribute "XY" "(7450,4275)"
					( Origin gFrontEnd )
				)
				( attribute "CHIPS_PART_NAME" "SC22U16V5MX-4-GP"
					( Origin gPackager )
				)
				( attribute "CDS_PART_NAME" "SC22U16V5MX-4-GP_SMD-BCG5-SC22A"
					( Origin gPackager )
				)
				( attribute "CDS_LOCATION" "C8E11"
					( Origin gPackager )
				)
				( attribute "CDS_SEC" "1"
					( Origin gPackager )
				)
				( attribute "ATTRIBUTE" "22UF"
					( Origin gFrontEnd )
				)
				( attribute "PACK_SIZE" "0805"
					( Origin gFrontEnd )
				)
				( attribute "RATED" "16V"
					( Origin gFrontEnd )
				)
				( attribute "TOLERANCE" "20%"
					( Origin gFrontEnd )
				)
				( attribute "TYPE" "X6S"
					( Origin gFrontEnd )
				)
				( objectStatus "C8E11" )
			)
			( gate "@baseboard_fab2_lib.baseboard_fab2(sch_1):page232_i313"
				( attribute "BOM_COST" "NT_GBE_BASE"
					( Origin gFrontEnd )
				)
				( attribute "CDS_LIB" "mstr_discrete"
					( Origin gPackager )
				)
				( attribute "CDS_LOCATION" "R7B19"
					( Origin gPackager )
				)
				( attribute "CDS_SEC" "1"
					( Origin gPackager )
				)
				( attribute "LOCATION" "R7B19"
					( Origin gFrontEnd )
				)
				( attribute "MATERIAL" "CHIP"
					( Origin gFrontEnd )
				)
				( attribute "PACK_TYPE" "0603"
					( Origin gFrontEnd )
				)
				( attribute "PART_NUMBER" "G22178-002"
					( Origin gFrontEnd )
				)
				( attribute "PHYS_PAGE" "232"
					( Origin gFrontEnd )
				)
				( attribute "ROOM" "NIC_SPRV"
					( Origin gFrontEnd )
				)
				( attribute "ROT" "0"
					( Origin gFrontEnd )
				)
				( attribute "SEC" "1"
					( Origin gFrontEnd )
				)
				( attribute "SEC_TYPE" "0603"
					( Origin gFrontEnd )
				)
				( attribute "TOLERANCE" "5.0%"
					( Origin gFrontEnd )
				)
				( attribute "VALUE" "0"
					( Origin gFrontEnd )
				)
				( attribute "VER" "1"
					( Origin gFrontEnd )
				)
				( attribute "WATTAGE" "1/10W"
					( Origin gFrontEnd )
				)
				( attribute "XY" "(-4500,4175)"
					( Origin gFrontEnd )
				)
				( attribute "CHIPS_PART_NAME" "RES"
					( Origin gPackager )
				)
				( attribute "CDS_PART_NAME" "RES_0603-0,5.0%,1/10W,CHIP,G22A"
					( Origin gPackager )
				)
				( objectStatus "R7B19" )
			)
			( gate "@baseboard_fab2_lib.baseboard_fab2(sch_1):page231_i159"
				( attribute "BOM_COST" "PVPP_KLM_VR"
					( Origin gFrontEnd )
				)
				( attribute "CDS_LIB" "mstr_discrete"
					( Origin gPackager )
				)
				( attribute "CDS_LOCATION" "C7F4"
					( Origin gPackager )
				)
				( attribute "CDS_SEC" "1"
					( Origin gPackager )
				)
				( attribute "LOCATION" "C7F4"
					( Origin gFrontEnd )
				)
				( attribute "MATERIAL" "X7R"
					( Origin gFrontEnd )
				)
				( attribute "PACK_TYPE" "0603LF"
					( Origin gFrontEnd )
				)
				( attribute "PART_NUMBER" "602433-020"
					( Origin gFrontEnd )
				)
				( attribute "PHYS_PAGE" "231"
					( Origin gFrontEnd )
				)
				( attribute "REUSE_ID" "27"
					( Origin gFrontEnd )
				)
				( attribute "ROOM" "PVPP_KLM_VR"
					( Origin gFrontEnd )
				)
				( attribute "ROT" "2"
					( Origin gFrontEnd )
				)
				( attribute "SEC" "1"
					( Origin gPackager )
				)
				( attribute "SPOF" "TRUE"
					( Origin gFrontEnd )
				)
				( attribute "TOLERANCE" "10%"
					( Origin gFrontEnd )
				)
				( attribute "VALUE" "0.1UF"
					( Origin gFrontEnd )
				)
				( attribute "VER" "2"
					( Origin gFrontEnd )
				)
				( attribute "VOLTAGE" "25V"
					( Units "uVoltage" "V" 1.000000)
					( Origin gFrontEnd )
				)
				( attribute "XY" "(-3025,4450)"
					( Origin gFrontEnd )
				)
				( attribute "CHIPS_PART_NAME" "CAP"
					( Origin gPackager )
				)
				( attribute "CDS_PART_NAME" "CAP_0603LF-0.1UF,25V,10%,X7R,6A"
					( Origin gPackager )
				)
				( objectStatus "C7F4" )
			)
			( gate "@baseboard_fab2_lib.baseboard_fab2(sch_1):page231_i161"
				( attribute "BOM_COST" "PVPP_KLM_VR"
					( Origin gFrontEnd )
				)
				( attribute "CDS_LIB" "mstr_discrete"
					( Origin gPackager )
				)
				( attribute "CDS_LOCATION" "C3T10"
					( Origin gPackager )
				)
				( attribute "CDS_SEC" "1"
					( Origin gPackager )
				)
				( attribute "FIN" "VR_1P2"
					( Origin gFrontEnd )
				)
				( attribute "LOCATION" "C3T10"
					( Origin gFrontEnd )
				)
				( attribute "MATERIAL" "X6S"
					( Origin gFrontEnd )
				)
				( attribute "PACK_TYPE" "0402"
					( Origin gFrontEnd )
				)
				( attribute "PART_NUMBER" "D97712-011"
					( Origin gFrontEnd )
				)
				( attribute "PHYS_PAGE" "231"
					( Origin gFrontEnd )
				)
				( attribute "REUSE_ID" "1"
					( Origin gFrontEnd )
				)
				( attribute "ROOM" "PVPP_KLM_VR"
					( Origin gFrontEnd )
				)
				( attribute "ROT" "0"
					( Origin gFrontEnd )
				)
				( attribute "SEC" "1"
					( Origin gPackager )
				)
				( attribute "TOLERANCE" "10%"
					( Origin gFrontEnd )
				)
				( attribute "VALUE" "1.0UF"
					( Origin gFrontEnd )
				)
				( attribute "VER" "1"
					( Origin gFrontEnd )
				)
				( attribute "VOLTAGE" "16V"
					( Units "uVoltage" "V" 1.000000)
					( Origin gFrontEnd )
				)
				( attribute "XY" "(-4700,4400)"
					( Origin gFrontEnd )
				)
				( attribute "CHIPS_PART_NAME" "CAP"
					( Origin gPackager )
				)
				( attribute "CDS_PART_NAME" "CAP_0402-1.0UF,16V,10%,X6S,D97A"
					( Origin gPackager )
				)
				( objectStatus "C3T10" )
			)
			( gate "@baseboard_fab2_lib.baseboard_fab2(sch_1):page231_i162"
				( attribute "CDS_LIB" "mstr_discrete"
					( Origin gPackager )
				)
				( attribute "CDS_LOCATION" "FB7F1"
					( Origin gPackager )
				)
				( attribute "CDS_SEC" "1"
					( Origin gPackager )
				)
				( attribute "LOCATION" "FB7F1"
					( Origin gFrontEnd )
				)
				( attribute "MATERIAL" "FB"
					( Origin gFrontEnd )
				)
				( attribute "PACK_TYPE" "SM"
					( Origin gFrontEnd )
				)
				( attribute "PART_NUMBER" "656554-051"
					( Origin gFrontEnd )
				)
				( attribute "PHYS_PAGE" "231"
					( Origin gFrontEnd )
				)
				( attribute "ROOM" "PVPP_KLM_VR"
					( Origin gFrontEnd )
				)
				( attribute "ROT" "0"
					( Origin gFrontEnd )
				)
				( attribute "SEC" "1"
					( Origin gFrontEnd )
				)
				( attribute "SEC_TYPE" "SM"
					( Origin gFrontEnd )
				)
				( attribute "TOLERANCE" "1%"
					( Origin gFrontEnd )
				)
				( attribute "VALUE" "22"
					( Origin gFrontEnd )
				)
				( attribute "VER" "1"
					( Origin gFrontEnd )
				)
				( attribute "XY" "(-7300,4550)"
					( Origin gFrontEnd )
				)
				( attribute "CHIPS_PART_NAME" "FERRITE"
					( Origin gPackager )
				)
				( attribute "CDS_PART_NAME" "FERRITE_SM-22,FB,656554-051"
					( Origin gPackager )
				)
				( objectStatus "FB7F1" )
			)
			( gate "@baseboard_fab2_lib.baseboard_fab2(sch_1):page232_i314"
				( attribute "BOM_COST" "IO_SLOT"
					( Origin gFrontEnd )
				)
				( attribute "CDS_LIB" "mstr_discrete"
					( Origin gPackager )
				)
				( attribute "CDS_LOCATION" "R7B13"
					( Origin gPackager )
				)
				( attribute "CDS_SEC" "1"
					( Origin gPackager )
				)
				( attribute "LOCATION" "R7B13"
					( Origin gFrontEnd )
				)
				( attribute "MATERIAL" "CHIP"
					( Origin gFrontEnd )
				)
				( attribute "PACK_TYPE" "0402"
					( Origin gFrontEnd )
				)
				( attribute "PART_NUMBER" "G21796-161"
					( Origin gFrontEnd )
				)
				( attribute "PHYS_PAGE" "232"
					( Origin gFrontEnd )
				)
				( attribute "ROOM" "IO_SLOT"
					( Origin gFrontEnd )
				)
				( attribute "ROT" "0"
					( Origin gFrontEnd )
				)
				( attribute "SEC" "1"
					( Origin gFrontEnd )
				)
				( attribute "SEC_TYPE" "0402"
					( Origin gFrontEnd )
				)
				( attribute "TOLERANCE" "1%"
					( Origin gFrontEnd )
				)
				( attribute "VALUE" "6.19K"
					( Origin gFrontEnd )
				)
				( attribute "VER" "2"
					( Origin gFrontEnd )
				)
				( attribute "WATTAGE" "1/16W"
					( Origin gFrontEnd )
				)
				( attribute "XY" "(-1700,1300)"
					( Origin gFrontEnd )
				)
				( attribute "CHIPS_PART_NAME" "RES"
					( Origin gPackager )
				)
				( attribute "CDS_PART_NAME" "RES_0402-6.19K,1%,1/16W,CHIP,GA"
					( Origin gPackager )
				)
				( objectStatus "R7B13" )
			)
			( gate "@baseboard_fab2_lib.baseboard_fab2(sch_1):page231_i167"
				( attribute "BOM_COST" "PVPP_KLM_VR"
					( Origin gFrontEnd )
				)
				( attribute "CDS_LIB" "mstr_discrete"
					( Origin gPackager )
				)
				( attribute "CDS_LOCATION" "R7F13"
					( Origin gPackager )
				)
				( attribute "CDS_SEC" "1"
					( Origin gPackager )
				)
				( attribute "LOCATION" "R7F13"
					( Origin gFrontEnd )
				)
				( attribute "MATERIAL" "CHIP"
					( Origin gFrontEnd )
				)
				( attribute "PACK_TYPE" "0402"
					( Origin gFrontEnd )
				)
				( attribute "PART_NUMBER" "G21796-040"
					( Origin gFrontEnd )
				)
				( attribute "PHYS_PAGE" "231"
					( Origin gFrontEnd )
				)
				( attribute "REUSE_ID" "9"
					( Origin gFrontEnd )
				)
				( attribute "ROOM" "PVPP_KLM_VR"
					( Origin gFrontEnd )
				)
				( attribute "ROT" "0"
					( Origin gFrontEnd )
				)
				( attribute "SEC" "1"
					( Origin gPackager )
				)
				( attribute "SPOF" "TRUE"
					( Origin gFrontEnd )
				)
				( attribute "TOLERANCE" "1%"
					( Origin gFrontEnd )
				)
				( attribute "VALUE" "20.0K"
					( Origin gFrontEnd )
				)
				( attribute "VER" "2"
					( Origin gFrontEnd )
				)
				( attribute "WATTAGE" "1/16W"
					( Origin gFrontEnd )
				)
				( attribute "XY" "(-1000,2250)"
					( Origin gFrontEnd )
				)
				( attribute "CHIPS_PART_NAME" "RES"
					( Origin gPackager )
				)
				( attribute "CDS_PART_NAME" "RES_0402-20.0K,1%,1/16W,CHIP,GA"
					( Origin gPackager )
				)
				( objectStatus "R7F13" )
			)
			( gate "@baseboard_fab2_lib.baseboard_fab2(sch_1):page231_i168"
				( attribute "CDS_LIB" "mstr_discrete"
					( Origin gPackager )
				)
				( attribute "CDS_LOCATION" "R7F12"
					( Origin gPackager )
				)
				( attribute "CDS_SEC" "1"
					( Origin gPackager )
				)
				( attribute "LOCATION" "R7F12"
					( Origin gFrontEnd )
				)
				( attribute "MATERIAL" "CHIP"
					( Origin gFrontEnd )
				)
				( attribute "PACK_TYPE" "0402"
					( Origin gFrontEnd )
				)
				( attribute "PART_NUMBER" "G21497-005"
					( Origin gFrontEnd )
				)
				( attribute "PHYS_PAGE" "231"
					( Origin gFrontEnd )
				)
				( attribute "ROOM" "PVPP_KLM_VR"
					( Origin gFrontEnd )
				)
				( attribute "ROT" "5"
					( Origin gFrontEnd )
				)
				( attribute "SEC" "1"
					( Origin gFrontEnd )
				)
				( attribute "SEC_TYPE" "0402"
					( Origin gFrontEnd )
				)
				( attribute "SPOF" "TRUE"
					( Origin gFrontEnd )
				)
				( attribute "TOLERANCE" "5%"
					( Origin gFrontEnd )
				)
				( attribute "VALUE" "0.0"
					( Origin gFrontEnd )
				)
				( attribute "VER" "1"
					( Origin gFrontEnd )
				)
				( attribute "WATTAGE" "1/16W"
					( Origin gFrontEnd )
				)
				( attribute "XY" "(-1000,3175)"
					( Origin gFrontEnd )
				)
				( attribute "CHIPS_PART_NAME" "RES"
					( Origin gPackager )
				)
				( attribute "CDS_PART_NAME" "RES_0402-0.0,5%,1/16W,CHIP,G21A"
					( Origin gPackager )
				)
				( objectStatus "R7F12" )
			)
			( gate "@baseboard_fab2_lib.baseboard_fab2(sch_1):page231_i170"
				( attribute "CDS_LIB" "mstr_discrete"
					( Origin gPackager )
				)
				( attribute "CDS_LOCATION" "R7F35"
					( Origin gPackager )
				)
				( attribute "CDS_SEC" "1"
					( Origin gPackager )
				)
				( attribute "LOCATION" "R7F35"
					( Origin gFrontEnd )
				)
				( attribute "MATERIAL" "CHIP"
					( Origin gFrontEnd )
				)
				( attribute "PACK_TYPE" "0402"
					( Origin gFrontEnd )
				)
				( attribute "PART_NUMBER" "G21497-005"
					( Origin gFrontEnd )
				)
				( attribute "PHYS_PAGE" "231"
					( Origin gFrontEnd )
				)
				( attribute "ROOM" "PVPP_KLM_VR"
					( Origin gFrontEnd )
				)
				( attribute "ROT" "0"
					( Origin gFrontEnd )
				)
				( attribute "SEC" "1"
					( Origin gPackager )
				)
				( attribute "TOLERANCE" "5%"
					( Origin gFrontEnd )
				)
				( attribute "VALUE" "0.0"
					( Origin gFrontEnd )
				)
				( attribute "VER" "1"
					( Origin gFrontEnd )
				)
				( attribute "WATTAGE" "1/16W"
					( Origin gFrontEnd )
				)
				( attribute "XY" "(-950,725)"
					( Origin gFrontEnd )
				)
				( attribute "CHIPS_PART_NAME" "RES"
					( Origin gPackager )
				)
				( attribute "CDS_PART_NAME" "RES_0402-0.0,5%,1/16W,CHIP,G21A"
					( Origin gPackager )
				)
				( objectStatus "R7F35" )
			)
			( gate "@baseboard_fab2_lib.baseboard_fab2(sch_1):page231_i174"
				( attribute "BOM_COST" "PVPP_KLM_VR"
					( Origin gFrontEnd )
				)
				( attribute "CDS_LIB" "mstr_discrete"
					( Origin gPackager )
				)
				( attribute "CDS_LOCATION" "R7F7"
					( Origin gPackager )
				)
				( attribute "CDS_SEC" "1"
					( Origin gPackager )
				)
				( attribute "LOCATION" "R7F7"
					( Origin gFrontEnd )
				)
				( attribute "MATERIAL" "EMPTY"
					( Origin gFrontEnd )
				)
				( attribute "PACK_TYPE" "0402"
					( Origin gFrontEnd )
				)
				( attribute "PART_NUMBER" "G21497-016"
					( Origin gFrontEnd )
				)
				( attribute "PHYS_PAGE" "231"
					( Origin gFrontEnd )
				)
				( attribute "REUSE_ID" "29"
					( Origin gFrontEnd )
				)
				( attribute "ROOM" "PVPP_KLM_VR"
					( Origin gFrontEnd )
				)
				( attribute "ROT" "0"
					( Origin gFrontEnd )
				)
				( attribute "SEC" "1"
					( Origin gPackager )
				)
				( attribute "TOLERANCE" "5%"
					( Origin gFrontEnd )
				)
				( attribute "VALUE" "2.2"
					( Origin gFrontEnd )
				)
				( attribute "VER" "2"
					( Origin gFrontEnd )
				)
				( attribute "WATTAGE" "1/16W"
					( Origin gFrontEnd )
				)
				( attribute "XY" "(-2300,3600)"
					( Origin gFrontEnd )
				)
				( attribute "CHIPS_PART_NAME" "RES"
					( Origin gPackager )
				)
				( attribute "CDS_PART_NAME" "RES_0402-2.2,5%,1/16W,EMPTY,G2A"
					( Origin gPackager )
				)
				( objectStatus "R7F7" )
			)
			( gate "@baseboard_fab2_lib.baseboard_fab2(sch_1):page231_i175"
				( attribute "BOM_COST" "PVPP_KLM_VR"
					( Origin gFrontEnd )
				)
				( attribute "CDS_LIB" "mstr_discrete"
					( Origin gPackager )
				)
				( attribute "CDS_LOCATION" "C7F3"
					( Origin gPackager )
				)
				( attribute "CDS_SEC" "1"
					( Origin gPackager )
				)
				( attribute "LOCATION" "C7F3"
					( Origin gFrontEnd )
				)
				( attribute "MATERIAL" "EMPTY"
					( Origin gFrontEnd )
				)
				( attribute "PACK_TYPE" "0402LF"
					( Origin gFrontEnd )
				)
				( attribute "PART_NUMBER" "A36096-091"
					( Origin gFrontEnd )
				)
				( attribute "PHYS_PAGE" "231"
					( Origin gFrontEnd )
				)
				( attribute "REUSE_ID" "26"
					( Origin gFrontEnd )
				)
				( attribute "ROOM" "PVPP_KLM_VR"
					( Origin gFrontEnd )
				)
				( attribute "ROT" "0"
					( Origin gFrontEnd )
				)
				( attribute "SEC" "1"
					( Origin gPackager )
				)
				( attribute "TOLERANCE" "10%"
					( Origin gFrontEnd )
				)
				( attribute "VALUE" "3300PF"
					( Origin gFrontEnd )
				)
				( attribute "VER" "1"
					( Origin gFrontEnd )
				)
				( attribute "VOLTAGE" "50V"
					( Units "uVoltage" "V" 1.000000)
					( Origin gFrontEnd )
				)
				( attribute "XY" "(-2300,3950)"
					( Origin gFrontEnd )
				)
				( attribute "CHIPS_PART_NAME" "CAP"
					( Origin gPackager )
				)
				( attribute "CDS_PART_NAME" "CAP_0402LF-3300PF,50V,10%,EMPTA"
					( Origin gPackager )
				)
				( objectStatus "C7F3" )
			)
			( gate "@baseboard_fab2_lib.baseboard_fab2(sch_1):page231_i177"
				( attribute "BOM_COST" "PVPP_KLM_VR"
					( Origin gFrontEnd )
				)
				( attribute "CDS_LIB" "mstr_discrete"
					( Origin gPackager )
				)
				( attribute "CDS_LOCATION" "R7F10"
					( Origin gPackager )
				)
				( attribute "CDS_SEC" "1"
					( Origin gPackager )
				)
				( attribute "LOCATION" "R7F10"
					( Origin gFrontEnd )
				)
				( attribute "MATERIAL" "CHIP"
					( Origin gFrontEnd )
				)
				( attribute "PACK_TYPE" "0603"
					( Origin gFrontEnd )
				)
				( attribute "PART_NUMBER" "G22026-003"
					( Origin gFrontEnd )
				)
				( attribute "PHYS_PAGE" "231"
					( Origin gFrontEnd )
				)
				( attribute "REUSE_ID" "34"
					( Origin gFrontEnd )
				)
				( attribute "ROOM" "PVPP_KLM_VR"
					( Origin gFrontEnd )
				)
				( attribute "ROT" "0"
					( Origin gFrontEnd )
				)
				( attribute "SEC" "1"
					( Origin gFrontEnd )
				)
				( attribute "SEC_TYPE" "0603"
					( Origin gFrontEnd )
				)
				( attribute "TOLERANCE" "1%"
					( Origin gFrontEnd )
				)
				( attribute "VALUE" "120.0"
					( Origin gFrontEnd )
				)
				( attribute "VER" "2"
					( Origin gFrontEnd )
				)
				( attribute "WATTAGE" "1/10W"
					( Origin gFrontEnd )
				)
				( attribute "XY" "(-1725,3925)"
					( Origin gFrontEnd )
				)
				( attribute "CHIPS_PART_NAME" "RES"
					( Origin gPackager )
				)
				( attribute "CDS_PART_NAME" "RES_0603-120.0,1%,1/10W,CHIP,GA"
					( Origin gPackager )
				)
				( objectStatus "R7F10" )
			)
			( gate "@baseboard_fab2_lib.baseboard_fab2(sch_1):page231_i178"
				( attribute "BOM_COST" "PVPP_KLM_VR"
					( Origin gFrontEnd )
				)
				( attribute "CDS_LIB" "mstr_discrete"
					( Origin gPackager )
				)
				( attribute "CDS_LOCATION" "L7F1"
					( Origin gPackager )
				)
				( attribute "CDS_SEC" "1"
					( Origin gPackager )
				)
				( attribute "LOCATION" "L7F1"
					( Origin gFrontEnd )
				)
				( attribute "MATERIAL" "IND"
					( Origin gFrontEnd )
				)
				( attribute "PACK_TYPE" "SM"
					( Origin gFrontEnd )
				)
				( attribute "PART_NUMBER" "E13358-018"
					( Origin gFrontEnd )
				)
				( attribute "PHYS_PAGE" "231"
					( Origin gFrontEnd )
				)
				( attribute "REUSE_ID" "30"
					( Origin gFrontEnd )
				)
				( attribute "ROOM" "PVPP_KLM_VR"
					( Origin gFrontEnd )
				)
				( attribute "ROT" "0"
					( Origin gFrontEnd )
				)
				( attribute "SEC" "1"
					( Origin gPackager )
				)
				( attribute "TOLERANCE" "1%"
					( Origin gFrontEnd )
				)
				( attribute "VALUE" "0.47UH"
					( Origin gFrontEnd )
				)
				( attribute "VER" "1"
					( Origin gFrontEnd )
				)
				( attribute "XY" "(-1950,4100)"
					( Origin gFrontEnd )
				)
				( attribute "CHIPS_PART_NAME" "INDUCTOR"
					( Origin gPackager )
				)
				( attribute "CDS_PART_NAME" "INDUCTOR_SM-0.47UH,IND,E13358-A"
					( Origin gPackager )
				)
				( objectStatus "L7F1" )
			)
			( gate "@baseboard_fab2_lib.baseboard_fab2(sch_1):page231_i180"
				( attribute "BOM_COST" "PVPP_KLM_VR"
					( Origin gFrontEnd )
				)
				( attribute "CDS_LIB" "mstr_discrete"
					( Origin gPackager )
				)
				( attribute "CDS_LOCATION" "C6F4"
					( Origin gPackager )
				)
				( attribute "CDS_SEC" "1"
					( Origin gPackager )
				)
				( attribute "LOCATION" "C6F4"
					( Origin gFrontEnd )
				)
				( attribute "MATERIAL" "POSCAP"
					( Origin gFrontEnd )
				)
				( attribute "PACK_TYPE" "7343LF"
					( Origin gFrontEnd )
				)
				( attribute "PART_NUMBER" "724613-042"
					( Origin gFrontEnd )
				)
				( attribute "PHYS_PAGE" "231"
					( Origin gFrontEnd )
				)
				( attribute "REUSE_ID" "28"
					( Origin gFrontEnd )
				)
				( attribute "ROOM" "PVPP_KLM_VR"
					( Origin gFrontEnd )
				)
				( attribute "ROT" "0"
					( Origin gFrontEnd )
				)
				( attribute "SEC" "1"
					( Origin gPackager )
				)
				( attribute "TOLERANCE" "20%"
					( Origin gFrontEnd )
				)
				( attribute "VALUE" "330UF"
					( Origin gFrontEnd )
				)
				( attribute "VER" "1"
					( Origin gFrontEnd )
				)
				( attribute "VOLTAGE" "6.3V"
					( Units "uVoltage" "V" 1.000000)
					( Origin gFrontEnd )
				)
				( attribute "XY" "(-1400,3900)"
					( Origin gFrontEnd )
				)
				( attribute "CHIPS_PART_NAME" "CAPP"
					( Origin gPackager )
				)
				( attribute "CDS_PART_NAME" "CAPP_7343LF-330UF,6.3V,20%,POSA"
					( Origin gPackager )
				)
				( attribute "GROUP" "PWR_BULK_CAP"
					( Origin gFrontEnd )
				)
				( objectStatus "C6F4" )
			)
			( gate "@baseboard_fab2_lib.baseboard_fab2(sch_1):page231_i184"
				( attribute "BOM_COST" "PVPP_KLM_VR"
					( Origin gFrontEnd )
				)
				( attribute "CDS_LIB" "mstr_discrete"
					( Origin gPackager )
				)
				( attribute "CDS_LOCATION" "C3T7"
					( Origin gPackager )
				)
				( attribute "CDS_SEC" "1"
					( Origin gPackager )
				)
				( attribute "LOCATION" "C3T7"
					( Origin gFrontEnd )
				)
				( attribute "MATERIAL" "X6S"
					( Origin gFrontEnd )
				)
				( attribute "PACK_TYPE" "0805"
					( Origin gFrontEnd )
				)
				( attribute "PART_NUMBER" "C95333-006"
					( Origin gFrontEnd )
				)
				( attribute "PHYS_PAGE" "231"
					( Origin gFrontEnd )
				)
				( attribute "REUSE_ID" "33"
					( Origin gFrontEnd )
				)
				( attribute "ROOM" "PVPP_KLM_VR"
					( Origin gFrontEnd )
				)
				( attribute "ROT" "0"
					( Origin gFrontEnd )
				)
				( attribute "SEC" "1"
					( Origin gPackager )
				)
				( attribute "TOLERANCE" "20%"
					( Origin gFrontEnd )
				)
				( attribute "VALUE" "47UF"
					( Origin gFrontEnd )
				)
				( attribute "VER" "1"
					( Origin gFrontEnd )
				)
				( attribute "VOLTAGE" "4V"
					( Units "uVoltage" "V" 1.000000)
					( Origin gFrontEnd )
				)
				( attribute "XY" "(-775,3900)"
					( Origin gFrontEnd )
				)
				( attribute "CHIPS_PART_NAME" "CAP"
					( Origin gPackager )
				)
				( attribute "CDS_PART_NAME" "CAP_0805-47UF,4V,20%,X6S,C9533A"
					( Origin gPackager )
				)
				( attribute "GROUP" "PWR_MLCC_CAP"
					( Origin gFrontEnd )
				)
				( objectStatus "C3T7" )
			)
			( gate "@baseboard_fab2_lib.baseboard_fab2(sch_1):page231_i186"
				( attribute "BOM_COST" "PVPP_KLM_VR"
					( Origin gFrontEnd )
				)
				( attribute "CDS_LIB" "mstr_discrete"
					( Origin gPackager )
				)
				( attribute "CDS_LOCATION" "C3T9"
					( Origin gPackager )
				)
				( attribute "CDS_SEC" "1"
					( Origin gPackager )
				)
				( attribute "LOCATION" "C3T9"
					( Origin gFrontEnd )
				)
				( attribute "MATERIAL" "X6S"
					( Origin gFrontEnd )
				)
				( attribute "PACK_TYPE" "0805"
					( Origin gFrontEnd )
				)
				( attribute "PART_NUMBER" "C95333-006"
					( Origin gFrontEnd )
				)
				( attribute "PHYS_PAGE" "231"
					( Origin gFrontEnd )
				)
				( attribute "REUSE_ID" "33"
					( Origin gFrontEnd )
				)
				( attribute "ROOM" "PVPP_KLM_VR"
					( Origin gFrontEnd )
				)
				( attribute "ROT" "0"
					( Origin gFrontEnd )
				)
				( attribute "SEC" "1"
					( Origin gPackager )
				)
				( attribute "TOLERANCE" "20%"
					( Origin gFrontEnd )
				)
				( attribute "VALUE" "47UF"
					( Origin gFrontEnd )
				)
				( attribute "VER" "1"
					( Origin gFrontEnd )
				)
				( attribute "VOLTAGE" "4V"
					( Units "uVoltage" "V" 1.000000)
					( Origin gFrontEnd )
				)
				( attribute "XY" "(-475,3925)"
					( Origin gFrontEnd )
				)
				( attribute "CHIPS_PART_NAME" "CAP"
					( Origin gPackager )
				)
				( attribute "CDS_PART_NAME" "CAP_0805-47UF,4V,20%,X6S,C9533A"
					( Origin gPackager )
				)
				( attribute "GROUP" "PWR_MLCC_CAP"
					( Origin gFrontEnd )
				)
				( objectStatus "C3T9" )
			)
			( gate "@baseboard_fab2_lib.baseboard_fab2(sch_1):page231_i193"
				( attribute "CDS_LIB" "mstr_vreg"
					( Origin gPackager )
				)
				( attribute "CDS_LMAN_SYM_OUTLINE" "-450,850,450,-900"
					( Origin gPackager )
				)
				( attribute "CDS_LOCATION" "EU7F1"
					( Origin gPackager )
				)
				( attribute "CDS_SEC" "1"
					( Origin gPackager )
				)
				( attribute "LOCATION" "EU7F1"
					( Origin gFrontEnd )
				)
				( attribute "MATERIAL" "IC"
					( Origin gFrontEnd )
				)
				( attribute "PACK_TYPE" "SM"
					( Origin gFrontEnd )
				)
				( attribute "PART_NUMBER" "H86355-001"
					( Origin gFrontEnd )
				)
				( attribute "PHYS_PAGE" "231"
					( Origin gFrontEnd )
				)
				( attribute "ROT" "0"
					( Origin gFrontEnd )
				)
				( attribute "SEC" "1"
					( Origin gFrontEnd )
				)
				( attribute "SEC_TYPE" "SM"
					( Origin gFrontEnd )
				)
				( attribute "VER" "1"
					( Origin gFrontEnd )
				)
				( attribute "XY" "(-3450,3125)"
					( Origin gFrontEnd )
				)
				( attribute "CHIPS_PART_NAME" "NCP3232L"
					( Origin gPackager )
				)
				( attribute "CDS_PART_NAME" "NCP3232L_SM-IC,H86355-001"
					( Origin gPackager )
				)
				( objectStatus "EU7F1" )
			)
			( gate "@baseboard_fab2_lib.baseboard_fab2(sch_1):page231_i194"
				( attribute "BOM_COST" "PVPP_KLM_VR"
					( Origin gFrontEnd )
				)
				( attribute "CDS_LIB" "mstr_discrete"
					( Origin gPackager )
				)
				( attribute "CDS_LOCATION" "C7F10"
					( Origin gPackager )
				)
				( attribute "CDS_SEC" "1"
					( Origin gPackager )
				)
				( attribute "LOCATION" "C7F10"
					( Origin gFrontEnd )
				)
				( attribute "MATERIAL" "X7R"
					( Origin gFrontEnd )
				)
				( attribute "PACK_TYPE" "0402"
					( Origin gFrontEnd )
				)
				( attribute "PART_NUMBER" "A36096-129"
					( Origin gFrontEnd )
				)
				( attribute "PHYS_PAGE" "231"
					( Origin gFrontEnd )
				)
				( attribute "REUSE_ID" "26"
					( Origin gFrontEnd )
				)
				( attribute "ROOM" "PVPP_KLM_VR"
					( Origin gFrontEnd )
				)
				( attribute "ROT" "0"
					( Origin gFrontEnd )
				)
				( attribute "SEC" "1"
					( Origin gFrontEnd )
				)
				( attribute "SEC_TYPE" "0402"
					( Origin gFrontEnd )
				)
				( attribute "TOLERANCE" "10%"
					( Origin gFrontEnd )
				)
				( attribute "VALUE" "0.027UF"
					( Origin gFrontEnd )
				)
				( attribute "VER" "1"
					( Origin gFrontEnd )
				)
				( attribute "VOLTAGE" "16V"
					( Units "uVoltage" "V" 1.000000)
					( Origin gFrontEnd )
				)
				( attribute "XY" "(-4725,2425)"
					( Origin gFrontEnd )
				)
				( attribute "CHIPS_PART_NAME" "CAP"
					( Origin gPackager )
				)
				( attribute "CDS_PART_NAME" "CAP_0402-0.027UF,16V,10%,X7R,AA"
					( Origin gPackager )
				)
				( objectStatus "C7F10" )
			)
			( gate "@baseboard_fab2_lib.baseboard_fab2(sch_1):page231_i199"
				( attribute "BOM_COST" "PVPP_KLM_VR"
					( Origin gFrontEnd )
				)
				( attribute "CDS_LIB" "mstr_discrete"
					( Origin gPackager )
				)
				( attribute "CDS_LOCATION" "C7F9"
					( Origin gPackager )
				)
				( attribute "CDS_SEC" "1"
					( Origin gPackager )
				)
				( attribute "LOCATION" "C7F9"
					( Origin gFrontEnd )
				)
				( attribute "MATERIAL" "COG"
					( Origin gFrontEnd )
				)
				( attribute "PACK_TYPE" "0402LF"
					( Origin gFrontEnd )
				)
				( attribute "PART_NUMBER" "A36095-026"
					( Origin gFrontEnd )
				)
				( attribute "PHYS_PAGE" "231"
					( Origin gFrontEnd )
				)
				( attribute "REUSE_ID" "27"
					( Origin gFrontEnd )
				)
				( attribute "ROOM" "PVPP_KLM_VR"
					( Origin gFrontEnd )
				)
				( attribute "ROT" "2"
					( Origin gFrontEnd )
				)
				( attribute "SEC" "1"
					( Origin gFrontEnd )
				)
				( attribute "SEC_TYPE" "0402LF"
					( Origin gFrontEnd )
				)
				( attribute "TOLERANCE" "5%"
					( Origin gFrontEnd )
				)
				( attribute "VALUE" "100.0PF"
					( Origin gFrontEnd )
				)
				( attribute "VER" "2"
					( Origin gFrontEnd )
				)
				( attribute "VOLTAGE" "50V"
					( Units "uVoltage" "V" 1.000000)
					( Origin gFrontEnd )
				)
				( attribute "XY" "(-1875,3075)"
					( Origin gFrontEnd )
				)
				( attribute "CHIPS_PART_NAME" "CAP"
					( Origin gPackager )
				)
				( attribute "CDS_PART_NAME" "CAP_0402LF-100.0PF,50V,5%,COG,A"
					( Origin gPackager )
				)
				( objectStatus "C7F9" )
			)
			( gate "@baseboard_fab2_lib.baseboard_fab2(sch_1):page231_i200"
				( attribute "BOM_COST" "PVPP_KLM_VR"
					( Origin gFrontEnd )
				)
				( attribute "CDS_LIB" "mstr_discrete"
					( Origin gPackager )
				)
				( attribute "CDS_LOCATION" "C7F12"
					( Origin gPackager )
				)
				( attribute "CDS_SEC" "1"
					( Origin gPackager )
				)
				( attribute "LOCATION" "C7F12"
					( Origin gFrontEnd )
				)
				( attribute "MATERIAL" "X7R"
					( Origin gFrontEnd )
				)
				( attribute "PACK_TYPE" "0402LF"
					( Origin gFrontEnd )
				)
				( attribute "PART_NUMBER" "A36096-075"
					( Origin gFrontEnd )
				)
				( attribute "PHYS_PAGE" "231"
					( Origin gFrontEnd )
				)
				( attribute "REUSE_ID" "27"
					( Origin gFrontEnd )
				)
				( attribute "ROOM" "PVPP_KLM_VR"
					( Origin gFrontEnd )
				)
				( attribute "ROT" "2"
					( Origin gFrontEnd )
				)
				( attribute "SEC" "1"
					( Origin gFrontEnd )
				)
				( attribute "SEC_TYPE" "0402LF"
					( Origin gFrontEnd )
				)
				( attribute "TOLERANCE" "10%"
					( Origin gFrontEnd )
				)
				( attribute "VALUE" "2200PF"
					( Origin gFrontEnd )
				)
				( attribute "VER" "2"
					( Origin gFrontEnd )
				)
				( attribute "VOLTAGE" "50V"
					( Units "uVoltage" "V" 1.000000)
					( Origin gFrontEnd )
				)
				( attribute "XY" "(-2500,2700)"
					( Origin gFrontEnd )
				)
				( attribute "CHIPS_PART_NAME" "CAP"
					( Origin gPackager )
				)
				( attribute "CDS_PART_NAME" "CAP_0402LF-2200PF,50V,10%,X7R,A"
					( Origin gPackager )
				)
				( objectStatus "C7F12" )
			)
			( gate "@baseboard_fab2_lib.baseboard_fab2(sch_1):page231_i201"
				( attribute "BOM_COST" "PVPP_KLM_VR"
					( Origin gFrontEnd )
				)
				( attribute "CDS_LIB" "mstr_discrete"
					( Origin gPackager )
				)
				( attribute "CDS_LOCATION" "R7F18"
					( Origin gPackager )
				)
				( attribute "CDS_SEC" "1"
					( Origin gPackager )
				)
				( attribute "LOCATION" "R7F18"
					( Origin gFrontEnd )
				)
				( attribute "MATERIAL" "CHIP"
					( Origin gFrontEnd )
				)
				( attribute "PACK_TYPE" "0402"
					( Origin gFrontEnd )
				)
				( attribute "PART_NUMBER" "G21796-242"
					( Origin gFrontEnd )
				)
				( attribute "PHYS_PAGE" "231"
					( Origin gFrontEnd )
				)
				( attribute "REUSE_ID" "13"
					( Origin gFrontEnd )
				)
				( attribute "ROOM" "PVPP_KLM_VR"
					( Origin gFrontEnd )
				)
				( attribute "ROT" "0"
					( Origin gFrontEnd )
				)
				( attribute "SEC" "1"
					( Origin gFrontEnd )
				)
				( attribute "SEC_TYPE" "0402"
					( Origin gFrontEnd )
				)
				( attribute "TOLERANCE" "1.0%"
					( Origin gFrontEnd )
				)
				( attribute "VALUE" "7.87K"
					( Origin gFrontEnd )
				)
				( attribute "VER" "1"
					( Origin gFrontEnd )
				)
				( attribute "WATTAGE" "1/16W"
					( Origin gFrontEnd )
				)
				( attribute "XY" "(-1800,2700)"
					( Origin gFrontEnd )
				)
				( attribute "CHIPS_PART_NAME" "RES"
					( Origin gPackager )
				)
				( attribute "CDS_PART_NAME" "RES_0402-7.87K,1.0%,1/16W,CHIPA"
					( Origin gPackager )
				)
				( objectStatus "R7F18" )
			)
			( gate "@baseboard_fab2_lib.baseboard_fab2(sch_1):page231_i202"
				( attribute "BOM_COST" "PVPP_KLM_VR"
					( Origin gFrontEnd )
				)
				( attribute "CDS_LIB" "mstr_discrete"
					( Origin gPackager )
				)
				( attribute "CDS_LOCATION" "C3T11"
					( Origin gPackager )
				)
				( attribute "CDS_SEC" "1"
					( Origin gPackager )
				)
				( attribute "LOCATION" "C3T11"
					( Origin gFrontEnd )
				)
				( attribute "MATERIAL" "X6S"
					( Origin gFrontEnd )
				)
				( attribute "PACK_TYPE" "0603"
					( Origin gFrontEnd )
				)
				( attribute "PART_NUMBER" "E15431-003"
					( Origin gFrontEnd )
				)
				( attribute "PHYS_PAGE" "231"
					( Origin gFrontEnd )
				)
				( attribute "REUSE_ID" "26"
					( Origin gFrontEnd )
				)
				( attribute "ROOM" "PVPP_KLM_VR"
					( Origin gFrontEnd )
				)
				( attribute "ROT" "0"
					( Origin gFrontEnd )
				)
				( attribute "SEC" "1"
					( Origin gFrontEnd )
				)
				( attribute "SEC_TYPE" "0603"
					( Origin gFrontEnd )
				)
				( attribute "TOLERANCE" "10%"
					( Origin gFrontEnd )
				)
				( attribute "VALUE" "4.7UF"
					( Origin gFrontEnd )
				)
				( attribute "VER" "1"
					( Origin gFrontEnd )
				)
				( attribute "VOLTAGE" "6.3V"
					( Units "uVoltage" "V" 1.000000)
					( Origin gFrontEnd )
				)
				( attribute "XY" "(-5375,2625)"
					( Origin gFrontEnd )
				)
				( attribute "CHIPS_PART_NAME" "CAP"
					( Origin gPackager )
				)
				( attribute "CDS_PART_NAME" "CAP_0603-4.7UF,6.3V,10%,X6S,E1A"
					( Origin gPackager )
				)
				( attribute "CONFIG" "078.47521.08BD"
					( Origin gFrontEnd )
				)
				( objectStatus "C3T11" )
			)
			( gate "@baseboard_fab2_lib.baseboard_fab2(sch_1):page231_i205"
				( attribute "CDS_LIB" "dev_discrete"
					( Origin gPackager )
				)
				( attribute "CDS_LOCATION" "C7F6"
					( Origin gPackager )
				)
				( attribute "CDS_SEC" "1"
					( Origin gPackager )
				)
				( attribute "LOCATION" "C7F6"
					( Origin gFrontEnd )
				)
				( attribute "MATERIAL" "X7R"
					( Origin gFrontEnd )
				)
				( attribute "PACK_TYPE" "0402V"
					( Origin gFrontEnd )
				)
				( attribute "PART_NUMBER" "A36096-030"
					( Origin gFrontEnd )
				)
				( attribute "PHYS_PAGE" "231"
					( Origin gFrontEnd )
				)
				( attribute "ROT" "0"
					( Origin gFrontEnd )
				)
				( attribute "SEC" "1"
					( Origin gFrontEnd )
				)
				( attribute "SEC_TYPE" "0402V"
					( Origin gFrontEnd )
				)
				( attribute "TOLERANCE" "10%"
					( Origin gFrontEnd )
				)
				( attribute "VALUE" "0.1UF"
					( Origin gFrontEnd )
				)
				( attribute "VER" "1"
					( Origin gFrontEnd )
				)
				( attribute "VOLTAGE" "16V"
					( Units "uVoltage" "V" 1.000000)
					( Origin gFrontEnd )
				)
				( attribute "XY" "(-4775,3750)"
					( Origin gFrontEnd )
				)
				( attribute "CHIPS_PART_NAME" "CAP_A"
					( Origin gPackager )
				)
				( attribute "CDS_PART_NAME" "CAP_A_0402V-0.1UF,16V,10%,X7R,A"
					( Origin gPackager )
				)
				( objectStatus "C7F6" )
			)
			( gate "@baseboard_fab2_lib.baseboard_fab2(sch_1):page231_i208"
				( attribute "CDS_LIB" "mstr_discrete"
					( Origin gPackager )
				)
				( attribute "CDS_LOCATION" "R7F16"
					( Origin gPackager )
				)
				( attribute "CDS_SEC" "1"
					( Origin gPackager )
				)
				( attribute "LOCATION" "R7F16"
					( Origin gFrontEnd )
				)
				( attribute "MATERIAL" "CHIP"
					( Origin gFrontEnd )
				)
				( attribute "PACK_TYPE" "0402"
					( Origin gFrontEnd )
				)
				( attribute "PART_NUMBER" "G21796-250"
					( Origin gFrontEnd )
				)
				( attribute "PHYS_PAGE" "231"
					( Origin gFrontEnd )
				)
				( attribute "ROOM" "PVPP_KLM_VR"
					( Origin gFrontEnd )
				)
				( attribute "ROT" "0"
					( Origin gFrontEnd )
				)
				( attribute "SEC" "1"
					( Origin gFrontEnd )
				)
				( attribute "SEC_TYPE" "0402"
					( Origin gFrontEnd )
				)
				( attribute "TOLERANCE" "1.0%"
					( Origin gFrontEnd )
				)
				( attribute "VALUE" "22.1"
					( Origin gFrontEnd )
				)
				( attribute "VER" "1"
					( Origin gFrontEnd )
				)
				( attribute "WATTAGE" "1/16W"
					( Origin gFrontEnd )
				)
				( attribute "XY" "(-3000,1225)"
					( Origin gFrontEnd )
				)
				( attribute "CHIPS_PART_NAME" "RES"
					( Origin gPackager )
				)
				( attribute "CDS_PART_NAME" "RES_0402-22.1,1.0%,1/16W,CHIP,A"
					( Origin gPackager )
				)
				( objectStatus "R7F16" )
			)
			( gate "@baseboard_fab2_lib.baseboard_fab2(sch_1):page231_i209"
				( attribute "CDS_LIB" "mstr_discrete"
					( Origin gPackager )
				)
				( attribute "CDS_LOCATION" "C7F5"
					( Origin gPackager )
				)
				( attribute "CDS_SEC" "1"
					( Origin gPackager )
				)
				( attribute "LOCATION" "C7F5"
					( Origin gFrontEnd )
				)
				( attribute "MATERIAL" "X6S"
					( Origin gFrontEnd )
				)
				( attribute "PACK_TYPE" "0805"
					( Origin gFrontEnd )
				)
				( attribute "PART_NUMBER" "C95333-007"
					( Origin gFrontEnd )
				)
				( attribute "PHYS_PAGE" "231"
					( Origin gFrontEnd )
				)
				( attribute "ROT" "0"
					( Origin gFrontEnd )
				)
				( attribute "SEC" "1"
					( Origin gFrontEnd )
				)
				( attribute "SEC_TYPE" "0805"
					( Origin gFrontEnd )
				)
				( attribute "TOLERANCE" "10%"
					( Origin gFrontEnd )
				)
				( attribute "VALUE" "10UF"
					( Origin gFrontEnd )
				)
				( attribute "VER" "1"
					( Origin gFrontEnd )
				)
				( attribute "VOLTAGE" "16V"
					( Units "uVoltage" "V" 1.000000)
					( Origin gFrontEnd )
				)
				( attribute "XY" "(-6225,4375)"
					( Origin gFrontEnd )
				)
				( attribute "CHIPS_PART_NAME" "CAP"
					( Origin gPackager )
				)
				( attribute "CDS_PART_NAME" "CAP_0805-10UF,16V,10%,X6S,C953A"
					( Origin gPackager )
				)
				( objectStatus "C7F5" )
			)
			( gate "@baseboard_fab2_lib.baseboard_fab2(sch_1):page231_i210"
				( attribute "CDS_LIB" "mstr_discrete"
					( Origin gPackager )
				)
				( attribute "CDS_LOCATION" "C3T8"
					( Origin gPackager )
				)
				( attribute "CDS_SEC" "1"
					( Origin gPackager )
				)
				( attribute "LOCATION" "C3T8"
					( Origin gFrontEnd )
				)
				( attribute "MATERIAL" "X6S"
					( Origin gFrontEnd )
				)
				( attribute "PACK_TYPE" "0805"
					( Origin gFrontEnd )
				)
				( attribute "PART_NUMBER" "C95333-007"
					( Origin gFrontEnd )
				)
				( attribute "PHYS_PAGE" "231"
					( Origin gFrontEnd )
				)
				( attribute "ROT" "0"
					( Origin gFrontEnd )
				)
				( attribute "SEC" "1"
					( Origin gFrontEnd )
				)
				( attribute "SEC_TYPE" "0805"
					( Origin gFrontEnd )
				)
				( attribute "TOLERANCE" "10%"
					( Origin gFrontEnd )
				)
				( attribute "VALUE" "10UF"
					( Origin gFrontEnd )
				)
				( attribute "VER" "1"
					( Origin gFrontEnd )
				)
				( attribute "VOLTAGE" "16V"
					( Units "uVoltage" "V" 1.000000)
					( Origin gFrontEnd )
				)
				( attribute "XY" "(-5825,4375)"
					( Origin gFrontEnd )
				)
				( attribute "CHIPS_PART_NAME" "CAP"
					( Origin gPackager )
				)
				( attribute "CDS_PART_NAME" "CAP_0805-10UF,16V,10%,X6S,C953A"
					( Origin gPackager )
				)
				( objectStatus "C3T8" )
			)
			( gate "@baseboard_fab2_lib.baseboard_fab2(sch_1):page231_i211"
				( attribute "CDS_LIB" "mstr_discrete"
					( Origin gPackager )
				)
				( attribute "CDS_LOCATION" "C3T14"
					( Origin gPackager )
				)
				( attribute "CDS_SEC" "1"
					( Origin gPackager )
				)
				( attribute "LOCATION" "C3T14"
					( Origin gFrontEnd )
				)
				( attribute "MATERIAL" "X6S"
					( Origin gFrontEnd )
				)
				( attribute "PACK_TYPE" "0805"
					( Origin gFrontEnd )
				)
				( attribute "PART_NUMBER" "C95333-007"
					( Origin gFrontEnd )
				)
				( attribute "PHYS_PAGE" "231"
					( Origin gFrontEnd )
				)
				( attribute "ROT" "0"
					( Origin gFrontEnd )
				)
				( attribute "SEC" "1"
					( Origin gFrontEnd )
				)
				( attribute "SEC_TYPE" "0805"
					( Origin gFrontEnd )
				)
				( attribute "TOLERANCE" "10%"
					( Origin gFrontEnd )
				)
				( attribute "VALUE" "10UF"
					( Origin gFrontEnd )
				)
				( attribute "VER" "1"
					( Origin gFrontEnd )
				)
				( attribute "VOLTAGE" "16V"
					( Units "uVoltage" "V" 1.000000)
					( Origin gFrontEnd )
				)
				( attribute "XY" "(-5425,4375)"
					( Origin gFrontEnd )
				)
				( attribute "CHIPS_PART_NAME" "CAP"
					( Origin gPackager )
				)
				( attribute "CDS_PART_NAME" "CAP_0805-10UF,16V,10%,X6S,C953A"
					( Origin gPackager )
				)
				( objectStatus "C3T14" )
			)
			( gate "@baseboard_fab2_lib.baseboard_fab2(sch_1):page231_i215"
				( attribute "CDS_LIB" "mstr_discrete"
					( Origin gPackager )
				)
				( attribute "CDS_LOCATION" "C3T12"
					( Origin gPackager )
				)
				( attribute "CDS_SEC" "1"
					( Origin gPackager )
				)
				( attribute "LOCATION" "C3T12"
					( Origin gFrontEnd )
				)
				( attribute "MATERIAL" "X6S"
					( Origin gFrontEnd )
				)
				( attribute "PACK_TYPE" "0805"
					( Origin gFrontEnd )
				)
				( attribute "PART_NUMBER" "C95333-007"
					( Origin gFrontEnd )
				)
				( attribute "PHYS_PAGE" "231"
					( Origin gFrontEnd )
				)
				( attribute "ROT" "0"
					( Origin gFrontEnd )
				)
				( attribute "SEC" "1"
					( Origin gFrontEnd )
				)
				( attribute "SEC_TYPE" "0805"
					( Origin gFrontEnd )
				)
				( attribute "TOLERANCE" "10%"
					( Origin gFrontEnd )
				)
				( attribute "VALUE" "10UF"
					( Origin gFrontEnd )
				)
				( attribute "VER" "1"
					( Origin gFrontEnd )
				)
				( attribute "VOLTAGE" "16V"
					( Units "uVoltage" "V" 1.000000)
					( Origin gFrontEnd )
				)
				( attribute "XY" "(-5075,4375)"
					( Origin gFrontEnd )
				)
				( attribute "CHIPS_PART_NAME" "CAP"
					( Origin gPackager )
				)
				( attribute "CDS_PART_NAME" "CAP_0805-10UF,16V,10%,X6S,C953A"
					( Origin gPackager )
				)
				( objectStatus "C3T12" )
			)
			( gate "@baseboard_fab2_lib.baseboard_fab2(sch_1):page231_i217"
				( attribute "CDS_LIB" "mstr_discrete"
					( Origin gPackager )
				)
				( attribute "CDS_LOCATION" "C4T3"
					( Origin gPackager )
				)
				( attribute "CDS_SEC" "1"
					( Origin gPackager )
				)
				( attribute "LOCATION" "C4T3"
					( Origin gFrontEnd )
				)
				( attribute "MATERIAL" "POSCAP"
					( Origin gFrontEnd )
				)
				( attribute "PACK_TYPE" "7343"
					( Origin gFrontEnd )
				)
				( attribute "PART_NUMBER" "724613-067"
					( Origin gFrontEnd )
				)
				( attribute "PHYS_PAGE" "231"
					( Origin gFrontEnd )
				)
				( attribute "ROT" "0"
					( Origin gFrontEnd )
				)
				( attribute "SEC" "1"
					( Origin gFrontEnd )
				)
				( attribute "SEC_TYPE" "7343"
					( Origin gFrontEnd )
				)
				( attribute "TOLERANCE" "20%"
					( Origin gFrontEnd )
				)
				( attribute "VALUE" "220UF"
					( Origin gFrontEnd )
				)
				( attribute "VER" "1"
					( Origin gFrontEnd )
				)
				( attribute "VOLTAGE" "4V"
					( Units "uVoltage" "V" 1.000000)
					( Origin gFrontEnd )
				)
				( attribute "XY" "(-1100,3900)"
					( Origin gFrontEnd )
				)
				( attribute "CHIPS_PART_NAME" "CAPP"
					( Origin gPackager )
				)
				( attribute "CDS_PART_NAME" "CAPP_7343-220UF,4V,20%,POSCAP,A"
					( Origin gPackager )
				)
				( attribute "GROUP" "PWR_BULK_CAP"
					( Origin gFrontEnd )
				)
				( objectStatus "C4T3" )
			)
			( gate "@baseboard_fab2_lib.baseboard_fab2(sch_1):page231_i218"
				( attribute "BOM_COST" "PVPP_KLM_VR"
					( Origin gFrontEnd )
				)
				( attribute "CDS_LIB" "mstr_discrete"
					( Origin gPackager )
				)
				( attribute "CDS_LOCATION" "R7F17"
					( Origin gPackager )
				)
				( attribute "CDS_SEC" "1"
					( Origin gPackager )
				)
				( attribute "LOCATION" "R7F17"
					( Origin gFrontEnd )
				)
				( attribute "MATERIAL" "CHIP"
					( Origin gFrontEnd )
				)
				( attribute "PACK_TYPE" "0402"
					( Origin gFrontEnd )
				)
				( attribute "PART_NUMBER" "G85996-004"
					( Origin gFrontEnd )
				)
				( attribute "PHYS_PAGE" "231"
					( Origin gFrontEnd )
				)
				( attribute "REUSE_ID" "9"
					( Origin gFrontEnd )
				)
				( attribute "ROOM" "PVPP_KLM_VR"
					( Origin gFrontEnd )
				)
				( attribute "ROT" "0"
					( Origin gFrontEnd )
				)
				( attribute "SEC" "1"
					( Origin gFrontEnd )
				)
				( attribute "SEC_TYPE" "0402"
					( Origin gFrontEnd )
				)
				( attribute "SPOF" "TRUE"
					( Origin gFrontEnd )
				)
				( attribute "TOLERANCE" "0.1%"
					( Origin gFrontEnd )
				)
				( attribute "VALUE" "1.0K"
					( Origin gFrontEnd )
				)
				( attribute "VER" "2"
					( Origin gFrontEnd )
				)
				( attribute "WATTAGE" "1/16W"
					( Origin gFrontEnd )
				)
				( attribute "XY" "(-675,2800)"
					( Origin gFrontEnd )
				)
				( attribute "CHIPS_PART_NAME" "RES"
					( Origin gPackager )
				)
				( attribute "CDS_PART_NAME" "RES_0402-1.0K,0.1%,1/16W,CHIP,A"
					( Origin gPackager )
				)
				( objectStatus "R7F17" )
			)
			( gate "@baseboard_fab2_lib.baseboard_fab2(sch_1):page231_i219"
				( attribute "BOM_COST" "PVPP_KLM_VR"
					( Origin gFrontEnd )
				)
				( attribute "CDS_LIB" "mstr_discrete"
					( Origin gPackager )
				)
				( attribute "CDS_LOCATION" "C7F13"
					( Origin gPackager )
				)
				( attribute "CDS_SEC" "1"
					( Origin gPackager )
				)
				( attribute "LOCATION" "C7F13"
					( Origin gFrontEnd )
				)
				( attribute "MATERIAL" "X7R"
					( Origin gFrontEnd )
				)
				( attribute "PACK_TYPE" "0402LF"
					( Origin gFrontEnd )
				)
				( attribute "PART_NUMBER" "A36096-075"
					( Origin gFrontEnd )
				)
				( attribute "PHYS_PAGE" "231"
					( Origin gFrontEnd )
				)
				( attribute "REUSE_ID" "26"
					( Origin gFrontEnd )
				)
				( attribute "ROOM" "PVPP_KLM_VR"
					( Origin gFrontEnd )
				)
				( attribute "ROT" "0"
					( Origin gFrontEnd )
				)
				( attribute "SEC" "1"
					( Origin gFrontEnd )
				)
				( attribute "SEC_TYPE" "0402LF"
					( Origin gFrontEnd )
				)
				( attribute "SPOF" "TRUE"
					( Origin gFrontEnd )
				)
				( attribute "TOLERANCE" "10%"
					( Origin gFrontEnd )
				)
				( attribute "VALUE" "2200PF"
					( Origin gFrontEnd )
				)
				( attribute "VER" "1"
					( Origin gFrontEnd )
				)
				( attribute "VOLTAGE" "50V"
					( Units "uVoltage" "V" 1.000000)
					( Origin gFrontEnd )
				)
				( attribute "XY" "(-675,2000)"
					( Origin gFrontEnd )
				)
				( attribute "CHIPS_PART_NAME" "CAP"
					( Origin gPackager )
				)
				( attribute "CDS_PART_NAME" "CAP_0402LF-2200PF,50V,10%,X7R,A"
					( Origin gPackager )
				)
				( objectStatus "C7F13" )
			)
			( gate "@baseboard_fab2_lib.baseboard_fab2(sch_1):page231_i220"
				( attribute "CDS_LIB" "mstr_discrete"
					( Origin gPackager )
				)
				( attribute "CDS_LOCATION" "R7F9"
					( Origin gPackager )
				)
				( attribute "CDS_SEC" "1"
					( Origin gPackager )
				)
				( attribute "LOCATION" "R7F9"
					( Origin gFrontEnd )
				)
				( attribute "MATERIAL" "CHIP"
					( Origin gFrontEnd )
				)
				( attribute "PACK_TYPE" "0402"
					( Origin gFrontEnd )
				)
				( attribute "PART_NUMBER" "G21497-005"
					( Origin gFrontEnd )
				)
				( attribute "PHYS_PAGE" "231"
					( Origin gFrontEnd )
				)
				( attribute "ROOM" "PVCCIN_CPU0_VR"
					( Origin gFrontEnd )
				)
				( attribute "ROT" "0"
					( Origin gFrontEnd )
				)
				( attribute "SEC" "1"
					( Origin gFrontEnd )
				)
				( attribute "SEC_TYPE" "0402"
					( Origin gFrontEnd )
				)
				( attribute "TOLERANCE" "5%"
					( Origin gFrontEnd )
				)
				( attribute "VALUE" "0.0"
					( Origin gFrontEnd )
				)
				( attribute "VER" "1"
					( Origin gFrontEnd )
				)
				( attribute "WATTAGE" "1/16W"
					( Origin gFrontEnd )
				)
				( attribute "XY" "(-5775,3075)"
					( Origin gFrontEnd )
				)
				( attribute "CHIPS_PART_NAME" "RES"
					( Origin gPackager )
				)
				( attribute "CDS_PART_NAME" "RES_0402-0.0,5%,1/16W,CHIP,G21A"
					( Origin gPackager )
				)
				( objectStatus "R7F9" )
			)
			( gate "@baseboard_fab2_lib.baseboard_fab2(sch_1):page232_i102"
				( attribute "BOM_COST" "MEM_VRD_PVPP_AB"
					( Origin gFrontEnd )
				)
				( attribute "CDS_LIB" "mstr_discrete"
					( Origin gPackager )
				)
				( attribute "CDS_LOCATION" "C4L2"
					( Origin gPackager )
				)
				( attribute "CDS_SEC" "1"
					( Origin gPackager )
				)
				( attribute "LOCATION" "C4L2"
					( Origin gFrontEnd )
				)
				( attribute "MATERIAL" "X6S"
					( Origin gFrontEnd )
				)
				( attribute "PACK_TYPE" "0603LF"
					( Origin gFrontEnd )
				)
				( attribute "PART_NUMBER" "E15431-001"
					( Origin gFrontEnd )
				)
				( attribute "PHYS_PAGE" "232"
					( Origin gFrontEnd )
				)
				( attribute "ROOM" "PVPP_KLM_VR"
					( Origin gFrontEnd )
				)
				( attribute "ROT" "0"
					( Origin gFrontEnd )
				)
				( attribute "SEC" "1"
					( Origin gPackager )
				)
				( attribute "TOLERANCE" "20%"
					( Origin gFrontEnd )
				)
				( attribute "VALUE" "10UF"
					( Origin gFrontEnd )
				)
				( attribute "VER" "1"
					( Origin gFrontEnd )
				)
				( attribute "VOLTAGE" "4V"
					( Units "uVoltage" "V" 1.000000)
					( Origin gFrontEnd )
				)
				( attribute "XY" "(-8600,875)"
					( Origin gFrontEnd )
				)
				( attribute "CHIPS_PART_NAME" "CAP"
					( Origin gPackager )
				)
				( attribute "CDS_PART_NAME" "CAP_0603LF-10UF,4V,20%,X6S,E15A"
					( Origin gPackager )
				)
				( attribute "GROUP" "PWR_MLCC_CAP"
					( Origin gFrontEnd )
				)
				( objectStatus "C4L2" )
			)
			( gate "@baseboard_fab2_lib.baseboard_fab2(sch_1):page232_i104"
				( attribute "BOM_COST" "MEM_VRD_PVPP_AB"
					( Origin gFrontEnd )
				)
				( attribute "CDS_LIB" "mstr_discrete"
					( Origin gPackager )
				)
				( attribute "CDS_LOCATION" "C6A3"
					( Origin gPackager )
				)
				( attribute "CDS_SEC" "1"
					( Origin gPackager )
				)
				( attribute "LOCATION" "C6A3"
					( Origin gFrontEnd )
				)
				( attribute "MATERIAL" "X6S"
					( Origin gFrontEnd )
				)
				( attribute "PACK_TYPE" "0603LF"
					( Origin gFrontEnd )
				)
				( attribute "PART_NUMBER" "E15431-001"
					( Origin gFrontEnd )
				)
				( attribute "PHYS_PAGE" "232"
					( Origin gFrontEnd )
				)
				( attribute "ROOM" "PVPP_KLM_VR"
					( Origin gFrontEnd )
				)
				( attribute "ROT" "0"
					( Origin gFrontEnd )
				)
				( attribute "SEC" "1"
					( Origin gPackager )
				)
				( attribute "TOLERANCE" "20%"
					( Origin gFrontEnd )
				)
				( attribute "VALUE" "10UF"
					( Origin gFrontEnd )
				)
				( attribute "VER" "1"
					( Origin gFrontEnd )
				)
				( attribute "VOLTAGE" "4V"
					( Units "uVoltage" "V" 1.000000)
					( Origin gFrontEnd )
				)
				( attribute "XY" "(-8325,875)"
					( Origin gFrontEnd )
				)
				( attribute "CHIPS_PART_NAME" "CAP"
					( Origin gPackager )
				)
				( attribute "CDS_PART_NAME" "CAP_0603LF-10UF,4V,20%,X6S,E15A"
					( Origin gPackager )
				)
				( attribute "GROUP" "PWR_MLCC_CAP"
					( Origin gFrontEnd )
				)
				( objectStatus "C6A3" )
			)
			( gate "@baseboard_fab2_lib.baseboard_fab2(sch_1):page232_i105"
				( attribute "BOM_COST" "MEM_VRD_PVPP_AB"
					( Origin gFrontEnd )
				)
				( attribute "CDS_LIB" "mstr_discrete"
					( Origin gPackager )
				)
				( attribute "CDS_LOCATION" "C6A2"
					( Origin gPackager )
				)
				( attribute "CDS_SEC" "1"
					( Origin gPackager )
				)
				( attribute "LOCATION" "C6A2"
					( Origin gFrontEnd )
				)
				( attribute "MATERIAL" "X6S"
					( Origin gFrontEnd )
				)
				( attribute "PACK_TYPE" "0603LF"
					( Origin gFrontEnd )
				)
				( attribute "PART_NUMBER" "E15431-001"
					( Origin gFrontEnd )
				)
				( attribute "PHYS_PAGE" "232"
					( Origin gFrontEnd )
				)
				( attribute "ROOM" "PVPP_KLM_VR"
					( Origin gFrontEnd )
				)
				( attribute "ROT" "0"
					( Origin gFrontEnd )
				)
				( attribute "SEC" "1"
					( Origin gPackager )
				)
				( attribute "TOLERANCE" "20%"
					( Origin gFrontEnd )
				)
				( attribute "VALUE" "10UF"
					( Origin gFrontEnd )
				)
				( attribute "VER" "1"
					( Origin gFrontEnd )
				)
				( attribute "VOLTAGE" "4V"
					( Units "uVoltage" "V" 1.000000)
					( Origin gFrontEnd )
				)
				( attribute "XY" "(-8050,875)"
					( Origin gFrontEnd )
				)
				( attribute "CHIPS_PART_NAME" "CAP"
					( Origin gPackager )
				)
				( attribute "CDS_PART_NAME" "CAP_0603LF-10UF,4V,20%,X6S,E15A"
					( Origin gPackager )
				)
				( attribute "GROUP" "PWR_MLCC_CAP"
					( Origin gFrontEnd )
				)
				( objectStatus "C6A2" )
			)
			( gate "@baseboard_fab2_lib.baseboard_fab2(sch_1):page232_i106"
				( attribute "BOM_COST" "MEM_VRD_PVPP_AB"
					( Origin gFrontEnd )
				)
				( attribute "CDS_LIB" "mstr_discrete"
					( Origin gPackager )
				)
				( attribute "CDS_LOCATION" "C4L3"
					( Origin gPackager )
				)
				( attribute "CDS_SEC" "1"
					( Origin gPackager )
				)
				( attribute "LOCATION" "C4L3"
					( Origin gFrontEnd )
				)
				( attribute "MATERIAL" "X6S"
					( Origin gFrontEnd )
				)
				( attribute "PACK_TYPE" "0603LF"
					( Origin gFrontEnd )
				)
				( attribute "PART_NUMBER" "E15431-001"
					( Origin gFrontEnd )
				)
				( attribute "PHYS_PAGE" "232"
					( Origin gFrontEnd )
				)
				( attribute "ROOM" "PVPP_KLM_VR"
					( Origin gFrontEnd )
				)
				( attribute "ROT" "0"
					( Origin gFrontEnd )
				)
				( attribute "SEC" "1"
					( Origin gPackager )
				)
				( attribute "TOLERANCE" "20%"
					( Origin gFrontEnd )
				)
				( attribute "VALUE" "10UF"
					( Origin gFrontEnd )
				)
				( attribute "VER" "1"
					( Origin gFrontEnd )
				)
				( attribute "VOLTAGE" "4V"
					( Units "uVoltage" "V" 1.000000)
					( Origin gFrontEnd )
				)
				( attribute "XY" "(-7775,875)"
					( Origin gFrontEnd )
				)
				( attribute "CHIPS_PART_NAME" "CAP"
					( Origin gPackager )
				)
				( attribute "CDS_PART_NAME" "CAP_0603LF-10UF,4V,20%,X6S,E15A"
					( Origin gPackager )
				)
				( attribute "GROUP" "PWR_MLCC_CAP"
					( Origin gFrontEnd )
				)
				( objectStatus "C4L3" )
			)
			( gate "@baseboard_fab2_lib.baseboard_fab2(sch_1):page232_i108"
				( attribute "BOM_COST" "MEM_VRD_PVPP_AB"
					( Origin gFrontEnd )
				)
				( attribute "CDS_LIB" "mstr_discrete"
					( Origin gPackager )
				)
				( attribute "CDS_LOCATION" "C4L4"
					( Origin gPackager )
				)
				( attribute "CDS_SEC" "1"
					( Origin gPackager )
				)
				( attribute "LOCATION" "C4L4"
					( Origin gFrontEnd )
				)
				( attribute "MATERIAL" "X6S"
					( Origin gFrontEnd )
				)
				( attribute "PACK_TYPE" "0603LF"
					( Origin gFrontEnd )
				)
				( attribute "PART_NUMBER" "E15431-001"
					( Origin gFrontEnd )
				)
				( attribute "PHYS_PAGE" "232"
					( Origin gFrontEnd )
				)
				( attribute "ROOM" "PVPP_KLM_VR"
					( Origin gFrontEnd )
				)
				( attribute "ROT" "0"
					( Origin gFrontEnd )
				)
				( attribute "SEC" "1"
					( Origin gPackager )
				)
				( attribute "TOLERANCE" "20%"
					( Origin gFrontEnd )
				)
				( attribute "VALUE" "10UF"
					( Origin gFrontEnd )
				)
				( attribute "VER" "1"
					( Origin gFrontEnd )
				)
				( attribute "VOLTAGE" "4V"
					( Units "uVoltage" "V" 1.000000)
					( Origin gFrontEnd )
				)
				( attribute "XY" "(-7500,875)"
					( Origin gFrontEnd )
				)
				( attribute "CHIPS_PART_NAME" "CAP"
					( Origin gPackager )
				)
				( attribute "CDS_PART_NAME" "CAP_0603LF-10UF,4V,20%,X6S,E15A"
					( Origin gPackager )
				)
				( attribute "GROUP" "PWR_MLCC_CAP"
					( Origin gFrontEnd )
				)
				( objectStatus "C4L4" )
			)
			( gate "@baseboard_fab2_lib.baseboard_fab2(sch_1):page232_i109"
				( attribute "BOM_COST" "MEM_VRD_PVPP_AB"
					( Origin gFrontEnd )
				)
				( attribute "CDS_LIB" "mstr_discrete"
					( Origin gPackager )
				)
				( attribute "CDS_LOCATION" "C6A7"
					( Origin gPackager )
				)
				( attribute "CDS_SEC" "1"
					( Origin gPackager )
				)
				( attribute "LOCATION" "C6A7"
					( Origin gFrontEnd )
				)
				( attribute "MATERIAL" "X6S"
					( Origin gFrontEnd )
				)
				( attribute "PACK_TYPE" "0603LF"
					( Origin gFrontEnd )
				)
				( attribute "PART_NUMBER" "E15431-001"
					( Origin gFrontEnd )
				)
				( attribute "PHYS_PAGE" "232"
					( Origin gFrontEnd )
				)
				( attribute "ROOM" "PVPP_KLM_VR"
					( Origin gFrontEnd )
				)
				( attribute "ROT" "0"
					( Origin gFrontEnd )
				)
				( attribute "SEC" "1"
					( Origin gPackager )
				)
				( attribute "TOLERANCE" "20%"
					( Origin gFrontEnd )
				)
				( attribute "VALUE" "10UF"
					( Origin gFrontEnd )
				)
				( attribute "VER" "1"
					( Origin gFrontEnd )
				)
				( attribute "VOLTAGE" "4V"
					( Units "uVoltage" "V" 1.000000)
					( Origin gFrontEnd )
				)
				( attribute "XY" "(-7200,875)"
					( Origin gFrontEnd )
				)
				( attribute "CHIPS_PART_NAME" "CAP"
					( Origin gPackager )
				)
				( attribute "CDS_PART_NAME" "CAP_0603LF-10UF,4V,20%,X6S,E15A"
					( Origin gPackager )
				)
				( attribute "GROUP" "PWR_MLCC_CAP"
					( Origin gFrontEnd )
				)
				( objectStatus "C6A7" )
			)
			( gate "@baseboard_fab2_lib.baseboard_fab2(sch_1):page232_i110"
				( attribute "BOM_COST" "MEM_VRD_PVPP_AB"
					( Origin gFrontEnd )
				)
				( attribute "CDS_LIB" "mstr_discrete"
					( Origin gPackager )
				)
				( attribute "CDS_LOCATION" "C6A6"
					( Origin gPackager )
				)
				( attribute "CDS_SEC" "1"
					( Origin gPackager )
				)
				( attribute "LOCATION" "C6A6"
					( Origin gFrontEnd )
				)
				( attribute "MATERIAL" "X6S"
					( Origin gFrontEnd )
				)
				( attribute "PACK_TYPE" "0603LF"
					( Origin gFrontEnd )
				)
				( attribute "PART_NUMBER" "E15431-001"
					( Origin gFrontEnd )
				)
				( attribute "PHYS_PAGE" "232"
					( Origin gFrontEnd )
				)
				( attribute "ROOM" "PVPP_KLM_VR"
					( Origin gFrontEnd )
				)
				( attribute "ROT" "0"
					( Origin gFrontEnd )
				)
				( attribute "SEC" "1"
					( Origin gPackager )
				)
				( attribute "TOLERANCE" "20%"
					( Origin gFrontEnd )
				)
				( attribute "VALUE" "10UF"
					( Origin gFrontEnd )
				)
				( attribute "VER" "1"
					( Origin gFrontEnd )
				)
				( attribute "VOLTAGE" "4V"
					( Units "uVoltage" "V" 1.000000)
					( Origin gFrontEnd )
				)
				( attribute "XY" "(-6925,875)"
					( Origin gFrontEnd )
				)
				( attribute "CHIPS_PART_NAME" "CAP"
					( Origin gPackager )
				)
				( attribute "CDS_PART_NAME" "CAP_0603LF-10UF,4V,20%,X6S,E15A"
					( Origin gPackager )
				)
				( attribute "GROUP" "PWR_MLCC_CAP"
					( Origin gFrontEnd )
				)
				( objectStatus "C6A6" )
			)
			( gate "@baseboard_fab2_lib.baseboard_fab2(sch_1):page232_i111"
				( attribute "BOM_COST" "MEM_VRD_PVPP_AB"
					( Origin gFrontEnd )
				)
				( attribute "CDS_LIB" "mstr_discrete"
					( Origin gPackager )
				)
				( attribute "CDS_LOCATION" "C4M3"
					( Origin gPackager )
				)
				( attribute "CDS_SEC" "1"
					( Origin gPackager )
				)
				( attribute "LOCATION" "C4M3"
					( Origin gFrontEnd )
				)
				( attribute "MATERIAL" "X6S"
					( Origin gFrontEnd )
				)
				( attribute "PACK_TYPE" "0603LF"
					( Origin gFrontEnd )
				)
				( attribute "PART_NUMBER" "E15431-001"
					( Origin gFrontEnd )
				)
				( attribute "PHYS_PAGE" "232"
					( Origin gFrontEnd )
				)
				( attribute "ROOM" "PVPP_KLM_VR"
					( Origin gFrontEnd )
				)
				( attribute "ROT" "0"
					( Origin gFrontEnd )
				)
				( attribute "SEC" "1"
					( Origin gPackager )
				)
				( attribute "TOLERANCE" "20%"
					( Origin gFrontEnd )
				)
				( attribute "VALUE" "10UF"
					( Origin gFrontEnd )
				)
				( attribute "VER" "1"
					( Origin gFrontEnd )
				)
				( attribute "VOLTAGE" "4V"
					( Units "uVoltage" "V" 1.000000)
					( Origin gFrontEnd )
				)
				( attribute "XY" "(-6625,875)"
					( Origin gFrontEnd )
				)
				( attribute "CHIPS_PART_NAME" "CAP"
					( Origin gPackager )
				)
				( attribute "CDS_PART_NAME" "CAP_0603LF-10UF,4V,20%,X6S,E15A"
					( Origin gPackager )
				)
				( attribute "GROUP" "PWR_MLCC_CAP"
					( Origin gFrontEnd )
				)
				( objectStatus "C4M3" )
			)
			( gate "@baseboard_fab2_lib.baseboard_fab2(sch_1):page232_i125"
				( attribute "BOM_COST" "MEM_VRD_PVPP_AB"
					( Origin gFrontEnd )
				)
				( attribute "CDS_LIB" "mstr_discrete"
					( Origin gPackager )
				)
				( attribute "CDS_LOCATION" "C4M4"
					( Origin gPackager )
				)
				( attribute "CDS_SEC" "1"
					( Origin gPackager )
				)
				( attribute "LOCATION" "C4M4"
					( Origin gFrontEnd )
				)
				( attribute "MATERIAL" "X6S"
					( Origin gFrontEnd )
				)
				( attribute "PACK_TYPE" "0603LF"
					( Origin gFrontEnd )
				)
				( attribute "PART_NUMBER" "E15431-001"
					( Origin gFrontEnd )
				)
				( attribute "PHYS_PAGE" "232"
					( Origin gFrontEnd )
				)
				( attribute "ROOM" "PVPP_KLM_VR"
					( Origin gFrontEnd )
				)
				( attribute "ROT" "0"
					( Origin gFrontEnd )
				)
				( attribute "SEC" "1"
					( Origin gPackager )
				)
				( attribute "TOLERANCE" "20%"
					( Origin gFrontEnd )
				)
				( attribute "VALUE" "10UF"
					( Origin gFrontEnd )
				)
				( attribute "VER" "1"
					( Origin gFrontEnd )
				)
				( attribute "VOLTAGE" "4V"
					( Units "uVoltage" "V" 1.000000)
					( Origin gFrontEnd )
				)
				( attribute "XY" "(-6325,875)"
					( Origin gFrontEnd )
				)
				( attribute "CHIPS_PART_NAME" "CAP"
					( Origin gPackager )
				)
				( attribute "CDS_PART_NAME" "CAP_0603LF-10UF,4V,20%,X6S,E15A"
					( Origin gPackager )
				)
				( attribute "GROUP" "PWR_MLCC_CAP"
					( Origin gFrontEnd )
				)
				( objectStatus "C4M4" )
			)
			( gate "@baseboard_fab2_lib.baseboard_fab2(sch_1):page232_i126"
				( attribute "BOM_COST" "MEM_VRD_PVPP_AB"
					( Origin gFrontEnd )
				)
				( attribute "CDS_LIB" "mstr_discrete"
					( Origin gPackager )
				)
				( attribute "CDS_LOCATION" "C6B2"
					( Origin gPackager )
				)
				( attribute "CDS_SEC" "1"
					( Origin gPackager )
				)
				( attribute "LOCATION" "C6B2"
					( Origin gFrontEnd )
				)
				( attribute "MATERIAL" "X6S"
					( Origin gFrontEnd )
				)
				( attribute "PACK_TYPE" "0603LF"
					( Origin gFrontEnd )
				)
				( attribute "PART_NUMBER" "E15431-001"
					( Origin gFrontEnd )
				)
				( attribute "PHYS_PAGE" "232"
					( Origin gFrontEnd )
				)
				( attribute "ROOM" "PVPP_KLM_VR"
					( Origin gFrontEnd )
				)
				( attribute "ROT" "0"
					( Origin gFrontEnd )
				)
				( attribute "SEC" "1"
					( Origin gPackager )
				)
				( attribute "TOLERANCE" "20%"
					( Origin gFrontEnd )
				)
				( attribute "VALUE" "10UF"
					( Origin gFrontEnd )
				)
				( attribute "VER" "1"
					( Origin gFrontEnd )
				)
				( attribute "VOLTAGE" "4V"
					( Units "uVoltage" "V" 1.000000)
					( Origin gFrontEnd )
				)
				( attribute "XY" "(-6050,875)"
					( Origin gFrontEnd )
				)
				( attribute "CHIPS_PART_NAME" "CAP"
					( Origin gPackager )
				)
				( attribute "CDS_PART_NAME" "CAP_0603LF-10UF,4V,20%,X6S,E15A"
					( Origin gPackager )
				)
				( attribute "GROUP" "PWR_MLCC_CAP"
					( Origin gFrontEnd )
				)
				( objectStatus "C6B2" )
			)
			( gate "@baseboard_fab2_lib.baseboard_fab2(sch_1):page232_i128"
				( attribute "BOM_COST" "MEM_VRD_PVPP_AB"
					( Origin gFrontEnd )
				)
				( attribute "CDS_LIB" "mstr_discrete"
					( Origin gPackager )
				)
				( attribute "CDS_LOCATION" "C6B1"
					( Origin gPackager )
				)
				( attribute "CDS_SEC" "1"
					( Origin gPackager )
				)
				( attribute "LOCATION" "C6B1"
					( Origin gFrontEnd )
				)
				( attribute "MATERIAL" "X6S"
					( Origin gFrontEnd )
				)
				( attribute "PACK_TYPE" "0603LF"
					( Origin gFrontEnd )
				)
				( attribute "PART_NUMBER" "E15431-001"
					( Origin gFrontEnd )
				)
				( attribute "PHYS_PAGE" "232"
					( Origin gFrontEnd )
				)
				( attribute "ROOM" "PVPP_KLM_VR"
					( Origin gFrontEnd )
				)
				( attribute "ROT" "0"
					( Origin gFrontEnd )
				)
				( attribute "SEC" "1"
					( Origin gPackager )
				)
				( attribute "TOLERANCE" "20%"
					( Origin gFrontEnd )
				)
				( attribute "VALUE" "10UF"
					( Origin gFrontEnd )
				)
				( attribute "VER" "1"
					( Origin gFrontEnd )
				)
				( attribute "VOLTAGE" "4V"
					( Units "uVoltage" "V" 1.000000)
					( Origin gFrontEnd )
				)
				( attribute "XY" "(-5775,875)"
					( Origin gFrontEnd )
				)
				( attribute "CHIPS_PART_NAME" "CAP"
					( Origin gPackager )
				)
				( attribute "CDS_PART_NAME" "CAP_0603LF-10UF,4V,20%,X6S,E15A"
					( Origin gPackager )
				)
				( attribute "GROUP" "PWR_MLCC_CAP"
					( Origin gFrontEnd )
				)
				( objectStatus "C6B1" )
			)
			( gate "@baseboard_fab2_lib.baseboard_fab2(sch_1):page232_i129"
				( attribute "BOM_COST" "MEM_VRD_PVPP_AB"
					( Origin gFrontEnd )
				)
				( attribute "CDS_LIB" "mstr_discrete"
					( Origin gPackager )
				)
				( attribute "CDS_LOCATION" "C4L1"
					( Origin gPackager )
				)
				( attribute "CDS_SEC" "1"
					( Origin gPackager )
				)
				( attribute "LOCATION" "C4L1"
					( Origin gFrontEnd )
				)
				( attribute "MATERIAL" "X6S"
					( Origin gFrontEnd )
				)
				( attribute "PACK_TYPE" "0603LF"
					( Origin gFrontEnd )
				)
				( attribute "PART_NUMBER" "E15431-001"
					( Origin gFrontEnd )
				)
				( attribute "PHYS_PAGE" "232"
					( Origin gFrontEnd )
				)
				( attribute "ROOM" "PVPP_KLM_VR"
					( Origin gFrontEnd )
				)
				( attribute "ROT" "0"
					( Origin gFrontEnd )
				)
				( attribute "SEC" "1"
					( Origin gFrontEnd )
				)
				( attribute "SEC_TYPE" "0603LF"
					( Origin gFrontEnd )
				)
				( attribute "TOLERANCE" "20%"
					( Origin gFrontEnd )
				)
				( attribute "VALUE" "10UF"
					( Origin gFrontEnd )
				)
				( attribute "VER" "1"
					( Origin gFrontEnd )
				)
				( attribute "VOLTAGE" "4V"
					( Units "uVoltage" "V" 1.000000)
					( Origin gFrontEnd )
				)
				( attribute "XY" "(-5500,875)"
					( Origin gFrontEnd )
				)
				( attribute "CHIPS_PART_NAME" "CAP"
					( Origin gPackager )
				)
				( attribute "CDS_PART_NAME" "CAP_0603LF-10UF,4V,20%,X6S,E15A"
					( Origin gPackager )
				)
				( attribute "GROUP" "PWR_MLCC_CAP"
					( Origin gFrontEnd )
				)
				( objectStatus "C4L1" )
			)
			( gate "@baseboard_fab2_lib.baseboard_fab2(sch_1):page232_i150"
				( attribute "CDS_LIB" "mstr_discrete"
					( Origin gPackager )
				)
				( attribute "CDS_LOCATION" "R7B20"
					( Origin gPackager )
				)
				( attribute "CDS_SEC" "1"
					( Origin gPackager )
				)
				( attribute "LOCATION" "R7B20"
					( Origin gFrontEnd )
				)
				( attribute "MATERIAL" "CHIP"
					( Origin gFrontEnd )
				)
				( attribute "PACK_TYPE" "0402"
					( Origin gFrontEnd )
				)
				( attribute "PART_NUMBER" "G21497-005"
					( Origin gFrontEnd )
				)
				( attribute "PHYS_PAGE" "232"
					( Origin gFrontEnd )
				)
				( attribute "ROOM" "PVPP_KLM_VR"
					( Origin gFrontEnd )
				)
				( attribute "ROT" "0"
					( Origin gFrontEnd )
				)
				( attribute "SEC" "1"
					( Origin gPackager )
				)
				( attribute "TOLERANCE" "5%"
					( Origin gFrontEnd )
				)
				( attribute "VALUE" "0.0"
					( Origin gFrontEnd )
				)
				( attribute "VER" "1"
					( Origin gFrontEnd )
				)
				( attribute "WATTAGE" "1/16W"
					( Origin gFrontEnd )
				)
				( attribute "XY" "(-1575,775)"
					( Origin gFrontEnd )
				)
				( attribute "CHIPS_PART_NAME" "RES"
					( Origin gPackager )
				)
				( attribute "CDS_PART_NAME" "RES_0402-0.0,5%,1/16W,CHIP,G21A"
					( Origin gPackager )
				)
				( objectStatus "R7B20" )
			)
			( gate "@baseboard_fab2_lib.baseboard_fab2(sch_1):page232_i185"
				( attribute "BOM_COST" "PVPP_KLM_VR"
					( Origin gFrontEnd )
				)
				( attribute "CDS_LIB" "mstr_discrete"
					( Origin gPackager )
				)
				( attribute "CDS_LOCATION" "C7B9"
					( Origin gPackager )
				)
				( attribute "CDS_SEC" "1"
					( Origin gPackager )
				)
				( attribute "FIN" "VR_1P2"
					( Origin gFrontEnd )
				)
				( attribute "LOCATION" "C7B9"
					( Origin gFrontEnd )
				)
				( attribute "MATERIAL" "EMPTY"
					( Origin gFrontEnd )
				)
				( attribute "PACK_TYPE" "0402LF"
					( Origin gFrontEnd )
				)
				( attribute "PART_NUMBER" "A36096-046"
					( Origin gFrontEnd )
				)
				( attribute "PHYS_PAGE" "232"
					( Origin gFrontEnd )
				)
				( attribute "REUSE_ID" "1"
					( Origin gFrontEnd )
				)
				( attribute "ROOM" "PVPP_KLM_VR"
					( Origin gFrontEnd )
				)
				( attribute "ROT" "2"
					( Origin gFrontEnd )
				)
				( attribute "SEC" "1"
					( Origin gPackager )
				)
				( attribute "TOLERANCE" "10%"
					( Origin gFrontEnd )
				)
				( attribute "VALUE" "1000PF"
					( Origin gFrontEnd )
				)
				( attribute "VER" "1"
					( Origin gFrontEnd )
				)
				( attribute "VOLTAGE" "50V"
					( Units "uVoltage" "V" 1.000000)
					( Origin gFrontEnd )
				)
				( attribute "XY" "(-6825,2500)"
					( Origin gFrontEnd )
				)
				( attribute "CHIPS_PART_NAME" "CAP"
					( Origin gPackager )
				)
				( attribute "CDS_PART_NAME" "CAP_0402LF-1000PF,50V,10%,EMPTA"
					( Origin gPackager )
				)
				( objectStatus "C7B9" )
			)
			( gate "@baseboard_fab2_lib.baseboard_fab2(sch_1):page233_i284"
				( attribute "BOM_COST" "PVPP_KLM_VR"
					( Origin gFrontEnd )
				)
				( attribute "CDS_LIB" "mstr_discrete"
					( Origin gPackager )
				)
				( attribute "CDS_LOCATION" "R4G11"
					( Origin gPackager )
				)
				( attribute "CDS_SEC" "1"
					( Origin gPackager )
				)
				( attribute "CONFIG" "64.39015.6DL"
					( Origin gFrontEnd )
				)
				( attribute "LOCATION" "R4G11"
					( Origin gFrontEnd )
				)
				( attribute "MATERIAL" "CHIP"
					( Origin gFrontEnd )
				)
				( attribute "NEW_VALUE" "3.9K"
					( Origin gFrontEnd )
				)
				( attribute "PACK_TYPE" "0402"
					( Origin gFrontEnd )
				)
				( attribute "PART_NUMBER" "G21796-242"
					( Origin gFrontEnd )
				)
				( attribute "PHYS_PAGE" "233"
					( Origin gFrontEnd )
				)
				( attribute "ROOM" "PVPP_KLM_VR"
					( Origin gFrontEnd )
				)
				( attribute "ROT" "2"
					( Origin gFrontEnd )
				)
				( attribute "SEC" "1"
					( Origin gPackager )
				)
				( attribute "TOLERANCE" "1.0%"
					( Origin gFrontEnd )
				)
				( attribute "VALUE" "7.87K"
					( Origin gFrontEnd )
				)
				( attribute "VER" "2"
					( Origin gFrontEnd )
				)
				( attribute "WATTAGE" "1/16W"
					( Origin gFrontEnd )
				)
				( attribute "XY" "(-4675,1500)"
					( Origin gFrontEnd )
				)
				( attribute "CHIPS_PART_NAME" "RES"
					( Origin gPackager )
				)
				( attribute "CDS_PART_NAME" "RES_0402-7.87K,1.0%,1/16W,CHIPA"
					( Origin gPackager )
				)
				( objectStatus "R4G11" )
			)
			( gate "@baseboard_fab2_lib.baseboard_fab2(sch_1):page232_i197"
				( attribute "BOM_COST" "PVPP_KLM_VR"
					( Origin gFrontEnd )
				)
				( attribute "CDS_LIB" "mstr_discrete"
					( Origin gPackager )
				)
				( attribute "CDS_LOCATION" "C7B11"
					( Origin gPackager )
				)
				( attribute "CDS_SEC" "1"
					( Origin gPackager )
				)
				( attribute "LOCATION" "C7B11"
					( Origin gFrontEnd )
				)
				( attribute "MATERIAL" "X7R"
					( Origin gFrontEnd )
				)
				( attribute "PACK_TYPE" "0402"
					( Origin gFrontEnd )
				)
				( attribute "PART_NUMBER" "A36096-129"
					( Origin gFrontEnd )
				)
				( attribute "PHYS_PAGE" "232"
					( Origin gFrontEnd )
				)
				( attribute "REUSE_ID" "26"
					( Origin gFrontEnd )
				)
				( attribute "ROOM" "PVPP_KLM_VR"
					( Origin gFrontEnd )
				)
				( attribute "ROT" "0"
					( Origin gFrontEnd )
				)
				( attribute "SEC" "1"
					( Origin gFrontEnd )
				)
				( attribute "SEC_TYPE" "0402"
					( Origin gFrontEnd )
				)
				( attribute "TOLERANCE" "10%"
					( Origin gFrontEnd )
				)
				( attribute "VALUE" "0.027UF"
					( Origin gFrontEnd )
				)
				( attribute "VER" "1"
					( Origin gFrontEnd )
				)
				( attribute "VOLTAGE" "16V"
					( Units "uVoltage" "V" 1.000000)
					( Origin gFrontEnd )
				)
				( attribute "XY" "(-5425,2175)"
					( Origin gFrontEnd )
				)
				( attribute "CHIPS_PART_NAME" "CAP"
					( Origin gPackager )
				)
				( attribute "CDS_PART_NAME" "CAP_0402-0.027UF,16V,10%,X7R,AA"
					( Origin gPackager )
				)
				( objectStatus "C7B11" )
			)
			( gate "@baseboard_fab2_lib.baseboard_fab2(sch_1):page232_i200"
				( attribute "CDS_LIB" "mstr_discrete"
					( Origin gPackager )
				)
				( attribute "CDS_LOCATION" "FB7B1"
					( Origin gPackager )
				)
				( attribute "CDS_SEC" "1"
					( Origin gPackager )
				)
				( attribute "LOCATION" "FB7B1"
					( Origin gFrontEnd )
				)
				( attribute "MATERIAL" "FB"
					( Origin gFrontEnd )
				)
				( attribute "PACK_TYPE" "SM"
					( Origin gFrontEnd )
				)
				( attribute "PART_NUMBER" "656554-051"
					( Origin gFrontEnd )
				)
				( attribute "PHYS_PAGE" "232"
					( Origin gFrontEnd )
				)
				( attribute "ROOM" "PVPP_KLM_VR"
					( Origin gFrontEnd )
				)
				( attribute "ROT" "0"
					( Origin gFrontEnd )
				)
				( attribute "SEC" "1"
					( Origin gFrontEnd )
				)
				( attribute "SEC_TYPE" "SM"
					( Origin gFrontEnd )
				)
				( attribute "TOLERANCE" "1%"
					( Origin gFrontEnd )
				)
				( attribute "VALUE" "22"
					( Origin gFrontEnd )
				)
				( attribute "VER" "1"
					( Origin gFrontEnd )
				)
				( attribute "XY" "(-7950,4300)"
					( Origin gFrontEnd )
				)
				( attribute "CHIPS_PART_NAME" "FERRITE"
					( Origin gPackager )
				)
				( attribute "CDS_PART_NAME" "FERRITE_SM-22,FB,656554-051"
					( Origin gPackager )
				)
				( objectStatus "FB7B1" )
			)
			( gate "@baseboard_fab2_lib.baseboard_fab2(sch_1):page241_i92"
				( attribute "CDS_LIB" "w_hdl"
					( Origin gPackager )
				)
				( attribute "CDS_LMAN_SYM_OUTLINE" "-50,25,50,-25"
					( Origin gPackager )
				)
				( attribute "LOCATION" "C7E13"
					( Origin gFrontEnd )
				)
				( attribute "PACK_TYPE" "SMD-BCG5"
					( Origin gFrontEnd )
				)
				( attribute "PART_NUMBER" "078.22611.0811"
					( Origin gFrontEnd )
				)
				( attribute "PHYS_PAGE" "241"
					( Origin gFrontEnd )
				)
				( attribute "ROT" "0"
					( Origin gFrontEnd )
				)
				( attribute "SEC" "1"
					( Origin gFrontEnd )
				)
				( attribute "SEC_TYPE" "SMD-BCG5"
					( Origin gFrontEnd )
				)
				( attribute "VALUE" "SC22U16V5MX-4-GP"
					( Origin gFrontEnd )
				)
				( attribute "VER" "1"
					( Origin gFrontEnd )
				)
				( attribute "XY" "(-2400,4325)"
					( Origin gFrontEnd )
				)
				( attribute "CHIPS_PART_NAME" "SC22U16V5MX-4-GP"
					( Origin gPackager )
				)
				( attribute "CDS_PART_NAME" "SC22U16V5MX-4-GP_SMD-BCG5-SC22A"
					( Origin gPackager )
				)
				( attribute "CDS_LOCATION" "C7E13"
					( Origin gPackager )
				)
				( attribute "CDS_SEC" "1"
					( Origin gPackager )
				)
				( attribute "ATTRIBUTE" "22UF"
					( Origin gFrontEnd )
				)
				( attribute "PACK_SIZE" "0805"
					( Origin gFrontEnd )
				)
				( attribute "RATED" "16V"
					( Origin gFrontEnd )
				)
				( attribute "TOLERANCE" "20%"
					( Origin gFrontEnd )
				)
				( attribute "TYPE" "X6S"
					( Origin gFrontEnd )
				)
				( objectStatus "C7E13" )
			)
			( gate "@baseboard_fab2_lib.baseboard_fab2(sch_1):page232_i207"
				( attribute "BOM_COST" "PVPP_KLM_VR"
					( Origin gFrontEnd )
				)
				( attribute "CDS_LIB" "mstr_discrete"
					( Origin gPackager )
				)
				( attribute "CDS_LOCATION" "C3M9"
					( Origin gPackager )
				)
				( attribute "CDS_SEC" "1"
					( Origin gPackager )
				)
				( attribute "FIN" "VR_1P2"
					( Origin gFrontEnd )
				)
				( attribute "LOCATION" "C3M9"
					( Origin gFrontEnd )
				)
				( attribute "MATERIAL" "X6S"
					( Origin gFrontEnd )
				)
				( attribute "PACK_TYPE" "0402"
					( Origin gFrontEnd )
				)
				( attribute "PART_NUMBER" "D97712-011"
					( Origin gFrontEnd )
				)
				( attribute "PHYS_PAGE" "232"
					( Origin gFrontEnd )
				)
				( attribute "REUSE_ID" "1"
					( Origin gFrontEnd )
				)
				( attribute "ROOM" "PVPP_KLM_VR"
					( Origin gFrontEnd )
				)
				( attribute "ROT" "0"
					( Origin gFrontEnd )
				)
				( attribute "SEC" "1"
					( Origin gPackager )
				)
				( attribute "TOLERANCE" "10%"
					( Origin gFrontEnd )
				)
				( attribute "VALUE" "1.0UF"
					( Origin gFrontEnd )
				)
				( attribute "VER" "1"
					( Origin gFrontEnd )
				)
				( attribute "VOLTAGE" "16V"
					( Units "uVoltage" "V" 1.000000)
					( Origin gFrontEnd )
				)
				( attribute "XY" "(-5425,4150)"
					( Origin gFrontEnd )
				)
				( attribute "CHIPS_PART_NAME" "CAP"
					( Origin gPackager )
				)
				( attribute "CDS_PART_NAME" "CAP_0402-1.0UF,16V,10%,X6S,D97A"
					( Origin gPackager )
				)
				( objectStatus "C3M9" )
			)
			( gate "@baseboard_fab2_lib.baseboard_fab2(sch_1):page232_i209"
				( attribute "BOM_COST" "PVPP_KLM_VR"
					( Origin gFrontEnd )
				)
				( attribute "CDS_LIB" "mstr_discrete"
					( Origin gPackager )
				)
				( attribute "CDS_LOCATION" "C7B12"
					( Origin gPackager )
				)
				( attribute "CDS_SEC" "1"
					( Origin gPackager )
				)
				( attribute "LOCATION" "C7B12"
					( Origin gFrontEnd )
				)
				( attribute "MATERIAL" "X7R"
					( Origin gFrontEnd )
				)
				( attribute "PACK_TYPE" "0402LF"
					( Origin gFrontEnd )
				)
				( attribute "PART_NUMBER" "A36096-046"
					( Origin gFrontEnd )
				)
				( attribute "PHYS_PAGE" "232"
					( Origin gFrontEnd )
				)
				( attribute "REUSE_ID" "17"
					( Origin gFrontEnd )
				)
				( attribute "ROOM" "PVPP_KLM_VR"
					( Origin gFrontEnd )
				)
				( attribute "ROT" "0"
					( Origin gFrontEnd )
				)
				( attribute "SEC" "1"
					( Origin gPackager )
				)
				( attribute "TOLERANCE" "10%"
					( Origin gFrontEnd )
				)
				( attribute "VALUE" "1000PF"
					( Origin gFrontEnd )
				)
				( attribute "VER" "1"
					( Origin gFrontEnd )
				)
				( attribute "VOLTAGE" "50V"
					( Units "uVoltage" "V" 1.000000)
					( Origin gFrontEnd )
				)
				( attribute "XY" "(-3975,725)"
					( Origin gFrontEnd )
				)
				( attribute "CHIPS_PART_NAME" "CAP"
					( Origin gPackager )
				)
				( attribute "CDS_PART_NAME" "CAP_0402LF-1000PF,50V,10%,X7R,A"
					( Origin gPackager )
				)
				( objectStatus "C7B12" )
			)
			( gate "@baseboard_fab2_lib.baseboard_fab2(sch_1):page232_i210"
				( attribute "BOM_COST" "PVPP_KLM_VR"
					( Origin gFrontEnd )
				)
				( attribute "CDS_LIB" "mstr_discrete"
					( Origin gPackager )
				)
				( attribute "CDS_LOCATION" "R7B17"
					( Origin gPackager )
				)
				( attribute "CDS_SEC" "1"
					( Origin gPackager )
				)
				( attribute "LOCATION" "R7B17"
					( Origin gFrontEnd )
				)
				( attribute "MATERIAL" "CHIP"
					( Origin gFrontEnd )
				)
				( attribute "PACK_TYPE" "0402"
					( Origin gFrontEnd )
				)
				( attribute "PART_NUMBER" "G21796-026"
					( Origin gFrontEnd )
				)
				( attribute "PHYS_PAGE" "232"
					( Origin gFrontEnd )
				)
				( attribute "REUSE_ID" "21"
					( Origin gFrontEnd )
				)
				( attribute "ROOM" "PVPP_KLM_VR"
					( Origin gFrontEnd )
				)
				( attribute "ROT" "0"
					( Origin gFrontEnd )
				)
				( attribute "SEC" "1"
					( Origin gFrontEnd )
				)
				( attribute "SEC_TYPE" "0402"
					( Origin gFrontEnd )
				)
				( attribute "TOLERANCE" "1%"
					( Origin gFrontEnd )
				)
				( attribute "VALUE" "1.00K"
					( Origin gFrontEnd )
				)
				( attribute "VER" "2"
					( Origin gFrontEnd )
				)
				( attribute "WATTAGE" "1/16W"
					( Origin gFrontEnd )
				)
				( attribute "XY" "(-4575,1250)"
					( Origin gFrontEnd )
				)
				( attribute "CHIPS_PART_NAME" "RES"
					( Origin gPackager )
				)
				( attribute "CDS_PART_NAME" "RES_0402-1.00K,1%,1/16W,CHIP,GA"
					( Origin gPackager )
				)
				( objectStatus "R7B17" )
			)
			( gate "@baseboard_fab2_lib.baseboard_fab2(sch_1):page232_i214"
				( attribute "CDS_LIB" "mstr_vreg"
					( Origin gPackager )
				)
				( attribute "CDS_LMAN_SYM_OUTLINE" "-450,850,450,-900"
					( Origin gPackager )
				)
				( attribute "CDS_LOCATION" "EU7B1"
					( Origin gPackager )
				)
				( attribute "CDS_SEC" "1"
					( Origin gPackager )
				)
				( attribute "LOCATION" "EU7B1"
					( Origin gFrontEnd )
				)
				( attribute "MATERIAL" "IC"
					( Origin gFrontEnd )
				)
				( attribute "PACK_TYPE" "SM"
					( Origin gFrontEnd )
				)
				( attribute "PART_NUMBER" "H86355-001"
					( Origin gFrontEnd )
				)
				( attribute "PHYS_PAGE" "232"
					( Origin gFrontEnd )
				)
				( attribute "ROT" "0"
					( Origin gFrontEnd )
				)
				( attribute "SEC" "1"
					( Origin gFrontEnd )
				)
				( attribute "SEC_TYPE" "SM"
					( Origin gFrontEnd )
				)
				( attribute "VER" "1"
					( Origin gFrontEnd )
				)
				( attribute "XY" "(-4150,2875)"
					( Origin gFrontEnd )
				)
				( attribute "CHIPS_PART_NAME" "NCP3232L"
					( Origin gPackager )
				)
				( attribute "CDS_PART_NAME" "NCP3232L_SM-IC,H86355-001"
					( Origin gPackager )
				)
				( objectStatus "EU7B1" )
			)
			( gate "@baseboard_fab2_lib.baseboard_fab2(sch_1):page232_i218"
				( attribute "BOM_COST" "PVPP_KLM_VR"
					( Origin gFrontEnd )
				)
				( attribute "CDS_LIB" "mstr_discrete"
					( Origin gPackager )
				)
				( attribute "CDS_LOCATION" "R7A15"
					( Origin gPackager )
				)
				( attribute "CDS_SEC" "1"
					( Origin gPackager )
				)
				( attribute "LOCATION" "R7A15"
					( Origin gFrontEnd )
				)
				( attribute "MATERIAL" "EMPTY"
					( Origin gFrontEnd )
				)
				( attribute "PACK_TYPE" "0402"
					( Origin gFrontEnd )
				)
				( attribute "PART_NUMBER" "G21497-016"
					( Origin gFrontEnd )
				)
				( attribute "PHYS_PAGE" "232"
					( Origin gFrontEnd )
				)
				( attribute "REUSE_ID" "29"
					( Origin gFrontEnd )
				)
				( attribute "ROOM" "PVPP_KLM_VR"
					( Origin gFrontEnd )
				)
				( attribute "ROT" "0"
					( Origin gFrontEnd )
				)
				( attribute "SEC" "1"
					( Origin gFrontEnd )
				)
				( attribute "SEC_TYPE" "0402"
					( Origin gFrontEnd )
				)
				( attribute "TOLERANCE" "5%"
					( Origin gFrontEnd )
				)
				( attribute "VALUE" "2.2"
					( Origin gFrontEnd )
				)
				( attribute "VER" "2"
					( Origin gFrontEnd )
				)
				( attribute "WATTAGE" "1/16W"
					( Origin gFrontEnd )
				)
				( attribute "XY" "(-2875,3325)"
					( Origin gFrontEnd )
				)
				( attribute "CHIPS_PART_NAME" "RES"
					( Origin gPackager )
				)
				( attribute "CDS_PART_NAME" "RES_0402-2.2,5%,1/16W,EMPTY,G2A"
					( Origin gPackager )
				)
				( objectStatus "R7A15" )
			)
			( gate "@baseboard_fab2_lib.baseboard_fab2(sch_1):page232_i220"
				( attribute "BOM_COST" "PVPP_KLM_VR"
					( Origin gFrontEnd )
				)
				( attribute "CDS_LIB" "mstr_discrete"
					( Origin gPackager )
				)
				( attribute "CDS_LOCATION" "C7A34"
					( Origin gPackager )
				)
				( attribute "CDS_SEC" "1"
					( Origin gPackager )
				)
				( attribute "LOCATION" "C7A34"
					( Origin gFrontEnd )
				)
				( attribute "MATERIAL" "EMPTY"
					( Origin gFrontEnd )
				)
				( attribute "PACK_TYPE" "0402LF"
					( Origin gFrontEnd )
				)
				( attribute "PART_NUMBER" "A36096-091"
					( Origin gFrontEnd )
				)
				( attribute "PHYS_PAGE" "232"
					( Origin gFrontEnd )
				)
				( attribute "REUSE_ID" "26"
					( Origin gFrontEnd )
				)
				( attribute "ROOM" "PVPP_KLM_VR"
					( Origin gFrontEnd )
				)
				( attribute "ROT" "0"
					( Origin gFrontEnd )
				)
				( attribute "SEC" "1"
					( Origin gFrontEnd )
				)
				( attribute "SEC_TYPE" "0402LF"
					( Origin gFrontEnd )
				)
				( attribute "TOLERANCE" "10%"
					( Origin gFrontEnd )
				)
				( attribute "VALUE" "3300PF"
					( Origin gFrontEnd )
				)
				( attribute "VER" "1"
					( Origin gFrontEnd )
				)
				( attribute "VOLTAGE" "50V"
					( Units "uVoltage" "V" 1.000000)
					( Origin gFrontEnd )
				)
				( attribute "XY" "(-2875,3700)"
					( Origin gFrontEnd )
				)
				( attribute "CHIPS_PART_NAME" "CAP"
					( Origin gPackager )
				)
				( attribute "CDS_PART_NAME" "CAP_0402LF-3300PF,50V,10%,EMPTA"
					( Origin gPackager )
				)
				( objectStatus "C7A34" )
			)
			( gate "@baseboard_fab2_lib.baseboard_fab2(sch_1):page232_i227"
				( attribute "BOM_COST" "PVPP_KLM_VR"
					( Origin gFrontEnd )
				)
				( attribute "CDS_LIB" "mstr_discrete"
					( Origin gPackager )
				)
				( attribute "CDS_LOCATION" "R7B10"
					( Origin gPackager )
				)
				( attribute "CDS_SEC" "1"
					( Origin gPackager )
				)
				( attribute "LOCATION" "R7B10"
					( Origin gFrontEnd )
				)
				( attribute "MATERIAL" "CHIP"
					( Origin gFrontEnd )
				)
				( attribute "PACK_TYPE" "0603"
					( Origin gFrontEnd )
				)
				( attribute "PART_NUMBER" "G22026-003"
					( Origin gFrontEnd )
				)
				( attribute "PHYS_PAGE" "232"
					( Origin gFrontEnd )
				)
				( attribute "REUSE_ID" "34"
					( Origin gFrontEnd )
				)
				( attribute "ROOM" "PVPP_KLM_VR"
					( Origin gFrontEnd )
				)
				( attribute "ROT" "0"
					( Origin gFrontEnd )
				)
				( attribute "SEC" "1"
					( Origin gFrontEnd )
				)
				( attribute "SEC_TYPE" "0603"
					( Origin gFrontEnd )
				)
				( attribute "TOLERANCE" "1%"
					( Origin gFrontEnd )
				)
				( attribute "VALUE" "120.0"
					( Origin gFrontEnd )
				)
				( attribute "VER" "2"
					( Origin gFrontEnd )
				)
				( attribute "WATTAGE" "1/10W"
					( Origin gFrontEnd )
				)
				( attribute "XY" "(-2400,3650)"
					( Origin gFrontEnd )
				)
				( attribute "CHIPS_PART_NAME" "RES"
					( Origin gPackager )
				)
				( attribute "CDS_PART_NAME" "RES_0603-120.0,1%,1/10W,CHIP,GA"
					( Origin gPackager )
				)
				( objectStatus "R7B10" )
			)
			( gate "@baseboard_fab2_lib.baseboard_fab2(sch_1):page232_i229"
				( attribute "BOM_COST" "PVPP_KLM_VR"
					( Origin gFrontEnd )
				)
				( attribute "CDS_LIB" "mstr_discrete"
					( Origin gPackager )
				)
				( attribute "CDS_LOCATION" "C6B7"
					( Origin gPackager )
				)
				( attribute "CDS_SEC" "1"
					( Origin gPackager )
				)
				( attribute "LOCATION" "C6B7"
					( Origin gFrontEnd )
				)
				( attribute "MATERIAL" "POSCAP"
					( Origin gFrontEnd )
				)
				( attribute "PACK_TYPE" "7343LF"
					( Origin gFrontEnd )
				)
				( attribute "PART_NUMBER" "724613-042"
					( Origin gFrontEnd )
				)
				( attribute "PHYS_PAGE" "232"
					( Origin gFrontEnd )
				)
				( attribute "REUSE_ID" "28"
					( Origin gFrontEnd )
				)
				( attribute "ROOM" "PVPP_KLM_VR"
					( Origin gFrontEnd )
				)
				( attribute "ROT" "0"
					( Origin gFrontEnd )
				)
				( attribute "SEC" "1"
					( Origin gPackager )
				)
				( attribute "TOLERANCE" "20%"
					( Origin gFrontEnd )
				)
				( attribute "VALUE" "330UF"
					( Origin gFrontEnd )
				)
				( attribute "VER" "1"
					( Origin gFrontEnd )
				)
				( attribute "VOLTAGE" "6.3V"
					( Units "uVoltage" "V" 1.000000)
					( Origin gFrontEnd )
				)
				( attribute "XY" "(-2100,3650)"
					( Origin gFrontEnd )
				)
				( attribute "CHIPS_PART_NAME" "CAPP"
					( Origin gPackager )
				)
				( attribute "CDS_PART_NAME" "CAPP_7343LF-330UF,6.3V,20%,POSA"
					( Origin gPackager )
				)
				( attribute "GROUP" "PWR_BULK_CAP"
					( Origin gFrontEnd )
				)
				( objectStatus "C6B7" )
			)
			( gate "@baseboard_fab2_lib.baseboard_fab2(sch_1):page232_i236"
				( attribute "BOM_COST" "PVPP_KLM_VR"
					( Origin gFrontEnd )
				)
				( attribute "CDS_LIB" "mstr_discrete"
					( Origin gPackager )
				)
				( attribute "CDS_LOCATION" "C6B3"
					( Origin gPackager )
				)
				( attribute "CDS_SEC" "1"
					( Origin gPackager )
				)
				( attribute "LOCATION" "C6B3"
					( Origin gFrontEnd )
				)
				( attribute "MATERIAL" "X6S"
					( Origin gFrontEnd )
				)
				( attribute "PACK_TYPE" "0805"
					( Origin gFrontEnd )
				)
				( attribute "PART_NUMBER" "C95333-006"
					( Origin gFrontEnd )
				)
				( attribute "PHYS_PAGE" "232"
					( Origin gFrontEnd )
				)
				( attribute "REUSE_ID" "33"
					( Origin gFrontEnd )
				)
				( attribute "ROOM" "PVPP_KLM_VR"
					( Origin gFrontEnd )
				)
				( attribute "ROT" "0"
					( Origin gFrontEnd )
				)
				( attribute "SEC" "1"
					( Origin gPackager )
				)
				( attribute "TOLERANCE" "20%"
					( Origin gFrontEnd )
				)
				( attribute "VALUE" "47UF"
					( Origin gFrontEnd )
				)
				( attribute "VER" "1"
					( Origin gFrontEnd )
				)
				( attribute "VOLTAGE" "4V"
					( Units "uVoltage" "V" 1.000000)
					( Origin gFrontEnd )
				)
				( attribute "XY" "(-1475,3675)"
					( Origin gFrontEnd )
				)
				( attribute "CHIPS_PART_NAME" "CAP"
					( Origin gPackager )
				)
				( attribute "CDS_PART_NAME" "CAP_0805-47UF,4V,20%,X6S,C9533A"
					( Origin gPackager )
				)
				( attribute "GROUP" "PWR_MLCC_CAP"
					( Origin gFrontEnd )
				)
				( objectStatus "C6B3" )
			)
			( gate "@baseboard_fab2_lib.baseboard_fab2(sch_1):page232_i238"
				( attribute "BOM_COST" "PVPP_KLM_VR"
					( Origin gFrontEnd )
				)
				( attribute "CDS_LIB" "mstr_discrete"
					( Origin gPackager )
				)
				( attribute "CDS_LOCATION" "C7B7"
					( Origin gPackager )
				)
				( attribute "CDS_SEC" "1"
					( Origin gPackager )
				)
				( attribute "LOCATION" "C7B7"
					( Origin gFrontEnd )
				)
				( attribute "MATERIAL" "X6S"
					( Origin gFrontEnd )
				)
				( attribute "PACK_TYPE" "0805"
					( Origin gFrontEnd )
				)
				( attribute "PART_NUMBER" "C95333-006"
					( Origin gFrontEnd )
				)
				( attribute "PHYS_PAGE" "232"
					( Origin gFrontEnd )
				)
				( attribute "REUSE_ID" "33"
					( Origin gFrontEnd )
				)
				( attribute "ROOM" "PVPP_KLM_VR"
					( Origin gFrontEnd )
				)
				( attribute "ROT" "0"
					( Origin gFrontEnd )
				)
				( attribute "SEC" "1"
					( Origin gPackager )
				)
				( attribute "TOLERANCE" "20%"
					( Origin gFrontEnd )
				)
				( attribute "VALUE" "47UF"
					( Origin gFrontEnd )
				)
				( attribute "VER" "1"
					( Origin gFrontEnd )
				)
				( attribute "VOLTAGE" "4V"
					( Units "uVoltage" "V" 1.000000)
					( Origin gFrontEnd )
				)
				( attribute "XY" "(-1200,3675)"
					( Origin gFrontEnd )
				)
				( attribute "CHIPS_PART_NAME" "CAP"
					( Origin gPackager )
				)
				( attribute "CDS_PART_NAME" "CAP_0805-47UF,4V,20%,X6S,C9533A"
					( Origin gPackager )
				)
				( attribute "GROUP" "PWR_MLCC_CAP"
					( Origin gFrontEnd )
				)
				( objectStatus "C7B7" )
			)
			( gate "@baseboard_fab2_lib.baseboard_fab2(sch_1):page232_i239"
				( attribute "BOM_COST" "PVPP_KLM_VR"
					( Origin gFrontEnd )
				)
				( attribute "CDS_LIB" "mstr_discrete"
					( Origin gPackager )
				)
				( attribute "CDS_LOCATION" "L7B1"
					( Origin gPackager )
				)
				( attribute "CDS_SEC" "1"
					( Origin gPackager )
				)
				( attribute "LOCATION" "L7B1"
					( Origin gFrontEnd )
				)
				( attribute "MATERIAL" "IND"
					( Origin gFrontEnd )
				)
				( attribute "PACK_TYPE" "SM"
					( Origin gFrontEnd )
				)
				( attribute "PART_NUMBER" "E13358-018"
					( Origin gFrontEnd )
				)
				( attribute "PHYS_PAGE" "232"
					( Origin gFrontEnd )
				)
				( attribute "REUSE_ID" "30"
					( Origin gFrontEnd )
				)
				( attribute "ROOM" "PVPP_KLM_VR"
					( Origin gFrontEnd )
				)
				( attribute "ROT" "0"
					( Origin gFrontEnd )
				)
				( attribute "SEC" "1"
					( Origin gPackager )
				)
				( attribute "TOLERANCE" "1%"
					( Origin gFrontEnd )
				)
				( attribute "VALUE" "0.47UH"
					( Origin gFrontEnd )
				)
				( attribute "VER" "1"
					( Origin gFrontEnd )
				)
				( attribute "XY" "(-2550,3850)"
					( Origin gFrontEnd )
				)
				( attribute "CHIPS_PART_NAME" "INDUCTOR"
					( Origin gPackager )
				)
				( attribute "CDS_PART_NAME" "INDUCTOR_SM-0.47UH,IND,E13358-A"
					( Origin gPackager )
				)
				( objectStatus "L7B1" )
			)
			( gate "@baseboard_fab2_lib.baseboard_fab2(sch_1):page234_i226"
				( attribute "BOM_COST" "NT_GBE_BASE"
					( Origin gFrontEnd )
				)
				( attribute "CDS_LIB" "mstr_discrete"
					( Origin gPackager )
				)
				( attribute "CDS_LOCATION" "R4B13"
					( Origin gPackager )
				)
				( attribute "CDS_SEC" "1"
					( Origin gPackager )
				)
				( attribute "LOCATION" "R4B13"
					( Origin gFrontEnd )
				)
				( attribute "MATERIAL" "CHIP"
					( Origin gFrontEnd )
				)
				( attribute "PACK_TYPE" "0603"
					( Origin gFrontEnd )
				)
				( attribute "PART_NUMBER" "G22178-002"
					( Origin gFrontEnd )
				)
				( attribute "PHYS_PAGE" "234"
					( Origin gFrontEnd )
				)
				( attribute "ROOM" "NIC_SPRV"
					( Origin gFrontEnd )
				)
				( attribute "ROT" "0"
					( Origin gFrontEnd )
				)
				( attribute "SEC" "1"
					( Origin gFrontEnd )
				)
				( attribute "SEC_TYPE" "0603"
					( Origin gFrontEnd )
				)
				( attribute "TOLERANCE" "5.0%"
					( Origin gFrontEnd )
				)
				( attribute "VALUE" "0"
					( Origin gFrontEnd )
				)
				( attribute "VER" "1"
					( Origin gFrontEnd )
				)
				( attribute "WATTAGE" "1/10W"
					( Origin gFrontEnd )
				)
				( attribute "XY" "(-4150,4200)"
					( Origin gFrontEnd )
				)
				( attribute "CHIPS_PART_NAME" "RES"
					( Origin gPackager )
				)
				( attribute "CDS_PART_NAME" "RES_0603-0,5.0%,1/10W,CHIP,G22A"
					( Origin gPackager )
				)
				( objectStatus "R4B13" )
			)
			( gate "@baseboard_fab2_lib.baseboard_fab2(sch_1):page232_i241"
				( attribute "BOM_COST" "PVPP_KLM_VR"
					( Origin gFrontEnd )
				)
				( attribute "CDS_LIB" "mstr_discrete"
					( Origin gPackager )
				)
				( attribute "CDS_LOCATION" "C7B30"
					( Origin gPackager )
				)
				( attribute "CDS_SEC" "1"
					( Origin gPackager )
				)
				( attribute "LOCATION" "C7B30"
					( Origin gFrontEnd )
				)
				( attribute "MATERIAL" "X7R"
					( Origin gFrontEnd )
				)
				( attribute "PACK_TYPE" "0603LF"
					( Origin gFrontEnd )
				)
				( attribute "PART_NUMBER" "602433-020"
					( Origin gFrontEnd )
				)
				( attribute "PHYS_PAGE" "232"
					( Origin gFrontEnd )
				)
				( attribute "REUSE_ID" "27"
					( Origin gFrontEnd )
				)
				( attribute "ROOM" "PVPP_KLM_VR"
					( Origin gFrontEnd )
				)
				( attribute "ROT" "2"
					( Origin gFrontEnd )
				)
				( attribute "SEC" "1"
					( Origin gPackager )
				)
				( attribute "SPOF" "TRUE"
					( Origin gFrontEnd )
				)
				( attribute "TOLERANCE" "10%"
					( Origin gFrontEnd )
				)
				( attribute "VALUE" "0.1UF"
					( Origin gFrontEnd )
				)
				( attribute "VER" "2"
					( Origin gFrontEnd )
				)
				( attribute "VOLTAGE" "25V"
					( Units "uVoltage" "V" 1.000000)
					( Origin gFrontEnd )
				)
				( attribute "XY" "(-3675,4200)"
					( Origin gFrontEnd )
				)
				( attribute "CHIPS_PART_NAME" "CAP"
					( Origin gPackager )
				)
				( attribute "CDS_PART_NAME" "CAP_0603LF-0.1UF,25V,10%,X7R,6A"
					( Origin gPackager )
				)
				( objectStatus "C7B30" )
			)
			( gate "@baseboard_fab2_lib.baseboard_fab2(sch_1):page232_i252"
				( attribute "CDS_LIB" "dev_discrete"
					( Origin gPackager )
				)
				( attribute "CDS_LOCATION" "C7B6"
					( Origin gPackager )
				)
				( attribute "CDS_SEC" "1"
					( Origin gPackager )
				)
				( attribute "LOCATION" "C7B6"
					( Origin gFrontEnd )
				)
				( attribute "MATERIAL" "X7R"
					( Origin gFrontEnd )
				)
				( attribute "PACK_TYPE" "0402V"
					( Origin gFrontEnd )
				)
				( attribute "PART_NUMBER" "A36096-030"
					( Origin gFrontEnd )
				)
				( attribute "PHYS_PAGE" "232"
					( Origin gFrontEnd )
				)
				( attribute "ROT" "0"
					( Origin gFrontEnd )
				)
				( attribute "SEC" "1"
					( Origin gFrontEnd )
				)
				( attribute "SEC_TYPE" "0402V"
					( Origin gFrontEnd )
				)
				( attribute "TOLERANCE" "10%"
					( Origin gFrontEnd )
				)
				( attribute "VALUE" "0.1UF"
					( Origin gFrontEnd )
				)
				( attribute "VER" "1"
					( Origin gFrontEnd )
				)
				( attribute "VOLTAGE" "16V"
					( Units "uVoltage" "V" 1.000000)
					( Origin gFrontEnd )
				)
				( attribute "XY" "(-5475,3525)"
					( Origin gFrontEnd )
				)
				( attribute "CHIPS_PART_NAME" "CAP_A"
					( Origin gPackager )
				)
				( attribute "CDS_PART_NAME" "CAP_A_0402V-0.1UF,16V,10%,X7R,A"
					( Origin gPackager )
				)
				( objectStatus "C7B6" )
			)
			( gate "@baseboard_fab2_lib.baseboard_fab2(sch_1):page232_i253"
				( attribute "BOM_COST" "PVPP_KLM_VR"
					( Origin gFrontEnd )
				)
				( attribute "CDS_LIB" "mstr_discrete"
					( Origin gPackager )
				)
				( attribute "CDS_LOCATION" "C3M10"
					( Origin gPackager )
				)
				( attribute "CDS_SEC" "1"
					( Origin gPackager )
				)
				( attribute "LOCATION" "C3M10"
					( Origin gFrontEnd )
				)
				( attribute "MATERIAL" "X6S"
					( Origin gFrontEnd )
				)
				( attribute "PACK_TYPE" "0603"
					( Origin gFrontEnd )
				)
				( attribute "PART_NUMBER" "E15431-003"
					( Origin gFrontEnd )
				)
				( attribute "PHYS_PAGE" "232"
					( Origin gFrontEnd )
				)
				( attribute "REUSE_ID" "26"
					( Origin gFrontEnd )
				)
				( attribute "ROOM" "PVPP_KLM_VR"
					( Origin gFrontEnd )
				)
				( attribute "ROT" "0"
					( Origin gFrontEnd )
				)
				( attribute "SEC" "1"
					( Origin gFrontEnd )
				)
				( attribute "SEC_TYPE" "0603"
					( Origin gFrontEnd )
				)
				( attribute "TOLERANCE" "10%"
					( Origin gFrontEnd )
				)
				( attribute "VALUE" "4.7UF"
					( Origin gFrontEnd )
				)
				( attribute "VER" "1"
					( Origin gFrontEnd )
				)
				( attribute "VOLTAGE" "6.3V"
					( Units "uVoltage" "V" 1.000000)
					( Origin gFrontEnd )
				)
				( attribute "XY" "(-6125,2425)"
					( Origin gFrontEnd )
				)
				( attribute "CHIPS_PART_NAME" "CAP"
					( Origin gPackager )
				)
				( attribute "CDS_PART_NAME" "CAP_0603-4.7UF,6.3V,10%,X6S,E1A"
					( Origin gPackager )
				)
				( attribute "CONFIG" "078.47521.08BD"
					( Origin gFrontEnd )
				)
				( objectStatus "C3M10" )
			)
			( gate "@baseboard_fab2_lib.baseboard_fab2(sch_1):page232_i257"
				( attribute "CDS_LIB" "mstr_discrete"
					( Origin gPackager )
				)
				( attribute "CDS_LOCATION" "R7B12"
					( Origin gPackager )
				)
				( attribute "CDS_SEC" "1"
					( Origin gPackager )
				)
				( attribute "LOCATION" "R7B12"
					( Origin gFrontEnd )
				)
				( attribute "MATERIAL" "CHIP"
					( Origin gFrontEnd )
				)
				( attribute "PACK_TYPE" "0402"
					( Origin gFrontEnd )
				)
				( attribute "PART_NUMBER" "G21796-250"
					( Origin gFrontEnd )
				)
				( attribute "PHYS_PAGE" "232"
					( Origin gFrontEnd )
				)
				( attribute "ROOM" "PVPP_DEF_VR"
					( Origin gFrontEnd )
				)
				( attribute "ROT" "0"
					( Origin gFrontEnd )
				)
				( attribute "SEC" "1"
					( Origin gFrontEnd )
				)
				( attribute "SEC_TYPE" "0402"
					( Origin gFrontEnd )
				)
				( attribute "TOLERANCE" "1.0%"
					( Origin gFrontEnd )
				)
				( attribute "VALUE" "22.1"
					( Origin gFrontEnd )
				)
				( attribute "VER" "1"
					( Origin gFrontEnd )
				)
				( attribute "WATTAGE" "1/16W"
					( Origin gFrontEnd )
				)
				( attribute "XY" "(-3650,975)"
					( Origin gFrontEnd )
				)
				( attribute "CHIPS_PART_NAME" "RES"
					( Origin gPackager )
				)
				( attribute "CDS_PART_NAME" "RES_0402-22.1,1.0%,1/16W,CHIP,A"
					( Origin gPackager )
				)
				( objectStatus "R7B12" )
			)
			( gate "@baseboard_fab2_lib.baseboard_fab2(sch_1):page232_i259"
				( attribute "CDS_LIB" "mstr_discrete"
					( Origin gPackager )
				)
				( attribute "CDS_LOCATION" "C3M8"
					( Origin gPackager )
				)
				( attribute "CDS_SEC" "1"
					( Origin gPackager )
				)
				( attribute "LOCATION" "C3M8"
					( Origin gFrontEnd )
				)
				( attribute "MATERIAL" "X6S"
					( Origin gFrontEnd )
				)
				( attribute "PACK_TYPE" "0805"
					( Origin gFrontEnd )
				)
				( attribute "PART_NUMBER" "C95333-007"
					( Origin gFrontEnd )
				)
				( attribute "PHYS_PAGE" "232"
					( Origin gFrontEnd )
				)
				( attribute "ROT" "0"
					( Origin gFrontEnd )
				)
				( attribute "SEC" "1"
					( Origin gFrontEnd )
				)
				( attribute "SEC_TYPE" "0805"
					( Origin gFrontEnd )
				)
				( attribute "TOLERANCE" "10%"
					( Origin gFrontEnd )
				)
				( attribute "VALUE" "10UF"
					( Origin gFrontEnd )
				)
				( attribute "VER" "1"
					( Origin gFrontEnd )
				)
				( attribute "VOLTAGE" "16V"
					( Units "uVoltage" "V" 1.000000)
					( Origin gFrontEnd )
				)
				( attribute "XY" "(-6950,4100)"
					( Origin gFrontEnd )
				)
				( attribute "CHIPS_PART_NAME" "CAP"
					( Origin gPackager )
				)
				( attribute "CDS_PART_NAME" "CAP_0805-10UF,16V,10%,X6S,C953A"
					( Origin gPackager )
				)
				( objectStatus "C3M8" )
			)
			( gate "@baseboard_fab2_lib.baseboard_fab2(sch_1):page232_i260"
				( attribute "CDS_LIB" "mstr_discrete"
					( Origin gPackager )
				)
				( attribute "CDS_LOCATION" "C3M15"
					( Origin gPackager )
				)
				( attribute "CDS_SEC" "1"
					( Origin gPackager )
				)
				( attribute "LOCATION" "C3M15"
					( Origin gFrontEnd )
				)
				( attribute "MATERIAL" "X6S"
					( Origin gFrontEnd )
				)
				( attribute "PACK_TYPE" "0805"
					( Origin gFrontEnd )
				)
				( attribute "PART_NUMBER" "C95333-007"
					( Origin gFrontEnd )
				)
				( attribute "PHYS_PAGE" "232"
					( Origin gFrontEnd )
				)
				( attribute "ROT" "0"
					( Origin gFrontEnd )
				)
				( attribute "SEC" "1"
					( Origin gFrontEnd )
				)
				( attribute "SEC_TYPE" "0805"
					( Origin gFrontEnd )
				)
				( attribute "TOLERANCE" "10%"
					( Origin gFrontEnd )
				)
				( attribute "VALUE" "10UF"
					( Origin gFrontEnd )
				)
				( attribute "VER" "1"
					( Origin gFrontEnd )
				)
				( attribute "VOLTAGE" "16V"
					( Units "uVoltage" "V" 1.000000)
					( Origin gFrontEnd )
				)
				( attribute "XY" "(-6600,4100)"
					( Origin gFrontEnd )
				)
				( attribute "CHIPS_PART_NAME" "CAP"
					( Origin gPackager )
				)
				( attribute "CDS_PART_NAME" "CAP_0805-10UF,16V,10%,X6S,C953A"
					( Origin gPackager )
				)
				( objectStatus "C3M15" )
			)
			( gate "@baseboard_fab2_lib.baseboard_fab2(sch_1):page232_i261"
				( attribute "CDS_LIB" "mstr_discrete"
					( Origin gPackager )
				)
				( attribute "CDS_LOCATION" "C3M16"
					( Origin gPackager )
				)
				( attribute "CDS_SEC" "1"
					( Origin gPackager )
				)
				( attribute "LOCATION" "C3M16"
					( Origin gFrontEnd )
				)
				( attribute "MATERIAL" "X6S"
					( Origin gFrontEnd )
				)
				( attribute "PACK_TYPE" "0805"
					( Origin gFrontEnd )
				)
				( attribute "PART_NUMBER" "C95333-007"
					( Origin gFrontEnd )
				)
				( attribute "PHYS_PAGE" "232"
					( Origin gFrontEnd )
				)
				( attribute "ROT" "0"
					( Origin gFrontEnd )
				)
				( attribute "SEC" "1"
					( Origin gFrontEnd )
				)
				( attribute "SEC_TYPE" "0805"
					( Origin gFrontEnd )
				)
				( attribute "TOLERANCE" "10%"
					( Origin gFrontEnd )
				)
				( attribute "VALUE" "10UF"
					( Origin gFrontEnd )
				)
				( attribute "VER" "1"
					( Origin gFrontEnd )
				)
				( attribute "VOLTAGE" "16V"
					( Units "uVoltage" "V" 1.000000)
					( Origin gFrontEnd )
				)
				( attribute "XY" "(-6225,4100)"
					( Origin gFrontEnd )
				)
				( attribute "CHIPS_PART_NAME" "CAP"
					( Origin gPackager )
				)
				( attribute "CDS_PART_NAME" "CAP_0805-10UF,16V,10%,X6S,C953A"
					( Origin gPackager )
				)
				( objectStatus "C3M16" )
			)
			( gate "@baseboard_fab2_lib.baseboard_fab2(sch_1):page232_i262"
				( attribute "CDS_LIB" "mstr_discrete"
					( Origin gPackager )
				)
				( attribute "CDS_LOCATION" "C7B5"
					( Origin gPackager )
				)
				( attribute "CDS_SEC" "1"
					( Origin gPackager )
				)
				( attribute "LOCATION" "C7B5"
					( Origin gFrontEnd )
				)
				( attribute "MATERIAL" "X6S"
					( Origin gFrontEnd )
				)
				( attribute "PACK_TYPE" "0805"
					( Origin gFrontEnd )
				)
				( attribute "PART_NUMBER" "C95333-007"
					( Origin gFrontEnd )
				)
				( attribute "PHYS_PAGE" "232"
					( Origin gFrontEnd )
				)
				( attribute "ROT" "0"
					( Origin gFrontEnd )
				)
				( attribute "SEC" "1"
					( Origin gFrontEnd )
				)
				( attribute "SEC_TYPE" "0805"
					( Origin gFrontEnd )
				)
				( attribute "TOLERANCE" "10%"
					( Origin gFrontEnd )
				)
				( attribute "VALUE" "10UF"
					( Origin gFrontEnd )
				)
				( attribute "VER" "1"
					( Origin gFrontEnd )
				)
				( attribute "VOLTAGE" "16V"
					( Units "uVoltage" "V" 1.000000)
					( Origin gFrontEnd )
				)
				( attribute "XY" "(-5850,4100)"
					( Origin gFrontEnd )
				)
				( attribute "CHIPS_PART_NAME" "CAP"
					( Origin gPackager )
				)
				( attribute "CDS_PART_NAME" "CAP_0805-10UF,16V,10%,X6S,C953A"
					( Origin gPackager )
				)
				( objectStatus "C7B5" )
			)
			( gate "@baseboard_fab2_lib.baseboard_fab2(sch_1):page232_i267"
				( attribute "CDS_LIB" "mstr_discrete"
					( Origin gPackager )
				)
				( attribute "CDS_LOCATION" "C4M1"
					( Origin gPackager )
				)
				( attribute "CDS_SEC" "1"
					( Origin gPackager )
				)
				( attribute "LOCATION" "C4M1"
					( Origin gFrontEnd )
				)
				( attribute "MATERIAL" "POSCAP"
					( Origin gFrontEnd )
				)
				( attribute "PACK_TYPE" "7343"
					( Origin gFrontEnd )
				)
				( attribute "PART_NUMBER" "724613-067"
					( Origin gFrontEnd )
				)
				( attribute "PHYS_PAGE" "232"
					( Origin gFrontEnd )
				)
				( attribute "ROT" "0"
					( Origin gFrontEnd )
				)
				( attribute "SEC" "1"
					( Origin gFrontEnd )
				)
				( attribute "SEC_TYPE" "7343"
					( Origin gFrontEnd )
				)
				( attribute "TOLERANCE" "20%"
					( Origin gFrontEnd )
				)
				( attribute "VALUE" "220UF"
					( Origin gFrontEnd )
				)
				( attribute "VER" "1"
					( Origin gFrontEnd )
				)
				( attribute "VOLTAGE" "4V"
					( Units "uVoltage" "V" 1.000000)
					( Origin gFrontEnd )
				)
				( attribute "XY" "(-1800,3650)"
					( Origin gFrontEnd )
				)
				( attribute "CHIPS_PART_NAME" "CAPP"
					( Origin gPackager )
				)
				( attribute "CDS_PART_NAME" "CAPP_7343-220UF,4V,20%,POSCAP,A"
					( Origin gPackager )
				)
				( attribute "GROUP" "PWR_BULK_CAP"
					( Origin gFrontEnd )
				)
				( objectStatus "C4M1" )
			)
			( gate "@baseboard_fab2_lib.baseboard_fab2(sch_1):page232_i298"
				( attribute "BOM_COST" "PVPP_KLM_VR"
					( Origin gFrontEnd )
				)
				( attribute "CDS_LIB" "mstr_discrete"
					( Origin gPackager )
				)
				( attribute "CDS_LOCATION" "R7B18"
					( Origin gPackager )
				)
				( attribute "CDS_SEC" "1"
					( Origin gPackager )
				)
				( attribute "LOCATION" "R7B18"
					( Origin gFrontEnd )
				)
				( attribute "MATERIAL" "CHIP"
					( Origin gFrontEnd )
				)
				( attribute "PACK_TYPE" "0402"
					( Origin gFrontEnd )
				)
				( attribute "PART_NUMBER" "G85996-004"
					( Origin gFrontEnd )
				)
				( attribute "PHYS_PAGE" "232"
					( Origin gFrontEnd )
				)
				( attribute "REUSE_ID" "9"
					( Origin gFrontEnd )
				)
				( attribute "ROOM" "PVPP_KLM_VR"
					( Origin gFrontEnd )
				)
				( attribute "ROT" "0"
					( Origin gFrontEnd )
				)
				( attribute "SEC" "1"
					( Origin gFrontEnd )
				)
				( attribute "SEC_TYPE" "0402"
					( Origin gFrontEnd )
				)
				( attribute "SPOF" "TRUE"
					( Origin gFrontEnd )
				)
				( attribute "TOLERANCE" "0.1%"
					( Origin gFrontEnd )
				)
				( attribute "VALUE" "1.0K"
					( Origin gFrontEnd )
				)
				( attribute "VER" "2"
					( Origin gFrontEnd )
				)
				( attribute "WATTAGE" "1/16W"
					( Origin gFrontEnd )
				)
				( attribute "XY" "(-1350,2525)"
					( Origin gFrontEnd )
				)
				( attribute "CHIPS_PART_NAME" "RES"
					( Origin gPackager )
				)
				( attribute "CDS_PART_NAME" "RES_0402-1.0K,0.1%,1/16W,CHIP,A"
					( Origin gPackager )
				)
				( objectStatus "R7B18" )
			)
			( gate "@baseboard_fab2_lib.baseboard_fab2(sch_1):page232_i299"
				( attribute "CDS_LIB" "mstr_discrete"
					( Origin gPackager )
				)
				( attribute "CDS_LOCATION" "R7B11"
					( Origin gPackager )
				)
				( attribute "CDS_SEC" "1"
					( Origin gPackager )
				)
				( attribute "LOCATION" "R7B11"
					( Origin gFrontEnd )
				)
				( attribute "MATERIAL" "CHIP"
					( Origin gFrontEnd )
				)
				( attribute "PACK_TYPE" "0402"
					( Origin gFrontEnd )
				)
				( attribute "PART_NUMBER" "G21497-005"
					( Origin gFrontEnd )
				)
				( attribute "PHYS_PAGE" "232"
					( Origin gFrontEnd )
				)
				( attribute "ROOM" "PVPP_KLM_VR"
					( Origin gFrontEnd )
				)
				( attribute "ROT" "5"
					( Origin gFrontEnd )
				)
				( attribute "SEC" "1"
					( Origin gFrontEnd )
				)
				( attribute "SEC_TYPE" "0402"
					( Origin gFrontEnd )
				)
				( attribute "SPOF" "TRUE"
					( Origin gFrontEnd )
				)
				( attribute "TOLERANCE" "5%"
					( Origin gFrontEnd )
				)
				( attribute "VALUE" "0.0"
					( Origin gFrontEnd )
				)
				( attribute "VER" "1"
					( Origin gFrontEnd )
				)
				( attribute "WATTAGE" "1/16W"
					( Origin gFrontEnd )
				)
				( attribute "XY" "(-1700,2925)"
					( Origin gFrontEnd )
				)
				( attribute "CHIPS_PART_NAME" "RES"
					( Origin gPackager )
				)
				( attribute "CDS_PART_NAME" "RES_0402-0.0,5%,1/16W,CHIP,G21A"
					( Origin gPackager )
				)
				( objectStatus "R7B11" )
			)
			( gate "@baseboard_fab2_lib.baseboard_fab2(sch_1):page232_i300"
				( attribute "BOM_COST" "PVPP_KLM_VR"
					( Origin gFrontEnd )
				)
				( attribute "CDS_LIB" "mstr_discrete"
					( Origin gPackager )
				)
				( attribute "CDS_LOCATION" "R7B16"
					( Origin gPackager )
				)
				( attribute "CDS_SEC" "1"
					( Origin gPackager )
				)
				( attribute "LOCATION" "R7B16"
					( Origin gFrontEnd )
				)
				( attribute "MATERIAL" "CHIP"
					( Origin gFrontEnd )
				)
				( attribute "PACK_TYPE" "0402"
					( Origin gFrontEnd )
				)
				( attribute "PART_NUMBER" "G21796-242"
					( Origin gFrontEnd )
				)
				( attribute "PHYS_PAGE" "232"
					( Origin gFrontEnd )
				)
				( attribute "REUSE_ID" "13"
					( Origin gFrontEnd )
				)
				( attribute "ROOM" "PVPP_KLM_VR"
					( Origin gFrontEnd )
				)
				( attribute "ROT" "0"
					( Origin gFrontEnd )
				)
				( attribute "SEC" "1"
					( Origin gFrontEnd )
				)
				( attribute "SEC_TYPE" "0402"
					( Origin gFrontEnd )
				)
				( attribute "TOLERANCE" "1.0%"
					( Origin gFrontEnd )
				)
				( attribute "VALUE" "7.87K"
					( Origin gFrontEnd )
				)
				( attribute "VER" "1"
					( Origin gFrontEnd )
				)
				( attribute "WATTAGE" "1/16W"
					( Origin gFrontEnd )
				)
				( attribute "XY" "(-2400,2450)"
					( Origin gFrontEnd )
				)
				( attribute "CHIPS_PART_NAME" "RES"
					( Origin gPackager )
				)
				( attribute "CDS_PART_NAME" "RES_0402-7.87K,1.0%,1/16W,CHIPA"
					( Origin gPackager )
				)
				( objectStatus "R7B16" )
			)
			( gate "@baseboard_fab2_lib.baseboard_fab2(sch_1):page232_i301"
				( attribute "BOM_COST" "PVPP_KLM_VR"
					( Origin gFrontEnd )
				)
				( attribute "CDS_LIB" "mstr_discrete"
					( Origin gPackager )
				)
				( attribute "CDS_LOCATION" "C7B10"
					( Origin gPackager )
				)
				( attribute "CDS_SEC" "1"
					( Origin gPackager )
				)
				( attribute "LOCATION" "C7B10"
					( Origin gFrontEnd )
				)
				( attribute "MATERIAL" "COG"
					( Origin gFrontEnd )
				)
				( attribute "PACK_TYPE" "0402LF"
					( Origin gFrontEnd )
				)
				( attribute "PART_NUMBER" "A36095-026"
					( Origin gFrontEnd )
				)
				( attribute "PHYS_PAGE" "232"
					( Origin gFrontEnd )
				)
				( attribute "REUSE_ID" "27"
					( Origin gFrontEnd )
				)
				( attribute "ROOM" "PVPP_KLM_VR"
					( Origin gFrontEnd )
				)
				( attribute "ROT" "2"
					( Origin gFrontEnd )
				)
				( attribute "SEC" "1"
					( Origin gFrontEnd )
				)
				( attribute "SEC_TYPE" "0402LF"
					( Origin gFrontEnd )
				)
				( attribute "TOLERANCE" "5%"
					( Origin gFrontEnd )
				)
				( attribute "VALUE" "100.0PF"
					( Origin gFrontEnd )
				)
				( attribute "VER" "2"
					( Origin gFrontEnd )
				)
				( attribute "VOLTAGE" "50V"
					( Units "uVoltage" "V" 1.000000)
					( Origin gFrontEnd )
				)
				( attribute "XY" "(-2600,2825)"
					( Origin gFrontEnd )
				)
				( attribute "CHIPS_PART_NAME" "CAP"
					( Origin gPackager )
				)
				( attribute "CDS_PART_NAME" "CAP_0402LF-100.0PF,50V,5%,COG,A"
					( Origin gPackager )
				)
				( objectStatus "C7B10" )
			)
			( gate "@baseboard_fab2_lib.baseboard_fab2(sch_1):page232_i302"
				( attribute "BOM_COST" "PVPP_KLM_VR"
					( Origin gFrontEnd )
				)
				( attribute "CDS_LIB" "mstr_discrete"
					( Origin gPackager )
				)
				( attribute "CDS_LOCATION" "C7B13"
					( Origin gPackager )
				)
				( attribute "CDS_SEC" "1"
					( Origin gPackager )
				)
				( attribute "LOCATION" "C7B13"
					( Origin gFrontEnd )
				)
				( attribute "MATERIAL" "X7R"
					( Origin gFrontEnd )
				)
				( attribute "PACK_TYPE" "0402LF"
					( Origin gFrontEnd )
				)
				( attribute "PART_NUMBER" "A36096-075"
					( Origin gFrontEnd )
				)
				( attribute "PHYS_PAGE" "232"
					( Origin gFrontEnd )
				)
				( attribute "REUSE_ID" "26"
					( Origin gFrontEnd )
				)
				( attribute "ROOM" "PVPP_KLM_VR"
					( Origin gFrontEnd )
				)
				( attribute "ROT" "0"
					( Origin gFrontEnd )
				)
				( attribute "SEC" "1"
					( Origin gFrontEnd )
				)
				( attribute "SEC_TYPE" "0402LF"
					( Origin gFrontEnd )
				)
				( attribute "SPOF" "TRUE"
					( Origin gFrontEnd )
				)
				( attribute "TOLERANCE" "10%"
					( Origin gFrontEnd )
				)
				( attribute "VALUE" "2200PF"
					( Origin gFrontEnd )
				)
				( attribute "VER" "1"
					( Origin gFrontEnd )
				)
				( attribute "VOLTAGE" "50V"
					( Units "uVoltage" "V" 1.000000)
					( Origin gFrontEnd )
				)
				( attribute "XY" "(-1350,1775)"
					( Origin gFrontEnd )
				)
				( attribute "CHIPS_PART_NAME" "CAP"
					( Origin gPackager )
				)
				( attribute "CDS_PART_NAME" "CAP_0402LF-2200PF,50V,10%,X7R,A"
					( Origin gPackager )
				)
				( objectStatus "C7B13" )
			)
			( gate "@baseboard_fab2_lib.baseboard_fab2(sch_1):page232_i303"
				( attribute "BOM_COST" "PVPP_KLM_VR"
					( Origin gFrontEnd )
				)
				( attribute "CDS_LIB" "mstr_discrete"
					( Origin gPackager )
				)
				( attribute "CDS_LOCATION" "R7B15"
					( Origin gPackager )
				)
				( attribute "CDS_SEC" "1"
					( Origin gPackager )
				)
				( attribute "LOCATION" "R7B15"
					( Origin gFrontEnd )
				)
				( attribute "MATERIAL" "CHIP"
					( Origin gFrontEnd )
				)
				( attribute "PACK_TYPE" "0402"
					( Origin gFrontEnd )
				)
				( attribute "PART_NUMBER" "G21796-040"
					( Origin gFrontEnd )
				)
				( attribute "PHYS_PAGE" "232"
					( Origin gFrontEnd )
				)
				( attribute "REUSE_ID" "9"
					( Origin gFrontEnd )
				)
				( attribute "ROOM" "PVPP_KLM_VR"
					( Origin gFrontEnd )
				)
				( attribute "ROT" "0"
					( Origin gFrontEnd )
				)
				( attribute "SEC" "1"
					( Origin gPackager )
				)
				( attribute "SPOF" "TRUE"
					( Origin gFrontEnd )
				)
				( attribute "TOLERANCE" "1%"
					( Origin gFrontEnd )
				)
				( attribute "VALUE" "20.0K"
					( Origin gFrontEnd )
				)
				( attribute "VER" "2"
					( Origin gFrontEnd )
				)
				( attribute "WATTAGE" "1/16W"
					( Origin gFrontEnd )
				)
				( attribute "XY" "(-1700,1850)"
					( Origin gFrontEnd )
				)
				( attribute "CHIPS_PART_NAME" "RES"
					( Origin gPackager )
				)
				( attribute "CDS_PART_NAME" "RES_0402-20.0K,1%,1/16W,CHIP,GA"
					( Origin gPackager )
				)
				( objectStatus "R7B15" )
			)
			( gate "@baseboard_fab2_lib.baseboard_fab2(sch_1):page233_i283"
				( attribute "BOM_COST" "IO_SLOT"
					( Origin gFrontEnd )
				)
				( attribute "CDS_LIB" "mstr_discrete"
					( Origin gPackager )
				)
				( attribute "CDS_LOCATION" "R4G9"
					( Origin gPackager )
				)
				( attribute "CDS_SEC" "1"
					( Origin gPackager )
				)
				( attribute "LOCATION" "R4G9"
					( Origin gFrontEnd )
				)
				( attribute "MATERIAL" "CHIP"
					( Origin gFrontEnd )
				)
				( attribute "PACK_TYPE" "0402"
					( Origin gFrontEnd )
				)
				( attribute "PART_NUMBER" "G21796-161"
					( Origin gFrontEnd )
				)
				( attribute "PHYS_PAGE" "233"
					( Origin gFrontEnd )
				)
				( attribute "ROOM" "IO_SLOT"
					( Origin gFrontEnd )
				)
				( attribute "ROT" "0"
					( Origin gFrontEnd )
				)
				( attribute "SEC" "1"
					( Origin gFrontEnd )
				)
				( attribute "SEC_TYPE" "0402"
					( Origin gFrontEnd )
				)
				( attribute "TOLERANCE" "1%"
					( Origin gFrontEnd )
				)
				( attribute "VALUE" "6.19K"
					( Origin gFrontEnd )
				)
				( attribute "VER" "2"
					( Origin gFrontEnd )
				)
				( attribute "WATTAGE" "1/16W"
					( Origin gFrontEnd )
				)
				( attribute "XY" "(-1275,1225)"
					( Origin gFrontEnd )
				)
				( attribute "CHIPS_PART_NAME" "RES"
					( Origin gPackager )
				)
				( attribute "CDS_PART_NAME" "RES_0402-6.19K,1%,1/16W,CHIP,GA"
					( Origin gPackager )
				)
				( objectStatus "R4G9" )
			)
			( gate "@baseboard_fab2_lib.baseboard_fab2(sch_1):page232_i306"
				( attribute "BOM_COST" "PVPP_KLM_VR"
					( Origin gFrontEnd )
				)
				( attribute "CDS_LIB" "mstr_discrete"
					( Origin gPackager )
				)
				( attribute "CDS_LOCATION" "C7B14"
					( Origin gPackager )
				)
				( attribute "CDS_SEC" "1"
					( Origin gPackager )
				)
				( attribute "LOCATION" "C7B14"
					( Origin gFrontEnd )
				)
				( attribute "MATERIAL" "X7R"
					( Origin gFrontEnd )
				)
				( attribute "PACK_TYPE" "0402LF"
					( Origin gFrontEnd )
				)
				( attribute "PART_NUMBER" "A36096-075"
					( Origin gFrontEnd )
				)
				( attribute "PHYS_PAGE" "232"
					( Origin gFrontEnd )
				)
				( attribute "REUSE_ID" "27"
					( Origin gFrontEnd )
				)
				( attribute "ROOM" "PVPP_KLM_VR"
					( Origin gFrontEnd )
				)
				( attribute "ROT" "2"
					( Origin gFrontEnd )
				)
				( attribute "SEC" "1"
					( Origin gFrontEnd )
				)
				( attribute "SEC_TYPE" "0402LF"
					( Origin gFrontEnd )
				)
				( attribute "TOLERANCE" "10%"
					( Origin gFrontEnd )
				)
				( attribute "VALUE" "2200PF"
					( Origin gFrontEnd )
				)
				( attribute "VER" "2"
					( Origin gFrontEnd )
				)
				( attribute "VOLTAGE" "50V"
					( Units "uVoltage" "V" 1.000000)
					( Origin gFrontEnd )
				)
				( attribute "XY" "(-3200,2450)"
					( Origin gFrontEnd )
				)
				( attribute "CHIPS_PART_NAME" "CAP"
					( Origin gPackager )
				)
				( attribute "CDS_PART_NAME" "CAP_0402LF-2200PF,50V,10%,X7R,A"
					( Origin gPackager )
				)
				( objectStatus "C7B14" )
			)
			( gate "@baseboard_fab2_lib.baseboard_fab2(sch_1):page232_i307"
				( attribute "CDS_LIB" "mstr_discrete"
					( Origin gPackager )
				)
				( attribute "CDS_LOCATION" "R7B9"
					( Origin gPackager )
				)
				( attribute "CDS_SEC" "1"
					( Origin gPackager )
				)
				( attribute "LOCATION" "R7B9"
					( Origin gFrontEnd )
				)
				( attribute "MATERIAL" "CHIP"
					( Origin gFrontEnd )
				)
				( attribute "PACK_TYPE" "0402"
					( Origin gFrontEnd )
				)
				( attribute "PART_NUMBER" "G21497-005"
					( Origin gFrontEnd )
				)
				( attribute "PHYS_PAGE" "232"
					( Origin gFrontEnd )
				)
				( attribute "ROOM" "PVCCIN_CPU0_VR"
					( Origin gFrontEnd )
				)
				( attribute "ROT" "0"
					( Origin gFrontEnd )
				)
				( attribute "SEC" "1"
					( Origin gFrontEnd )
				)
				( attribute "SEC_TYPE" "0402"
					( Origin gFrontEnd )
				)
				( attribute "TOLERANCE" "5%"
					( Origin gFrontEnd )
				)
				( attribute "VALUE" "0.0"
					( Origin gFrontEnd )
				)
				( attribute "VER" "1"
					( Origin gFrontEnd )
				)
				( attribute "WATTAGE" "1/16W"
					( Origin gFrontEnd )
				)
				( attribute "XY" "(-6500,2825)"
					( Origin gFrontEnd )
				)
				( attribute "CHIPS_PART_NAME" "RES"
					( Origin gPackager )
				)
				( attribute "CDS_PART_NAME" "RES_0402-0.0,5%,1/16W,CHIP,G21A"
					( Origin gPackager )
				)
				( objectStatus "R7B9" )
			)
			( gate "@baseboard_fab2_lib.baseboard_fab2(sch_1):page233_i109"
				( attribute "BOM_COST" "MEM_VRD_PVPP_AB"
					( Origin gFrontEnd )
				)
				( attribute "CDS_LIB" "mstr_discrete"
					( Origin gPackager )
				)
				( attribute "CDS_LOCATION" "C7U4"
					( Origin gPackager )
				)
				( attribute "CDS_SEC" "1"
					( Origin gPackager )
				)
				( attribute "LOCATION" "C7U4"
					( Origin gFrontEnd )
				)
				( attribute "MATERIAL" "X6S"
					( Origin gFrontEnd )
				)
				( attribute "PACK_TYPE" "0603LF"
					( Origin gFrontEnd )
				)
				( attribute "PART_NUMBER" "E15431-001"
					( Origin gFrontEnd )
				)
				( attribute "PHYS_PAGE" "233"
					( Origin gFrontEnd )
				)
				( attribute "ROOM" "PVPP_KLM_VR"
					( Origin gFrontEnd )
				)
				( attribute "ROT" "0"
					( Origin gFrontEnd )
				)
				( attribute "SEC" "1"
					( Origin gPackager )
				)
				( attribute "TOLERANCE" "20%"
					( Origin gFrontEnd )
				)
				( attribute "VALUE" "10UF"
					( Origin gFrontEnd )
				)
				( attribute "VER" "1"
					( Origin gFrontEnd )
				)
				( attribute "VOLTAGE" "4V"
					( Units "uVoltage" "V" 1.000000)
					( Origin gFrontEnd )
				)
				( attribute "XY" "(-8150,725)"
					( Origin gFrontEnd )
				)
				( attribute "CHIPS_PART_NAME" "CAP"
					( Origin gPackager )
				)
				( attribute "CDS_PART_NAME" "CAP_0603LF-10UF,4V,20%,X6S,E15A"
					( Origin gPackager )
				)
				( attribute "GROUP" "PWR_MLCC_CAP"
					( Origin gFrontEnd )
				)
				( objectStatus "C7U4" )
			)
			( gate "@baseboard_fab2_lib.baseboard_fab2(sch_1):page233_i111"
				( attribute "BOM_COST" "MEM_VRD_PVPP_AB"
					( Origin gFrontEnd )
				)
				( attribute "CDS_LIB" "mstr_discrete"
					( Origin gPackager )
				)
				( attribute "CDS_LOCATION" "C7U5"
					( Origin gPackager )
				)
				( attribute "CDS_SEC" "1"
					( Origin gPackager )
				)
				( attribute "LOCATION" "C7U5"
					( Origin gFrontEnd )
				)
				( attribute "MATERIAL" "X6S"
					( Origin gFrontEnd )
				)
				( attribute "PACK_TYPE" "0603LF"
					( Origin gFrontEnd )
				)
				( attribute "PART_NUMBER" "E15431-001"
					( Origin gFrontEnd )
				)
				( attribute "PHYS_PAGE" "233"
					( Origin gFrontEnd )
				)
				( attribute "ROOM" "PVPP_KLM_VR"
					( Origin gFrontEnd )
				)
				( attribute "ROT" "0"
					( Origin gFrontEnd )
				)
				( attribute "SEC" "1"
					( Origin gPackager )
				)
				( attribute "TOLERANCE" "20%"
					( Origin gFrontEnd )
				)
				( attribute "VALUE" "10UF"
					( Origin gFrontEnd )
				)
				( attribute "VER" "1"
					( Origin gFrontEnd )
				)
				( attribute "VOLTAGE" "4V"
					( Units "uVoltage" "V" 1.000000)
					( Origin gFrontEnd )
				)
				( attribute "XY" "(-7875,725)"
					( Origin gFrontEnd )
				)
				( attribute "CHIPS_PART_NAME" "CAP"
					( Origin gPackager )
				)
				( attribute "CDS_PART_NAME" "CAP_0603LF-10UF,4V,20%,X6S,E15A"
					( Origin gPackager )
				)
				( attribute "GROUP" "PWR_MLCC_CAP"
					( Origin gFrontEnd )
				)
				( objectStatus "C7U5" )
			)
			( gate "@baseboard_fab2_lib.baseboard_fab2(sch_1):page233_i112"
				( attribute "BOM_COST" "MEM_VRD_PVPP_AB"
					( Origin gFrontEnd )
				)
				( attribute "CDS_LIB" "mstr_discrete"
					( Origin gPackager )
				)
				( attribute "CDS_LOCATION" "C7T2"
					( Origin gPackager )
				)
				( attribute "CDS_SEC" "1"
					( Origin gPackager )
				)
				( attribute "LOCATION" "C7T2"
					( Origin gFrontEnd )
				)
				( attribute "MATERIAL" "X6S"
					( Origin gFrontEnd )
				)
				( attribute "PACK_TYPE" "0603LF"
					( Origin gFrontEnd )
				)
				( attribute "PART_NUMBER" "E15431-001"
					( Origin gFrontEnd )
				)
				( attribute "PHYS_PAGE" "233"
					( Origin gFrontEnd )
				)
				( attribute "ROOM" "PVPP_KLM_VR"
					( Origin gFrontEnd )
				)
				( attribute "ROT" "0"
					( Origin gFrontEnd )
				)
				( attribute "SEC" "1"
					( Origin gPackager )
				)
				( attribute "TOLERANCE" "20%"
					( Origin gFrontEnd )
				)
				( attribute "VALUE" "10UF"
					( Origin gFrontEnd )
				)
				( attribute "VER" "1"
					( Origin gFrontEnd )
				)
				( attribute "VOLTAGE" "4V"
					( Units "uVoltage" "V" 1.000000)
					( Origin gFrontEnd )
				)
				( attribute "XY" "(-7600,725)"
					( Origin gFrontEnd )
				)
				( attribute "CHIPS_PART_NAME" "CAP"
					( Origin gPackager )
				)
				( attribute "CDS_PART_NAME" "CAP_0603LF-10UF,4V,20%,X6S,E15A"
					( Origin gPackager )
				)
				( attribute "GROUP" "PWR_MLCC_CAP"
					( Origin gFrontEnd )
				)
				( objectStatus "C7T2" )
			)
			( gate "@baseboard_fab2_lib.baseboard_fab2(sch_1):page233_i113"
				( attribute "BOM_COST" "MEM_VRD_PVPP_AB"
					( Origin gFrontEnd )
				)
				( attribute "CDS_LIB" "mstr_discrete"
					( Origin gPackager )
				)
				( attribute "CDS_LOCATION" "C7T3"
					( Origin gPackager )
				)
				( attribute "CDS_SEC" "1"
					( Origin gPackager )
				)
				( attribute "LOCATION" "C7T3"
					( Origin gFrontEnd )
				)
				( attribute "MATERIAL" "X6S"
					( Origin gFrontEnd )
				)
				( attribute "PACK_TYPE" "0603LF"
					( Origin gFrontEnd )
				)
				( attribute "PART_NUMBER" "E15431-001"
					( Origin gFrontEnd )
				)
				( attribute "PHYS_PAGE" "233"
					( Origin gFrontEnd )
				)
				( attribute "ROOM" "PVPP_KLM_VR"
					( Origin gFrontEnd )
				)
				( attribute "ROT" "0"
					( Origin gFrontEnd )
				)
				( attribute "SEC" "1"
					( Origin gPackager )
				)
				( attribute "TOLERANCE" "20%"
					( Origin gFrontEnd )
				)
				( attribute "VALUE" "10UF"
					( Origin gFrontEnd )
				)
				( attribute "VER" "1"
					( Origin gFrontEnd )
				)
				( attribute "VOLTAGE" "4V"
					( Units "uVoltage" "V" 1.000000)
					( Origin gFrontEnd )
				)
				( attribute "XY" "(-7325,725)"
					( Origin gFrontEnd )
				)
				( attribute "CHIPS_PART_NAME" "CAP"
					( Origin gPackager )
				)
				( attribute "CDS_PART_NAME" "CAP_0603LF-10UF,4V,20%,X6S,E15A"
					( Origin gPackager )
				)
				( attribute "GROUP" "PWR_MLCC_CAP"
					( Origin gFrontEnd )
				)
				( objectStatus "C7T3" )
			)
			( gate "@baseboard_fab2_lib.baseboard_fab2(sch_1):page233_i115"
				( attribute "BOM_COST" "MEM_VRD_PVPP_AB"
					( Origin gFrontEnd )
				)
				( attribute "CDS_LIB" "mstr_discrete"
					( Origin gPackager )
				)
				( attribute "CDS_LOCATION" "C7U6"
					( Origin gPackager )
				)
				( attribute "CDS_SEC" "1"
					( Origin gPackager )
				)
				( attribute "LOCATION" "C7U6"
					( Origin gFrontEnd )
				)
				( attribute "MATERIAL" "X6S"
					( Origin gFrontEnd )
				)
				( attribute "PACK_TYPE" "0603LF"
					( Origin gFrontEnd )
				)
				( attribute "PART_NUMBER" "E15431-001"
					( Origin gFrontEnd )
				)
				( attribute "PHYS_PAGE" "233"
					( Origin gFrontEnd )
				)
				( attribute "ROOM" "PVPP_KLM_VR"
					( Origin gFrontEnd )
				)
				( attribute "ROT" "0"
					( Origin gFrontEnd )
				)
				( attribute "SEC" "1"
					( Origin gPackager )
				)
				( attribute "TOLERANCE" "20%"
					( Origin gFrontEnd )
				)
				( attribute "VALUE" "10UF"
					( Origin gFrontEnd )
				)
				( attribute "VER" "1"
					( Origin gFrontEnd )
				)
				( attribute "VOLTAGE" "4V"
					( Units "uVoltage" "V" 1.000000)
					( Origin gFrontEnd )
				)
				( attribute "XY" "(-7050,725)"
					( Origin gFrontEnd )
				)
				( attribute "CHIPS_PART_NAME" "CAP"
					( Origin gPackager )
				)
				( attribute "CDS_PART_NAME" "CAP_0603LF-10UF,4V,20%,X6S,E15A"
					( Origin gPackager )
				)
				( attribute "GROUP" "PWR_MLCC_CAP"
					( Origin gFrontEnd )
				)
				( objectStatus "C7U6" )
			)
			( gate "@baseboard_fab2_lib.baseboard_fab2(sch_1):page233_i116"
				( attribute "BOM_COST" "MEM_VRD_PVPP_AB"
					( Origin gFrontEnd )
				)
				( attribute "CDS_LIB" "mstr_discrete"
					( Origin gPackager )
				)
				( attribute "CDS_LOCATION" "C3F3"
					( Origin gPackager )
				)
				( attribute "CDS_SEC" "1"
					( Origin gPackager )
				)
				( attribute "LOCATION" "C3F3"
					( Origin gFrontEnd )
				)
				( attribute "MATERIAL" "X6S"
					( Origin gFrontEnd )
				)
				( attribute "PACK_TYPE" "0603LF"
					( Origin gFrontEnd )
				)
				( attribute "PART_NUMBER" "E15431-001"
					( Origin gFrontEnd )
				)
				( attribute "PHYS_PAGE" "233"
					( Origin gFrontEnd )
				)
				( attribute "ROOM" "PVPP_KLM_VR"
					( Origin gFrontEnd )
				)
				( attribute "ROT" "0"
					( Origin gFrontEnd )
				)
				( attribute "SEC" "1"
					( Origin gPackager )
				)
				( attribute "TOLERANCE" "20%"
					( Origin gFrontEnd )
				)
				( attribute "VALUE" "10UF"
					( Origin gFrontEnd )
				)
				( attribute "VER" "1"
					( Origin gFrontEnd )
				)
				( attribute "VOLTAGE" "4V"
					( Units "uVoltage" "V" 1.000000)
					( Origin gFrontEnd )
				)
				( attribute "XY" "(-6750,725)"
					( Origin gFrontEnd )
				)
				( attribute "CHIPS_PART_NAME" "CAP"
					( Origin gPackager )
				)
				( attribute "CDS_PART_NAME" "CAP_0603LF-10UF,4V,20%,X6S,E15A"
					( Origin gPackager )
				)
				( attribute "GROUP" "PWR_MLCC_CAP"
					( Origin gFrontEnd )
				)
				( objectStatus "C3F3" )
			)
			( gate "@baseboard_fab2_lib.baseboard_fab2(sch_1):page233_i117"
				( attribute "BOM_COST" "MEM_VRD_PVPP_AB"
					( Origin gFrontEnd )
				)
				( attribute "CDS_LIB" "mstr_discrete"
					( Origin gPackager )
				)
				( attribute "CDS_LOCATION" "C3F4"
					( Origin gPackager )
				)
				( attribute "CDS_SEC" "1"
					( Origin gPackager )
				)
				( attribute "LOCATION" "C3F4"
					( Origin gFrontEnd )
				)
				( attribute "MATERIAL" "X6S"
					( Origin gFrontEnd )
				)
				( attribute "PACK_TYPE" "0603LF"
					( Origin gFrontEnd )
				)
				( attribute "PART_NUMBER" "E15431-001"
					( Origin gFrontEnd )
				)
				( attribute "PHYS_PAGE" "233"
					( Origin gFrontEnd )
				)
				( attribute "ROOM" "PVPP_KLM_VR"
					( Origin gFrontEnd )
				)
				( attribute "ROT" "0"
					( Origin gFrontEnd )
				)
				( attribute "SEC" "1"
					( Origin gPackager )
				)
				( attribute "TOLERANCE" "20%"
					( Origin gFrontEnd )
				)
				( attribute "VALUE" "10UF"
					( Origin gFrontEnd )
				)
				( attribute "VER" "1"
					( Origin gFrontEnd )
				)
				( attribute "VOLTAGE" "4V"
					( Units "uVoltage" "V" 1.000000)
					( Origin gFrontEnd )
				)
				( attribute "XY" "(-6475,725)"
					( Origin gFrontEnd )
				)
				( attribute "CHIPS_PART_NAME" "CAP"
					( Origin gPackager )
				)
				( attribute "CDS_PART_NAME" "CAP_0603LF-10UF,4V,20%,X6S,E15A"
					( Origin gPackager )
				)
				( attribute "GROUP" "PWR_MLCC_CAP"
					( Origin gFrontEnd )
				)
				( objectStatus "C3F4" )
			)
			( gate "@baseboard_fab2_lib.baseboard_fab2(sch_1):page233_i118"
				( attribute "BOM_COST" "MEM_VRD_PVPP_AB"
					( Origin gFrontEnd )
				)
				( attribute "CDS_LIB" "mstr_discrete"
					( Origin gPackager )
				)
				( attribute "CDS_LOCATION" "C3G3"
					( Origin gPackager )
				)
				( attribute "CDS_SEC" "1"
					( Origin gPackager )
				)
				( attribute "LOCATION" "C3G3"
					( Origin gFrontEnd )
				)
				( attribute "MATERIAL" "X6S"
					( Origin gFrontEnd )
				)
				( attribute "PACK_TYPE" "0603LF"
					( Origin gFrontEnd )
				)
				( attribute "PART_NUMBER" "E15431-001"
					( Origin gFrontEnd )
				)
				( attribute "PHYS_PAGE" "233"
					( Origin gFrontEnd )
				)
				( attribute "ROOM" "PVPP_KLM_VR"
					( Origin gFrontEnd )
				)
				( attribute "ROT" "0"
					( Origin gFrontEnd )
				)
				( attribute "SEC" "1"
					( Origin gPackager )
				)
				( attribute "TOLERANCE" "20%"
					( Origin gFrontEnd )
				)
				( attribute "VALUE" "10UF"
					( Origin gFrontEnd )
				)
				( attribute "VER" "1"
					( Origin gFrontEnd )
				)
				( attribute "VOLTAGE" "4V"
					( Units "uVoltage" "V" 1.000000)
					( Origin gFrontEnd )
				)
				( attribute "XY" "(-6175,725)"
					( Origin gFrontEnd )
				)
				( attribute "CHIPS_PART_NAME" "CAP"
					( Origin gPackager )
				)
				( attribute "CDS_PART_NAME" "CAP_0603LF-10UF,4V,20%,X6S,E15A"
					( Origin gPackager )
				)
				( attribute "GROUP" "PWR_MLCC_CAP"
					( Origin gFrontEnd )
				)
				( objectStatus "C3G3" )
			)
			( gate "@baseboard_fab2_lib.baseboard_fab2(sch_1):page233_i132"
				( attribute "BOM_COST" "MEM_VRD_PVPP_AB"
					( Origin gFrontEnd )
				)
				( attribute "CDS_LIB" "mstr_discrete"
					( Origin gPackager )
				)
				( attribute "CDS_LOCATION" "C3G7"
					( Origin gPackager )
				)
				( attribute "CDS_SEC" "1"
					( Origin gPackager )
				)
				( attribute "LOCATION" "C3G7"
					( Origin gFrontEnd )
				)
				( attribute "MATERIAL" "X6S"
					( Origin gFrontEnd )
				)
				( attribute "PACK_TYPE" "0603LF"
					( Origin gFrontEnd )
				)
				( attribute "PART_NUMBER" "E15431-001"
					( Origin gFrontEnd )
				)
				( attribute "PHYS_PAGE" "233"
					( Origin gFrontEnd )
				)
				( attribute "ROOM" "PVPP_KLM_VR"
					( Origin gFrontEnd )
				)
				( attribute "ROT" "0"
					( Origin gFrontEnd )
				)
				( attribute "SEC" "1"
					( Origin gPackager )
				)
				( attribute "TOLERANCE" "20%"
					( Origin gFrontEnd )
				)
				( attribute "VALUE" "10UF"
					( Origin gFrontEnd )
				)
				( attribute "VER" "1"
					( Origin gFrontEnd )
				)
				( attribute "VOLTAGE" "4V"
					( Units "uVoltage" "V" 1.000000)
					( Origin gFrontEnd )
				)
				( attribute "XY" "(-5875,725)"
					( Origin gFrontEnd )
				)
				( attribute "CHIPS_PART_NAME" "CAP"
					( Origin gPackager )
				)
				( attribute "CDS_PART_NAME" "CAP_0603LF-10UF,4V,20%,X6S,E15A"
					( Origin gPackager )
				)
				( attribute "GROUP" "PWR_MLCC_CAP"
					( Origin gFrontEnd )
				)
				( objectStatus "C3G7" )
			)
			( gate "@baseboard_fab2_lib.baseboard_fab2(sch_1):page233_i133"
				( attribute "BOM_COST" "MEM_VRD_PVPP_AB"
					( Origin gFrontEnd )
				)
				( attribute "CDS_LIB" "mstr_discrete"
					( Origin gPackager )
				)
				( attribute "CDS_LOCATION" "C3G4"
					( Origin gPackager )
				)
				( attribute "CDS_SEC" "1"
					( Origin gPackager )
				)
				( attribute "LOCATION" "C3G4"
					( Origin gFrontEnd )
				)
				( attribute "MATERIAL" "X6S"
					( Origin gFrontEnd )
				)
				( attribute "PACK_TYPE" "0603LF"
					( Origin gFrontEnd )
				)
				( attribute "PART_NUMBER" "E15431-001"
					( Origin gFrontEnd )
				)
				( attribute "PHYS_PAGE" "233"
					( Origin gFrontEnd )
				)
				( attribute "ROOM" "PVPP_KLM_VR"
					( Origin gFrontEnd )
				)
				( attribute "ROT" "0"
					( Origin gFrontEnd )
				)
				( attribute "SEC" "1"
					( Origin gPackager )
				)
				( attribute "TOLERANCE" "20%"
					( Origin gFrontEnd )
				)
				( attribute "VALUE" "10UF"
					( Origin gFrontEnd )
				)
				( attribute "VER" "1"
					( Origin gFrontEnd )
				)
				( attribute "VOLTAGE" "4V"
					( Units "uVoltage" "V" 1.000000)
					( Origin gFrontEnd )
				)
				( attribute "XY" "(-5600,725)"
					( Origin gFrontEnd )
				)
				( attribute "CHIPS_PART_NAME" "CAP"
					( Origin gPackager )
				)
				( attribute "CDS_PART_NAME" "CAP_0603LF-10UF,4V,20%,X6S,E15A"
					( Origin gPackager )
				)
				( attribute "GROUP" "PWR_MLCC_CAP"
					( Origin gFrontEnd )
				)
				( objectStatus "C3G4" )
			)
			( gate "@baseboard_fab2_lib.baseboard_fab2(sch_1):page233_i135"
				( attribute "BOM_COST" "MEM_VRD_PVPP_AB"
					( Origin gFrontEnd )
				)
				( attribute "CDS_LIB" "mstr_discrete"
					( Origin gPackager )
				)
				( attribute "CDS_LOCATION" "C3G8"
					( Origin gPackager )
				)
				( attribute "CDS_SEC" "1"
					( Origin gPackager )
				)
				( attribute "LOCATION" "C3G8"
					( Origin gFrontEnd )
				)
				( attribute "MATERIAL" "X6S"
					( Origin gFrontEnd )
				)
				( attribute "PACK_TYPE" "0603LF"
					( Origin gFrontEnd )
				)
				( attribute "PART_NUMBER" "E15431-001"
					( Origin gFrontEnd )
				)
				( attribute "PHYS_PAGE" "233"
					( Origin gFrontEnd )
				)
				( attribute "ROOM" "PVPP_KLM_VR"
					( Origin gFrontEnd )
				)
				( attribute "ROT" "0"
					( Origin gFrontEnd )
				)
				( attribute "SEC" "1"
					( Origin gPackager )
				)
				( attribute "TOLERANCE" "20%"
					( Origin gFrontEnd )
				)
				( attribute "VALUE" "10UF"
					( Origin gFrontEnd )
				)
				( attribute "VER" "1"
					( Origin gFrontEnd )
				)
				( attribute "VOLTAGE" "4V"
					( Units "uVoltage" "V" 1.000000)
					( Origin gFrontEnd )
				)
				( attribute "XY" "(-5325,725)"
					( Origin gFrontEnd )
				)
				( attribute "CHIPS_PART_NAME" "CAP"
					( Origin gPackager )
				)
				( attribute "CDS_PART_NAME" "CAP_0603LF-10UF,4V,20%,X6S,E15A"
					( Origin gPackager )
				)
				( attribute "GROUP" "PWR_MLCC_CAP"
					( Origin gFrontEnd )
				)
				( objectStatus "C3G8" )
			)
			( gate "@baseboard_fab2_lib.baseboard_fab2(sch_1):page233_i136"
				( attribute "BOM_COST" "MEM_VRD_PVPP_AB"
					( Origin gFrontEnd )
				)
				( attribute "CDS_LIB" "mstr_discrete"
					( Origin gPackager )
				)
				( attribute "CDS_LOCATION" "C7U3"
					( Origin gPackager )
				)
				( attribute "CDS_SEC" "1"
					( Origin gPackager )
				)
				( attribute "LOCATION" "C7U3"
					( Origin gFrontEnd )
				)
				( attribute "MATERIAL" "X6S"
					( Origin gFrontEnd )
				)
				( attribute "PACK_TYPE" "0603LF"
					( Origin gFrontEnd )
				)
				( attribute "PART_NUMBER" "E15431-001"
					( Origin gFrontEnd )
				)
				( attribute "PHYS_PAGE" "233"
					( Origin gFrontEnd )
				)
				( attribute "ROOM" "PVPP_KLM_VR"
					( Origin gFrontEnd )
				)
				( attribute "ROT" "0"
					( Origin gFrontEnd )
				)
				( attribute "SEC" "1"
					( Origin gFrontEnd )
				)
				( attribute "SEC_TYPE" "0603LF"
					( Origin gFrontEnd )
				)
				( attribute "TOLERANCE" "20%"
					( Origin gFrontEnd )
				)
				( attribute "VALUE" "10UF"
					( Origin gFrontEnd )
				)
				( attribute "VER" "1"
					( Origin gFrontEnd )
				)
				( attribute "VOLTAGE" "4V"
					( Units "uVoltage" "V" 1.000000)
					( Origin gFrontEnd )
				)
				( attribute "XY" "(-5000,725)"
					( Origin gFrontEnd )
				)
				( attribute "CHIPS_PART_NAME" "CAP"
					( Origin gPackager )
				)
				( attribute "CDS_PART_NAME" "CAP_0603LF-10UF,4V,20%,X6S,E15A"
					( Origin gPackager )
				)
				( attribute "GROUP" "PWR_MLCC_CAP"
					( Origin gFrontEnd )
				)
				( objectStatus "C7U3" )
			)
			( gate "@baseboard_fab2_lib.baseboard_fab2(sch_1):page233_i157"
				( attribute "CDS_LIB" "mstr_discrete"
					( Origin gPackager )
				)
				( attribute "CDS_LOCATION" "R4G25"
					( Origin gPackager )
				)
				( attribute "CDS_SEC" "1"
					( Origin gPackager )
				)
				( attribute "LOCATION" "R4G25"
					( Origin gFrontEnd )
				)
				( attribute "MATERIAL" "CHIP"
					( Origin gFrontEnd )
				)
				( attribute "PACK_TYPE" "0402"
					( Origin gFrontEnd )
				)
				( attribute "PART_NUMBER" "G21497-005"
					( Origin gFrontEnd )
				)
				( attribute "PHYS_PAGE" "233"
					( Origin gFrontEnd )
				)
				( attribute "ROOM" "PVPP_KLM_VR"
					( Origin gFrontEnd )
				)
				( attribute "ROT" "0"
					( Origin gFrontEnd )
				)
				( attribute "SEC" "1"
					( Origin gPackager )
				)
				( attribute "TOLERANCE" "5%"
					( Origin gFrontEnd )
				)
				( attribute "VALUE" "0.0"
					( Origin gFrontEnd )
				)
				( attribute "VER" "1"
					( Origin gFrontEnd )
				)
				( attribute "WATTAGE" "1/16W"
					( Origin gFrontEnd )
				)
				( attribute "XY" "(-1100,550)"
					( Origin gFrontEnd )
				)
				( attribute "CHIPS_PART_NAME" "RES"
					( Origin gPackager )
				)
				( attribute "CDS_PART_NAME" "RES_0402-0.0,5%,1/16W,CHIP,G21A"
					( Origin gPackager )
				)
				( objectStatus "R4G25" )
			)
			( gate "@baseboard_fab2_lib.baseboard_fab2(sch_1):page233_i182"
				( attribute "BOM" "SYSB_CPLD"
					( Origin gFrontEnd )
				)
				( attribute "BOM_COST" "PVPP_KLM_VR"
					( Origin gFrontEnd )
				)
				( attribute "CDS_LIB" "mstr_discrete"
					( Origin gPackager )
				)
				( attribute "CDS_LOCATION" "R4G5"
					( Origin gPackager )
				)
				( attribute "CDS_SEC" "1"
					( Origin gPackager )
				)
				( attribute "LOCATION" "R4G5"
					( Origin gFrontEnd )
				)
				( attribute "MATERIAL" "CHIP"
					( Origin gFrontEnd )
				)
				( attribute "PACK_TYPE" "0402"
					( Origin gFrontEnd )
				)
				( attribute "PART_NUMBER" "G21796-016"
					( Origin gFrontEnd )
				)
				( attribute "PHYS_PAGE" "233"
					( Origin gFrontEnd )
				)
				( attribute "ROOM" "PVPP_KLM_VR"
					( Origin gFrontEnd )
				)
				( attribute "ROT" "0"
					( Origin gFrontEnd )
				)
				( attribute "SEC" "1"
					( Origin gPackager )
				)
				( attribute "TOLERANCE" "1%"
					( Origin gFrontEnd )
				)
				( attribute "VALUE" "10.0K"
					( Origin gFrontEnd )
				)
				( attribute "VER" "2"
					( Origin gFrontEnd )
				)
				( attribute "WATTAGE" "1/16W"
					( Origin gFrontEnd )
				)
				( attribute "XY" "(-7100,2200)"
					( Origin gFrontEnd )
				)
				( attribute "CHIPS_PART_NAME" "RES"
					( Origin gPackager )
				)
				( attribute "CDS_PART_NAME" "RES_0402-10.0K,1%,1/16W,CHIP,GA"
					( Origin gPackager )
				)
				( objectStatus "R4G5" )
			)
			( gate "@baseboard_fab2_lib.baseboard_fab2(sch_1):page233_i183"
				( attribute "BOM_COST" "PVPP_KLM_VR"
					( Origin gFrontEnd )
				)
				( attribute "CDS_LIB" "mstr_discrete"
					( Origin gPackager )
				)
				( attribute "CDS_LOCATION" "C4G7"
					( Origin gPackager )
				)
				( attribute "CDS_SEC" "1"
					( Origin gPackager )
				)
				( attribute "FIN" "VR_1P2"
					( Origin gFrontEnd )
				)
				( attribute "LOCATION" "C4G7"
					( Origin gFrontEnd )
				)
				( attribute "MATERIAL" "EMPTY"
					( Origin gFrontEnd )
				)
				( attribute "PACK_TYPE" "0402LF"
					( Origin gFrontEnd )
				)
				( attribute "PART_NUMBER" "A36096-046"
					( Origin gFrontEnd )
				)
				( attribute "PHYS_PAGE" "233"
					( Origin gFrontEnd )
				)
				( attribute "REUSE_ID" "1"
					( Origin gFrontEnd )
				)
				( attribute "ROOM" "PVPP_KLM_VR"
					( Origin gFrontEnd )
				)
				( attribute "ROT" "2"
					( Origin gFrontEnd )
				)
				( attribute "SEC" "1"
					( Origin gPackager )
				)
				( attribute "TOLERANCE" "10%"
					( Origin gFrontEnd )
				)
				( attribute "VALUE" "1000PF"
					( Origin gFrontEnd )
				)
				( attribute "VER" "1"
					( Origin gFrontEnd )
				)
				( attribute "VOLTAGE" "50V"
					( Units "uVoltage" "V" 1.000000)
					( Origin gFrontEnd )
				)
				( attribute "XY" "(-6500,2200)"
					( Origin gFrontEnd )
				)
				( attribute "CHIPS_PART_NAME" "CAP"
					( Origin gPackager )
				)
				( attribute "CDS_PART_NAME" "CAP_0402LF-1000PF,50V,10%,EMPTA"
					( Origin gPackager )
				)
				( objectStatus "C4G7" )
			)
			( gate "@baseboard_fab2_lib.baseboard_fab2(sch_1):page234_i228"
				( attribute "BOM_COST" "PVPP_KLM_VR"
					( Origin gFrontEnd )
				)
				( attribute "CDS_LIB" "mstr_discrete"
					( Origin gPackager )
				)
				( attribute "CDS_LOCATION" "R4B6"
					( Origin gPackager )
				)
				( attribute "CDS_SEC" "1"
					( Origin gPackager )
				)
				( attribute "CONFIG" "64.39015.6DL"
					( Origin gFrontEnd )
				)
				( attribute "LOCATION" "R4B6"
					( Origin gFrontEnd )
				)
				( attribute "MATERIAL" "CHIP"
					( Origin gFrontEnd )
				)
				( attribute "NEW_VALUE" "3.9K"
					( Origin gFrontEnd )
				)
				( attribute "PACK_TYPE" "0402"
					( Origin gFrontEnd )
				)
				( attribute "PART_NUMBER" "G21796-242"
					( Origin gFrontEnd )
				)
				( attribute "PHYS_PAGE" "234"
					( Origin gFrontEnd )
				)
				( attribute "ROOM" "PVPP_KLM_VR"
					( Origin gFrontEnd )
				)
				( attribute "ROT" "2"
					( Origin gFrontEnd )
				)
				( attribute "SEC" "1"
					( Origin gPackager )
				)
				( attribute "TOLERANCE" "1.0%"
					( Origin gFrontEnd )
				)
				( attribute "VALUE" "7.87K"
					( Origin gFrontEnd )
				)
				( attribute "VER" "2"
					( Origin gFrontEnd )
				)
				( attribute "WATTAGE" "1/16W"
					( Origin gFrontEnd )
				)
				( attribute "XY" "(-4750,1650)"
					( Origin gFrontEnd )
				)
				( attribute "CHIPS_PART_NAME" "RES"
					( Origin gPackager )
				)
				( attribute "CDS_PART_NAME" "RES_0402-7.87K,1.0%,1/16W,CHIPA"
					( Origin gPackager )
				)
				( objectStatus "R4B6" )
			)
			( gate "@baseboard_fab2_lib.baseboard_fab2(sch_1):page233_i185"
				( attribute "BOM_COST" "PVPP_KLM_VR"
					( Origin gFrontEnd )
				)
				( attribute "CDS_LIB" "mstr_discrete"
					( Origin gPackager )
				)
				( attribute "CDS_LOCATION" "R4G14"
					( Origin gPackager )
				)
				( attribute "CDS_SEC" "1"
					( Origin gPackager )
				)
				( attribute "LOCATION" "R4G14"
					( Origin gFrontEnd )
				)
				( attribute "MATERIAL" "CHIP"
					( Origin gFrontEnd )
				)
				( attribute "PACK_TYPE" "0402"
					( Origin gFrontEnd )
				)
				( attribute "PART_NUMBER" "G21796-026"
					( Origin gFrontEnd )
				)
				( attribute "PHYS_PAGE" "233"
					( Origin gFrontEnd )
				)
				( attribute "REUSE_ID" "21"
					( Origin gFrontEnd )
				)
				( attribute "ROOM" "PVPP_KLM_VR"
					( Origin gFrontEnd )
				)
				( attribute "ROT" "0"
					( Origin gFrontEnd )
				)
				( attribute "SEC" "1"
					( Origin gFrontEnd )
				)
				( attribute "SEC_TYPE" "0402"
					( Origin gFrontEnd )
				)
				( attribute "TOLERANCE" "1%"
					( Origin gFrontEnd )
				)
				( attribute "VALUE" "1.00K"
					( Origin gFrontEnd )
				)
				( attribute "VER" "2"
					( Origin gFrontEnd )
				)
				( attribute "WATTAGE" "1/16W"
					( Origin gFrontEnd )
				)
				( attribute "XY" "(-4150,1100)"
					( Origin gFrontEnd )
				)
				( attribute "CHIPS_PART_NAME" "RES"
					( Origin gPackager )
				)
				( attribute "CDS_PART_NAME" "RES_0402-1.00K,1%,1/16W,CHIP,GA"
					( Origin gPackager )
				)
				( objectStatus "R4G14" )
			)
			( gate "@baseboard_fab2_lib.baseboard_fab2(sch_1):page233_i187"
				( attribute "BOM_COST" "PVPP_KLM_VR"
					( Origin gFrontEnd )
				)
				( attribute "CDS_LIB" "mstr_discrete"
					( Origin gPackager )
				)
				( attribute "CDS_LOCATION" "C6U6"
					( Origin gPackager )
				)
				( attribute "CDS_SEC" "1"
					( Origin gPackager )
				)
				( attribute "LOCATION" "C6U6"
					( Origin gFrontEnd )
				)
				( attribute "MATERIAL" "X6S"
					( Origin gFrontEnd )
				)
				( attribute "PACK_TYPE" "0603"
					( Origin gFrontEnd )
				)
				( attribute "PART_NUMBER" "E15431-003"
					( Origin gFrontEnd )
				)
				( attribute "PHYS_PAGE" "233"
					( Origin gFrontEnd )
				)
				( attribute "REUSE_ID" "26"
					( Origin gFrontEnd )
				)
				( attribute "ROOM" "PVPP_KLM_VR"
					( Origin gFrontEnd )
				)
				( attribute "ROT" "0"
					( Origin gFrontEnd )
				)
				( attribute "SEC" "1"
					( Origin gFrontEnd )
				)
				( attribute "SEC_TYPE" "0603"
					( Origin gFrontEnd )
				)
				( attribute "TOLERANCE" "10%"
					( Origin gFrontEnd )
				)
				( attribute "VALUE" "4.7UF"
					( Origin gFrontEnd )
				)
				( attribute "VER" "1"
					( Origin gFrontEnd )
				)
				( attribute "VOLTAGE" "6.3V"
					( Units "uVoltage" "V" 1.000000)
					( Origin gFrontEnd )
				)
				( attribute "XY" "(-5800,2350)"
					( Origin gFrontEnd )
				)
				( attribute "CHIPS_PART_NAME" "CAP"
					( Origin gPackager )
				)
				( attribute "CDS_PART_NAME" "CAP_0603-4.7UF,6.3V,10%,X6S,E1A"
					( Origin gPackager )
				)
				( attribute "CONFIG" "078.47521.08BD"
					( Origin gFrontEnd )
				)
				( objectStatus "C6U6" )
			)
			( gate "@baseboard_fab2_lib.baseboard_fab2(sch_1):page232_i309"
				( attribute "CDS_LIB" "w_hdl"
					( Origin gPackager )
				)
				( attribute "CDS_LMAN_SYM_OUTLINE" "-50,25,50,-25"
					( Origin gPackager )
				)
				( attribute "LOCATION" "C7B8"
					( Origin gFrontEnd )
				)
				( attribute "PACK_TYPE" "SMD-BCG5"
					( Origin gFrontEnd )
				)
				( attribute "PART_NUMBER" "078.22611.0811"
					( Origin gFrontEnd )
				)
				( attribute "PHYS_PAGE" "232"
					( Origin gFrontEnd )
				)
				( attribute "ROT" "0"
					( Origin gFrontEnd )
				)
				( attribute "SEC" "1"
					( Origin gFrontEnd )
				)
				( attribute "SEC_TYPE" "SMD-BCG5"
					( Origin gFrontEnd )
				)
				( attribute "VALUE" "SC22U16V5MX-4-GP"
					( Origin gFrontEnd )
				)
				( attribute "VER" "1"
					( Origin gFrontEnd )
				)
				( attribute "XY" "(-7600,4100)"
					( Origin gFrontEnd )
				)
				( attribute "CHIPS_PART_NAME" "SC22U16V5MX-4-GP"
					( Origin gPackager )
				)
				( attribute "CDS_PART_NAME" "SC22U16V5MX-4-GP_SMD-BCG5-SC22A"
					( Origin gPackager )
				)
				( attribute "CDS_LOCATION" "C7B8"
					( Origin gPackager )
				)
				( attribute "CDS_SEC" "1"
					( Origin gPackager )
				)
				( attribute "ATTRIBUTE" "22UF"
					( Origin gFrontEnd )
				)
				( attribute "PACK_SIZE" "0805"
					( Origin gFrontEnd )
				)
				( attribute "RATED" "16V"
					( Origin gFrontEnd )
				)
				( attribute "TOLERANCE" "20%"
					( Origin gFrontEnd )
				)
				( attribute "TYPE" "X6S"
					( Origin gFrontEnd )
				)
				( objectStatus "C7B8" )
			)
			( gate "@baseboard_fab2_lib.baseboard_fab2(sch_1):page233_i194"
				( attribute "BOM_COST" "PVPP_KLM_VR"
					( Origin gFrontEnd )
				)
				( attribute "CDS_LIB" "mstr_discrete"
					( Origin gPackager )
				)
				( attribute "CDS_LOCATION" "C4G8"
					( Origin gPackager )
				)
				( attribute "CDS_SEC" "1"
					( Origin gPackager )
				)
				( attribute "LOCATION" "C4G8"
					( Origin gFrontEnd )
				)
				( attribute "MATERIAL" "X7R"
					( Origin gFrontEnd )
				)
				( attribute "PACK_TYPE" "0402"
					( Origin gFrontEnd )
				)
				( attribute "PART_NUMBER" "A36096-129"
					( Origin gFrontEnd )
				)
				( attribute "PHYS_PAGE" "233"
					( Origin gFrontEnd )
				)
				( attribute "REUSE_ID" "26"
					( Origin gFrontEnd )
				)
				( attribute "ROOM" "PVPP_KLM_VR"
					( Origin gFrontEnd )
				)
				( attribute "ROT" "0"
					( Origin gFrontEnd )
				)
				( attribute "SEC" "1"
					( Origin gFrontEnd )
				)
				( attribute "SEC_TYPE" "0402"
					( Origin gFrontEnd )
				)
				( attribute "TOLERANCE" "10%"
					( Origin gFrontEnd )
				)
				( attribute "VALUE" "0.027UF"
					( Origin gFrontEnd )
				)
				( attribute "VER" "1"
					( Origin gFrontEnd )
				)
				( attribute "VOLTAGE" "16V"
					( Units "uVoltage" "V" 1.000000)
					( Origin gFrontEnd )
				)
				( attribute "XY" "(-5000,2025)"
					( Origin gFrontEnd )
				)
				( attribute "CHIPS_PART_NAME" "CAP"
					( Origin gPackager )
				)
				( attribute "CDS_PART_NAME" "CAP_0402-0.027UF,16V,10%,X7R,AA"
					( Origin gPackager )
				)
				( objectStatus "C4G8" )
			)
			( gate "@baseboard_fab2_lib.baseboard_fab2(sch_1):page233_i196"
				( attribute "BOM_COST" "PVPP_KLM_VR"
					( Origin gFrontEnd )
				)
				( attribute "CDS_LIB" "mstr_discrete"
					( Origin gPackager )
				)
				( attribute "CDS_LOCATION" "C4G4"
					( Origin gPackager )
				)
				( attribute "CDS_SEC" "1"
					( Origin gPackager )
				)
				( attribute "FIN" "VR_1P2"
					( Origin gFrontEnd )
				)
				( attribute "LOCATION" "C4G4"
					( Origin gFrontEnd )
				)
				( attribute "MATERIAL" "X6S"
					( Origin gFrontEnd )
				)
				( attribute "PACK_TYPE" "0402"
					( Origin gFrontEnd )
				)
				( attribute "PART_NUMBER" "D97712-011"
					( Origin gFrontEnd )
				)
				( attribute "PHYS_PAGE" "233"
					( Origin gFrontEnd )
				)
				( attribute "REUSE_ID" "1"
					( Origin gFrontEnd )
				)
				( attribute "ROOM" "PVPP_KLM_VR"
					( Origin gFrontEnd )
				)
				( attribute "ROT" "0"
					( Origin gFrontEnd )
				)
				( attribute "SEC" "1"
					( Origin gPackager )
				)
				( attribute "TOLERANCE" "10%"
					( Origin gFrontEnd )
				)
				( attribute "VALUE" "1.0UF"
					( Origin gFrontEnd )
				)
				( attribute "VER" "1"
					( Origin gFrontEnd )
				)
				( attribute "VOLTAGE" "16V"
					( Units "uVoltage" "V" 1.000000)
					( Origin gFrontEnd )
				)
				( attribute "XY" "(-5000,4000)"
					( Origin gFrontEnd )
				)
				( attribute "CHIPS_PART_NAME" "CAP"
					( Origin gPackager )
				)
				( attribute "CDS_PART_NAME" "CAP_0402-1.0UF,16V,10%,X6S,D97A"
					( Origin gPackager )
				)
				( objectStatus "C4G4" )
			)
			( gate "@baseboard_fab2_lib.baseboard_fab2(sch_1):page233_i198"
				( attribute "CDS_LIB" "mstr_discrete"
					( Origin gPackager )
				)
				( attribute "CDS_LOCATION" "FB4G1"
					( Origin gPackager )
				)
				( attribute "CDS_SEC" "1"
					( Origin gPackager )
				)
				( attribute "LOCATION" "FB4G1"
					( Origin gFrontEnd )
				)
				( attribute "MATERIAL" "FB"
					( Origin gFrontEnd )
				)
				( attribute "PACK_TYPE" "SM"
					( Origin gFrontEnd )
				)
				( attribute "PART_NUMBER" "656554-051"
					( Origin gFrontEnd )
				)
				( attribute "PHYS_PAGE" "233"
					( Origin gFrontEnd )
				)
				( attribute "ROOM" "PVPP_KLM_VR"
					( Origin gFrontEnd )
				)
				( attribute "ROT" "0"
					( Origin gFrontEnd )
				)
				( attribute "SEC" "1"
					( Origin gFrontEnd )
				)
				( attribute "SEC_TYPE" "SM"
					( Origin gFrontEnd )
				)
				( attribute "TOLERANCE" "1%"
					( Origin gFrontEnd )
				)
				( attribute "VALUE" "22"
					( Origin gFrontEnd )
				)
				( attribute "VER" "1"
					( Origin gFrontEnd )
				)
				( attribute "XY" "(-7600,4150)"
					( Origin gFrontEnd )
				)
				( attribute "CHIPS_PART_NAME" "FERRITE"
					( Origin gPackager )
				)
				( attribute "CDS_PART_NAME" "FERRITE_SM-22,FB,656554-051"
					( Origin gPackager )
				)
				( objectStatus "FB4G1" )
			)
			( gate "@baseboard_fab2_lib.baseboard_fab2(sch_1):page233_i201"
				( attribute "BOM_COST" "PVPP_KLM_VR"
					( Origin gFrontEnd )
				)
				( attribute "CDS_LIB" "mstr_discrete"
					( Origin gPackager )
				)
				( attribute "CDS_LOCATION" "C4G9"
					( Origin gPackager )
				)
				( attribute "CDS_SEC" "1"
					( Origin gPackager )
				)
				( attribute "LOCATION" "C4G9"
					( Origin gFrontEnd )
				)
				( attribute "MATERIAL" "X7R"
					( Origin gFrontEnd )
				)
				( attribute "PACK_TYPE" "0402LF"
					( Origin gFrontEnd )
				)
				( attribute "PART_NUMBER" "A36096-046"
					( Origin gFrontEnd )
				)
				( attribute "PHYS_PAGE" "233"
					( Origin gFrontEnd )
				)
				( attribute "REUSE_ID" "17"
					( Origin gFrontEnd )
				)
				( attribute "ROOM" "PVPP_KLM_VR"
					( Origin gFrontEnd )
				)
				( attribute "ROT" "0"
					( Origin gFrontEnd )
				)
				( attribute "SEC" "1"
					( Origin gPackager )
				)
				( attribute "TOLERANCE" "10%"
					( Origin gFrontEnd )
				)
				( attribute "VALUE" "1000PF"
					( Origin gFrontEnd )
				)
				( attribute "VER" "1"
					( Origin gFrontEnd )
				)
				( attribute "VOLTAGE" "50V"
					( Units "uVoltage" "V" 1.000000)
					( Origin gFrontEnd )
				)
				( attribute "XY" "(-3800,575)"
					( Origin gFrontEnd )
				)
				( attribute "CHIPS_PART_NAME" "CAP"
					( Origin gPackager )
				)
				( attribute "CDS_PART_NAME" "CAP_0402LF-1000PF,50V,10%,X7R,A"
					( Origin gPackager )
				)
				( objectStatus "C4G9" )
			)
			( gate "@baseboard_fab2_lib.baseboard_fab2(sch_1):page233_i208"
				( attribute "BOM_COST" "PVPP_KLM_VR"
					( Origin gFrontEnd )
				)
				( attribute "CDS_LIB" "mstr_discrete"
					( Origin gPackager )
				)
				( attribute "CDS_LOCATION" "R4F6"
					( Origin gPackager )
				)
				( attribute "CDS_SEC" "1"
					( Origin gPackager )
				)
				( attribute "LOCATION" "R4F6"
					( Origin gFrontEnd )
				)
				( attribute "MATERIAL" "EMPTY"
					( Origin gFrontEnd )
				)
				( attribute "PACK_TYPE" "0402"
					( Origin gFrontEnd )
				)
				( attribute "PART_NUMBER" "G21497-016"
					( Origin gFrontEnd )
				)
				( attribute "PHYS_PAGE" "233"
					( Origin gFrontEnd )
				)
				( attribute "REUSE_ID" "29"
					( Origin gFrontEnd )
				)
				( attribute "ROOM" "PVPP_KLM_VR"
					( Origin gFrontEnd )
				)
				( attribute "ROT" "0"
					( Origin gFrontEnd )
				)
				( attribute "SEC" "1"
					( Origin gPackager )
				)
				( attribute "TOLERANCE" "5%"
					( Origin gFrontEnd )
				)
				( attribute "VALUE" "2.2"
					( Origin gFrontEnd )
				)
				( attribute "VER" "2"
					( Origin gFrontEnd )
				)
				( attribute "WATTAGE" "1/16W"
					( Origin gFrontEnd )
				)
				( attribute "XY" "(-2450,3100)"
					( Origin gFrontEnd )
				)
				( attribute "CHIPS_PART_NAME" "RES"
					( Origin gPackager )
				)
				( attribute "CDS_PART_NAME" "RES_0402-2.2,5%,1/16W,EMPTY,G2A"
					( Origin gPackager )
				)
				( objectStatus "R4F6" )
			)
			( gate "@baseboard_fab2_lib.baseboard_fab2(sch_1):page233_i209"
				( attribute "BOM_COST" "PVPP_KLM_VR"
					( Origin gFrontEnd )
				)
				( attribute "CDS_LIB" "mstr_discrete"
					( Origin gPackager )
				)
				( attribute "CDS_LOCATION" "C4F12"
					( Origin gPackager )
				)
				( attribute "CDS_SEC" "1"
					( Origin gPackager )
				)
				( attribute "LOCATION" "C4F12"
					( Origin gFrontEnd )
				)
				( attribute "MATERIAL" "EMPTY"
					( Origin gFrontEnd )
				)
				( attribute "PACK_TYPE" "0402LF"
					( Origin gFrontEnd )
				)
				( attribute "PART_NUMBER" "A36096-091"
					( Origin gFrontEnd )
				)
				( attribute "PHYS_PAGE" "233"
					( Origin gFrontEnd )
				)
				( attribute "REUSE_ID" "26"
					( Origin gFrontEnd )
				)
				( attribute "ROOM" "PVPP_KLM_VR"
					( Origin gFrontEnd )
				)
				( attribute "ROT" "0"
					( Origin gFrontEnd )
				)
				( attribute "SEC" "1"
					( Origin gPackager )
				)
				( attribute "TOLERANCE" "10%"
					( Origin gFrontEnd )
				)
				( attribute "VALUE" "3300PF"
					( Origin gFrontEnd )
				)
				( attribute "VER" "1"
					( Origin gFrontEnd )
				)
				( attribute "VOLTAGE" "50V"
					( Units "uVoltage" "V" 1.000000)
					( Origin gFrontEnd )
				)
				( attribute "XY" "(-2450,3475)"
					( Origin gFrontEnd )
				)
				( attribute "CHIPS_PART_NAME" "CAP"
					( Origin gPackager )
				)
				( attribute "CDS_PART_NAME" "CAP_0402LF-3300PF,50V,10%,EMPTA"
					( Origin gPackager )
				)
				( objectStatus "C4F12" )
			)
			( gate "@baseboard_fab2_lib.baseboard_fab2(sch_1):page233_i211"
				( attribute "BOM_COST" "PVPP_KLM_VR"
					( Origin gFrontEnd )
				)
				( attribute "CDS_LIB" "mstr_discrete"
					( Origin gPackager )
				)
				( attribute "CDS_LOCATION" "R4G6"
					( Origin gPackager )
				)
				( attribute "CDS_SEC" "1"
					( Origin gPackager )
				)
				( attribute "LOCATION" "R4G6"
					( Origin gFrontEnd )
				)
				( attribute "MATERIAL" "CHIP"
					( Origin gFrontEnd )
				)
				( attribute "PACK_TYPE" "0603"
					( Origin gFrontEnd )
				)
				( attribute "PART_NUMBER" "G22026-003"
					( Origin gFrontEnd )
				)
				( attribute "PHYS_PAGE" "233"
					( Origin gFrontEnd )
				)
				( attribute "REUSE_ID" "34"
					( Origin gFrontEnd )
				)
				( attribute "ROOM" "PVPP_KLM_VR"
					( Origin gFrontEnd )
				)
				( attribute "ROT" "0"
					( Origin gFrontEnd )
				)
				( attribute "SEC" "1"
					( Origin gPackager )
				)
				( attribute "TOLERANCE" "1%"
					( Origin gFrontEnd )
				)
				( attribute "VALUE" "120.0"
					( Origin gFrontEnd )
				)
				( attribute "VER" "2"
					( Origin gFrontEnd )
				)
				( attribute "WATTAGE" "1/10W"
					( Origin gFrontEnd )
				)
				( attribute "XY" "(-2000,3525)"
					( Origin gFrontEnd )
				)
				( attribute "CHIPS_PART_NAME" "RES"
					( Origin gPackager )
				)
				( attribute "CDS_PART_NAME" "RES_0603-120.0,1%,1/10W,CHIP,GA"
					( Origin gPackager )
				)
				( objectStatus "R4G6" )
			)
			( gate "@baseboard_fab2_lib.baseboard_fab2(sch_1):page233_i217"
				( attribute "BOM_COST" "PVPP_KLM_VR"
					( Origin gFrontEnd )
				)
				( attribute "CDS_LIB" "mstr_discrete"
					( Origin gPackager )
				)
				( attribute "CDS_LOCATION" "C4F7"
					( Origin gPackager )
				)
				( attribute "CDS_SEC" "1"
					( Origin gPackager )
				)
				( attribute "LOCATION" "C4F7"
					( Origin gFrontEnd )
				)
				( attribute "MATERIAL" "POSCAP"
					( Origin gFrontEnd )
				)
				( attribute "PACK_TYPE" "7343LF"
					( Origin gFrontEnd )
				)
				( attribute "PART_NUMBER" "724613-042"
					( Origin gFrontEnd )
				)
				( attribute "PHYS_PAGE" "233"
					( Origin gFrontEnd )
				)
				( attribute "REUSE_ID" "28"
					( Origin gFrontEnd )
				)
				( attribute "ROOM" "PVPP_KLM_VR"
					( Origin gFrontEnd )
				)
				( attribute "ROT" "0"
					( Origin gFrontEnd )
				)
				( attribute "SEC" "1"
					( Origin gPackager )
				)
				( attribute "TOLERANCE" "20%"
					( Origin gFrontEnd )
				)
				( attribute "VALUE" "330UF"
					( Origin gFrontEnd )
				)
				( attribute "VER" "1"
					( Origin gFrontEnd )
				)
				( attribute "VOLTAGE" "6.3V"
					( Units "uVoltage" "V" 1.000000)
					( Origin gFrontEnd )
				)
				( attribute "XY" "(-1700,3500)"
					( Origin gFrontEnd )
				)
				( attribute "CHIPS_PART_NAME" "CAPP"
					( Origin gPackager )
				)
				( attribute "CDS_PART_NAME" "CAPP_7343LF-330UF,6.3V,20%,POSA"
					( Origin gPackager )
				)
				( attribute "GROUP" "PWR_BULK_CAP"
					( Origin gFrontEnd )
				)
				( objectStatus "C4F7" )
			)
			( gate "@baseboard_fab2_lib.baseboard_fab2(sch_1):page233_i221"
				( attribute "BOM_COST" "PVPP_KLM_VR"
					( Origin gFrontEnd )
				)
				( attribute "CDS_LIB" "mstr_discrete"
					( Origin gPackager )
				)
				( attribute "CDS_LOCATION" "C6U3"
					( Origin gPackager )
				)
				( attribute "CDS_SEC" "1"
					( Origin gPackager )
				)
				( attribute "LOCATION" "C6U3"
					( Origin gFrontEnd )
				)
				( attribute "MATERIAL" "X6S"
					( Origin gFrontEnd )
				)
				( attribute "PACK_TYPE" "0805"
					( Origin gFrontEnd )
				)
				( attribute "PART_NUMBER" "C95333-006"
					( Origin gFrontEnd )
				)
				( attribute "PHYS_PAGE" "233"
					( Origin gFrontEnd )
				)
				( attribute "REUSE_ID" "33"
					( Origin gFrontEnd )
				)
				( attribute "ROOM" "PVPP_KLM_VR"
					( Origin gFrontEnd )
				)
				( attribute "ROT" "0"
					( Origin gFrontEnd )
				)
				( attribute "SEC" "1"
					( Origin gPackager )
				)
				( attribute "TOLERANCE" "20%"
					( Origin gFrontEnd )
				)
				( attribute "VALUE" "47UF"
					( Origin gFrontEnd )
				)
				( attribute "VER" "1"
					( Origin gFrontEnd )
				)
				( attribute "VOLTAGE" "4V"
					( Units "uVoltage" "V" 1.000000)
					( Origin gFrontEnd )
				)
				( attribute "XY" "(-1075,3525)"
					( Origin gFrontEnd )
				)
				( attribute "CHIPS_PART_NAME" "CAP"
					( Origin gPackager )
				)
				( attribute "CDS_PART_NAME" "CAP_0805-47UF,4V,20%,X6S,C9533A"
					( Origin gPackager )
				)
				( attribute "GROUP" "PWR_MLCC_CAP"
					( Origin gFrontEnd )
				)
				( objectStatus "C6U3" )
			)
			( gate "@baseboard_fab2_lib.baseboard_fab2(sch_1):page233_i223"
				( attribute "BOM_COST" "PVPP_KLM_VR"
					( Origin gFrontEnd )
				)
				( attribute "CDS_LIB" "mstr_discrete"
					( Origin gPackager )
				)
				( attribute "CDS_LOCATION" "C6U2"
					( Origin gPackager )
				)
				( attribute "CDS_SEC" "1"
					( Origin gPackager )
				)
				( attribute "LOCATION" "C6U2"
					( Origin gFrontEnd )
				)
				( attribute "MATERIAL" "X6S"
					( Origin gFrontEnd )
				)
				( attribute "PACK_TYPE" "0805"
					( Origin gFrontEnd )
				)
				( attribute "PART_NUMBER" "C95333-006"
					( Origin gFrontEnd )
				)
				( attribute "PHYS_PAGE" "233"
					( Origin gFrontEnd )
				)
				( attribute "REUSE_ID" "33"
					( Origin gFrontEnd )
				)
				( attribute "ROOM" "PVPP_KLM_VR"
					( Origin gFrontEnd )
				)
				( attribute "ROT" "0"
					( Origin gFrontEnd )
				)
				( attribute "SEC" "1"
					( Origin gPackager )
				)
				( attribute "TOLERANCE" "20%"
					( Origin gFrontEnd )
				)
				( attribute "VALUE" "47UF"
					( Origin gFrontEnd )
				)
				( attribute "VER" "1"
					( Origin gFrontEnd )
				)
				( attribute "VOLTAGE" "4V"
					( Units "uVoltage" "V" 1.000000)
					( Origin gFrontEnd )
				)
				( attribute "XY" "(-775,3525)"
					( Origin gFrontEnd )
				)
				( attribute "CHIPS_PART_NAME" "CAP"
					( Origin gPackager )
				)
				( attribute "CDS_PART_NAME" "CAP_0805-47UF,4V,20%,X6S,C9533A"
					( Origin gPackager )
				)
				( attribute "GROUP" "PWR_MLCC_CAP"
					( Origin gFrontEnd )
				)
				( objectStatus "C6U2" )
			)
			( gate "@baseboard_fab2_lib.baseboard_fab2(sch_1):page233_i224"
				( attribute "BOM_COST" "PVPP_KLM_VR"
					( Origin gFrontEnd )
				)
				( attribute "CDS_LIB" "mstr_discrete"
					( Origin gPackager )
				)
				( attribute "CDS_LOCATION" "C4G26"
					( Origin gPackager )
				)
				( attribute "CDS_SEC" "1"
					( Origin gPackager )
				)
				( attribute "LOCATION" "C4G26"
					( Origin gFrontEnd )
				)
				( attribute "MATERIAL" "X7R"
					( Origin gFrontEnd )
				)
				( attribute "PACK_TYPE" "0603LF"
					( Origin gFrontEnd )
				)
				( attribute "PART_NUMBER" "602433-020"
					( Origin gFrontEnd )
				)
				( attribute "PHYS_PAGE" "233"
					( Origin gFrontEnd )
				)
				( attribute "REUSE_ID" "27"
					( Origin gFrontEnd )
				)
				( attribute "ROOM" "PVPP_KLM_VR"
					( Origin gFrontEnd )
				)
				( attribute "ROT" "2"
					( Origin gFrontEnd )
				)
				( attribute "SEC" "1"
					( Origin gPackager )
				)
				( attribute "SPOF" "TRUE"
					( Origin gFrontEnd )
				)
				( attribute "TOLERANCE" "10%"
					( Origin gFrontEnd )
				)
				( attribute "VALUE" "0.1UF"
					( Origin gFrontEnd )
				)
				( attribute "VER" "2"
					( Origin gFrontEnd )
				)
				( attribute "VOLTAGE" "25V"
					( Units "uVoltage" "V" 1.000000)
					( Origin gFrontEnd )
				)
				( attribute "XY" "(-3300,4050)"
					( Origin gFrontEnd )
				)
				( attribute "CHIPS_PART_NAME" "CAP"
					( Origin gPackager )
				)
				( attribute "CDS_PART_NAME" "CAP_0603LF-0.1UF,25V,10%,X7R,6A"
					( Origin gPackager )
				)
				( objectStatus "C4G26" )
			)
			( gate "@baseboard_fab2_lib.baseboard_fab2(sch_1):page233_i225"
				( attribute "CDS_LIB" "mstr_vreg"
					( Origin gPackager )
				)
				( attribute "CDS_LMAN_SYM_OUTLINE" "-450,850,450,-900"
					( Origin gPackager )
				)
				( attribute "CDS_LOCATION" "EU4G1"
					( Origin gPackager )
				)
				( attribute "CDS_SEC" "1"
					( Origin gPackager )
				)
				( attribute "LOCATION" "EU4G1"
					( Origin gFrontEnd )
				)
				( attribute "MATERIAL" "IC"
					( Origin gFrontEnd )
				)
				( attribute "PACK_TYPE" "SM"
					( Origin gFrontEnd )
				)
				( attribute "PART_NUMBER" "H86355-001"
					( Origin gFrontEnd )
				)
				( attribute "PHYS_PAGE" "233"
					( Origin gFrontEnd )
				)
				( attribute "ROT" "0"
					( Origin gFrontEnd )
				)
				( attribute "SEC" "1"
					( Origin gFrontEnd )
				)
				( attribute "SEC_TYPE" "SM"
					( Origin gFrontEnd )
				)
				( attribute "VER" "1"
					( Origin gFrontEnd )
				)
				( attribute "XY" "(-3725,2725)"
					( Origin gFrontEnd )
				)
				( attribute "CHIPS_PART_NAME" "NCP3232L"
					( Origin gPackager )
				)
				( attribute "CDS_PART_NAME" "NCP3232L_SM-IC,H86355-001"
					( Origin gPackager )
				)
				( objectStatus "EU4G1" )
			)
			( gate "@baseboard_fab2_lib.baseboard_fab2(sch_1):page233_i242"
				( attribute "CDS_LIB" "dev_discrete"
					( Origin gPackager )
				)
				( attribute "CDS_LOCATION" "C6U5"
					( Origin gPackager )
				)
				( attribute "CDS_SEC" "1"
					( Origin gPackager )
				)
				( attribute "LOCATION" "C6U5"
					( Origin gFrontEnd )
				)
				( attribute "MATERIAL" "X7R"
					( Origin gFrontEnd )
				)
				( attribute "PACK_TYPE" "0402V"
					( Origin gFrontEnd )
				)
				( attribute "PART_NUMBER" "A36096-030"
					( Origin gFrontEnd )
				)
				( attribute "PHYS_PAGE" "233"
					( Origin gFrontEnd )
				)
				( attribute "ROT" "0"
					( Origin gFrontEnd )
				)
				( attribute "SEC" "1"
					( Origin gFrontEnd )
				)
				( attribute "SEC_TYPE" "0402V"
					( Origin gFrontEnd )
				)
				( attribute "TOLERANCE" "10%"
					( Origin gFrontEnd )
				)
				( attribute "VALUE" "0.1UF"
					( Origin gFrontEnd )
				)
				( attribute "VER" "1"
					( Origin gFrontEnd )
				)
				( attribute "VOLTAGE" "16V"
					( Units "uVoltage" "V" 1.000000)
					( Origin gFrontEnd )
				)
				( attribute "XY" "(-5050,3325)"
					( Origin gFrontEnd )
				)
				( attribute "CHIPS_PART_NAME" "CAP_A"
					( Origin gPackager )
				)
				( attribute "CDS_PART_NAME" "CAP_A_0402V-0.1UF,16V,10%,X7R,A"
					( Origin gPackager )
				)
				( objectStatus "C6U5" )
			)
			( gate "@baseboard_fab2_lib.baseboard_fab2(sch_1):page233_i247"
				( attribute "CDS_LIB" "mstr_discrete"
					( Origin gPackager )
				)
				( attribute "CDS_LOCATION" "R4G12"
					( Origin gPackager )
				)
				( attribute "CDS_SEC" "1"
					( Origin gPackager )
				)
				( attribute "LOCATION" "R4G12"
					( Origin gFrontEnd )
				)
				( attribute "MATERIAL" "CHIP"
					( Origin gFrontEnd )
				)
				( attribute "PACK_TYPE" "0402"
					( Origin gFrontEnd )
				)
				( attribute "PART_NUMBER" "G21796-250"
					( Origin gFrontEnd )
				)
				( attribute "PHYS_PAGE" "233"
					( Origin gFrontEnd )
				)
				( attribute "ROOM" "PVPP_GHJ_VR"
					( Origin gFrontEnd )
				)
				( attribute "ROT" "0"
					( Origin gFrontEnd )
				)
				( attribute "SEC" "1"
					( Origin gFrontEnd )
				)
				( attribute "SEC_TYPE" "0402"
					( Origin gFrontEnd )
				)
				( attribute "TOLERANCE" "1.0%"
					( Origin gFrontEnd )
				)
				( attribute "VALUE" "22.1"
					( Origin gFrontEnd )
				)
				( attribute "VER" "1"
					( Origin gFrontEnd )
				)
				( attribute "WATTAGE" "1/16W"
					( Origin gFrontEnd )
				)
				( attribute "XY" "(-3375,825)"
					( Origin gFrontEnd )
				)
				( attribute "CHIPS_PART_NAME" "RES"
					( Origin gPackager )
				)
				( attribute "CDS_PART_NAME" "RES_0402-22.1,1.0%,1/16W,CHIP,A"
					( Origin gPackager )
				)
				( objectStatus "R4G12" )
			)
			( gate "@baseboard_fab2_lib.baseboard_fab2(sch_1):page233_i248"
				( attribute "CDS_LIB" "mstr_discrete"
					( Origin gPackager )
				)
				( attribute "CDS_LOCATION" "C6U4"
					( Origin gPackager )
				)
				( attribute "CDS_SEC" "1"
					( Origin gPackager )
				)
				( attribute "LOCATION" "C6U4"
					( Origin gFrontEnd )
				)
				( attribute "MATERIAL" "X6S"
					( Origin gFrontEnd )
				)
				( attribute "PACK_TYPE" "0805"
					( Origin gFrontEnd )
				)
				( attribute "PART_NUMBER" "C95333-007"
					( Origin gFrontEnd )
				)
				( attribute "PHYS_PAGE" "233"
					( Origin gFrontEnd )
				)
				( attribute "ROT" "0"
					( Origin gFrontEnd )
				)
				( attribute "SEC" "1"
					( Origin gFrontEnd )
				)
				( attribute "SEC_TYPE" "0805"
					( Origin gFrontEnd )
				)
				( attribute "TOLERANCE" "10%"
					( Origin gFrontEnd )
				)
				( attribute "VALUE" "10UF"
					( Origin gFrontEnd )
				)
				( attribute "VER" "1"
					( Origin gFrontEnd )
				)
				( attribute "VOLTAGE" "16V"
					( Units "uVoltage" "V" 1.000000)
					( Origin gFrontEnd )
				)
				( attribute "XY" "(-6600,4000)"
					( Origin gFrontEnd )
				)
				( attribute "CHIPS_PART_NAME" "CAP"
					( Origin gPackager )
				)
				( attribute "CDS_PART_NAME" "CAP_0805-10UF,16V,10%,X6S,C953A"
					( Origin gPackager )
				)
				( objectStatus "C6U4" )
			)
			( gate "@baseboard_fab2_lib.baseboard_fab2(sch_1):page233_i253"
				( attribute "CDS_LIB" "mstr_discrete"
					( Origin gPackager )
				)
				( attribute "CDS_LOCATION" "C4G2"
					( Origin gPackager )
				)
				( attribute "CDS_SEC" "1"
					( Origin gPackager )
				)
				( attribute "LOCATION" "C4G2"
					( Origin gFrontEnd )
				)
				( attribute "MATERIAL" "X6S"
					( Origin gFrontEnd )
				)
				( attribute "PACK_TYPE" "0805"
					( Origin gFrontEnd )
				)
				( attribute "PART_NUMBER" "C95333-007"
					( Origin gFrontEnd )
				)
				( attribute "PHYS_PAGE" "233"
					( Origin gFrontEnd )
				)
				( attribute "ROT" "0"
					( Origin gFrontEnd )
				)
				( attribute "SEC" "1"
					( Origin gFrontEnd )
				)
				( attribute "SEC_TYPE" "0805"
					( Origin gFrontEnd )
				)
				( attribute "TOLERANCE" "10%"
					( Origin gFrontEnd )
				)
				( attribute "VALUE" "10UF"
					( Origin gFrontEnd )
				)
				( attribute "VER" "1"
					( Origin gFrontEnd )
				)
				( attribute "VOLTAGE" "16V"
					( Units "uVoltage" "V" 1.000000)
					( Origin gFrontEnd )
				)
				( attribute "XY" "(-6250,4000)"
					( Origin gFrontEnd )
				)
				( attribute "CHIPS_PART_NAME" "CAP"
					( Origin gPackager )
				)
				( attribute "CDS_PART_NAME" "CAP_0805-10UF,16V,10%,X6S,C953A"
					( Origin gPackager )
				)
				( objectStatus "C4G2" )
			)
			( gate "@baseboard_fab2_lib.baseboard_fab2(sch_1):page233_i254"
				( attribute "CDS_LIB" "mstr_discrete"
					( Origin gPackager )
				)
				( attribute "CDS_LOCATION" "C6U7"
					( Origin gPackager )
				)
				( attribute "CDS_SEC" "1"
					( Origin gPackager )
				)
				( attribute "LOCATION" "C6U7"
					( Origin gFrontEnd )
				)
				( attribute "MATERIAL" "X6S"
					( Origin gFrontEnd )
				)
				( attribute "PACK_TYPE" "0805"
					( Origin gFrontEnd )
				)
				( attribute "PART_NUMBER" "C95333-007"
					( Origin gFrontEnd )
				)
				( attribute "PHYS_PAGE" "233"
					( Origin gFrontEnd )
				)
				( attribute "ROT" "0"
					( Origin gFrontEnd )
				)
				( attribute "SEC" "1"
					( Origin gFrontEnd )
				)
				( attribute "SEC_TYPE" "0805"
					( Origin gFrontEnd )
				)
				( attribute "TOLERANCE" "10%"
					( Origin gFrontEnd )
				)
				( attribute "VALUE" "10UF"
					( Origin gFrontEnd )
				)
				( attribute "VER" "1"
					( Origin gFrontEnd )
				)
				( attribute "VOLTAGE" "16V"
					( Units "uVoltage" "V" 1.000000)
					( Origin gFrontEnd )
				)
				( attribute "XY" "(-5875,4000)"
					( Origin gFrontEnd )
				)
				( attribute "CHIPS_PART_NAME" "CAP"
					( Origin gPackager )
				)
				( attribute "CDS_PART_NAME" "CAP_0805-10UF,16V,10%,X6S,C953A"
					( Origin gPackager )
				)
				( objectStatus "C6U7" )
			)
			( gate "@baseboard_fab2_lib.baseboard_fab2(sch_1):page233_i255"
				( attribute "CDS_LIB" "mstr_discrete"
					( Origin gPackager )
				)
				( attribute "CDS_LOCATION" "C6U8"
					( Origin gPackager )
				)
				( attribute "CDS_SEC" "1"
					( Origin gPackager )
				)
				( attribute "LOCATION" "C6U8"
					( Origin gFrontEnd )
				)
				( attribute "MATERIAL" "X6S"
					( Origin gFrontEnd )
				)
				( attribute "PACK_TYPE" "0805"
					( Origin gFrontEnd )
				)
				( attribute "PART_NUMBER" "C95333-007"
					( Origin gFrontEnd )
				)
				( attribute "PHYS_PAGE" "233"
					( Origin gFrontEnd )
				)
				( attribute "ROT" "0"
					( Origin gFrontEnd )
				)
				( attribute "SEC" "1"
					( Origin gFrontEnd )
				)
				( attribute "SEC_TYPE" "0805"
					( Origin gFrontEnd )
				)
				( attribute "TOLERANCE" "10%"
					( Origin gFrontEnd )
				)
				( attribute "VALUE" "10UF"
					( Origin gFrontEnd )
				)
				( attribute "VER" "1"
					( Origin gFrontEnd )
				)
				( attribute "VOLTAGE" "16V"
					( Units "uVoltage" "V" 1.000000)
					( Origin gFrontEnd )
				)
				( attribute "XY" "(-5450,4000)"
					( Origin gFrontEnd )
				)
				( attribute "CHIPS_PART_NAME" "CAP"
					( Origin gPackager )
				)
				( attribute "CDS_PART_NAME" "CAP_0805-10UF,16V,10%,X6S,C953A"
					( Origin gPackager )
				)
				( objectStatus "C6U8" )
			)
			( gate "@baseboard_fab2_lib.baseboard_fab2(sch_1):page233_i256"
				( attribute "CDS_LIB" "mstr_discrete"
					( Origin gPackager )
				)
				( attribute "CDS_LOCATION" "C4F11"
					( Origin gPackager )
				)
				( attribute "CDS_SEC" "1"
					( Origin gPackager )
				)
				( attribute "LOCATION" "C4F11"
					( Origin gFrontEnd )
				)
				( attribute "MATERIAL" "POSCAP"
					( Origin gFrontEnd )
				)
				( attribute "PACK_TYPE" "7343"
					( Origin gFrontEnd )
				)
				( attribute "PART_NUMBER" "724613-067"
					( Origin gFrontEnd )
				)
				( attribute "PHYS_PAGE" "233"
					( Origin gFrontEnd )
				)
				( attribute "ROT" "0"
					( Origin gFrontEnd )
				)
				( attribute "SEC" "1"
					( Origin gFrontEnd )
				)
				( attribute "SEC_TYPE" "7343"
					( Origin gFrontEnd )
				)
				( attribute "TOLERANCE" "20%"
					( Origin gFrontEnd )
				)
				( attribute "VALUE" "220UF"
					( Origin gFrontEnd )
				)
				( attribute "VER" "1"
					( Origin gFrontEnd )
				)
				( attribute "VOLTAGE" "4V"
					( Units "uVoltage" "V" 1.000000)
					( Origin gFrontEnd )
				)
				( attribute "XY" "(-1400,3500)"
					( Origin gFrontEnd )
				)
				( attribute "CHIPS_PART_NAME" "CAPP"
					( Origin gPackager )
				)
				( attribute "CDS_PART_NAME" "CAPP_7343-220UF,4V,20%,POSCAP,A"
					( Origin gPackager )
				)
				( attribute "GROUP" "PWR_BULK_CAP"
					( Origin gFrontEnd )
				)
				( objectStatus "C4F11" )
			)
			( gate "@baseboard_fab2_lib.baseboard_fab2(sch_1):page233_i266"
				( attribute "BOM_COST" "PVPP_KLM_VR"
					( Origin gFrontEnd )
				)
				( attribute "CDS_LIB" "mstr_discrete"
					( Origin gPackager )
				)
				( attribute "CDS_LOCATION" "R4G10"
					( Origin gPackager )
				)
				( attribute "CDS_SEC" "1"
					( Origin gPackager )
				)
				( attribute "LOCATION" "R4G10"
					( Origin gFrontEnd )
				)
				( attribute "MATERIAL" "CHIP"
					( Origin gFrontEnd )
				)
				( attribute "PACK_TYPE" "0402"
					( Origin gFrontEnd )
				)
				( attribute "PART_NUMBER" "G85996-004"
					( Origin gFrontEnd )
				)
				( attribute "PHYS_PAGE" "233"
					( Origin gFrontEnd )
				)
				( attribute "REUSE_ID" "9"
					( Origin gFrontEnd )
				)
				( attribute "ROOM" "PVPP_KLM_VR"
					( Origin gFrontEnd )
				)
				( attribute "ROT" "0"
					( Origin gFrontEnd )
				)
				( attribute "SEC" "1"
					( Origin gFrontEnd )
				)
				( attribute "SEC_TYPE" "0402"
					( Origin gFrontEnd )
				)
				( attribute "SPOF" "TRUE"
					( Origin gFrontEnd )
				)
				( attribute "TOLERANCE" "0.1%"
					( Origin gFrontEnd )
				)
				( attribute "VALUE" "1.0K"
					( Origin gFrontEnd )
				)
				( attribute "VER" "2"
					( Origin gFrontEnd )
				)
				( attribute "WATTAGE" "1/16W"
					( Origin gFrontEnd )
				)
				( attribute "XY" "(-950,2475)"
					( Origin gFrontEnd )
				)
				( attribute "CHIPS_PART_NAME" "RES"
					( Origin gPackager )
				)
				( attribute "CDS_PART_NAME" "RES_0402-1.0K,0.1%,1/16W,CHIP,A"
					( Origin gPackager )
				)
				( objectStatus "R4G10" )
			)
			( gate "@baseboard_fab2_lib.baseboard_fab2(sch_1):page233_i267"
				( attribute "BOM_COST" "PVPP_KLM_VR"
					( Origin gFrontEnd )
				)
				( attribute "CDS_LIB" "mstr_discrete"
					( Origin gPackager )
				)
				( attribute "CDS_LOCATION" "C4G11"
					( Origin gPackager )
				)
				( attribute "CDS_SEC" "1"
					( Origin gPackager )
				)
				( attribute "LOCATION" "C4G11"
					( Origin gFrontEnd )
				)
				( attribute "MATERIAL" "X7R"
					( Origin gFrontEnd )
				)
				( attribute "PACK_TYPE" "0402LF"
					( Origin gFrontEnd )
				)
				( attribute "PART_NUMBER" "A36096-075"
					( Origin gFrontEnd )
				)
				( attribute "PHYS_PAGE" "233"
					( Origin gFrontEnd )
				)
				( attribute "REUSE_ID" "26"
					( Origin gFrontEnd )
				)
				( attribute "ROOM" "PVPP_KLM_VR"
					( Origin gFrontEnd )
				)
				( attribute "ROT" "0"
					( Origin gFrontEnd )
				)
				( attribute "SEC" "1"
					( Origin gFrontEnd )
				)
				( attribute "SEC_TYPE" "0402LF"
					( Origin gFrontEnd )
				)
				( attribute "SPOF" "TRUE"
					( Origin gFrontEnd )
				)
				( attribute "TOLERANCE" "10%"
					( Origin gFrontEnd )
				)
				( attribute "VALUE" "2200PF"
					( Origin gFrontEnd )
				)
				( attribute "VER" "1"
					( Origin gFrontEnd )
				)
				( attribute "VOLTAGE" "50V"
					( Units "uVoltage" "V" 1.000000)
					( Origin gFrontEnd )
				)
				( attribute "XY" "(-950,1700)"
					( Origin gFrontEnd )
				)
				( attribute "CHIPS_PART_NAME" "CAP"
					( Origin gPackager )
				)
				( attribute "CDS_PART_NAME" "CAP_0402LF-2200PF,50V,10%,X7R,A"
					( Origin gPackager )
				)
				( objectStatus "C4G11" )
			)
			( gate "@baseboard_fab2_lib.baseboard_fab2(sch_1):page234_i227"
				( attribute "BOM_COST" "IO_SLOT"
					( Origin gFrontEnd )
				)
				( attribute "CDS_LIB" "mstr_discrete"
					( Origin gPackager )
				)
				( attribute "CDS_LOCATION" "R4B4"
					( Origin gPackager )
				)
				( attribute "CDS_SEC" "1"
					( Origin gPackager )
				)
				( attribute "LOCATION" "R4B4"
					( Origin gFrontEnd )
				)
				( attribute "MATERIAL" "CHIP"
					( Origin gFrontEnd )
				)
				( attribute "PACK_TYPE" "0402"
					( Origin gFrontEnd )
				)
				( attribute "PART_NUMBER" "G21796-161"
					( Origin gFrontEnd )
				)
				( attribute "PHYS_PAGE" "234"
					( Origin gFrontEnd )
				)
				( attribute "ROOM" "IO_SLOT"
					( Origin gFrontEnd )
				)
				( attribute "ROT" "0"
					( Origin gFrontEnd )
				)
				( attribute "SEC" "1"
					( Origin gFrontEnd )
				)
				( attribute "SEC_TYPE" "0402"
					( Origin gFrontEnd )
				)
				( attribute "TOLERANCE" "1%"
					( Origin gFrontEnd )
				)
				( attribute "VALUE" "6.19K"
					( Origin gFrontEnd )
				)
				( attribute "VER" "2"
					( Origin gFrontEnd )
				)
				( attribute "WATTAGE" "1/16W"
					( Origin gFrontEnd )
				)
				( attribute "XY" "(-1350,1450)"
					( Origin gFrontEnd )
				)
				( attribute "CHIPS_PART_NAME" "RES"
					( Origin gPackager )
				)
				( attribute "CDS_PART_NAME" "RES_0402-6.19K,1%,1/16W,CHIP,GA"
					( Origin gPackager )
				)
				( objectStatus "R4B4" )
			)
			( gate "@baseboard_fab2_lib.baseboard_fab2(sch_1):page233_i270"
				( attribute "BOM_COST" "PVPP_KLM_VR"
					( Origin gFrontEnd )
				)
				( attribute "CDS_LIB" "mstr_discrete"
					( Origin gPackager )
				)
				( attribute "CDS_LOCATION" "R4G7"
					( Origin gPackager )
				)
				( attribute "CDS_SEC" "1"
					( Origin gPackager )
				)
				( attribute "LOCATION" "R4G7"
					( Origin gFrontEnd )
				)
				( attribute "MATERIAL" "CHIP"
					( Origin gFrontEnd )
				)
				( attribute "PACK_TYPE" "0402"
					( Origin gFrontEnd )
				)
				( attribute "PART_NUMBER" "G21796-040"
					( Origin gFrontEnd )
				)
				( attribute "PHYS_PAGE" "233"
					( Origin gFrontEnd )
				)
				( attribute "REUSE_ID" "9"
					( Origin gFrontEnd )
				)
				( attribute "ROOM" "PVPP_KLM_VR"
					( Origin gFrontEnd )
				)
				( attribute "ROT" "0"
					( Origin gFrontEnd )
				)
				( attribute "SEC" "1"
					( Origin gPackager )
				)
				( attribute "SPOF" "TRUE"
					( Origin gFrontEnd )
				)
				( attribute "TOLERANCE" "1%"
					( Origin gFrontEnd )
				)
				( attribute "VALUE" "20.0K"
					( Origin gFrontEnd )
				)
				( attribute "VER" "2"
					( Origin gFrontEnd )
				)
				( attribute "WATTAGE" "1/16W"
					( Origin gFrontEnd )
				)
				( attribute "XY" "(-1275,1800)"
					( Origin gFrontEnd )
				)
				( attribute "CHIPS_PART_NAME" "RES"
					( Origin gPackager )
				)
				( attribute "CDS_PART_NAME" "RES_0402-20.0K,1%,1/16W,CHIP,GA"
					( Origin gPackager )
				)
				( objectStatus "R4G7" )
			)
			( gate "@baseboard_fab2_lib.baseboard_fab2(sch_1):page233_i271"
				( attribute "CDS_LIB" "mstr_discrete"
					( Origin gPackager )
				)
				( attribute "CDS_LOCATION" "R4G8"
					( Origin gPackager )
				)
				( attribute "CDS_SEC" "1"
					( Origin gPackager )
				)
				( attribute "LOCATION" "R4G8"
					( Origin gFrontEnd )
				)
				( attribute "MATERIAL" "CHIP"
					( Origin gFrontEnd )
				)
				( attribute "PACK_TYPE" "0402"
					( Origin gFrontEnd )
				)
				( attribute "PART_NUMBER" "G21497-005"
					( Origin gFrontEnd )
				)
				( attribute "PHYS_PAGE" "233"
					( Origin gFrontEnd )
				)
				( attribute "ROOM" "PVPP_KLM_VR"
					( Origin gFrontEnd )
				)
				( attribute "ROT" "5"
					( Origin gFrontEnd )
				)
				( attribute "SEC" "1"
					( Origin gFrontEnd )
				)
				( attribute "SEC_TYPE" "0402"
					( Origin gFrontEnd )
				)
				( attribute "SPOF" "TRUE"
					( Origin gFrontEnd )
				)
				( attribute "TOLERANCE" "5%"
					( Origin gFrontEnd )
				)
				( attribute "VALUE" "0.0"
					( Origin gFrontEnd )
				)
				( attribute "VER" "1"
					( Origin gFrontEnd )
				)
				( attribute "WATTAGE" "1/16W"
					( Origin gFrontEnd )
				)
				( attribute "XY" "(-1275,2900)"
					( Origin gFrontEnd )
				)
				( attribute "CHIPS_PART_NAME" "RES"
					( Origin gPackager )
				)
				( attribute "CDS_PART_NAME" "RES_0402-0.0,5%,1/16W,CHIP,G21A"
					( Origin gPackager )
				)
				( objectStatus "R4G8" )
			)
			( gate "@baseboard_fab2_lib.baseboard_fab2(sch_1):page233_i272"
				( attribute "BOM_COST" "PVPP_KLM_VR"
					( Origin gFrontEnd )
				)
				( attribute "CDS_LIB" "mstr_discrete"
					( Origin gPackager )
				)
				( attribute "CDS_LOCATION" "R4G13"
					( Origin gPackager )
				)
				( attribute "CDS_SEC" "1"
					( Origin gPackager )
				)
				( attribute "LOCATION" "R4G13"
					( Origin gFrontEnd )
				)
				( attribute "MATERIAL" "CHIP"
					( Origin gFrontEnd )
				)
				( attribute "PACK_TYPE" "0402"
					( Origin gFrontEnd )
				)
				( attribute "PART_NUMBER" "G21796-242"
					( Origin gFrontEnd )
				)
				( attribute "PHYS_PAGE" "233"
					( Origin gFrontEnd )
				)
				( attribute "REUSE_ID" "13"
					( Origin gFrontEnd )
				)
				( attribute "ROOM" "PVPP_KLM_VR"
					( Origin gFrontEnd )
				)
				( attribute "ROT" "0"
					( Origin gFrontEnd )
				)
				( attribute "SEC" "1"
					( Origin gFrontEnd )
				)
				( attribute "SEC_TYPE" "0402"
					( Origin gFrontEnd )
				)
				( attribute "TOLERANCE" "1.0%"
					( Origin gFrontEnd )
				)
				( attribute "VALUE" "7.87K"
					( Origin gFrontEnd )
				)
				( attribute "VER" "1"
					( Origin gFrontEnd )
				)
				( attribute "WATTAGE" "1/16W"
					( Origin gFrontEnd )
				)
				( attribute "XY" "(-2000,2300)"
					( Origin gFrontEnd )
				)
				( attribute "CHIPS_PART_NAME" "RES"
					( Origin gPackager )
				)
				( attribute "CDS_PART_NAME" "RES_0402-7.87K,1.0%,1/16W,CHIPA"
					( Origin gPackager )
				)
				( objectStatus "R4G13" )
			)
			( gate "@baseboard_fab2_lib.baseboard_fab2(sch_1):page233_i273"
				( attribute "BOM_COST" "PVPP_KLM_VR"
					( Origin gFrontEnd )
				)
				( attribute "CDS_LIB" "mstr_discrete"
					( Origin gPackager )
				)
				( attribute "CDS_LOCATION" "C4G6"
					( Origin gPackager )
				)
				( attribute "CDS_SEC" "1"
					( Origin gPackager )
				)
				( attribute "LOCATION" "C4G6"
					( Origin gFrontEnd )
				)
				( attribute "MATERIAL" "COG"
					( Origin gFrontEnd )
				)
				( attribute "PACK_TYPE" "0402LF"
					( Origin gFrontEnd )
				)
				( attribute "PART_NUMBER" "A36095-026"
					( Origin gFrontEnd )
				)
				( attribute "PHYS_PAGE" "233"
					( Origin gFrontEnd )
				)
				( attribute "REUSE_ID" "27"
					( Origin gFrontEnd )
				)
				( attribute "ROOM" "PVPP_KLM_VR"
					( Origin gFrontEnd )
				)
				( attribute "ROT" "2"
					( Origin gFrontEnd )
				)
				( attribute "SEC" "1"
					( Origin gFrontEnd )
				)
				( attribute "SEC_TYPE" "0402LF"
					( Origin gFrontEnd )
				)
				( attribute "TOLERANCE" "5%"
					( Origin gFrontEnd )
				)
				( attribute "VALUE" "100.0PF"
					( Origin gFrontEnd )
				)
				( attribute "VER" "2"
					( Origin gFrontEnd )
				)
				( attribute "VOLTAGE" "50V"
					( Units "uVoltage" "V" 1.000000)
					( Origin gFrontEnd )
				)
				( attribute "XY" "(-2150,2675)"
					( Origin gFrontEnd )
				)
				( attribute "CHIPS_PART_NAME" "CAP"
					( Origin gPackager )
				)
				( attribute "CDS_PART_NAME" "CAP_0402LF-100.0PF,50V,5%,COG,A"
					( Origin gPackager )
				)
				( objectStatus "C4G6" )
			)
			( gate "@baseboard_fab2_lib.baseboard_fab2(sch_1):page233_i274"
				( attribute "BOM_COST" "PVPP_KLM_VR"
					( Origin gFrontEnd )
				)
				( attribute "CDS_LIB" "mstr_discrete"
					( Origin gPackager )
				)
				( attribute "CDS_LOCATION" "C4G10"
					( Origin gPackager )
				)
				( attribute "CDS_SEC" "1"
					( Origin gPackager )
				)
				( attribute "LOCATION" "C4G10"
					( Origin gFrontEnd )
				)
				( attribute "MATERIAL" "X7R"
					( Origin gFrontEnd )
				)
				( attribute "PACK_TYPE" "0402LF"
					( Origin gFrontEnd )
				)
				( attribute "PART_NUMBER" "A36096-075"
					( Origin gFrontEnd )
				)
				( attribute "PHYS_PAGE" "233"
					( Origin gFrontEnd )
				)
				( attribute "REUSE_ID" "27"
					( Origin gFrontEnd )
				)
				( attribute "ROOM" "PVPP_KLM_VR"
					( Origin gFrontEnd )
				)
				( attribute "ROT" "2"
					( Origin gFrontEnd )
				)
				( attribute "SEC" "1"
					( Origin gFrontEnd )
				)
				( attribute "SEC_TYPE" "0402LF"
					( Origin gFrontEnd )
				)
				( attribute "TOLERANCE" "10%"
					( Origin gFrontEnd )
				)
				( attribute "VALUE" "2200PF"
					( Origin gFrontEnd )
				)
				( attribute "VER" "2"
					( Origin gFrontEnd )
				)
				( attribute "VOLTAGE" "50V"
					( Units "uVoltage" "V" 1.000000)
					( Origin gFrontEnd )
				)
				( attribute "XY" "(-2775,2300)"
					( Origin gFrontEnd )
				)
				( attribute "CHIPS_PART_NAME" "CAP"
					( Origin gPackager )
				)
				( attribute "CDS_PART_NAME" "CAP_0402LF-2200PF,50V,10%,X7R,A"
					( Origin gPackager )
				)
				( objectStatus "C4G10" )
			)
			( gate "@baseboard_fab2_lib.baseboard_fab2(sch_1):page233_i275"
				( attribute "CDS_LIB" "mstr_discrete"
					( Origin gPackager )
				)
				( attribute "CDS_LOCATION" "R4G4"
					( Origin gPackager )
				)
				( attribute "CDS_SEC" "1"
					( Origin gPackager )
				)
				( attribute "LOCATION" "R4G4"
					( Origin gFrontEnd )
				)
				( attribute "MATERIAL" "CHIP"
					( Origin gFrontEnd )
				)
				( attribute "PACK_TYPE" "0402"
					( Origin gFrontEnd )
				)
				( attribute "PART_NUMBER" "G21497-005"
					( Origin gFrontEnd )
				)
				( attribute "PHYS_PAGE" "233"
					( Origin gFrontEnd )
				)
				( attribute "ROOM" "PVCCIN_CPU0_VR"
					( Origin gFrontEnd )
				)
				( attribute "ROT" "0"
					( Origin gFrontEnd )
				)
				( attribute "SEC" "1"
					( Origin gFrontEnd )
				)
				( attribute "SEC_TYPE" "0402"
					( Origin gFrontEnd )
				)
				( attribute "TOLERANCE" "5%"
					( Origin gFrontEnd )
				)
				( attribute "VALUE" "0.0"
					( Origin gFrontEnd )
				)
				( attribute "VER" "1"
					( Origin gFrontEnd )
				)
				( attribute "WATTAGE" "1/16W"
					( Origin gFrontEnd )
				)
				( attribute "XY" "(-6075,2675)"
					( Origin gFrontEnd )
				)
				( attribute "CHIPS_PART_NAME" "RES"
					( Origin gPackager )
				)
				( attribute "CDS_PART_NAME" "RES_0402-0.0,5%,1/16W,CHIP,G21A"
					( Origin gPackager )
				)
				( objectStatus "R4G4" )
			)
			( gate "@baseboard_fab2_lib.baseboard_fab2(sch_1):page233_i277"
				( attribute "BOM_COST" "PVPP_GHJ_VR"
					( Origin gFrontEnd )
				)
				( attribute "CDS_LIB" "mstr_discrete"
					( Origin gPackager )
				)
				( attribute "CDS_LOCATION" "L4G1"
					( Origin gPackager )
				)
				( attribute "CDS_SEC" "1"
					( Origin gPackager )
				)
				( attribute "LOCATION" "L4G1"
					( Origin gFrontEnd )
				)
				( attribute "MATERIAL" "IND"
					( Origin gFrontEnd )
				)
				( attribute "PACK_TYPE" "SM"
					( Origin gFrontEnd )
				)
				( attribute "PART_NUMBER" "E13358-018"
					( Origin gFrontEnd )
				)
				( attribute "PHYS_PAGE" "233"
					( Origin gFrontEnd )
				)
				( attribute "REUSE_ID" "30"
					( Origin gFrontEnd )
				)
				( attribute "ROOM" "PVPP_GHJ_VR"
					( Origin gFrontEnd )
				)
				( attribute "ROT" "0"
					( Origin gFrontEnd )
				)
				( attribute "SEC" "1"
					( Origin gFrontEnd )
				)
				( attribute "SEC_TYPE" "SM"
					( Origin gFrontEnd )
				)
				( attribute "TOLERANCE" "1%"
					( Origin gFrontEnd )
				)
				( attribute "VALUE" "0.47UH"
					( Origin gFrontEnd )
				)
				( attribute "VER" "1"
					( Origin gFrontEnd )
				)
				( attribute "XY" "(-2175,3700)"
					( Origin gFrontEnd )
				)
				( attribute "CHIPS_PART_NAME" "INDUCTOR"
					( Origin gPackager )
				)
				( attribute "CDS_PART_NAME" "INDUCTOR_SM-0.47UH,IND,E13358-A"
					( Origin gPackager )
				)
				( objectStatus "L4G1" )
			)
			( gate "@baseboard_fab2_lib.baseboard_fab2(sch_1):page234_i29"
				( attribute "CDS_LIB" "mstr_discrete"
					( Origin gPackager )
				)
				( attribute "CDS_LOCATION" "R4B14"
					( Origin gPackager )
				)
				( attribute "CDS_SEC" "1"
					( Origin gPackager )
				)
				( attribute "LOCATION" "R4B14"
					( Origin gFrontEnd )
				)
				( attribute "MATERIAL" "CHIP"
					( Origin gFrontEnd )
				)
				( attribute "PACK_TYPE" "0402"
					( Origin gFrontEnd )
				)
				( attribute "PART_NUMBER" "G21497-005"
					( Origin gFrontEnd )
				)
				( attribute "PHYS_PAGE" "234"
					( Origin gFrontEnd )
				)
				( attribute "ROOM" "PVPP_KLM_VR"
					( Origin gFrontEnd )
				)
				( attribute "ROT" "0"
					( Origin gFrontEnd )
				)
				( attribute "SEC" "1"
					( Origin gPackager )
				)
				( attribute "TOLERANCE" "5%"
					( Origin gFrontEnd )
				)
				( attribute "VALUE" "0.0"
					( Origin gFrontEnd )
				)
				( attribute "VER" "1"
					( Origin gFrontEnd )
				)
				( attribute "WATTAGE" "1/16W"
					( Origin gFrontEnd )
				)
				( attribute "XY" "(-1150,650)"
					( Origin gFrontEnd )
				)
				( attribute "CHIPS_PART_NAME" "RES"
					( Origin gPackager )
				)
				( attribute "CDS_PART_NAME" "RES_0402-0.0,5%,1/16W,CHIP,G21A"
					( Origin gPackager )
				)
				( objectStatus "R4B14" )
			)
			( gate "@baseboard_fab2_lib.baseboard_fab2(sch_1):page234_i84"
				( attribute "BOM_COST" "MEM_VRD_PVPP_AB"
					( Origin gFrontEnd )
				)
				( attribute "CDS_LIB" "mstr_discrete"
					( Origin gPackager )
				)
				( attribute "CDS_LOCATION" "C3B2"
					( Origin gPackager )
				)
				( attribute "CDS_SEC" "1"
					( Origin gPackager )
				)
				( attribute "LOCATION" "C3B2"
					( Origin gFrontEnd )
				)
				( attribute "MATERIAL" "X6S"
					( Origin gFrontEnd )
				)
				( attribute "PACK_TYPE" "0603LF"
					( Origin gFrontEnd )
				)
				( attribute "PART_NUMBER" "E15431-001"
					( Origin gFrontEnd )
				)
				( attribute "PHYS_PAGE" "234"
					( Origin gFrontEnd )
				)
				( attribute "ROOM" "PVPP_KLM_VR"
					( Origin gFrontEnd )
				)
				( attribute "ROT" "0"
					( Origin gFrontEnd )
				)
				( attribute "SEC" "1"
					( Origin gFrontEnd )
				)
				( attribute "SEC_TYPE" "0603LF"
					( Origin gFrontEnd )
				)
				( attribute "TOLERANCE" "20%"
					( Origin gFrontEnd )
				)
				( attribute "VALUE" "10UF"
					( Origin gFrontEnd )
				)
				( attribute "VER" "1"
					( Origin gFrontEnd )
				)
				( attribute "VOLTAGE" "4V"
					( Units "uVoltage" "V" 1.000000)
					( Origin gFrontEnd )
				)
				( attribute "XY" "(-5125,725)"
					( Origin gFrontEnd )
				)
				( attribute "CHIPS_PART_NAME" "CAP"
					( Origin gPackager )
				)
				( attribute "CDS_PART_NAME" "CAP_0603LF-10UF,4V,20%,X6S,E15A"
					( Origin gPackager )
				)
				( attribute "GROUP" "PWR_MLCC_CAP"
					( Origin gFrontEnd )
				)
				( objectStatus "C3B2" )
			)
			( gate "@baseboard_fab2_lib.baseboard_fab2(sch_1):page234_i86"
				( attribute "BOM_COST" "MEM_VRD_PVPP_AB"
					( Origin gFrontEnd )
				)
				( attribute "CDS_LIB" "mstr_discrete"
					( Origin gPackager )
				)
				( attribute "CDS_LOCATION" "C3A8"
					( Origin gPackager )
				)
				( attribute "CDS_SEC" "1"
					( Origin gPackager )
				)
				( attribute "LOCATION" "C3A8"
					( Origin gFrontEnd )
				)
				( attribute "MATERIAL" "X6S"
					( Origin gFrontEnd )
				)
				( attribute "PACK_TYPE" "0603LF"
					( Origin gFrontEnd )
				)
				( attribute "PART_NUMBER" "E15431-001"
					( Origin gFrontEnd )
				)
				( attribute "PHYS_PAGE" "234"
					( Origin gFrontEnd )
				)
				( attribute "ROOM" "PVPP_KLM_VR"
					( Origin gFrontEnd )
				)
				( attribute "ROT" "0"
					( Origin gFrontEnd )
				)
				( attribute "SEC" "1"
					( Origin gPackager )
				)
				( attribute "TOLERANCE" "20%"
					( Origin gFrontEnd )
				)
				( attribute "VALUE" "10UF"
					( Origin gFrontEnd )
				)
				( attribute "VER" "1"
					( Origin gFrontEnd )
				)
				( attribute "VOLTAGE" "4V"
					( Units "uVoltage" "V" 1.000000)
					( Origin gFrontEnd )
				)
				( attribute "XY" "(-5400,700)"
					( Origin gFrontEnd )
				)
				( attribute "CHIPS_PART_NAME" "CAP"
					( Origin gPackager )
				)
				( attribute "CDS_PART_NAME" "CAP_0603LF-10UF,4V,20%,X6S,E15A"
					( Origin gPackager )
				)
				( attribute "GROUP" "PWR_MLCC_CAP"
					( Origin gFrontEnd )
				)
				( objectStatus "C3A8" )
			)
			( gate "@baseboard_fab2_lib.baseboard_fab2(sch_1):page234_i87"
				( attribute "BOM_COST" "MEM_VRD_PVPP_AB"
					( Origin gFrontEnd )
				)
				( attribute "CDS_LIB" "mstr_discrete"
					( Origin gPackager )
				)
				( attribute "CDS_LOCATION" "C7L3"
					( Origin gPackager )
				)
				( attribute "CDS_SEC" "1"
					( Origin gPackager )
				)
				( attribute "LOCATION" "C7L3"
					( Origin gFrontEnd )
				)
				( attribute "MATERIAL" "X6S"
					( Origin gFrontEnd )
				)
				( attribute "PACK_TYPE" "0603LF"
					( Origin gFrontEnd )
				)
				( attribute "PART_NUMBER" "E15431-001"
					( Origin gFrontEnd )
				)
				( attribute "PHYS_PAGE" "234"
					( Origin gFrontEnd )
				)
				( attribute "ROOM" "PVPP_KLM_VR"
					( Origin gFrontEnd )
				)
				( attribute "ROT" "0"
					( Origin gFrontEnd )
				)
				( attribute "SEC" "1"
					( Origin gPackager )
				)
				( attribute "TOLERANCE" "20%"
					( Origin gFrontEnd )
				)
				( attribute "VALUE" "10UF"
					( Origin gFrontEnd )
				)
				( attribute "VER" "1"
					( Origin gFrontEnd )
				)
				( attribute "VOLTAGE" "4V"
					( Units "uVoltage" "V" 1.000000)
					( Origin gFrontEnd )
				)
				( attribute "XY" "(-5675,700)"
					( Origin gFrontEnd )
				)
				( attribute "CHIPS_PART_NAME" "CAP"
					( Origin gPackager )
				)
				( attribute "CDS_PART_NAME" "CAP_0603LF-10UF,4V,20%,X6S,E15A"
					( Origin gPackager )
				)
				( attribute "GROUP" "PWR_MLCC_CAP"
					( Origin gFrontEnd )
				)
				( objectStatus "C7L3" )
			)
			( gate "@baseboard_fab2_lib.baseboard_fab2(sch_1):page234_i88"
				( attribute "BOM_COST" "MEM_VRD_PVPP_AB"
					( Origin gFrontEnd )
				)
				( attribute "CDS_LIB" "mstr_discrete"
					( Origin gPackager )
				)
				( attribute "CDS_LOCATION" "C7L2"
					( Origin gPackager )
				)
				( attribute "CDS_SEC" "1"
					( Origin gPackager )
				)
				( attribute "LOCATION" "C7L2"
					( Origin gFrontEnd )
				)
				( attribute "MATERIAL" "X6S"
					( Origin gFrontEnd )
				)
				( attribute "PACK_TYPE" "0603LF"
					( Origin gFrontEnd )
				)
				( attribute "PART_NUMBER" "E15431-001"
					( Origin gFrontEnd )
				)
				( attribute "PHYS_PAGE" "234"
					( Origin gFrontEnd )
				)
				( attribute "ROOM" "PVPP_KLM_VR"
					( Origin gFrontEnd )
				)
				( attribute "ROT" "0"
					( Origin gFrontEnd )
				)
				( attribute "SEC" "1"
					( Origin gPackager )
				)
				( attribute "TOLERANCE" "20%"
					( Origin gFrontEnd )
				)
				( attribute "VALUE" "10UF"
					( Origin gFrontEnd )
				)
				( attribute "VER" "1"
					( Origin gFrontEnd )
				)
				( attribute "VOLTAGE" "4V"
					( Units "uVoltage" "V" 1.000000)
					( Origin gFrontEnd )
				)
				( attribute "XY" "(-5950,725)"
					( Origin gFrontEnd )
				)
				( attribute "CHIPS_PART_NAME" "CAP"
					( Origin gPackager )
				)
				( attribute "CDS_PART_NAME" "CAP_0603LF-10UF,4V,20%,X6S,E15A"
					( Origin gPackager )
				)
				( attribute "GROUP" "PWR_MLCC_CAP"
					( Origin gFrontEnd )
				)
				( objectStatus "C7L2" )
			)
			( gate "@baseboard_fab2_lib.baseboard_fab2(sch_1):page234_i89"
				( attribute "BOM_COST" "MEM_VRD_PVPP_AB"
					( Origin gFrontEnd )
				)
				( attribute "CDS_LIB" "mstr_discrete"
					( Origin gPackager )
				)
				( attribute "CDS_LOCATION" "C7L7"
					( Origin gPackager )
				)
				( attribute "CDS_SEC" "1"
					( Origin gPackager )
				)
				( attribute "LOCATION" "C7L7"
					( Origin gFrontEnd )
				)
				( attribute "MATERIAL" "X6S"
					( Origin gFrontEnd )
				)
				( attribute "PACK_TYPE" "0603LF"
					( Origin gFrontEnd )
				)
				( attribute "PART_NUMBER" "E15431-001"
					( Origin gFrontEnd )
				)
				( attribute "PHYS_PAGE" "234"
					( Origin gFrontEnd )
				)
				( attribute "ROOM" "PVPP_KLM_VR"
					( Origin gFrontEnd )
				)
				( attribute "ROT" "0"
					( Origin gFrontEnd )
				)
				( attribute "SEC" "1"
					( Origin gPackager )
				)
				( attribute "TOLERANCE" "20%"
					( Origin gFrontEnd )
				)
				( attribute "VALUE" "10UF"
					( Origin gFrontEnd )
				)
				( attribute "VER" "1"
					( Origin gFrontEnd )
				)
				( attribute "VOLTAGE" "4V"
					( Units "uVoltage" "V" 1.000000)
					( Origin gFrontEnd )
				)
				( attribute "XY" "(-6250,725)"
					( Origin gFrontEnd )
				)
				( attribute "CHIPS_PART_NAME" "CAP"
					( Origin gPackager )
				)
				( attribute "CDS_PART_NAME" "CAP_0603LF-10UF,4V,20%,X6S,E15A"
					( Origin gPackager )
				)
				( attribute "GROUP" "PWR_MLCC_CAP"
					( Origin gFrontEnd )
				)
				( objectStatus "C7L7" )
			)
			( gate "@baseboard_fab2_lib.baseboard_fab2(sch_1):page234_i90"
				( attribute "BOM_COST" "MEM_VRD_PVPP_AB"
					( Origin gFrontEnd )
				)
				( attribute "CDS_LIB" "mstr_discrete"
					( Origin gPackager )
				)
				( attribute "CDS_LOCATION" "C7L6"
					( Origin gPackager )
				)
				( attribute "CDS_SEC" "1"
					( Origin gPackager )
				)
				( attribute "LOCATION" "C7L6"
					( Origin gFrontEnd )
				)
				( attribute "MATERIAL" "X6S"
					( Origin gFrontEnd )
				)
				( attribute "PACK_TYPE" "0603LF"
					( Origin gFrontEnd )
				)
				( attribute "PART_NUMBER" "E15431-001"
					( Origin gFrontEnd )
				)
				( attribute "PHYS_PAGE" "234"
					( Origin gFrontEnd )
				)
				( attribute "ROOM" "PVPP_KLM_VR"
					( Origin gFrontEnd )
				)
				( attribute "ROT" "0"
					( Origin gFrontEnd )
				)
				( attribute "SEC" "1"
					( Origin gPackager )
				)
				( attribute "TOLERANCE" "20%"
					( Origin gFrontEnd )
				)
				( attribute "VALUE" "10UF"
					( Origin gFrontEnd )
				)
				( attribute "VER" "1"
					( Origin gFrontEnd )
				)
				( attribute "VOLTAGE" "4V"
					( Units "uVoltage" "V" 1.000000)
					( Origin gFrontEnd )
				)
				( attribute "XY" "(-6550,725)"
					( Origin gFrontEnd )
				)
				( attribute "CHIPS_PART_NAME" "CAP"
					( Origin gPackager )
				)
				( attribute "CDS_PART_NAME" "CAP_0603LF-10UF,4V,20%,X6S,E15A"
					( Origin gPackager )
				)
				( attribute "GROUP" "PWR_MLCC_CAP"
					( Origin gFrontEnd )
				)
				( objectStatus "C7L6" )
			)
			( gate "@baseboard_fab2_lib.baseboard_fab2(sch_1):page234_i91"
				( attribute "BOM_COST" "MEM_VRD_PVPP_AB"
					( Origin gFrontEnd )
				)
				( attribute "CDS_LIB" "mstr_discrete"
					( Origin gPackager )
				)
				( attribute "CDS_LOCATION" "C7M4"
					( Origin gPackager )
				)
				( attribute "CDS_SEC" "1"
					( Origin gPackager )
				)
				( attribute "LOCATION" "C7M4"
					( Origin gFrontEnd )
				)
				( attribute "MATERIAL" "X6S"
					( Origin gFrontEnd )
				)
				( attribute "PACK_TYPE" "0603LF"
					( Origin gFrontEnd )
				)
				( attribute "PART_NUMBER" "E15431-001"
					( Origin gFrontEnd )
				)
				( attribute "PHYS_PAGE" "234"
					( Origin gFrontEnd )
				)
				( attribute "ROOM" "PVPP_KLM_VR"
					( Origin gFrontEnd )
				)
				( attribute "ROT" "0"
					( Origin gFrontEnd )
				)
				( attribute "SEC" "1"
					( Origin gPackager )
				)
				( attribute "TOLERANCE" "20%"
					( Origin gFrontEnd )
				)
				( attribute "VALUE" "10UF"
					( Origin gFrontEnd )
				)
				( attribute "VER" "1"
					( Origin gFrontEnd )
				)
				( attribute "VOLTAGE" "4V"
					( Units "uVoltage" "V" 1.000000)
					( Origin gFrontEnd )
				)
				( attribute "XY" "(-6825,725)"
					( Origin gFrontEnd )
				)
				( attribute "CHIPS_PART_NAME" "CAP"
					( Origin gPackager )
				)
				( attribute "CDS_PART_NAME" "CAP_0603LF-10UF,4V,20%,X6S,E15A"
					( Origin gPackager )
				)
				( attribute "GROUP" "PWR_MLCC_CAP"
					( Origin gFrontEnd )
				)
				( objectStatus "C7M4" )
			)
			( gate "@baseboard_fab2_lib.baseboard_fab2(sch_1):page234_i92"
				( attribute "BOM_COST" "MEM_VRD_PVPP_AB"
					( Origin gFrontEnd )
				)
				( attribute "CDS_LIB" "mstr_discrete"
					( Origin gPackager )
				)
				( attribute "CDS_LOCATION" "C7M3"
					( Origin gPackager )
				)
				( attribute "CDS_SEC" "1"
					( Origin gPackager )
				)
				( attribute "LOCATION" "C7M3"
					( Origin gFrontEnd )
				)
				( attribute "MATERIAL" "X6S"
					( Origin gFrontEnd )
				)
				( attribute "PACK_TYPE" "0603LF"
					( Origin gFrontEnd )
				)
				( attribute "PART_NUMBER" "E15431-001"
					( Origin gFrontEnd )
				)
				( attribute "PHYS_PAGE" "234"
					( Origin gFrontEnd )
				)
				( attribute "ROOM" "PVPP_KLM_VR"
					( Origin gFrontEnd )
				)
				( attribute "ROT" "0"
					( Origin gFrontEnd )
				)
				( attribute "SEC" "1"
					( Origin gPackager )
				)
				( attribute "TOLERANCE" "20%"
					( Origin gFrontEnd )
				)
				( attribute "VALUE" "10UF"
					( Origin gFrontEnd )
				)
				( attribute "VER" "1"
					( Origin gFrontEnd )
				)
				( attribute "VOLTAGE" "4V"
					( Units "uVoltage" "V" 1.000000)
					( Origin gFrontEnd )
				)
				( attribute "XY" "(-7125,725)"
					( Origin gFrontEnd )
				)
				( attribute "CHIPS_PART_NAME" "CAP"
					( Origin gPackager )
				)
				( attribute "CDS_PART_NAME" "CAP_0603LF-10UF,4V,20%,X6S,E15A"
					( Origin gPackager )
				)
				( attribute "GROUP" "PWR_MLCC_CAP"
					( Origin gFrontEnd )
				)
				( objectStatus "C7M3" )
			)
			( gate "@baseboard_fab2_lib.baseboard_fab2(sch_1):page234_i93"
				( attribute "BOM_COST" "MEM_VRD_PVPP_AB"
					( Origin gFrontEnd )
				)
				( attribute "CDS_LIB" "mstr_discrete"
					( Origin gPackager )
				)
				( attribute "CDS_LOCATION" "C3A4"
					( Origin gPackager )
				)
				( attribute "CDS_SEC" "1"
					( Origin gPackager )
				)
				( attribute "LOCATION" "C3A4"
					( Origin gFrontEnd )
				)
				( attribute "MATERIAL" "X6S"
					( Origin gFrontEnd )
				)
				( attribute "PACK_TYPE" "0603LF"
					( Origin gFrontEnd )
				)
				( attribute "PART_NUMBER" "E15431-001"
					( Origin gFrontEnd )
				)
				( attribute "PHYS_PAGE" "234"
					( Origin gFrontEnd )
				)
				( attribute "ROOM" "PVPP_KLM_VR"
					( Origin gFrontEnd )
				)
				( attribute "ROT" "0"
					( Origin gFrontEnd )
				)
				( attribute "SEC" "1"
					( Origin gPackager )
				)
				( attribute "TOLERANCE" "20%"
					( Origin gFrontEnd )
				)
				( attribute "VALUE" "10UF"
					( Origin gFrontEnd )
				)
				( attribute "VER" "1"
					( Origin gFrontEnd )
				)
				( attribute "VOLTAGE" "4V"
					( Units "uVoltage" "V" 1.000000)
					( Origin gFrontEnd )
				)
				( attribute "XY" "(-7400,700)"
					( Origin gFrontEnd )
				)
				( attribute "CHIPS_PART_NAME" "CAP"
					( Origin gPackager )
				)
				( attribute "CDS_PART_NAME" "CAP_0603LF-10UF,4V,20%,X6S,E15A"
					( Origin gPackager )
				)
				( attribute "GROUP" "PWR_MLCC_CAP"
					( Origin gFrontEnd )
				)
				( objectStatus "C3A4" )
			)
			( gate "@baseboard_fab2_lib.baseboard_fab2(sch_1):page234_i94"
				( attribute "BOM_COST" "MEM_VRD_PVPP_AB"
					( Origin gFrontEnd )
				)
				( attribute "CDS_LIB" "mstr_discrete"
					( Origin gPackager )
				)
				( attribute "CDS_LOCATION" "C3B1"
					( Origin gPackager )
				)
				( attribute "CDS_SEC" "1"
					( Origin gPackager )
				)
				( attribute "LOCATION" "C3B1"
					( Origin gFrontEnd )
				)
				( attribute "MATERIAL" "X6S"
					( Origin gFrontEnd )
				)
				( attribute "PACK_TYPE" "0603LF"
					( Origin gFrontEnd )
				)
				( attribute "PART_NUMBER" "E15431-001"
					( Origin gFrontEnd )
				)
				( attribute "PHYS_PAGE" "234"
					( Origin gFrontEnd )
				)
				( attribute "ROOM" "PVPP_KLM_VR"
					( Origin gFrontEnd )
				)
				( attribute "ROT" "0"
					( Origin gFrontEnd )
				)
				( attribute "SEC" "1"
					( Origin gPackager )
				)
				( attribute "TOLERANCE" "20%"
					( Origin gFrontEnd )
				)
				( attribute "VALUE" "10UF"
					( Origin gFrontEnd )
				)
				( attribute "VER" "1"
					( Origin gFrontEnd )
				)
				( attribute "VOLTAGE" "4V"
					( Units "uVoltage" "V" 1.000000)
					( Origin gFrontEnd )
				)
				( attribute "XY" "(-7675,725)"
					( Origin gFrontEnd )
				)
				( attribute "CHIPS_PART_NAME" "CAP"
					( Origin gPackager )
				)
				( attribute "CDS_PART_NAME" "CAP_0603LF-10UF,4V,20%,X6S,E15A"
					( Origin gPackager )
				)
				( attribute "GROUP" "PWR_MLCC_CAP"
					( Origin gFrontEnd )
				)
				( objectStatus "C3B1" )
			)
			( gate "@baseboard_fab2_lib.baseboard_fab2(sch_1):page234_i95"
				( attribute "BOM_COST" "MEM_VRD_PVPP_AB"
					( Origin gFrontEnd )
				)
				( attribute "CDS_LIB" "mstr_discrete"
					( Origin gPackager )
				)
				( attribute "CDS_LOCATION" "C3A7"
					( Origin gPackager )
				)
				( attribute "CDS_SEC" "1"
					( Origin gPackager )
				)
				( attribute "LOCATION" "C3A7"
					( Origin gFrontEnd )
				)
				( attribute "MATERIAL" "X6S"
					( Origin gFrontEnd )
				)
				( attribute "PACK_TYPE" "0603LF"
					( Origin gFrontEnd )
				)
				( attribute "PART_NUMBER" "E15431-001"
					( Origin gFrontEnd )
				)
				( attribute "PHYS_PAGE" "234"
					( Origin gFrontEnd )
				)
				( attribute "ROOM" "PVPP_KLM_VR"
					( Origin gFrontEnd )
				)
				( attribute "ROT" "0"
					( Origin gFrontEnd )
				)
				( attribute "SEC" "1"
					( Origin gPackager )
				)
				( attribute "TOLERANCE" "20%"
					( Origin gFrontEnd )
				)
				( attribute "VALUE" "10UF"
					( Origin gFrontEnd )
				)
				( attribute "VER" "1"
					( Origin gFrontEnd )
				)
				( attribute "VOLTAGE" "4V"
					( Units "uVoltage" "V" 1.000000)
					( Origin gFrontEnd )
				)
				( attribute "XY" "(-7950,725)"
					( Origin gFrontEnd )
				)
				( attribute "CHIPS_PART_NAME" "CAP"
					( Origin gPackager )
				)
				( attribute "CDS_PART_NAME" "CAP_0603LF-10UF,4V,20%,X6S,E15A"
					( Origin gPackager )
				)
				( attribute "GROUP" "PWR_MLCC_CAP"
					( Origin gFrontEnd )
				)
				( objectStatus "C3A7" )
			)
			( gate "@baseboard_fab2_lib.baseboard_fab2(sch_1):page234_i97"
				( attribute "BOM_COST" "MEM_VRD_PVPP_AB"
					( Origin gFrontEnd )
				)
				( attribute "CDS_LIB" "mstr_discrete"
					( Origin gPackager )
				)
				( attribute "CDS_LOCATION" "C3A3"
					( Origin gPackager )
				)
				( attribute "CDS_SEC" "1"
					( Origin gPackager )
				)
				( attribute "LOCATION" "C3A3"
					( Origin gFrontEnd )
				)
				( attribute "MATERIAL" "X6S"
					( Origin gFrontEnd )
				)
				( attribute "PACK_TYPE" "0603LF"
					( Origin gFrontEnd )
				)
				( attribute "PART_NUMBER" "E15431-001"
					( Origin gFrontEnd )
				)
				( attribute "PHYS_PAGE" "234"
					( Origin gFrontEnd )
				)
				( attribute "ROOM" "PVPP_KLM_VR"
					( Origin gFrontEnd )
				)
				( attribute "ROT" "0"
					( Origin gFrontEnd )
				)
				( attribute "SEC" "1"
					( Origin gPackager )
				)
				( attribute "TOLERANCE" "20%"
					( Origin gFrontEnd )
				)
				( attribute "VALUE" "10UF"
					( Origin gFrontEnd )
				)
				( attribute "VER" "1"
					( Origin gFrontEnd )
				)
				( attribute "VOLTAGE" "4V"
					( Units "uVoltage" "V" 1.000000)
					( Origin gFrontEnd )
				)
				( attribute "XY" "(-8225,725)"
					( Origin gFrontEnd )
				)
				( attribute "CHIPS_PART_NAME" "CAP"
					( Origin gPackager )
				)
				( attribute "CDS_PART_NAME" "CAP_0603LF-10UF,4V,20%,X6S,E15A"
					( Origin gPackager )
				)
				( attribute "GROUP" "PWR_MLCC_CAP"
					( Origin gFrontEnd )
				)
				( objectStatus "C3A3" )
			)
			( gate "@baseboard_fab2_lib.baseboard_fab2(sch_1):page234_i129"
				( attribute "BOM_COST" "PVPP_KLM_VR"
					( Origin gFrontEnd )
				)
				( attribute "CDS_LIB" "mstr_discrete"
					( Origin gPackager )
				)
				( attribute "CDS_LOCATION" "C4B5"
					( Origin gPackager )
				)
				( attribute "CDS_SEC" "1"
					( Origin gPackager )
				)
				( attribute "FIN" "VR_1P2"
					( Origin gFrontEnd )
				)
				( attribute "LOCATION" "C4B5"
					( Origin gFrontEnd )
				)
				( attribute "MATERIAL" "EMPTY"
					( Origin gFrontEnd )
				)
				( attribute "PACK_TYPE" "0402LF"
					( Origin gFrontEnd )
				)
				( attribute "PART_NUMBER" "A36096-046"
					( Origin gFrontEnd )
				)
				( attribute "PHYS_PAGE" "234"
					( Origin gFrontEnd )
				)
				( attribute "REUSE_ID" "1"
					( Origin gFrontEnd )
				)
				( attribute "ROOM" "PVPP_KLM_VR"
					( Origin gFrontEnd )
				)
				( attribute "ROT" "2"
					( Origin gFrontEnd )
				)
				( attribute "SEC" "1"
					( Origin gPackager )
				)
				( attribute "TOLERANCE" "10%"
					( Origin gFrontEnd )
				)
				( attribute "VALUE" "1000PF"
					( Origin gFrontEnd )
				)
				( attribute "VER" "1"
					( Origin gFrontEnd )
				)
				( attribute "VOLTAGE" "50V"
					( Units "uVoltage" "V" 1.000000)
					( Origin gFrontEnd )
				)
				( attribute "XY" "(-6300,2400)"
					( Origin gFrontEnd )
				)
				( attribute "CHIPS_PART_NAME" "CAP"
					( Origin gPackager )
				)
				( attribute "CDS_PART_NAME" "CAP_0402LF-1000PF,50V,10%,EMPTA"
					( Origin gPackager )
				)
				( objectStatus "C4B5" )
			)
			( gate "@baseboard_fab2_lib.baseboard_fab2(sch_1):page233_i278"
				( attribute "CDS_LIB" "w_hdl"
					( Origin gPackager )
				)
				( attribute "CDS_LMAN_SYM_OUTLINE" "-50,25,50,-25"
					( Origin gPackager )
				)
				( attribute "LOCATION" "C22W6"
					( Origin gFrontEnd )
				)
				( attribute "PACK_TYPE" "SMD-BCG5"
					( Origin gFrontEnd )
				)
				( attribute "PART_NUMBER" "078.22611.0811"
					( Origin gFrontEnd )
				)
				( attribute "PHYS_PAGE" "233"
					( Origin gFrontEnd )
				)
				( attribute "ROT" "0"
					( Origin gFrontEnd )
				)
				( attribute "SEC" "1"
					( Origin gFrontEnd )
				)
				( attribute "SEC_TYPE" "SMD-BCG5"
					( Origin gFrontEnd )
				)
				( attribute "VALUE" "SC22U16V5MX-4-GP"
					( Origin gFrontEnd )
				)
				( attribute "VER" "1"
					( Origin gFrontEnd )
				)
				( attribute "XY" "(-7000,3950)"
					( Origin gFrontEnd )
				)
				( attribute "CHIPS_PART_NAME" "SC22U16V5MX-4-GP"
					( Origin gPackager )
				)
				( attribute "CDS_PART_NAME" "SC22U16V5MX-4-GP_SMD-BCG5-SC22A"
					( Origin gPackager )
				)
				( attribute "CDS_LOCATION" "C22W6"
					( Origin gPackager )
				)
				( attribute "CDS_SEC" "1"
					( Origin gPackager )
				)
				( attribute "ATTRIBUTE" "22UF"
					( Origin gFrontEnd )
				)
				( attribute "PACK_SIZE" "0805"
					( Origin gFrontEnd )
				)
				( attribute "RATED" "16V"
					( Origin gFrontEnd )
				)
				( attribute "TOLERANCE" "20%"
					( Origin gFrontEnd )
				)
				( attribute "TYPE" "X6S"
					( Origin gFrontEnd )
				)
				( objectStatus "C22W6" )
			)
			( gate "@baseboard_fab2_lib.baseboard_fab2(sch_1):page234_i139"
				( attribute "BOM_COST" "PVPP_KLM_VR"
					( Origin gFrontEnd )
				)
				( attribute "CDS_LIB" "mstr_discrete"
					( Origin gPackager )
				)
				( attribute "CDS_LOCATION" "C4B8"
					( Origin gPackager )
				)
				( attribute "CDS_SEC" "1"
					( Origin gPackager )
				)
				( attribute "LOCATION" "C4B8"
					( Origin gFrontEnd )
				)
				( attribute "MATERIAL" "X7R"
					( Origin gFrontEnd )
				)
				( attribute "PACK_TYPE" "0402LF"
					( Origin gFrontEnd )
				)
				( attribute "PART_NUMBER" "A36096-046"
					( Origin gFrontEnd )
				)
				( attribute "PHYS_PAGE" "234"
					( Origin gFrontEnd )
				)
				( attribute "REUSE_ID" "17"
					( Origin gFrontEnd )
				)
				( attribute "ROOM" "PVPP_KLM_VR"
					( Origin gFrontEnd )
				)
				( attribute "ROT" "0"
					( Origin gFrontEnd )
				)
				( attribute "SEC" "1"
					( Origin gPackager )
				)
				( attribute "TOLERANCE" "10%"
					( Origin gFrontEnd )
				)
				( attribute "VALUE" "1000PF"
					( Origin gFrontEnd )
				)
				( attribute "VER" "1"
					( Origin gFrontEnd )
				)
				( attribute "VOLTAGE" "50V"
					( Units "uVoltage" "V" 1.000000)
					( Origin gFrontEnd )
				)
				( attribute "XY" "(-3875,725)"
					( Origin gFrontEnd )
				)
				( attribute "CHIPS_PART_NAME" "CAP"
					( Origin gPackager )
				)
				( attribute "CDS_PART_NAME" "CAP_0402LF-1000PF,50V,10%,X7R,A"
					( Origin gPackager )
				)
				( objectStatus "C4B8" )
			)
			( gate "@baseboard_fab2_lib.baseboard_fab2(sch_1):page234_i143"
				( attribute "BOM_COST" "PVPP_KLM_VR"
					( Origin gFrontEnd )
				)
				( attribute "CDS_LIB" "mstr_discrete"
					( Origin gPackager )
				)
				( attribute "CDS_LOCATION" "R4B10"
					( Origin gPackager )
				)
				( attribute "CDS_SEC" "1"
					( Origin gPackager )
				)
				( attribute "LOCATION" "R4B10"
					( Origin gFrontEnd )
				)
				( attribute "MATERIAL" "CHIP"
					( Origin gFrontEnd )
				)
				( attribute "PACK_TYPE" "0402"
					( Origin gFrontEnd )
				)
				( attribute "PART_NUMBER" "G21796-026"
					( Origin gFrontEnd )
				)
				( attribute "PHYS_PAGE" "234"
					( Origin gFrontEnd )
				)
				( attribute "REUSE_ID" "21"
					( Origin gFrontEnd )
				)
				( attribute "ROOM" "PVPP_KLM_VR"
					( Origin gFrontEnd )
				)
				( attribute "ROT" "0"
					( Origin gFrontEnd )
				)
				( attribute "SEC" "1"
					( Origin gFrontEnd )
				)
				( attribute "SEC_TYPE" "0402"
					( Origin gFrontEnd )
				)
				( attribute "TOLERANCE" "1%"
					( Origin gFrontEnd )
				)
				( attribute "VALUE" "1.00K"
					( Origin gFrontEnd )
				)
				( attribute "VER" "2"
					( Origin gFrontEnd )
				)
				( attribute "WATTAGE" "1/16W"
					( Origin gFrontEnd )
				)
				( attribute "XY" "(-4225,1250)"
					( Origin gFrontEnd )
				)
				( attribute "CHIPS_PART_NAME" "RES"
					( Origin gPackager )
				)
				( attribute "CDS_PART_NAME" "RES_0402-1.00K,1%,1/16W,CHIP,GA"
					( Origin gPackager )
				)
				( objectStatus "R4B10" )
			)
			( gate "@baseboard_fab2_lib.baseboard_fab2(sch_1):page234_i144"
				( attribute "BOM_COST" "PVPP_KLM_VR"
					( Origin gFrontEnd )
				)
				( attribute "CDS_LIB" "mstr_discrete"
					( Origin gPackager )
				)
				( attribute "CDS_LOCATION" "C6L12"
					( Origin gPackager )
				)
				( attribute "CDS_SEC" "1"
					( Origin gPackager )
				)
				( attribute "LOCATION" "C6L12"
					( Origin gFrontEnd )
				)
				( attribute "MATERIAL" "X6S"
					( Origin gFrontEnd )
				)
				( attribute "PACK_TYPE" "0603"
					( Origin gFrontEnd )
				)
				( attribute "PART_NUMBER" "E15431-003"
					( Origin gFrontEnd )
				)
				( attribute "PHYS_PAGE" "234"
					( Origin gFrontEnd )
				)
				( attribute "REUSE_ID" "26"
					( Origin gFrontEnd )
				)
				( attribute "ROOM" "PVPP_KLM_VR"
					( Origin gFrontEnd )
				)
				( attribute "ROT" "0"
					( Origin gFrontEnd )
				)
				( attribute "SEC" "1"
					( Origin gFrontEnd )
				)
				( attribute "SEC_TYPE" "0603"
					( Origin gFrontEnd )
				)
				( attribute "TOLERANCE" "10%"
					( Origin gFrontEnd )
				)
				( attribute "VALUE" "4.7UF"
					( Origin gFrontEnd )
				)
				( attribute "VER" "1"
					( Origin gFrontEnd )
				)
				( attribute "VOLTAGE" "6.3V"
					( Units "uVoltage" "V" 1.000000)
					( Origin gFrontEnd )
				)
				( attribute "XY" "(-5650,2400)"
					( Origin gFrontEnd )
				)
				( attribute "CHIPS_PART_NAME" "CAP"
					( Origin gPackager )
				)
				( attribute "CDS_PART_NAME" "CAP_0603-4.7UF,6.3V,10%,X6S,E1A"
					( Origin gPackager )
				)
				( attribute "CONFIG" "078.47521.08BD"
					( Origin gFrontEnd )
				)
				( objectStatus "C6L12" )
			)
			( gate "@baseboard_fab2_lib.baseboard_fab2(sch_1):page234_i146"
				( attribute "BOM_COST" "PVPP_KLM_VR"
					( Origin gFrontEnd )
				)
				( attribute "CDS_LIB" "mstr_discrete"
					( Origin gPackager )
				)
				( attribute "CDS_LOCATION" "C4B6"
					( Origin gPackager )
				)
				( attribute "CDS_SEC" "1"
					( Origin gPackager )
				)
				( attribute "LOCATION" "C4B6"
					( Origin gFrontEnd )
				)
				( attribute "MATERIAL" "X7R"
					( Origin gFrontEnd )
				)
				( attribute "PACK_TYPE" "0402"
					( Origin gFrontEnd )
				)
				( attribute "PART_NUMBER" "A36096-129"
					( Origin gFrontEnd )
				)
				( attribute "PHYS_PAGE" "234"
					( Origin gFrontEnd )
				)
				( attribute "REUSE_ID" "26"
					( Origin gFrontEnd )
				)
				( attribute "ROOM" "PVPP_KLM_VR"
					( Origin gFrontEnd )
				)
				( attribute "ROT" "0"
					( Origin gFrontEnd )
				)
				( attribute "SEC" "1"
					( Origin gFrontEnd )
				)
				( attribute "SEC_TYPE" "0402"
					( Origin gFrontEnd )
				)
				( attribute "TOLERANCE" "10%"
					( Origin gFrontEnd )
				)
				( attribute "VALUE" "0.027UF"
					( Origin gFrontEnd )
				)
				( attribute "VER" "1"
					( Origin gFrontEnd )
				)
				( attribute "VOLTAGE" "16V"
					( Units "uVoltage" "V" 1.000000)
					( Origin gFrontEnd )
				)
				( attribute "XY" "(-5075,2175)"
					( Origin gFrontEnd )
				)
				( attribute "CHIPS_PART_NAME" "CAP"
					( Origin gPackager )
				)
				( attribute "CDS_PART_NAME" "CAP_0402-0.027UF,16V,10%,X7R,AA"
					( Origin gPackager )
				)
				( objectStatus "C4B6" )
			)
			( gate "@baseboard_fab2_lib.baseboard_fab2(sch_1):page234_i152"
				( attribute "BOM_COST" "PVPP_KLM_VR"
					( Origin gFrontEnd )
				)
				( attribute "CDS_LIB" "mstr_discrete"
					( Origin gPackager )
				)
				( attribute "CDS_LOCATION" "C6L11"
					( Origin gPackager )
				)
				( attribute "CDS_SEC" "1"
					( Origin gPackager )
				)
				( attribute "FIN" "VR_1P2"
					( Origin gFrontEnd )
				)
				( attribute "LOCATION" "C6L11"
					( Origin gFrontEnd )
				)
				( attribute "MATERIAL" "X6S"
					( Origin gFrontEnd )
				)
				( attribute "PACK_TYPE" "0402"
					( Origin gFrontEnd )
				)
				( attribute "PART_NUMBER" "D97712-011"
					( Origin gFrontEnd )
				)
				( attribute "PHYS_PAGE" "234"
					( Origin gFrontEnd )
				)
				( attribute "REUSE_ID" "1"
					( Origin gFrontEnd )
				)
				( attribute "ROOM" "PVPP_KLM_VR"
					( Origin gFrontEnd )
				)
				( attribute "ROT" "0"
					( Origin gFrontEnd )
				)
				( attribute "SEC" "1"
					( Origin gPackager )
				)
				( attribute "TOLERANCE" "10%"
					( Origin gFrontEnd )
				)
				( attribute "VALUE" "1.0UF"
					( Origin gFrontEnd )
				)
				( attribute "VER" "1"
					( Origin gFrontEnd )
				)
				( attribute "VOLTAGE" "16V"
					( Units "uVoltage" "V" 1.000000)
					( Origin gFrontEnd )
				)
				( attribute "XY" "(-5100,4150)"
					( Origin gFrontEnd )
				)
				( attribute "CHIPS_PART_NAME" "CAP"
					( Origin gPackager )
				)
				( attribute "CDS_PART_NAME" "CAP_0402-1.0UF,16V,10%,X6S,D97A"
					( Origin gPackager )
				)
				( objectStatus "C6L11" )
			)
			( gate "@baseboard_fab2_lib.baseboard_fab2(sch_1):page234_i154"
				( attribute "CDS_LIB" "mstr_discrete"
					( Origin gPackager )
				)
				( attribute "CDS_LOCATION" "FB4A1"
					( Origin gPackager )
				)
				( attribute "CDS_SEC" "1"
					( Origin gPackager )
				)
				( attribute "LOCATION" "FB4A1"
					( Origin gFrontEnd )
				)
				( attribute "MATERIAL" "FB"
					( Origin gFrontEnd )
				)
				( attribute "PACK_TYPE" "SM"
					( Origin gFrontEnd )
				)
				( attribute "PART_NUMBER" "656554-051"
					( Origin gFrontEnd )
				)
				( attribute "PHYS_PAGE" "234"
					( Origin gFrontEnd )
				)
				( attribute "ROOM" "PVPP_KLM_VR"
					( Origin gFrontEnd )
				)
				( attribute "ROT" "0"
					( Origin gFrontEnd )
				)
				( attribute "SEC" "1"
					( Origin gFrontEnd )
				)
				( attribute "SEC_TYPE" "SM"
					( Origin gFrontEnd )
				)
				( attribute "TOLERANCE" "1%"
					( Origin gFrontEnd )
				)
				( attribute "VALUE" "22"
					( Origin gFrontEnd )
				)
				( attribute "VER" "1"
					( Origin gFrontEnd )
				)
				( attribute "XY" "(-7650,4300)"
					( Origin gFrontEnd )
				)
				( attribute "CHIPS_PART_NAME" "FERRITE"
					( Origin gPackager )
				)
				( attribute "CDS_PART_NAME" "FERRITE_SM-22,FB,656554-051"
					( Origin gPackager )
				)
				( objectStatus "FB4A1" )
			)
			( gate "@baseboard_fab2_lib.baseboard_fab2(sch_1):page233_i282"
				( attribute "BOM_COST" "NT_GBE_BASE"
					( Origin gFrontEnd )
				)
				( attribute "CDS_LIB" "mstr_discrete"
					( Origin gPackager )
				)
				( attribute "CDS_LOCATION" "R4G24"
					( Origin gPackager )
				)
				( attribute "CDS_SEC" "1"
					( Origin gPackager )
				)
				( attribute "LOCATION" "R4G24"
					( Origin gFrontEnd )
				)
				( attribute "MATERIAL" "CHIP"
					( Origin gFrontEnd )
				)
				( attribute "PACK_TYPE" "0603"
					( Origin gFrontEnd )
				)
				( attribute "PART_NUMBER" "G22178-002"
					( Origin gFrontEnd )
				)
				( attribute "PHYS_PAGE" "233"
					( Origin gFrontEnd )
				)
				( attribute "ROOM" "NIC_SPRV"
					( Origin gFrontEnd )
				)
				( attribute "ROT" "0"
					( Origin gFrontEnd )
				)
				( attribute "SEC" "1"
					( Origin gFrontEnd )
				)
				( attribute "SEC_TYPE" "0603"
					( Origin gFrontEnd )
				)
				( attribute "TOLERANCE" "5.0%"
					( Origin gFrontEnd )
				)
				( attribute "VALUE" "0"
					( Origin gFrontEnd )
				)
				( attribute "VER" "1"
					( Origin gFrontEnd )
				)
				( attribute "WATTAGE" "1/10W"
					( Origin gFrontEnd )
				)
				( attribute "XY" "(-4075,4050)"
					( Origin gFrontEnd )
				)
				( attribute "CHIPS_PART_NAME" "RES"
					( Origin gPackager )
				)
				( attribute "CDS_PART_NAME" "RES_0603-0,5.0%,1/10W,CHIP,G22A"
					( Origin gPackager )
				)
				( objectStatus "R4G24" )
			)
			( gate "@baseboard_fab2_lib.baseboard_fab2(sch_1):page234_i162"
				( attribute "BOM_COST" "PVPP_KLM_VR"
					( Origin gFrontEnd )
				)
				( attribute "CDS_LIB" "mstr_discrete"
					( Origin gPackager )
				)
				( attribute "CDS_LOCATION" "R4A7"
					( Origin gPackager )
				)
				( attribute "CDS_SEC" "1"
					( Origin gPackager )
				)
				( attribute "LOCATION" "R4A7"
					( Origin gFrontEnd )
				)
				( attribute "MATERIAL" "EMPTY"
					( Origin gFrontEnd )
				)
				( attribute "PACK_TYPE" "0402"
					( Origin gFrontEnd )
				)
				( attribute "PART_NUMBER" "G21497-016"
					( Origin gFrontEnd )
				)
				( attribute "PHYS_PAGE" "234"
					( Origin gFrontEnd )
				)
				( attribute "REUSE_ID" "29"
					( Origin gFrontEnd )
				)
				( attribute "ROOM" "PVPP_KLM_VR"
					( Origin gFrontEnd )
				)
				( attribute "ROT" "0"
					( Origin gFrontEnd )
				)
				( attribute "SEC" "1"
					( Origin gPackager )
				)
				( attribute "TOLERANCE" "5%"
					( Origin gFrontEnd )
				)
				( attribute "VALUE" "2.2"
					( Origin gFrontEnd )
				)
				( attribute "VER" "2"
					( Origin gFrontEnd )
				)
				( attribute "WATTAGE" "1/16W"
					( Origin gFrontEnd )
				)
				( attribute "XY" "(-2575,3275)"
					( Origin gFrontEnd )
				)
				( attribute "CHIPS_PART_NAME" "RES"
					( Origin gPackager )
				)
				( attribute "CDS_PART_NAME" "RES_0402-2.2,5%,1/16W,EMPTY,G2A"
					( Origin gPackager )
				)
				( objectStatus "R4A7" )
			)
			( gate "@baseboard_fab2_lib.baseboard_fab2(sch_1):page234_i163"
				( attribute "BOM_COST" "PVPP_KLM_VR"
					( Origin gFrontEnd )
				)
				( attribute "CDS_LIB" "mstr_discrete"
					( Origin gPackager )
				)
				( attribute "CDS_LOCATION" "C4A16"
					( Origin gPackager )
				)
				( attribute "CDS_SEC" "1"
					( Origin gPackager )
				)
				( attribute "LOCATION" "C4A16"
					( Origin gFrontEnd )
				)
				( attribute "MATERIAL" "EMPTY"
					( Origin gFrontEnd )
				)
				( attribute "PACK_TYPE" "0402LF"
					( Origin gFrontEnd )
				)
				( attribute "PART_NUMBER" "A36096-091"
					( Origin gFrontEnd )
				)
				( attribute "PHYS_PAGE" "234"
					( Origin gFrontEnd )
				)
				( attribute "REUSE_ID" "26"
					( Origin gFrontEnd )
				)
				( attribute "ROOM" "PVPP_KLM_VR"
					( Origin gFrontEnd )
				)
				( attribute "ROT" "0"
					( Origin gFrontEnd )
				)
				( attribute "SEC" "1"
					( Origin gPackager )
				)
				( attribute "TOLERANCE" "10%"
					( Origin gFrontEnd )
				)
				( attribute "VALUE" "3300PF"
					( Origin gFrontEnd )
				)
				( attribute "VER" "1"
					( Origin gFrontEnd )
				)
				( attribute "VOLTAGE" "50V"
					( Units "uVoltage" "V" 1.000000)
					( Origin gFrontEnd )
				)
				( attribute "XY" "(-2575,3600)"
					( Origin gFrontEnd )
				)
				( attribute "CHIPS_PART_NAME" "CAP"
					( Origin gPackager )
				)
				( attribute "CDS_PART_NAME" "CAP_0402LF-3300PF,50V,10%,EMPTA"
					( Origin gPackager )
				)
				( objectStatus "C4A16" )
			)
			( gate "@baseboard_fab2_lib.baseboard_fab2(sch_1):page234_i164"
				( attribute "BOM_COST" "PVPP_KLM_VR"
					( Origin gFrontEnd )
				)
				( attribute "CDS_LIB" "mstr_discrete"
					( Origin gPackager )
				)
				( attribute "CDS_LOCATION" "L4A1"
					( Origin gPackager )
				)
				( attribute "CDS_SEC" "1"
					( Origin gPackager )
				)
				( attribute "LOCATION" "L4A1"
					( Origin gFrontEnd )
				)
				( attribute "MATERIAL" "IND"
					( Origin gFrontEnd )
				)
				( attribute "PACK_TYPE" "SM"
					( Origin gFrontEnd )
				)
				( attribute "PART_NUMBER" "E13358-018"
					( Origin gFrontEnd )
				)
				( attribute "PHYS_PAGE" "234"
					( Origin gFrontEnd )
				)
				( attribute "REUSE_ID" "30"
					( Origin gFrontEnd )
				)
				( attribute "ROOM" "PVPP_KLM_VR"
					( Origin gFrontEnd )
				)
				( attribute "ROT" "0"
					( Origin gFrontEnd )
				)
				( attribute "SEC" "1"
					( Origin gPackager )
				)
				( attribute "TOLERANCE" "1%"
					( Origin gFrontEnd )
				)
				( attribute "VALUE" "0.47UH"
					( Origin gFrontEnd )
				)
				( attribute "VER" "1"
					( Origin gFrontEnd )
				)
				( attribute "XY" "(-2300,3850)"
					( Origin gFrontEnd )
				)
				( attribute "CHIPS_PART_NAME" "INDUCTOR"
					( Origin gPackager )
				)
				( attribute "CDS_PART_NAME" "INDUCTOR_SM-0.47UH,IND,E13358-A"
					( Origin gPackager )
				)
				( objectStatus "L4A1" )
			)
			( gate "@baseboard_fab2_lib.baseboard_fab2(sch_1):page234_i167"
				( attribute "BOM_COST" "PVPP_KLM_VR"
					( Origin gFrontEnd )
				)
				( attribute "CDS_LIB" "mstr_discrete"
					( Origin gPackager )
				)
				( attribute "CDS_LOCATION" "C3B3"
					( Origin gPackager )
				)
				( attribute "CDS_SEC" "1"
					( Origin gPackager )
				)
				( attribute "LOCATION" "C3B3"
					( Origin gFrontEnd )
				)
				( attribute "MATERIAL" "POSCAP"
					( Origin gFrontEnd )
				)
				( attribute "PACK_TYPE" "7343LF"
					( Origin gFrontEnd )
				)
				( attribute "PART_NUMBER" "724613-042"
					( Origin gFrontEnd )
				)
				( attribute "PHYS_PAGE" "234"
					( Origin gFrontEnd )
				)
				( attribute "REUSE_ID" "28"
					( Origin gFrontEnd )
				)
				( attribute "ROOM" "PVPP_KLM_VR"
					( Origin gFrontEnd )
				)
				( attribute "ROT" "0"
					( Origin gFrontEnd )
				)
				( attribute "SEC" "1"
					( Origin gPackager )
				)
				( attribute "TOLERANCE" "20%"
					( Origin gFrontEnd )
				)
				( attribute "VALUE" "330UF"
					( Origin gFrontEnd )
				)
				( attribute "VER" "1"
					( Origin gFrontEnd )
				)
				( attribute "VOLTAGE" "6.3V"
					( Units "uVoltage" "V" 1.000000)
					( Origin gFrontEnd )
				)
				( attribute "XY" "(-1750,3650)"
					( Origin gFrontEnd )
				)
				( attribute "CHIPS_PART_NAME" "CAPP"
					( Origin gPackager )
				)
				( attribute "CDS_PART_NAME" "CAPP_7343LF-330UF,6.3V,20%,POSA"
					( Origin gPackager )
				)
				( attribute "GROUP" "PWR_BULK_CAP"
					( Origin gFrontEnd )
				)
				( objectStatus "C3B3" )
			)
			( gate "@baseboard_fab2_lib.baseboard_fab2(sch_1):page234_i177"
				( attribute "BOM_COST" "PVPP_KLM_VR"
					( Origin gFrontEnd )
				)
				( attribute "CDS_LIB" "mstr_discrete"
					( Origin gPackager )
				)
				( attribute "CDS_LOCATION" "C4B3"
					( Origin gPackager )
				)
				( attribute "CDS_SEC" "1"
					( Origin gPackager )
				)
				( attribute "LOCATION" "C4B3"
					( Origin gFrontEnd )
				)
				( attribute "MATERIAL" "X6S"
					( Origin gFrontEnd )
				)
				( attribute "PACK_TYPE" "0805"
					( Origin gFrontEnd )
				)
				( attribute "PART_NUMBER" "C95333-006"
					( Origin gFrontEnd )
				)
				( attribute "PHYS_PAGE" "234"
					( Origin gFrontEnd )
				)
				( attribute "REUSE_ID" "33"
					( Origin gFrontEnd )
				)
				( attribute "ROOM" "PVPP_KLM_VR"
					( Origin gFrontEnd )
				)
				( attribute "ROT" "0"
					( Origin gFrontEnd )
				)
				( attribute "SEC" "1"
					( Origin gPackager )
				)
				( attribute "TOLERANCE" "20%"
					( Origin gFrontEnd )
				)
				( attribute "VALUE" "47UF"
					( Origin gFrontEnd )
				)
				( attribute "VER" "1"
					( Origin gFrontEnd )
				)
				( attribute "VOLTAGE" "4V"
					( Units "uVoltage" "V" 1.000000)
					( Origin gFrontEnd )
				)
				( attribute "XY" "(-1150,3700)"
					( Origin gFrontEnd )
				)
				( attribute "CHIPS_PART_NAME" "CAP"
					( Origin gPackager )
				)
				( attribute "CDS_PART_NAME" "CAP_0805-47UF,4V,20%,X6S,C9533A"
					( Origin gPackager )
				)
				( attribute "GROUP" "PWR_MLCC_CAP"
					( Origin gFrontEnd )
				)
				( objectStatus "C4B3" )
			)
			( gate "@baseboard_fab2_lib.baseboard_fab2(sch_1):page234_i180"
				( attribute "BOM_COST" "PVPP_KLM_VR"
					( Origin gFrontEnd )
				)
				( attribute "CDS_LIB" "mstr_discrete"
					( Origin gPackager )
				)
				( attribute "CDS_LOCATION" "C4B2"
					( Origin gPackager )
				)
				( attribute "CDS_SEC" "1"
					( Origin gPackager )
				)
				( attribute "LOCATION" "C4B2"
					( Origin gFrontEnd )
				)
				( attribute "MATERIAL" "X6S"
					( Origin gFrontEnd )
				)
				( attribute "PACK_TYPE" "0805"
					( Origin gFrontEnd )
				)
				( attribute "PART_NUMBER" "C95333-006"
					( Origin gFrontEnd )
				)
				( attribute "PHYS_PAGE" "234"
					( Origin gFrontEnd )
				)
				( attribute "REUSE_ID" "33"
					( Origin gFrontEnd )
				)
				( attribute "ROOM" "PVPP_KLM_VR"
					( Origin gFrontEnd )
				)
				( attribute "ROT" "0"
					( Origin gFrontEnd )
				)
				( attribute "SEC" "1"
					( Origin gPackager )
				)
				( attribute "TOLERANCE" "20%"
					( Origin gFrontEnd )
				)
				( attribute "VALUE" "47UF"
					( Origin gFrontEnd )
				)
				( attribute "VER" "1"
					( Origin gFrontEnd )
				)
				( attribute "VOLTAGE" "4V"
					( Units "uVoltage" "V" 1.000000)
					( Origin gFrontEnd )
				)
				( attribute "XY" "(-850,3700)"
					( Origin gFrontEnd )
				)
				( attribute "CHIPS_PART_NAME" "CAP"
					( Origin gPackager )
				)
				( attribute "CDS_PART_NAME" "CAP_0805-47UF,4V,20%,X6S,C9533A"
					( Origin gPackager )
				)
				( attribute "GROUP" "PWR_MLCC_CAP"
					( Origin gFrontEnd )
				)
				( objectStatus "C4B2" )
			)
			( gate "@baseboard_fab2_lib.baseboard_fab2(sch_1):page234_i182"
				( attribute "BOM_COST" "PVPP_KLM_VR"
					( Origin gFrontEnd )
				)
				( attribute "CDS_LIB" "mstr_discrete"
					( Origin gPackager )
				)
				( attribute "CDS_LOCATION" "C4B15"
					( Origin gPackager )
				)
				( attribute "CDS_SEC" "1"
					( Origin gPackager )
				)
				( attribute "LOCATION" "C4B15"
					( Origin gFrontEnd )
				)
				( attribute "MATERIAL" "X7R"
					( Origin gFrontEnd )
				)
				( attribute "PACK_TYPE" "0603LF"
					( Origin gFrontEnd )
				)
				( attribute "PART_NUMBER" "602433-020"
					( Origin gFrontEnd )
				)
				( attribute "PHYS_PAGE" "234"
					( Origin gFrontEnd )
				)
				( attribute "REUSE_ID" "27"
					( Origin gFrontEnd )
				)
				( attribute "ROOM" "PVPP_KLM_VR"
					( Origin gFrontEnd )
				)
				( attribute "ROT" "2"
					( Origin gFrontEnd )
				)
				( attribute "SEC" "1"
					( Origin gPackager )
				)
				( attribute "TOLERANCE" "10%"
					( Origin gFrontEnd )
				)
				( attribute "VALUE" "0.1UF"
					( Origin gFrontEnd )
				)
				( attribute "VER" "2"
					( Origin gFrontEnd )
				)
				( attribute "VOLTAGE" "25V"
					( Units "uVoltage" "V" 1.000000)
					( Origin gFrontEnd )
				)
				( attribute "XY" "(-3375,4200)"
					( Origin gFrontEnd )
				)
				( attribute "CHIPS_PART_NAME" "CAP"
					( Origin gPackager )
				)
				( attribute "CDS_PART_NAME" "CAP_0603LF-0.1UF,25V,10%,X7R,6A"
					( Origin gPackager )
				)
				( objectStatus "C4B15" )
			)
			( gate "@baseboard_fab2_lib.baseboard_fab2(sch_1):page234_i183"
				( attribute "BOM_COST" "PVPP_KLM_VR"
					( Origin gFrontEnd )
				)
				( attribute "CDS_LIB" "mstr_discrete"
					( Origin gPackager )
				)
				( attribute "CDS_LOCATION" "R4B2"
					( Origin gPackager )
				)
				( attribute "CDS_SEC" "1"
					( Origin gPackager )
				)
				( attribute "LOCATION" "R4B2"
					( Origin gFrontEnd )
				)
				( attribute "MATERIAL" "CHIP"
					( Origin gFrontEnd )
				)
				( attribute "PACK_TYPE" "0603"
					( Origin gFrontEnd )
				)
				( attribute "PART_NUMBER" "G22026-003"
					( Origin gFrontEnd )
				)
				( attribute "PHYS_PAGE" "234"
					( Origin gFrontEnd )
				)
				( attribute "REUSE_ID" "34"
					( Origin gFrontEnd )
				)
				( attribute "ROOM" "PVPP_KLM_VR"
					( Origin gFrontEnd )
				)
				( attribute "ROT" "0"
					( Origin gFrontEnd )
				)
				( attribute "SEC" "1"
					( Origin gPackager )
				)
				( attribute "TOLERANCE" "1%"
					( Origin gFrontEnd )
				)
				( attribute "VALUE" "120.0"
					( Origin gFrontEnd )
				)
				( attribute "VER" "2"
					( Origin gFrontEnd )
				)
				( attribute "WATTAGE" "1/10W"
					( Origin gFrontEnd )
				)
				( attribute "XY" "(-2050,3650)"
					( Origin gFrontEnd )
				)
				( attribute "CHIPS_PART_NAME" "RES"
					( Origin gPackager )
				)
				( attribute "CDS_PART_NAME" "RES_0603-120.0,1%,1/10W,CHIP,GA"
					( Origin gPackager )
				)
				( objectStatus "R4B2" )
			)
			( gate "@baseboard_fab2_lib.baseboard_fab2(sch_1):page234_i184"
				( attribute "CDS_LIB" "mstr_vreg"
					( Origin gPackager )
				)
				( attribute "CDS_LMAN_SYM_OUTLINE" "-450,850,450,-900"
					( Origin gPackager )
				)
				( attribute "CDS_LOCATION" "EU4A3"
					( Origin gPackager )
				)
				( attribute "CDS_SEC" "1"
					( Origin gPackager )
				)
				( attribute "LOCATION" "EU4A3"
					( Origin gFrontEnd )
				)
				( attribute "MATERIAL" "IC"
					( Origin gFrontEnd )
				)
				( attribute "PACK_TYPE" "SM"
					( Origin gFrontEnd )
				)
				( attribute "PART_NUMBER" "H86355-001"
					( Origin gFrontEnd )
				)
				( attribute "PHYS_PAGE" "234"
					( Origin gFrontEnd )
				)
				( attribute "ROT" "0"
					( Origin gFrontEnd )
				)
				( attribute "SEC" "1"
					( Origin gFrontEnd )
				)
				( attribute "SEC_TYPE" "SM"
					( Origin gFrontEnd )
				)
				( attribute "VER" "1"
					( Origin gFrontEnd )
				)
				( attribute "XY" "(-3800,2875)"
					( Origin gFrontEnd )
				)
				( attribute "CHIPS_PART_NAME" "NCP3232L"
					( Origin gPackager )
				)
				( attribute "CDS_PART_NAME" "NCP3232L_SM-IC,H86355-001"
					( Origin gPackager )
				)
				( objectStatus "EU4A3" )
			)
			( gate "@baseboard_fab2_lib.baseboard_fab2(sch_1):page234_i199"
				( attribute "CDS_LIB" "dev_discrete"
					( Origin gPackager )
				)
				( attribute "CDS_LOCATION" "C4A20"
					( Origin gPackager )
				)
				( attribute "CDS_SEC" "1"
					( Origin gPackager )
				)
				( attribute "LOCATION" "C4A20"
					( Origin gFrontEnd )
				)
				( attribute "MATERIAL" "X7R"
					( Origin gFrontEnd )
				)
				( attribute "PACK_TYPE" "0402V"
					( Origin gFrontEnd )
				)
				( attribute "PART_NUMBER" "A36096-030"
					( Origin gFrontEnd )
				)
				( attribute "PHYS_PAGE" "234"
					( Origin gFrontEnd )
				)
				( attribute "ROT" "0"
					( Origin gFrontEnd )
				)
				( attribute "SEC" "1"
					( Origin gFrontEnd )
				)
				( attribute "SEC_TYPE" "0402V"
					( Origin gFrontEnd )
				)
				( attribute "TOLERANCE" "10%"
					( Origin gFrontEnd )
				)
				( attribute "VALUE" "0.1UF"
					( Origin gFrontEnd )
				)
				( attribute "VER" "1"
					( Origin gFrontEnd )
				)
				( attribute "VOLTAGE" "16V"
					( Units "uVoltage" "V" 1.000000)
					( Origin gFrontEnd )
				)
				( attribute "XY" "(-5175,3525)"
					( Origin gFrontEnd )
				)
				( attribute "CHIPS_PART_NAME" "CAP_A"
					( Origin gPackager )
				)
				( attribute "CDS_PART_NAME" "CAP_A_0402V-0.1UF,16V,10%,X7R,A"
					( Origin gPackager )
				)
				( objectStatus "C4A20" )
			)
			( gate "@baseboard_fab2_lib.baseboard_fab2(sch_1):page234_i201"
				( attribute "CDS_LIB" "mstr_discrete"
					( Origin gPackager )
				)
				( attribute "CDS_LOCATION" "R4B7"
					( Origin gPackager )
				)
				( attribute "CDS_SEC" "1"
					( Origin gPackager )
				)
				( attribute "LOCATION" "R4B7"
					( Origin gFrontEnd )
				)
				( attribute "MATERIAL" "CHIP"
					( Origin gFrontEnd )
				)
				( attribute "PACK_TYPE" "0402"
					( Origin gFrontEnd )
				)
				( attribute "PART_NUMBER" "G21796-250"
					( Origin gFrontEnd )
				)
				( attribute "PHYS_PAGE" "234"
					( Origin gFrontEnd )
				)
				( attribute "ROOM" "PVPP_KLM_VR"
					( Origin gFrontEnd )
				)
				( attribute "ROT" "0"
					( Origin gFrontEnd )
				)
				( attribute "SEC" "1"
					( Origin gFrontEnd )
				)
				( attribute "SEC_TYPE" "0402"
					( Origin gFrontEnd )
				)
				( attribute "TOLERANCE" "1.0%"
					( Origin gFrontEnd )
				)
				( attribute "VALUE" "22.1"
					( Origin gFrontEnd )
				)
				( attribute "VER" "1"
					( Origin gFrontEnd )
				)
				( attribute "WATTAGE" "1/16W"
					( Origin gFrontEnd )
				)
				( attribute "XY" "(-3350,975)"
					( Origin gFrontEnd )
				)
				( attribute "CHIPS_PART_NAME" "RES"
					( Origin gPackager )
				)
				( attribute "CDS_PART_NAME" "RES_0402-22.1,1.0%,1/16W,CHIP,A"
					( Origin gPackager )
				)
				( objectStatus "R4B7" )
			)
			( gate "@baseboard_fab2_lib.baseboard_fab2(sch_1):page234_i202"
				( attribute "CDS_LIB" "mstr_discrete"
					( Origin gPackager )
				)
				( attribute "CDS_LOCATION" "C6L10"
					( Origin gPackager )
				)
				( attribute "CDS_SEC" "1"
					( Origin gPackager )
				)
				( attribute "LOCATION" "C6L10"
					( Origin gFrontEnd )
				)
				( attribute "MATERIAL" "X6S"
					( Origin gFrontEnd )
				)
				( attribute "PACK_TYPE" "0805"
					( Origin gFrontEnd )
				)
				( attribute "PART_NUMBER" "C95333-007"
					( Origin gFrontEnd )
				)
				( attribute "PHYS_PAGE" "234"
					( Origin gFrontEnd )
				)
				( attribute "ROT" "0"
					( Origin gFrontEnd )
				)
				( attribute "SEC" "1"
					( Origin gFrontEnd )
				)
				( attribute "SEC_TYPE" "0805"
					( Origin gFrontEnd )
				)
				( attribute "TOLERANCE" "10%"
					( Origin gFrontEnd )
				)
				( attribute "VALUE" "10UF"
					( Origin gFrontEnd )
				)
				( attribute "VER" "1"
					( Origin gFrontEnd )
				)
				( attribute "VOLTAGE" "16V"
					( Units "uVoltage" "V" 1.000000)
					( Origin gFrontEnd )
				)
				( attribute "XY" "(-6750,4150)"
					( Origin gFrontEnd )
				)
				( attribute "CHIPS_PART_NAME" "CAP"
					( Origin gPackager )
				)
				( attribute "CDS_PART_NAME" "CAP_0805-10UF,16V,10%,X6S,C953A"
					( Origin gPackager )
				)
				( objectStatus "C6L10" )
			)
			( gate "@baseboard_fab2_lib.baseboard_fab2(sch_1):page234_i203"
				( attribute "CDS_LIB" "mstr_discrete"
					( Origin gPackager )
				)
				( attribute "CDS_LOCATION" "C6M3"
					( Origin gPackager )
				)
				( attribute "CDS_SEC" "1"
					( Origin gPackager )
				)
				( attribute "LOCATION" "C6M3"
					( Origin gFrontEnd )
				)
				( attribute "MATERIAL" "X6S"
					( Origin gFrontEnd )
				)
				( attribute "PACK_TYPE" "0805"
					( Origin gFrontEnd )
				)
				( attribute "PART_NUMBER" "C95333-007"
					( Origin gFrontEnd )
				)
				( attribute "PHYS_PAGE" "234"
					( Origin gFrontEnd )
				)
				( attribute "ROT" "0"
					( Origin gFrontEnd )
				)
				( attribute "SEC" "1"
					( Origin gFrontEnd )
				)
				( attribute "SEC_TYPE" "0805"
					( Origin gFrontEnd )
				)
				( attribute "TOLERANCE" "10%"
					( Origin gFrontEnd )
				)
				( attribute "VALUE" "10UF"
					( Origin gFrontEnd )
				)
				( attribute "VER" "1"
					( Origin gFrontEnd )
				)
				( attribute "VOLTAGE" "16V"
					( Units "uVoltage" "V" 1.000000)
					( Origin gFrontEnd )
				)
				( attribute "XY" "(-6375,4150)"
					( Origin gFrontEnd )
				)
				( attribute "CHIPS_PART_NAME" "CAP"
					( Origin gPackager )
				)
				( attribute "CDS_PART_NAME" "CAP_0805-10UF,16V,10%,X6S,C953A"
					( Origin gPackager )
				)
				( objectStatus "C6M3" )
			)
			( gate "@baseboard_fab2_lib.baseboard_fab2(sch_1):page234_i204"
				( attribute "CDS_LIB" "mstr_discrete"
					( Origin gPackager )
				)
				( attribute "CDS_LOCATION" "C6M5"
					( Origin gPackager )
				)
				( attribute "CDS_SEC" "1"
					( Origin gPackager )
				)
				( attribute "LOCATION" "C6M5"
					( Origin gFrontEnd )
				)
				( attribute "MATERIAL" "X6S"
					( Origin gFrontEnd )
				)
				( attribute "PACK_TYPE" "0805"
					( Origin gFrontEnd )
				)
				( attribute "PART_NUMBER" "C95333-007"
					( Origin gFrontEnd )
				)
				( attribute "PHYS_PAGE" "234"
					( Origin gFrontEnd )
				)
				( attribute "ROT" "0"
					( Origin gFrontEnd )
				)
				( attribute "SEC" "1"
					( Origin gFrontEnd )
				)
				( attribute "SEC_TYPE" "0805"
					( Origin gFrontEnd )
				)
				( attribute "TOLERANCE" "10%"
					( Origin gFrontEnd )
				)
				( attribute "VALUE" "10UF"
					( Origin gFrontEnd )
				)
				( attribute "VER" "1"
					( Origin gFrontEnd )
				)
				( attribute "VOLTAGE" "16V"
					( Units "uVoltage" "V" 1.000000)
					( Origin gFrontEnd )
				)
				( attribute "XY" "(-5925,4150)"
					( Origin gFrontEnd )
				)
				( attribute "CHIPS_PART_NAME" "CAP"
					( Origin gPackager )
				)
				( attribute "CDS_PART_NAME" "CAP_0805-10UF,16V,10%,X6S,C953A"
					( Origin gPackager )
				)
				( objectStatus "C6M5" )
			)
			( gate "@baseboard_fab2_lib.baseboard_fab2(sch_1):page234_i205"
				( attribute "CDS_LIB" "mstr_discrete"
					( Origin gPackager )
				)
				( attribute "CDS_LOCATION" "C4A19"
					( Origin gPackager )
				)
				( attribute "CDS_SEC" "1"
					( Origin gPackager )
				)
				( attribute "LOCATION" "C4A19"
					( Origin gFrontEnd )
				)
				( attribute "MATERIAL" "X6S"
					( Origin gFrontEnd )
				)
				( attribute "PACK_TYPE" "0805"
					( Origin gFrontEnd )
				)
				( attribute "PART_NUMBER" "C95333-007"
					( Origin gFrontEnd )
				)
				( attribute "PHYS_PAGE" "234"
					( Origin gFrontEnd )
				)
				( attribute "ROT" "0"
					( Origin gFrontEnd )
				)
				( attribute "SEC" "1"
					( Origin gFrontEnd )
				)
				( attribute "SEC_TYPE" "0805"
					( Origin gFrontEnd )
				)
				( attribute "TOLERANCE" "10%"
					( Origin gFrontEnd )
				)
				( attribute "VALUE" "10UF"
					( Origin gFrontEnd )
				)
				( attribute "VER" "1"
					( Origin gFrontEnd )
				)
				( attribute "VOLTAGE" "16V"
					( Units "uVoltage" "V" 1.000000)
					( Origin gFrontEnd )
				)
				( attribute "XY" "(-5475,4150)"
					( Origin gFrontEnd )
				)
				( attribute "CHIPS_PART_NAME" "CAP"
					( Origin gPackager )
				)
				( attribute "CDS_PART_NAME" "CAP_0805-10UF,16V,10%,X6S,C953A"
					( Origin gPackager )
				)
				( objectStatus "C4A19" )
			)
			( gate "@baseboard_fab2_lib.baseboard_fab2(sch_1):page234_i210"
				( attribute "CDS_LIB" "mstr_discrete"
					( Origin gPackager )
				)
				( attribute "CDS_LOCATION" "C6L8"
					( Origin gPackager )
				)
				( attribute "CDS_SEC" "1"
					( Origin gPackager )
				)
				( attribute "LOCATION" "C6L8"
					( Origin gFrontEnd )
				)
				( attribute "MATERIAL" "POSCAP"
					( Origin gFrontEnd )
				)
				( attribute "PACK_TYPE" "7343"
					( Origin gFrontEnd )
				)
				( attribute "PART_NUMBER" "724613-067"
					( Origin gFrontEnd )
				)
				( attribute "PHYS_PAGE" "234"
					( Origin gFrontEnd )
				)
				( attribute "ROT" "0"
					( Origin gFrontEnd )
				)
				( attribute "SEC" "1"
					( Origin gFrontEnd )
				)
				( attribute "SEC_TYPE" "7343"
					( Origin gFrontEnd )
				)
				( attribute "TOLERANCE" "20%"
					( Origin gFrontEnd )
				)
				( attribute "VALUE" "220UF"
					( Origin gFrontEnd )
				)
				( attribute "VER" "1"
					( Origin gFrontEnd )
				)
				( attribute "VOLTAGE" "4V"
					( Units "uVoltage" "V" 1.000000)
					( Origin gFrontEnd )
				)
				( attribute "XY" "(-1450,3650)"
					( Origin gFrontEnd )
				)
				( attribute "CHIPS_PART_NAME" "CAPP"
					( Origin gPackager )
				)
				( attribute "CDS_PART_NAME" "CAPP_7343-220UF,4V,20%,POSCAP,A"
					( Origin gPackager )
				)
				( attribute "GROUP" "PWR_BULK_CAP"
					( Origin gFrontEnd )
				)
				( objectStatus "C6L8" )
			)
			( gate "@baseboard_fab2_lib.baseboard_fab2(sch_1):page234_i211"
				( attribute "BOM_COST" "PVPP_KLM_VR"
					( Origin gFrontEnd )
				)
				( attribute "CDS_LIB" "mstr_discrete"
					( Origin gPackager )
				)
				( attribute "CDS_LOCATION" "C4B9"
					( Origin gPackager )
				)
				( attribute "CDS_SEC" "1"
					( Origin gPackager )
				)
				( attribute "LOCATION" "C4B9"
					( Origin gFrontEnd )
				)
				( attribute "MATERIAL" "X7R"
					( Origin gFrontEnd )
				)
				( attribute "PACK_TYPE" "0402LF"
					( Origin gFrontEnd )
				)
				( attribute "PART_NUMBER" "A36096-075"
					( Origin gFrontEnd )
				)
				( attribute "PHYS_PAGE" "234"
					( Origin gFrontEnd )
				)
				( attribute "REUSE_ID" "27"
					( Origin gFrontEnd )
				)
				( attribute "ROOM" "PVPP_KLM_VR"
					( Origin gFrontEnd )
				)
				( attribute "ROT" "2"
					( Origin gFrontEnd )
				)
				( attribute "SEC" "1"
					( Origin gFrontEnd )
				)
				( attribute "SEC_TYPE" "0402LF"
					( Origin gFrontEnd )
				)
				( attribute "TOLERANCE" "10%"
					( Origin gFrontEnd )
				)
				( attribute "VALUE" "2200PF"
					( Origin gFrontEnd )
				)
				( attribute "VER" "2"
					( Origin gFrontEnd )
				)
				( attribute "VOLTAGE" "50V"
					( Units "uVoltage" "V" 1.000000)
					( Origin gFrontEnd )
				)
				( attribute "XY" "(-2850,2450)"
					( Origin gFrontEnd )
				)
				( attribute "CHIPS_PART_NAME" "CAP"
					( Origin gPackager )
				)
				( attribute "CDS_PART_NAME" "CAP_0402LF-2200PF,50V,10%,X7R,A"
					( Origin gPackager )
				)
				( objectStatus "C4B9" )
			)
			( gate "@baseboard_fab2_lib.baseboard_fab2(sch_1):page234_i212"
				( attribute "BOM_COST" "PVPP_KLM_VR"
					( Origin gFrontEnd )
				)
				( attribute "CDS_LIB" "mstr_discrete"
					( Origin gPackager )
				)
				( attribute "CDS_LOCATION" "C4B4"
					( Origin gPackager )
				)
				( attribute "CDS_SEC" "1"
					( Origin gPackager )
				)
				( attribute "LOCATION" "C4B4"
					( Origin gFrontEnd )
				)
				( attribute "MATERIAL" "COG"
					( Origin gFrontEnd )
				)
				( attribute "PACK_TYPE" "0402LF"
					( Origin gFrontEnd )
				)
				( attribute "PART_NUMBER" "A36095-026"
					( Origin gFrontEnd )
				)
				( attribute "PHYS_PAGE" "234"
					( Origin gFrontEnd )
				)
				( attribute "REUSE_ID" "27"
					( Origin gFrontEnd )
				)
				( attribute "ROOM" "PVPP_KLM_VR"
					( Origin gFrontEnd )
				)
				( attribute "ROT" "2"
					( Origin gFrontEnd )
				)
				( attribute "SEC" "1"
					( Origin gFrontEnd )
				)
				( attribute "SEC_TYPE" "0402LF"
					( Origin gFrontEnd )
				)
				( attribute "TOLERANCE" "5%"
					( Origin gFrontEnd )
				)
				( attribute "VALUE" "100.0PF"
					( Origin gFrontEnd )
				)
				( attribute "VER" "2"
					( Origin gFrontEnd )
				)
				( attribute "VOLTAGE" "50V"
					( Units "uVoltage" "V" 1.000000)
					( Origin gFrontEnd )
				)
				( attribute "XY" "(-2225,2825)"
					( Origin gFrontEnd )
				)
				( attribute "CHIPS_PART_NAME" "CAP"
					( Origin gPackager )
				)
				( attribute "CDS_PART_NAME" "CAP_0402LF-100.0PF,50V,5%,COG,A"
					( Origin gPackager )
				)
				( objectStatus "C4B4" )
			)
			( gate "@baseboard_fab2_lib.baseboard_fab2(sch_1):page234_i213"
				( attribute "BOM_COST" "PVPP_KLM_VR"
					( Origin gFrontEnd )
				)
				( attribute "CDS_LIB" "mstr_discrete"
					( Origin gPackager )
				)
				( attribute "CDS_LOCATION" "R4B8"
					( Origin gPackager )
				)
				( attribute "CDS_SEC" "1"
					( Origin gPackager )
				)
				( attribute "LOCATION" "R4B8"
					( Origin gFrontEnd )
				)
				( attribute "MATERIAL" "CHIP"
					( Origin gFrontEnd )
				)
				( attribute "PACK_TYPE" "0402"
					( Origin gFrontEnd )
				)
				( attribute "PART_NUMBER" "G21796-242"
					( Origin gFrontEnd )
				)
				( attribute "PHYS_PAGE" "234"
					( Origin gFrontEnd )
				)
				( attribute "REUSE_ID" "13"
					( Origin gFrontEnd )
				)
				( attribute "ROOM" "PVPP_KLM_VR"
					( Origin gFrontEnd )
				)
				( attribute "ROT" "0"
					( Origin gFrontEnd )
				)
				( attribute "SEC" "1"
					( Origin gFrontEnd )
				)
				( attribute "SEC_TYPE" "0402"
					( Origin gFrontEnd )
				)
				( attribute "TOLERANCE" "1.0%"
					( Origin gFrontEnd )
				)
				( attribute "VALUE" "7.87K"
					( Origin gFrontEnd )
				)
				( attribute "VER" "1"
					( Origin gFrontEnd )
				)
				( attribute "WATTAGE" "1/16W"
					( Origin gFrontEnd )
				)
				( attribute "XY" "(-2150,2450)"
					( Origin gFrontEnd )
				)
				( attribute "CHIPS_PART_NAME" "RES"
					( Origin gPackager )
				)
				( attribute "CDS_PART_NAME" "RES_0402-7.87K,1.0%,1/16W,CHIPA"
					( Origin gPackager )
				)
				( objectStatus "R4B8" )
			)
			( gate "@baseboard_fab2_lib.baseboard_fab2(sch_1):page234_i214"
				( attribute "CDS_LIB" "mstr_discrete"
					( Origin gPackager )
				)
				( attribute "CDS_LOCATION" "R4B3"
					( Origin gPackager )
				)
				( attribute "CDS_SEC" "1"
					( Origin gPackager )
				)
				( attribute "LOCATION" "R4B3"
					( Origin gFrontEnd )
				)
				( attribute "MATERIAL" "CHIP"
					( Origin gFrontEnd )
				)
				( attribute "PACK_TYPE" "0402"
					( Origin gFrontEnd )
				)
				( attribute "PART_NUMBER" "G21497-005"
					( Origin gFrontEnd )
				)
				( attribute "PHYS_PAGE" "234"
					( Origin gFrontEnd )
				)
				( attribute "ROOM" "PVPP_KLM_VR"
					( Origin gFrontEnd )
				)
				( attribute "ROT" "5"
					( Origin gFrontEnd )
				)
				( attribute "SEC" "1"
					( Origin gFrontEnd )
				)
				( attribute "SEC_TYPE" "0402"
					( Origin gFrontEnd )
				)
				( attribute "SPOF" "TRUE"
					( Origin gFrontEnd )
				)
				( attribute "TOLERANCE" "5%"
					( Origin gFrontEnd )
				)
				( attribute "VALUE" "0.0"
					( Origin gFrontEnd )
				)
				( attribute "VER" "1"
					( Origin gFrontEnd )
				)
				( attribute "WATTAGE" "1/16W"
					( Origin gFrontEnd )
				)
				( attribute "XY" "(-1350,3050)"
					( Origin gFrontEnd )
				)
				( attribute "CHIPS_PART_NAME" "RES"
					( Origin gPackager )
				)
				( attribute "CDS_PART_NAME" "RES_0402-0.0,5%,1/16W,CHIP,G21A"
					( Origin gPackager )
				)
				( objectStatus "R4B3" )
			)
			( gate "@baseboard_fab2_lib.baseboard_fab2(sch_1):page234_i215"
				( attribute "BOM_COST" "PVPP_KLM_VR"
					( Origin gFrontEnd )
				)
				( attribute "CDS_LIB" "mstr_discrete"
					( Origin gPackager )
				)
				( attribute "CDS_LOCATION" "R4B5"
					( Origin gPackager )
				)
				( attribute "CDS_SEC" "1"
					( Origin gPackager )
				)
				( attribute "LOCATION" "R4B5"
					( Origin gFrontEnd )
				)
				( attribute "MATERIAL" "CHIP"
					( Origin gFrontEnd )
				)
				( attribute "PACK_TYPE" "0402"
					( Origin gFrontEnd )
				)
				( attribute "PART_NUMBER" "G21796-040"
					( Origin gFrontEnd )
				)
				( attribute "PHYS_PAGE" "234"
					( Origin gFrontEnd )
				)
				( attribute "REUSE_ID" "9"
					( Origin gFrontEnd )
				)
				( attribute "ROOM" "PVPP_KLM_VR"
					( Origin gFrontEnd )
				)
				( attribute "ROT" "0"
					( Origin gFrontEnd )
				)
				( attribute "SEC" "1"
					( Origin gPackager )
				)
				( attribute "SPOF" "TRUE"
					( Origin gFrontEnd )
				)
				( attribute "TOLERANCE" "1%"
					( Origin gFrontEnd )
				)
				( attribute "VALUE" "20.0K"
					( Origin gFrontEnd )
				)
				( attribute "VER" "2"
					( Origin gFrontEnd )
				)
				( attribute "WATTAGE" "1/16W"
					( Origin gFrontEnd )
				)
				( attribute "XY" "(-1350,2175)"
					( Origin gFrontEnd )
				)
				( attribute "CHIPS_PART_NAME" "RES"
					( Origin gPackager )
				)
				( attribute "CDS_PART_NAME" "RES_0402-20.0K,1%,1/16W,CHIP,GA"
					( Origin gPackager )
				)
				( objectStatus "R4B5" )
			)
			( gate "@baseboard_fab2_lib.baseboard_fab2(sch_1):page234_i218"
				( attribute "BOM_COST" "PVPP_KLM_VR"
					( Origin gFrontEnd )
				)
				( attribute "CDS_LIB" "mstr_discrete"
					( Origin gPackager )
				)
				( attribute "CDS_LOCATION" "C4B7"
					( Origin gPackager )
				)
				( attribute "CDS_SEC" "1"
					( Origin gPackager )
				)
				( attribute "LOCATION" "C4B7"
					( Origin gFrontEnd )
				)
				( attribute "MATERIAL" "X7R"
					( Origin gFrontEnd )
				)
				( attribute "PACK_TYPE" "0402LF"
					( Origin gFrontEnd )
				)
				( attribute "PART_NUMBER" "A36096-075"
					( Origin gFrontEnd )
				)
				( attribute "PHYS_PAGE" "234"
					( Origin gFrontEnd )
				)
				( attribute "REUSE_ID" "26"
					( Origin gFrontEnd )
				)
				( attribute "ROOM" "PVPP_KLM_VR"
					( Origin gFrontEnd )
				)
				( attribute "ROT" "0"
					( Origin gFrontEnd )
				)
				( attribute "SEC" "1"
					( Origin gFrontEnd )
				)
				( attribute "SEC_TYPE" "0402LF"
					( Origin gFrontEnd )
				)
				( attribute "SPOF" "TRUE"
					( Origin gFrontEnd )
				)
				( attribute "TOLERANCE" "10%"
					( Origin gFrontEnd )
				)
				( attribute "VALUE" "2200PF"
					( Origin gFrontEnd )
				)
				( attribute "VER" "1"
					( Origin gFrontEnd )
				)
				( attribute "VOLTAGE" "50V"
					( Units "uVoltage" "V" 1.000000)
					( Origin gFrontEnd )
				)
				( attribute "XY" "(-1025,1950)"
					( Origin gFrontEnd )
				)
				( attribute "CHIPS_PART_NAME" "CAP"
					( Origin gPackager )
				)
				( attribute "CDS_PART_NAME" "CAP_0402LF-2200PF,50V,10%,X7R,A"
					( Origin gPackager )
				)
				( objectStatus "C4B7" )
			)
			( gate "@baseboard_fab2_lib.baseboard_fab2(sch_1):page234_i219"
				( attribute "BOM_COST" "PVPP_KLM_VR"
					( Origin gFrontEnd )
				)
				( attribute "CDS_LIB" "mstr_discrete"
					( Origin gPackager )
				)
				( attribute "CDS_LOCATION" "R4B9"
					( Origin gPackager )
				)
				( attribute "CDS_SEC" "1"
					( Origin gPackager )
				)
				( attribute "LOCATION" "R4B9"
					( Origin gFrontEnd )
				)
				( attribute "MATERIAL" "CHIP"
					( Origin gFrontEnd )
				)
				( attribute "PACK_TYPE" "0402"
					( Origin gFrontEnd )
				)
				( attribute "PART_NUMBER" "G85996-004"
					( Origin gFrontEnd )
				)
				( attribute "PHYS_PAGE" "234"
					( Origin gFrontEnd )
				)
				( attribute "REUSE_ID" "9"
					( Origin gFrontEnd )
				)
				( attribute "ROOM" "PVPP_KLM_VR"
					( Origin gFrontEnd )
				)
				( attribute "ROT" "0"
					( Origin gFrontEnd )
				)
				( attribute "SEC" "1"
					( Origin gFrontEnd )
				)
				( attribute "SEC_TYPE" "0402"
					( Origin gFrontEnd )
				)
				( attribute "SPOF" "TRUE"
					( Origin gFrontEnd )
				)
				( attribute "TOLERANCE" "0.1%"
					( Origin gFrontEnd )
				)
				( attribute "VALUE" "1.0K"
					( Origin gFrontEnd )
				)
				( attribute "VER" "2"
					( Origin gFrontEnd )
				)
				( attribute "WATTAGE" "1/16W"
					( Origin gFrontEnd )
				)
				( attribute "XY" "(-1025,2750)"
					( Origin gFrontEnd )
				)
				( attribute "CHIPS_PART_NAME" "RES"
					( Origin gPackager )
				)
				( attribute "CDS_PART_NAME" "RES_0402-1.0K,0.1%,1/16W,CHIP,A"
					( Origin gPackager )
				)
				( objectStatus "R4B9" )
			)
			( gate "@baseboard_fab2_lib.baseboard_fab2(sch_1):page234_i220"
				( attribute "CDS_LIB" "mstr_discrete"
					( Origin gPackager )
				)
				( attribute "CDS_LOCATION" "R4B1"
					( Origin gPackager )
				)
				( attribute "LOCATION" "R4B1"
					( Origin gFrontEnd )
				)
				( attribute "MATERIAL" "CHIP"
					( Origin gFrontEnd )
				)
				( attribute "PACK_TYPE" "0402"
					( Origin gFrontEnd )
				)
				( attribute "PART_NUMBER" "G21497-005"
					( Origin gFrontEnd )
				)
				( attribute "PHYS_PAGE" "234"
					( Origin gFrontEnd )
				)
				( attribute "ROOM" "PVCCIN_CPU0_VR"
					( Origin gFrontEnd )
				)
				( attribute "ROT" "0"
					( Origin gFrontEnd )
				)
				( attribute "SEC" "1"
					( Origin gFrontEnd )
				)
				( attribute "TOLERANCE" "5%"
					( Origin gFrontEnd )
				)
				( attribute "VALUE" "0.0"
					( Origin gFrontEnd )
				)
				( attribute "VER" "1"
					( Origin gFrontEnd )
				)
				( attribute "WATTAGE" "1/16W"
					( Origin gFrontEnd )
				)
				( attribute "XY" "(-5925,2825)"
					( Origin gFrontEnd )
				)
				( attribute "CHIPS_PART_NAME" "RES"
					( Origin gPackager )
				)
				( attribute "CDS_PART_NAME" "RES_0402-0.0,5%,1/16W,CHIP,G21A"
					( Origin gPackager )
				)
				( attribute "SEC_TYPE" "0402"
					( Origin gFrontEnd )
				)
				( attribute "CDS_SEC" "1"
					( Origin gPackager )
				)
				( objectStatus "R4B1" )
			)
			( gate "@baseboard_fab2_lib.baseboard_fab2(sch_1):page235_i143"
				( attribute "CDS_LIB" "dev_discrete"
					( Origin gPackager )
				)
				( attribute "CDS_LOCATION" "C8A7"
					( Origin gPackager )
				)
				( attribute "CDS_SEC" "1"
					( Origin gPackager )
				)
				( attribute "LOCATION" "C8A7"
					( Origin gFrontEnd )
				)
				( attribute "MATERIAL" "X6S"
					( Origin gFrontEnd )
				)
				( attribute "PACK_TYPE" "0402V"
					( Origin gFrontEnd )
				)
				( attribute "PART_NUMBER" "D97712-004"
					( Origin gFrontEnd )
				)
				( attribute "PHYS_PAGE" "235"
					( Origin gFrontEnd )
				)
				( attribute "ROOM" "PVNN_PCH_STBY"
					( Origin gFrontEnd )
				)
				( attribute "ROT" "0"
					( Origin gFrontEnd )
				)
				( attribute "SEC" "1"
					( Origin gFrontEnd )
				)
				( attribute "SEC_TYPE" "0402V"
					( Origin gFrontEnd )
				)
				( attribute "TOLERANCE" "10%"
					( Origin gFrontEnd )
				)
				( attribute "VALUE" "1.0UF"
					( Origin gFrontEnd )
				)
				( attribute "VER" "1"
					( Origin gFrontEnd )
				)
				( attribute "VOLTAGE" "6.3V"
					( Units "uVoltage" "V" 1.000000)
					( Origin gFrontEnd )
				)
				( attribute "XY" "(-8800,1975)"
					( Origin gFrontEnd )
				)
				( attribute "CHIPS_PART_NAME" "CAP_A"
					( Origin gPackager )
				)
				( attribute "CDS_PART_NAME" "CAP_A_0402V-1.0UF,6.3V,10%,X6SA"
					( Origin gPackager )
				)
				( objectStatus "C8A7" )
			)
			( gate "@baseboard_fab2_lib.baseboard_fab2(sch_1):page235_i145"
				( attribute "CDS_LIB" "dev_discrete"
					( Origin gPackager )
				)
				( attribute "CDS_LOCATION" "C8A8"
					( Origin gPackager )
				)
				( attribute "CDS_SEC" "1"
					( Origin gPackager )
				)
				( attribute "LOCATION" "C8A8"
					( Origin gFrontEnd )
				)
				( attribute "MATERIAL" "X7R"
					( Origin gFrontEnd )
				)
				( attribute "PACK_TYPE" "0402V"
					( Origin gFrontEnd )
				)
				( attribute "PART_NUMBER" "A36096-030"
					( Origin gFrontEnd )
				)
				( attribute "PHYS_PAGE" "235"
					( Origin gFrontEnd )
				)
				( attribute "ROOM" "PVNN_PCH_STBY"
					( Origin gFrontEnd )
				)
				( attribute "ROT" "0"
					( Origin gFrontEnd )
				)
				( attribute "SEC" "1"
					( Origin gFrontEnd )
				)
				( attribute "SEC_TYPE" "0402V"
					( Origin gFrontEnd )
				)
				( attribute "TOLERANCE" "10%"
					( Origin gFrontEnd )
				)
				( attribute "VALUE" "0.1UF"
					( Origin gFrontEnd )
				)
				( attribute "VER" "1"
					( Origin gFrontEnd )
				)
				( attribute "VOLTAGE" "16V"
					( Units "uVoltage" "V" 1.000000)
					( Origin gFrontEnd )
				)
				( attribute "XY" "(-9200,1975)"
					( Origin gFrontEnd )
				)
				( attribute "CHIPS_PART_NAME" "CAP_A"
					( Origin gPackager )
				)
				( attribute "CDS_PART_NAME" "CAP_A_0402V-0.1UF,16V,10%,X7R,A"
					( Origin gPackager )
				)
				( objectStatus "C8A8" )
			)
			( gate "@baseboard_fab2_lib.baseboard_fab2(sch_1):page235_i147"
				( attribute "CDS_LIB" "mstr_discrete"
					( Origin gPackager )
				)
				( attribute "CDS_LOCATION" "R2L16"
					( Origin gPackager )
				)
				( attribute "CDS_SEC" "1"
					( Origin gPackager )
				)
				( attribute "LOCATION" "R2L16"
					( Origin gFrontEnd )
				)
				( attribute "MATERIAL" "CHIP"
					( Origin gFrontEnd )
				)
				( attribute "PACK_TYPE" "0402"
					( Origin gFrontEnd )
				)
				( attribute "PART_NUMBER" "G21796-250"
					( Origin gFrontEnd )
				)
				( attribute "PHYS_PAGE" "235"
					( Origin gFrontEnd )
				)
				( attribute "ROOM" "PVNN_PCH_STBY"
					( Origin gFrontEnd )
				)
				( attribute "ROT" "0"
					( Origin gFrontEnd )
				)
				( attribute "SEC" "1"
					( Origin gFrontEnd )
				)
				( attribute "SEC_TYPE" "0402"
					( Origin gFrontEnd )
				)
				( attribute "TOLERANCE" "1.0%"
					( Origin gFrontEnd )
				)
				( attribute "VALUE" "22.1"
					( Origin gFrontEnd )
				)
				( attribute "VER" "1"
					( Origin gFrontEnd )
				)
				( attribute "WATTAGE" "1/16W"
					( Origin gFrontEnd )
				)
				( attribute "XY" "(-7100,4500)"
					( Origin gFrontEnd )
				)
				( attribute "CHIPS_PART_NAME" "RES"
					( Origin gPackager )
				)
				( attribute "CDS_PART_NAME" "RES_0402-22.1,1.0%,1/16W,CHIP,A"
					( Origin gPackager )
				)
				( objectStatus "R2L16" )
			)
			( gate "@baseboard_fab2_lib.baseboard_fab2(sch_1):page235_i148"
				( attribute "CDS_LIB" "mstr_discrete"
					( Origin gPackager )
				)
				( attribute "CDS_LOCATION" "R2L24"
					( Origin gPackager )
				)
				( attribute "CDS_SEC" "1"
					( Origin gPackager )
				)
				( attribute "LOCATION" "R2L24"
					( Origin gFrontEnd )
				)
				( attribute "MATERIAL" "EMPTY"
					( Origin gFrontEnd )
				)
				( attribute "PACK_TYPE" "0402"
					( Origin gFrontEnd )
				)
				( attribute "PART_NUMBER" "G21796-311"
					( Origin gFrontEnd )
				)
				( attribute "PHYS_PAGE" "235"
					( Origin gFrontEnd )
				)
				( attribute "ROOM" "PVNN_PCH_STBY"
					( Origin gFrontEnd )
				)
				( attribute "ROT" "0"
					( Origin gFrontEnd )
				)
				( attribute "SEC" "1"
					( Origin gFrontEnd )
				)
				( attribute "SEC_TYPE" "0402"
					( Origin gFrontEnd )
				)
				( attribute "TOLERANCE" "1.0%"
					( Origin gFrontEnd )
				)
				( attribute "VALUE" "2.26K"
					( Origin gFrontEnd )
				)
				( attribute "VER" "2"
					( Origin gFrontEnd )
				)
				( attribute "WATTAGE" "1/16W"
					( Origin gFrontEnd )
				)
				( attribute "XY" "(-8400,4950)"
					( Origin gFrontEnd )
				)
				( attribute "CHIPS_PART_NAME" "RES"
					( Origin gPackager )
				)
				( attribute "CDS_PART_NAME" "RES_0402-2.26K,1.0%,1/16W,EMPTA"
					( Origin gPackager )
				)
				( objectStatus "R2L24" )
			)
			( gate "@baseboard_fab2_lib.baseboard_fab2(sch_1):page235_i149"
				( attribute "CDS_LIB" "mstr_discrete"
					( Origin gPackager )
				)
				( attribute "CDS_LOCATION" "R8A6"
					( Origin gPackager )
				)
				( attribute "CDS_SEC" "1"
					( Origin gPackager )
				)
				( attribute "LOCATION" "R8A6"
					( Origin gFrontEnd )
				)
				( attribute "MATERIAL" "CHIP"
					( Origin gFrontEnd )
				)
				( attribute "PACK_TYPE" "0402"
					( Origin gFrontEnd )
				)
				( attribute "PART_NUMBER" "G21796-026"
					( Origin gFrontEnd )
				)
				( attribute "PHYS_PAGE" "235"
					( Origin gFrontEnd )
				)
				( attribute "ROOM" "PVNN_PCH_STBY"
					( Origin gFrontEnd )
				)
				( attribute "ROT" "0"
					( Origin gFrontEnd )
				)
				( attribute "SEC" "1"
					( Origin gFrontEnd )
				)
				( attribute "SEC_TYPE" "0402"
					( Origin gFrontEnd )
				)
				( attribute "TOLERANCE" "1%"
					( Origin gFrontEnd )
				)
				( attribute "VALUE" "1.00K"
					( Origin gFrontEnd )
				)
				( attribute "VER" "2"
					( Origin gFrontEnd )
				)
				( attribute "WATTAGE" "1/16W"
					( Origin gFrontEnd )
				)
				( attribute "XY" "(-9100,4950)"
					( Origin gFrontEnd )
				)
				( attribute "CHIPS_PART_NAME" "RES"
					( Origin gPackager )
				)
				( attribute "CDS_PART_NAME" "RES_0402-1.00K,1%,1/16W,CHIP,GA"
					( Origin gPackager )
				)
				( objectStatus "R8A6" )
			)
			( gate "@baseboard_fab2_lib.baseboard_fab2(sch_1):page235_i151"
				( attribute "CDS_LIB" "dev_discrete"
					( Origin gPackager )
				)
				( attribute "CDS_LOCATION" "C2L8"
					( Origin gPackager )
				)
				( attribute "CDS_SEC" "1"
					( Origin gPackager )
				)
				( attribute "LOCATION" "C2L8"
					( Origin gFrontEnd )
				)
				( attribute "MATERIAL" "X6S"
					( Origin gFrontEnd )
				)
				( attribute "PACK_TYPE" "0402V"
					( Origin gFrontEnd )
				)
				( attribute "PART_NUMBER" "D97712-004"
					( Origin gFrontEnd )
				)
				( attribute "PHYS_PAGE" "235"
					( Origin gFrontEnd )
				)
				( attribute "ROOM" "PVNN_PCH_STBY"
					( Origin gFrontEnd )
				)
				( attribute "ROT" "0"
					( Origin gFrontEnd )
				)
				( attribute "SEC" "1"
					( Origin gFrontEnd )
				)
				( attribute "SEC_TYPE" "0402V"
					( Origin gFrontEnd )
				)
				( attribute "TOLERANCE" "10%"
					( Origin gFrontEnd )
				)
				( attribute "VALUE" "1.0UF"
					( Origin gFrontEnd )
				)
				( attribute "VER" "1"
					( Origin gFrontEnd )
				)
				( attribute "VOLTAGE" "6.3V"
					( Units "uVoltage" "V" 1.000000)
					( Origin gFrontEnd )
				)
				( attribute "XY" "(-9750,5075)"
					( Origin gFrontEnd )
				)
				( attribute "CHIPS_PART_NAME" "CAP_A"
					( Origin gPackager )
				)
				( attribute "CDS_PART_NAME" "CAP_A_0402V-1.0UF,6.3V,10%,X6SA"
					( Origin gPackager )
				)
				( objectStatus "C2L8" )
			)
			( gate "@baseboard_fab2_lib.baseboard_fab2(sch_1):page235_i153"
				( attribute "CDS_LIB" "mstr_discrete"
					( Origin gPackager )
				)
				( attribute "CDS_LOCATION" "C2L2"
					( Origin gPackager )
				)
				( attribute "CDS_SEC" "1"
					( Origin gPackager )
				)
				( attribute "LOCATION" "C2L2"
					( Origin gFrontEnd )
				)
				( attribute "MATERIAL" "X7R"
					( Origin gFrontEnd )
				)
				( attribute "NO_XNET_CONNECTION" "1"
					( Origin gFrontEnd )
				)
				( attribute "PACK_TYPE" "0402LF"
					( Origin gFrontEnd )
				)
				( attribute "PART_NUMBER" "A36096-050"
					( Origin gFrontEnd )
				)
				( attribute "PHYS_PAGE" "235"
					( Origin gFrontEnd )
				)
				( attribute "ROOM" "PVNN_PCH_STBY"
					( Origin gFrontEnd )
				)
				( attribute "ROT" "0"
					( Origin gFrontEnd )
				)
				( attribute "SEC" "1"
					( Origin gFrontEnd )
				)
				( attribute "SEC_TYPE" "0402LF"
					( Origin gFrontEnd )
				)
				( attribute "TOLERANCE" "10%"
					( Origin gFrontEnd )
				)
				( attribute "VALUE" "220PF"
					( Origin gFrontEnd )
				)
				( attribute "VER" "1"
					( Origin gFrontEnd )
				)
				( attribute "VOLTAGE" "50V"
					( Units "uVoltage" "V" 1.000000)
					( Origin gFrontEnd )
				)
				( attribute "XY" "(-12475,2075)"
					( Origin gFrontEnd )
				)
				( attribute "CHIPS_PART_NAME" "CAP"
					( Origin gPackager )
				)
				( attribute "CDS_PART_NAME" "CAP_0402LF-220PF,50V,10%,X7R,AA"
					( Origin gPackager )
				)
				( objectStatus "C2L2" )
			)
			( gate "@baseboard_fab2_lib.baseboard_fab2(sch_1):page235_i154"
				( attribute "CDS_LIB" "mstr_discrete"
					( Origin gPackager )
				)
				( attribute "CDS_LOCATION" "R2L8"
					( Origin gPackager )
				)
				( attribute "CDS_SEC" "1"
					( Origin gPackager )
				)
				( attribute "LOCATION" "R2L8"
					( Origin gFrontEnd )
				)
				( attribute "MATERIAL" "CHIP"
					( Origin gFrontEnd )
				)
				( attribute "PACK_TYPE" "0603"
					( Origin gFrontEnd )
				)
				( attribute "PART_NUMBER" "G22026-041"
					( Origin gFrontEnd )
				)
				( attribute "PHYS_PAGE" "235"
					( Origin gFrontEnd )
				)
				( attribute "ROOM" "PVNN_PCH_STBY"
					( Origin gFrontEnd )
				)
				( attribute "ROT" "0"
					( Origin gFrontEnd )
				)
				( attribute "SEC" "1"
					( Origin gFrontEnd )
				)
				( attribute "SEC_TYPE" "0603"
					( Origin gFrontEnd )
				)
				( attribute "TOLERANCE" "1%"
					( Origin gFrontEnd )
				)
				( attribute "VALUE" "10.0"
					( Origin gFrontEnd )
				)
				( attribute "VER" "1"
					( Origin gFrontEnd )
				)
				( attribute "WATTAGE" "1/10W"
					( Origin gFrontEnd )
				)
				( attribute "XY" "(-12675,2225)"
					( Origin gFrontEnd )
				)
				( attribute "CHIPS_PART_NAME" "RES"
					( Origin gPackager )
				)
				( attribute "CDS_PART_NAME" "RES_0603-10.0,1%,1/10W,CHIP,G2A"
					( Origin gPackager )
				)
				( objectStatus "R2L8" )
			)
			( gate "@baseboard_fab2_lib.baseboard_fab2(sch_1):page235_i159"
				( attribute "CDS_LIB" "mstr_discrete"
					( Origin gPackager )
				)
				( attribute "CDS_LOCATION" "R2L14"
					( Origin gPackager )
				)
				( attribute "CDS_SEC" "1"
					( Origin gPackager )
				)
				( attribute "LOCATION" "R2L14"
					( Origin gFrontEnd )
				)
				( attribute "MATERIAL" "CHIP"
					( Origin gFrontEnd )
				)
				( attribute "PACK_TYPE" "0402"
					( Origin gFrontEnd )
				)
				( attribute "PART_NUMBER" "G21497-005"
					( Origin gFrontEnd )
				)
				( attribute "PHYS_PAGE" "235"
					( Origin gFrontEnd )
				)
				( attribute "ROOM" "PVNN_PCH_STBY"
					( Origin gFrontEnd )
				)
				( attribute "ROT" "0"
					( Origin gFrontEnd )
				)
				( attribute "SEC" "1"
					( Origin gFrontEnd )
				)
				( attribute "SEC_TYPE" "0402"
					( Origin gFrontEnd )
				)
				( attribute "TOLERANCE" "5%"
					( Origin gFrontEnd )
				)
				( attribute "VALUE" "0.0"
					( Origin gFrontEnd )
				)
				( attribute "VER" "2"
					( Origin gFrontEnd )
				)
				( attribute "WATTAGE" "1/16W"
					( Origin gFrontEnd )
				)
				( attribute "XY" "(-10450,5425)"
					( Origin gFrontEnd )
				)
				( attribute "CHIPS_PART_NAME" "RES"
					( Origin gPackager )
				)
				( attribute "CDS_PART_NAME" "RES_0402-0.0,5%,1/16W,CHIP,G21A"
					( Origin gPackager )
				)
				( objectStatus "R2L14" )
			)
			( gate "@baseboard_fab2_lib.baseboard_fab2(sch_1):page235_i165"
				( attribute "CDS_LIB" "mstr_discrete"
					( Origin gPackager )
				)
				( attribute "CDS_LOCATION" "R8A4"
					( Origin gPackager )
				)
				( attribute "CDS_SEC" "1"
					( Origin gPackager )
				)
				( attribute "LOCATION" "R8A4"
					( Origin gFrontEnd )
				)
				( attribute "MATERIAL" "CHIP"
					( Origin gFrontEnd )
				)
				( attribute "PACK_TYPE" "0402"
					( Origin gFrontEnd )
				)
				( attribute "PART_NUMBER" "G21796-160"
					( Origin gFrontEnd )
				)
				( attribute "PHYS_PAGE" "235"
					( Origin gFrontEnd )
				)
				( attribute "ROOM" "PVNN_PCH_STBY"
					( Origin gFrontEnd )
				)
				( attribute "ROT" "0"
					( Origin gFrontEnd )
				)
				( attribute "SEC" "1"
					( Origin gFrontEnd )
				)
				( attribute "SEC_TYPE" "0402"
					( Origin gFrontEnd )
				)
				( attribute "TOLERANCE" "1%"
					( Origin gFrontEnd )
				)
				( attribute "VALUE" "100.0K"
					( Origin gFrontEnd )
				)
				( attribute "VER" "2"
					( Origin gFrontEnd )
				)
				( attribute "WATTAGE" "1/16W"
					( Origin gFrontEnd )
				)
				( attribute "XY" "(-12325,5500)"
					( Origin gFrontEnd )
				)
				( attribute "CHIPS_PART_NAME" "RES"
					( Origin gPackager )
				)
				( attribute "CDS_PART_NAME" "RES_0402-100.0K,1%,1/16W,CHIP,B"
					( Origin gPackager )
				)
				( objectStatus "R8A4" )
			)
			( gate "@baseboard_fab2_lib.baseboard_fab2(sch_1):page235_i166"
				( attribute "CDS_LIB" "mstr_discrete"
					( Origin gPackager )
				)
				( attribute "CDS_LOCATION" "R2L10"
					( Origin gPackager )
				)
				( attribute "CDS_SEC" "1"
					( Origin gPackager )
				)
				( attribute "LOCATION" "R2L10"
					( Origin gFrontEnd )
				)
				( attribute "MATERIAL" "CHIP"
					( Origin gFrontEnd )
				)
				( attribute "PACK_TYPE" "0402"
					( Origin gFrontEnd )
				)
				( attribute "PART_NUMBER" "G21796-003"
					( Origin gFrontEnd )
				)
				( attribute "PHYS_PAGE" "235"
					( Origin gFrontEnd )
				)
				( attribute "ROOM" "PVNN_PCH_STBY"
					( Origin gFrontEnd )
				)
				( attribute "ROT" "0"
					( Origin gFrontEnd )
				)
				( attribute "SEC" "1"
					( Origin gFrontEnd )
				)
				( attribute "SEC_TYPE" "0402"
					( Origin gFrontEnd )
				)
				( attribute "TOLERANCE" "1%"
					( Origin gFrontEnd )
				)
				( attribute "VALUE" "1.5K"
					( Origin gFrontEnd )
				)
				( attribute "VER" "2"
					( Origin gFrontEnd )
				)
				( attribute "WATTAGE" "1/16W"
					( Origin gFrontEnd )
				)
				( attribute "XY" "(-12325,5175)"
					( Origin gFrontEnd )
				)
				( attribute "CHIPS_PART_NAME" "RES"
					( Origin gPackager )
				)
				( attribute "CDS_PART_NAME" "RES_0402-1.5K,1%,1/16W,CHIP,G2A"
					( Origin gPackager )
				)
				( objectStatus "R2L10" )
			)
			( gate "@baseboard_fab2_lib.baseboard_fab2(sch_1):page235_i169"
				( attribute "CDS_LIB" "dev_discrete"
					( Origin gPackager )
				)
				( attribute "CDS_LOCATION" "C2L11"
					( Origin gPackager )
				)
				( attribute "CDS_SEC" "1"
					( Origin gPackager )
				)
				( attribute "LOCATION" "C2L11"
					( Origin gFrontEnd )
				)
				( attribute "MATERIAL" "X7R"
					( Origin gFrontEnd )
				)
				( attribute "PACK_TYPE" "0402V"
					( Origin gFrontEnd )
				)
				( attribute "PART_NUMBER" "A36096-030"
					( Origin gFrontEnd )
				)
				( attribute "PHYS_PAGE" "235"
					( Origin gFrontEnd )
				)
				( attribute "ROOM" "PVNN_PCH_STBY"
					( Origin gFrontEnd )
				)
				( attribute "ROT" "0"
					( Origin gFrontEnd )
				)
				( attribute "SEC" "1"
					( Origin gFrontEnd )
				)
				( attribute "SEC_TYPE" "0402V"
					( Origin gFrontEnd )
				)
				( attribute "TOLERANCE" "10%"
					( Origin gFrontEnd )
				)
				( attribute "VALUE" "0.1UF"
					( Origin gFrontEnd )
				)
				( attribute "VER" "1"
					( Origin gFrontEnd )
				)
				( attribute "VOLTAGE" "16V"
					( Units "uVoltage" "V" 1.000000)
					( Origin gFrontEnd )
				)
				( attribute "XY" "(-10150,5075)"
					( Origin gFrontEnd )
				)
				( attribute "CHIPS_PART_NAME" "CAP_A"
					( Origin gPackager )
				)
				( attribute "CDS_PART_NAME" "CAP_A_0402V-0.1UF,16V,10%,X7R,A"
					( Origin gPackager )
				)
				( objectStatus "C2L11" )
			)
			( gate "@baseboard_fab2_lib.baseboard_fab2(sch_1):page235_i209"
				( attribute "CDS_LIB" "mstr_discrete"
					( Origin gPackager )
				)
				( attribute "CDS_LOCATION" "C8A2"
					( Origin gPackager )
				)
				( attribute "CDS_SEC" "1"
					( Origin gPackager )
				)
				( attribute "LOCATION" "C8A2"
					( Origin gFrontEnd )
				)
				( attribute "MATERIAL" "X7R"
					( Origin gFrontEnd )
				)
				( attribute "NO_XNET_CONNECTION" "1"
					( Origin gFrontEnd )
				)
				( attribute "PACK_TYPE" "0402LF"
					( Origin gFrontEnd )
				)
				( attribute "PART_NUMBER" "A36096-050"
					( Origin gFrontEnd )
				)
				( attribute "PHYS_PAGE" "235"
					( Origin gFrontEnd )
				)
				( attribute "ROOM" "PVNN_PCH_STBY"
					( Origin gFrontEnd )
				)
				( attribute "ROT" "0"
					( Origin gFrontEnd )
				)
				( attribute "SEC" "1"
					( Origin gFrontEnd )
				)
				( attribute "SEC_TYPE" "0402LF"
					( Origin gFrontEnd )
				)
				( attribute "TOLERANCE" "10%"
					( Origin gFrontEnd )
				)
				( attribute "VALUE" "220PF"
					( Origin gFrontEnd )
				)
				( attribute "VER" "1"
					( Origin gFrontEnd )
				)
				( attribute "VOLTAGE" "50V"
					( Units "uVoltage" "V" 1.000000)
					( Origin gFrontEnd )
				)
				( attribute "XY" "(-12375,2600)"
					( Origin gFrontEnd )
				)
				( attribute "CHIPS_PART_NAME" "CAP"
					( Origin gPackager )
				)
				( attribute "CDS_PART_NAME" "CAP_0402LF-220PF,50V,10%,X7R,AA"
					( Origin gPackager )
				)
				( objectStatus "C8A2" )
			)
			( gate "@baseboard_fab2_lib.baseboard_fab2(sch_1):page235_i210"
				( attribute "CDS_LIB" "mstr_discrete"
					( Origin gPackager )
				)
				( attribute "CDS_LOCATION" "R8A1"
					( Origin gPackager )
				)
				( attribute "CDS_SEC" "1"
					( Origin gPackager )
				)
				( attribute "LOCATION" "R8A1"
					( Origin gFrontEnd )
				)
				( attribute "MATERIAL" "CHIP"
					( Origin gFrontEnd )
				)
				( attribute "NO_XNET_CONNECTION" "1"
					( Origin gFrontEnd )
				)
				( attribute "PACK_TYPE" "0402"
					( Origin gFrontEnd )
				)
				( attribute "PART_NUMBER" "G21796-066"
					( Origin gFrontEnd )
				)
				( attribute "PHYS_PAGE" "235"
					( Origin gFrontEnd )
				)
				( attribute "ROOM" "PVNN_PCH_STBY"
					( Origin gFrontEnd )
				)
				( attribute "ROT" "0"
					( Origin gFrontEnd )
				)
				( attribute "SEC" "1"
					( Origin gFrontEnd )
				)
				( attribute "SEC_TYPE" "0402"
					( Origin gFrontEnd )
				)
				( attribute "TOLERANCE" "1%"
					( Origin gFrontEnd )
				)
				( attribute "VALUE" "10.0"
					( Origin gFrontEnd )
				)
				( attribute "VER" "1"
					( Origin gFrontEnd )
				)
				( attribute "WATTAGE" "1/16W"
					( Origin gFrontEnd )
				)
				( attribute "XY" "(-12675,2750)"
					( Origin gFrontEnd )
				)
				( attribute "CHIPS_PART_NAME" "RES"
					( Origin gPackager )
				)
				( attribute "CDS_PART_NAME" "RES_0402-10.0,1%,1/16W,CHIP,G2A"
					( Origin gPackager )
				)
				( objectStatus "R8A1" )
			)
			( gate "@baseboard_fab2_lib.baseboard_fab2(sch_1):page235_i216"
				( attribute "CDS_LIB" "mstr_discrete"
					( Origin gPackager )
				)
				( attribute "CDS_LOCATION" "R8A5"
					( Origin gPackager )
				)
				( attribute "LOCATION" "R8A5"
					( Origin gFrontEnd )
				)
				( attribute "MATERIAL" "CHIP"
					( Origin gFrontEnd )
				)
				( attribute "PACK_TYPE" "0402"
					( Origin gFrontEnd )
				)
				( attribute "PART_NUMBER" "G21796-026"
					( Origin gFrontEnd )
				)
				( attribute "PHYS_PAGE" "235"
					( Origin gFrontEnd )
				)
				( attribute "ROT" "0"
					( Origin gFrontEnd )
				)
				( attribute "SEC" "1"
					( Origin gFrontEnd )
				)
				( attribute "TOLERANCE" "1%"
					( Origin gFrontEnd )
				)
				( attribute "VALUE" "1.00K"
					( Origin gFrontEnd )
				)
				( attribute "VER" "2"
					( Origin gFrontEnd )
				)
				( attribute "WATTAGE" "1/16W"
					( Origin gFrontEnd )
				)
				( attribute "XY" "(-8075,4950)"
					( Origin gFrontEnd )
				)
				( attribute "CHIPS_PART_NAME" "RES"
					( Origin gPackager )
				)
				( attribute "CDS_PART_NAME" "RES_0402-1.00K,1%,1/16W,CHIP,GA"
					( Origin gPackager )
				)
				( attribute "SEC_TYPE" "0402"
					( Origin gFrontEnd )
				)
				( attribute "CDS_SEC" "1"
					( Origin gPackager )
				)
				( objectStatus "R8A5" )
			)
			( gate "@baseboard_fab2_lib.baseboard_fab2(sch_1):page235_i217"
				( attribute "CDS_LIB" "mstr_discrete"
					( Origin gPackager )
				)
				( attribute "CDS_LOCATION" "R8A2"
					( Origin gPackager )
				)
				( attribute "LOCATION" "R8A2"
					( Origin gFrontEnd )
				)
				( attribute "MATERIAL" "CHIP"
					( Origin gFrontEnd )
				)
				( attribute "PACK_TYPE" "0402"
					( Origin gFrontEnd )
				)
				( attribute "PART_NUMBER" "G21796-180"
					( Origin gFrontEnd )
				)
				( attribute "PHYS_PAGE" "235"
					( Origin gFrontEnd )
				)
				( attribute "ROT" "0"
					( Origin gFrontEnd )
				)
				( attribute "SEC" "1"
					( Origin gFrontEnd )
				)
				( attribute "TOLERANCE" "1%"
					( Origin gFrontEnd )
				)
				( attribute "VALUE" "2.67K"
					( Origin gFrontEnd )
				)
				( attribute "VER" "2"
					( Origin gFrontEnd )
				)
				( attribute "WATTAGE" "1/16W"
					( Origin gFrontEnd )
				)
				( attribute "XY" "(-10450,2150)"
					( Origin gFrontEnd )
				)
				( attribute "CHIPS_PART_NAME" "RES"
					( Origin gPackager )
				)
				( attribute "CDS_PART_NAME" "RES_0402-2.67K,1%,1/16W,CHIP,GA"
					( Origin gPackager )
				)
				( attribute "SEC_TYPE" "0402"
					( Origin gFrontEnd )
				)
				( attribute "CDS_SEC" "1"
					( Origin gPackager )
				)
				( objectStatus "R8A2" )
			)
			( gate "@baseboard_fab2_lib.baseboard_fab2(sch_1):page235_i218"
				( attribute "CDS_LIB" "mstr_discrete"
					( Origin gPackager )
				)
				( attribute "CDS_LOCATION" "C8A9"
					( Origin gPackager )
				)
				( attribute "CDS_SEC" "1"
					( Origin gPackager )
				)
				( attribute "LOCATION" "C8A9"
					( Origin gFrontEnd )
				)
				( attribute "MATERIAL" "X7R"
					( Origin gFrontEnd )
				)
				( attribute "PACK_TYPE" "0402LF"
					( Origin gFrontEnd )
				)
				( attribute "PART_NUMBER" "A36096-046"
					( Origin gFrontEnd )
				)
				( attribute "PHYS_PAGE" "235"
					( Origin gFrontEnd )
				)
				( attribute "ROOM" "PVNN_PCH_STBY"
					( Origin gFrontEnd )
				)
				( attribute "ROT" "0"
					( Origin gFrontEnd )
				)
				( attribute "SEC" "1"
					( Origin gFrontEnd )
				)
				( attribute "SEC_TYPE" "0402LF"
					( Origin gFrontEnd )
				)
				( attribute "TOLERANCE" "10%"
					( Origin gFrontEnd )
				)
				( attribute "VALUE" "1000PF"
					( Origin gFrontEnd )
				)
				( attribute "VER" "1"
					( Origin gFrontEnd )
				)
				( attribute "VOLTAGE" "50V"
					( Units "uVoltage" "V" 1.000000)
					( Origin gFrontEnd )
				)
				( attribute "XY" "(-8000,4325)"
					( Origin gFrontEnd )
				)
				( attribute "CHIPS_PART_NAME" "CAP"
					( Origin gPackager )
				)
				( attribute "CDS_PART_NAME" "CAP_0402LF-1000PF,50V,10%,X7R,A"
					( Origin gPackager )
				)
				( objectStatus "C8A9" )
			)
			( gate "@baseboard_fab2_lib.baseboard_fab2(sch_1):page235_i221"
				( attribute "CDS_LIB" "mstr_discrete"
					( Origin gPackager )
				)
				( attribute "CDS_LOCATION" "R2L17"
					( Origin gPackager )
				)
				( attribute "CDS_SEC" "1"
					( Origin gPackager )
				)
				( attribute "LOCATION" "R2L17"
					( Origin gFrontEnd )
				)
				( attribute "MATERIAL" "CHIP"
					( Origin gFrontEnd )
				)
				( attribute "PACK_TYPE" "0402"
					( Origin gFrontEnd )
				)
				( attribute "PART_NUMBER" "G21497-005"
					( Origin gFrontEnd )
				)
				( attribute "PHYS_PAGE" "235"
					( Origin gFrontEnd )
				)
				( attribute "ROOM" "PVCCIN_CPU0_VR"
					( Origin gFrontEnd )
				)
				( attribute "ROT" "0"
					( Origin gFrontEnd )
				)
				( attribute "SEC" "1"
					( Origin gFrontEnd )
				)
				( attribute "SEC_TYPE" "0402"
					( Origin gFrontEnd )
				)
				( attribute "TOLERANCE" "5%"
					( Origin gFrontEnd )
				)
				( attribute "VALUE" "0.0"
					( Origin gFrontEnd )
				)
				( attribute "VER" "1"
					( Origin gFrontEnd )
				)
				( attribute "WATTAGE" "1/16W"
					( Origin gFrontEnd )
				)
				( attribute "XY" "(-11800,4150)"
					( Origin gFrontEnd )
				)
				( attribute "CHIPS_PART_NAME" "RES"
					( Origin gPackager )
				)
				( attribute "CDS_PART_NAME" "RES_0402-0.0,5%,1/16W,CHIP,G21A"
					( Origin gPackager )
				)
				( objectStatus "R2L17" )
			)
			( gate "@baseboard_fab2_lib.baseboard_fab2(sch_1):page235_i222"
				( attribute "BOM_COST" "SM_CONTROLLER"
					( Origin gFrontEnd )
				)
				( attribute "CDS_LIB" "mstr_discrete"
					( Origin gPackager )
				)
				( attribute "CDS_LOCATION" "R8A7"
					( Origin gPackager )
				)
				( attribute "CDS_SEC" "1"
					( Origin gPackager )
				)
				( attribute "LOCATION" "R8A7"
					( Origin gFrontEnd )
				)
				( attribute "MATERIAL" "EMPTY"
					( Origin gFrontEnd )
				)
				( attribute "PACK_TYPE" "0402"
					( Origin gFrontEnd )
				)
				( attribute "PART_NUMBER" "G21796-010"
					( Origin gFrontEnd )
				)
				( attribute "PHYS_PAGE" "235"
					( Origin gFrontEnd )
				)
				( attribute "ROOM" "BMC"
					( Origin gFrontEnd )
				)
				( attribute "ROT" "0"
					( Origin gFrontEnd )
				)
				( attribute "SEC" "1"
					( Origin gFrontEnd )
				)
				( attribute "SEC_TYPE" "0402"
					( Origin gFrontEnd )
				)
				( attribute "TOLERANCE" "1%"
					( Origin gFrontEnd )
				)
				( attribute "VALUE" "100.0K"
					( Origin gFrontEnd )
				)
				( attribute "VER" "2"
					( Origin gFrontEnd )
				)
				( attribute "WATTAGE" "1/16W"
					( Origin gFrontEnd )
				)
				( attribute "XY" "(-11175,5075)"
					( Origin gFrontEnd )
				)
				( attribute "CHIPS_PART_NAME" "RES"
					( Origin gPackager )
				)
				( attribute "CDS_PART_NAME" "RES_0402-100.0K,1%,1/16W,EMPTYA"
					( Origin gPackager )
				)
				( objectStatus "R8A7" )
			)
			( gate "@baseboard_fab2_lib.baseboard_fab2(sch_1):page235_i229"
				( attribute "CDS_LIB" "mstr_controller"
					( Origin gPackager )
				)
				( attribute "CDS_LMAN_SYM_OUTLINE" "-400,850,400,-850"
					( Origin gPackager )
				)
				( attribute "CDS_LOCATION" "EU8A1"
					( Origin gPackager )
				)
				( attribute "CDS_SEC" "1"
					( Origin gPackager )
				)
				( attribute "LOCATION" "EU8A1"
					( Origin gFrontEnd )
				)
				( attribute "MATERIAL" "IC"
					( Origin gFrontEnd )
				)
				( attribute "PACK_TYPE" "QFN"
					( Origin gFrontEnd )
				)
				( attribute "PART_NUMBER" "H89187-001"
					( Origin gFrontEnd )
				)
				( attribute "PHYS_PAGE" "235"
					( Origin gFrontEnd )
				)
				( attribute "ROT" "0"
					( Origin gFrontEnd )
				)
				( attribute "SEC" "1"
					( Origin gFrontEnd )
				)
				( attribute "SEC_TYPE" "QFN"
					( Origin gFrontEnd )
				)
				( attribute "VER" "1"
					( Origin gFrontEnd )
				)
				( attribute "XY" "(-9725,3750)"
					( Origin gFrontEnd )
				)
				( attribute "CHIPS_PART_NAME" "PXE1110B"
					( Origin gPackager )
				)
				( attribute "CDS_PART_NAME" "PXE1110B_QFN-IC,H89187-001"
					( Origin gPackager )
				)
				( objectStatus "EU8A1" )
			)
			( gate "@baseboard_fab2_lib.baseboard_fab2(sch_1):page170_i75"
				( attribute "BOM_COST" "PROC_SIDEBAND"
					( Origin gFrontEnd )
				)
				( attribute "CDS_LIB" "mstr_discrete"
					( Origin gPackager )
				)
				( attribute "CDS_LOCATION" "R2P8"
					( Origin gPackager )
				)
				( attribute "CDS_SEC" "1"
					( Origin gPackager )
				)
				( attribute "LOCATION" "R2P8"
					( Origin gFrontEnd )
				)
				( attribute "MATERIAL" "CHIP"
					( Origin gFrontEnd )
				)
				( attribute "PACK_TYPE" "0402"
					( Origin gFrontEnd )
				)
				( attribute "PART_NUMBER" "G21796-072"
					( Origin gFrontEnd )
				)
				( attribute "PHYS_PAGE" "170"
					( Origin gFrontEnd )
				)
				( attribute "ROOM" "PROC_SIDEBAND"
					( Origin gFrontEnd )
				)
				( attribute "ROT" "0"
					( Origin gFrontEnd )
				)
				( attribute "SEC" "1"
					( Origin gFrontEnd )
				)
				( attribute "SEC_TYPE" "0402"
					( Origin gFrontEnd )
				)
				( attribute "TOLERANCE" "1%"
					( Origin gFrontEnd )
				)
				( attribute "VALUE" "4.75K"
					( Origin gFrontEnd )
				)
				( attribute "VER" "2"
					( Origin gFrontEnd )
				)
				( attribute "WATTAGE" "1/16W"
					( Origin gFrontEnd )
				)
				( attribute "XY" "(-3825,5100)"
					( Origin gFrontEnd )
				)
				( attribute "CHIPS_PART_NAME" "RES"
					( Origin gPackager )
				)
				( attribute "CDS_PART_NAME" "RES_0402-4.75K,1%,1/16W,CHIP,GA"
					( Origin gPackager )
				)
				( objectStatus "R2P8" )
			)
			( gate "@baseboard_fab2_lib.baseboard_fab2(sch_1):page236_i9"
				( attribute "BOM_COST" "PROC_VRD_PVCCIO_CPU0"
					( Origin gFrontEnd )
				)
				( attribute "CDS_LIB" "mstr_discrete"
					( Origin gPackager )
				)
				( attribute "CDS_LOCATION" "C7A30"
					( Origin gPackager )
				)
				( attribute "CDS_SEC" "1"
					( Origin gPackager )
				)
				( attribute "LOCATION" "C7A30"
					( Origin gFrontEnd )
				)
				( attribute "MATERIAL" "X6S"
					( Origin gFrontEnd )
				)
				( attribute "PACK_TYPE" "0805LF"
					( Origin gFrontEnd )
				)
				( attribute "PART_NUMBER" "C95333-002"
					( Origin gFrontEnd )
				)
				( attribute "PHYS_PAGE" "236"
					( Origin gFrontEnd )
				)
				( attribute "ROOM" "PVNN_PCH_STBY"
					( Origin gFrontEnd )
				)
				( attribute "ROT" "0"
					( Origin gFrontEnd )
				)
				( attribute "SEC" "1"
					( Origin gFrontEnd )
				)
				( attribute "SEC_TYPE" "0805LF"
					( Origin gFrontEnd )
				)
				( attribute "TOLERANCE" "20%"
					( Origin gFrontEnd )
				)
				( attribute "VALUE" "22UF"
					( Origin gFrontEnd )
				)
				( attribute "VER" "1"
					( Origin gFrontEnd )
				)
				( attribute "VOLTAGE" "4V"
					( Units "uVoltage" "V" 1.000000)
					( Origin gFrontEnd )
				)
				( attribute "XY" "(11725,3775)"
					( Origin gFrontEnd )
				)
				( attribute "CHIPS_PART_NAME" "CAP"
					( Origin gPackager )
				)
				( attribute "CDS_PART_NAME" "CAP_0805LF-22UF,4V,20%,X6S,C95A"
					( Origin gPackager )
				)
				( objectStatus "C7A30" )
			)
			( gate "@baseboard_fab2_lib.baseboard_fab2(sch_1):page236_i16"
				( attribute "CDS_LIB" "mstr_discrete"
					( Origin gPackager )
				)
				( attribute "CDS_LOCATION" "C7A8"
					( Origin gPackager )
				)
				( attribute "CDS_SEC" "1"
					( Origin gPackager )
				)
				( attribute "LOCATION" "C7A8"
					( Origin gFrontEnd )
				)
				( attribute "MATERIAL" "X7R"
					( Origin gFrontEnd )
				)
				( attribute "PACK_TYPE" "0402"
					( Origin gFrontEnd )
				)
				( attribute "PART_NUMBER" "A36096-155"
					( Origin gFrontEnd )
				)
				( attribute "PHYS_PAGE" "236"
					( Origin gFrontEnd )
				)
				( attribute "ROOM" "PVNN_PCH_STBY"
					( Origin gFrontEnd )
				)
				( attribute "ROT" "0"
					( Origin gFrontEnd )
				)
				( attribute "SEC" "1"
					( Origin gFrontEnd )
				)
				( attribute "SEC_TYPE" "0402"
					( Origin gFrontEnd )
				)
				( attribute "TOLERANCE" "10%"
					( Origin gFrontEnd )
				)
				( attribute "VALUE" "0.22UF"
					( Origin gFrontEnd )
				)
				( attribute "VER" "1"
					( Origin gFrontEnd )
				)
				( attribute "VOLTAGE" "16V"
					( Units "uVoltage" "V" 1.000000)
					( Origin gFrontEnd )
				)
				( attribute "XY" "(8125,4575)"
					( Origin gFrontEnd )
				)
				( attribute "CHIPS_PART_NAME" "CAP"
					( Origin gPackager )
				)
				( attribute "CDS_PART_NAME" "CAP_0402-0.22UF,16V,10%,X7R,A3A"
					( Origin gPackager )
				)
				( objectStatus "C7A8" )
			)
			( gate "@baseboard_fab2_lib.baseboard_fab2(sch_1):page203_i133"
				( attribute "CDS_LIB" "w_hdl"
					( Origin gPackager )
				)
				( attribute "CDS_LMAN_SYM_OUTLINE" "-50,25,50,-25"
					( Origin gPackager )
				)
				( attribute "LOCATION" "C4D6"
					( Origin gFrontEnd )
				)
				( attribute "PACK_TYPE" "SMD-BCG6"
					( Origin gFrontEnd )
				)
				( attribute "PART_NUMBER" "78.10523.8FL"
					( Origin gFrontEnd )
				)
				( attribute "PHYS_PAGE" "203"
					( Origin gFrontEnd )
				)
				( attribute "ROT" "0"
					( Origin gFrontEnd )
				)
				( attribute "SEC" "1"
					( Origin gFrontEnd )
				)
				( attribute "SEC_TYPE" "SMD-BCG6"
					( Origin gFrontEnd )
				)
				( attribute "VALUE" "SC1U10V2KX-4-GP"
					( Origin gFrontEnd )
				)
				( attribute "VER" "1"
					( Origin gFrontEnd )
				)
				( attribute "XY" "(-5200,1475)"
					( Origin gFrontEnd )
				)
				( attribute "CHIPS_PART_NAME" "SC1U10V2KX-4-GP"
					( Origin gPackager )
				)
				( attribute "CDS_PART_NAME" "SC1U10V2KX-4-GP_SMD-BCG6-SC1U1A"
					( Origin gPackager )
				)
				( attribute "CDS_LOCATION" "C4D6"
					( Origin gPackager )
				)
				( attribute "CDS_SEC" "1"
					( Origin gPackager )
				)
				( attribute "ATTRIBUTE" "1UF"
					( Origin gFrontEnd )
				)
				( attribute "PACK_SIZE" "0402"
					( Origin gFrontEnd )
				)
				( attribute "RATED" "10V"
					( Origin gFrontEnd )
				)
				( attribute "TOLERANCE" "10%"
					( Origin gFrontEnd )
				)
				( objectStatus "C4D6" )
			)
			( gate "@baseboard_fab2_lib.baseboard_fab2(sch_1):page236_i19"
				( attribute "CDS_LIB" "mstr_discrete"
					( Origin gPackager )
				)
				( attribute "CDS_LOCATION" "C7A6"
					( Origin gPackager )
				)
				( attribute "CDS_SEC" "1"
					( Origin gPackager )
				)
				( attribute "LOCATION" "C7A6"
					( Origin gFrontEnd )
				)
				( attribute "MATERIAL" "X6S"
					( Origin gFrontEnd )
				)
				( attribute "PACK_TYPE" "0402"
					( Origin gFrontEnd )
				)
				( attribute "PART_NUMBER" "D97712-011"
					( Origin gFrontEnd )
				)
				( attribute "PHYS_PAGE" "236"
					( Origin gFrontEnd )
				)
				( attribute "ROOM" "P1V05_PCH_STBY_VR"
					( Origin gFrontEnd )
				)
				( attribute "ROT" "0"
					( Origin gFrontEnd )
				)
				( attribute "SEC" "1"
					( Origin gFrontEnd )
				)
				( attribute "SEC_TYPE" "0402"
					( Origin gFrontEnd )
				)
				( attribute "TOLERANCE" "10%"
					( Origin gFrontEnd )
				)
				( attribute "VALUE" "1.0UF"
					( Origin gFrontEnd )
				)
				( attribute "VER" "1"
					( Origin gFrontEnd )
				)
				( attribute "VOLTAGE" "16V"
					( Units "uVoltage" "V" 1.000000)
					( Origin gFrontEnd )
				)
				( attribute "XY" "(7300,4500)"
					( Origin gFrontEnd )
				)
				( attribute "CHIPS_PART_NAME" "CAP"
					( Origin gPackager )
				)
				( attribute "CDS_PART_NAME" "CAP_0402-1.0UF,16V,10%,X6S,D97A"
					( Origin gPackager )
				)
				( objectStatus "C7A6" )
			)
			( gate "@baseboard_fab2_lib.baseboard_fab2(sch_1):page236_i20"
				( attribute "CDS_LIB" "dev_discrete"
					( Origin gPackager )
				)
				( attribute "CDS_LOCATION" "C7A39"
					( Origin gPackager )
				)
				( attribute "CDS_SEC" "1"
					( Origin gPackager )
				)
				( attribute "LOCATION" "C7A39"
					( Origin gFrontEnd )
				)
				( attribute "MATERIAL" "X7R"
					( Origin gFrontEnd )
				)
				( attribute "PACK_TYPE" "0402V"
					( Origin gFrontEnd )
				)
				( attribute "PART_NUMBER" "A36096-030"
					( Origin gFrontEnd )
				)
				( attribute "PHYS_PAGE" "236"
					( Origin gFrontEnd )
				)
				( attribute "ROOM" "PVNN_PCH_STBY"
					( Origin gFrontEnd )
				)
				( attribute "ROT" "0"
					( Origin gFrontEnd )
				)
				( attribute "SEC" "1"
					( Origin gFrontEnd )
				)
				( attribute "SEC_TYPE" "0402V"
					( Origin gFrontEnd )
				)
				( attribute "TOLERANCE" "10%"
					( Origin gFrontEnd )
				)
				( attribute "VALUE" "0.1UF"
					( Origin gFrontEnd )
				)
				( attribute "VER" "1"
					( Origin gFrontEnd )
				)
				( attribute "VOLTAGE" "16V"
					( Units "uVoltage" "V" 1.000000)
					( Origin gFrontEnd )
				)
				( attribute "XY" "(7025,4550)"
					( Origin gFrontEnd )
				)
				( attribute "CHIPS_PART_NAME" "CAP_A"
					( Origin gPackager )
				)
				( attribute "CDS_PART_NAME" "CAP_A_0402V-0.1UF,16V,10%,X7R,A"
					( Origin gPackager )
				)
				( objectStatus "C7A39" )
			)
			( gate "@baseboard_fab2_lib.baseboard_fab2(sch_1):page236_i21"
				( attribute "CDS_LIB" "mstr_discrete"
					( Origin gPackager )
				)
				( attribute "CDS_LOCATION" "C7A43"
					( Origin gPackager )
				)
				( attribute "CDS_SEC" "1"
					( Origin gPackager )
				)
				( attribute "LOCATION" "C7A43"
					( Origin gFrontEnd )
				)
				( attribute "MATERIAL" "X7R"
					( Origin gFrontEnd )
				)
				( attribute "PACK_TYPE" "0402"
					( Origin gFrontEnd )
				)
				( attribute "PART_NUMBER" "A36096-104"
					( Origin gFrontEnd )
				)
				( attribute "PHYS_PAGE" "236"
					( Origin gFrontEnd )
				)
				( attribute "ROOM" "PVNN_PCH_STBY"
					( Origin gFrontEnd )
				)
				( attribute "ROT" "2"
					( Origin gFrontEnd )
				)
				( attribute "SEC" "1"
					( Origin gFrontEnd )
				)
				( attribute "SEC_TYPE" "0402"
					( Origin gFrontEnd )
				)
				( attribute "SPOF" "TRUE"
					( Origin gFrontEnd )
				)
				( attribute "TOLERANCE" "10%"
					( Origin gFrontEnd )
				)
				( attribute "VALUE" "0.220UF"
					( Origin gFrontEnd )
				)
				( attribute "VER" "1"
					( Origin gFrontEnd )
				)
				( attribute "VOLTAGE" "16V"
					( Units "uVoltage" "V" 1.000000)
					( Origin gFrontEnd )
				)
				( attribute "XY" "(6975,3850)"
					( Origin gFrontEnd )
				)
				( attribute "CHIPS_PART_NAME" "CAP"
					( Origin gPackager )
				)
				( attribute "CDS_PART_NAME" "CAP_0402-0.220UF,16V,10%,X7R,AA"
					( Origin gPackager )
				)
				( objectStatus "C7A43" )
			)
			( gate "@baseboard_fab2_lib.baseboard_fab2(sch_1):page236_i22"
				( attribute "CDS_LIB" "mstr_discrete"
					( Origin gPackager )
				)
				( attribute "CDS_LOCATION" "C7A7"
					( Origin gPackager )
				)
				( attribute "CDS_SEC" "1"
					( Origin gPackager )
				)
				( attribute "LOCATION" "C7A7"
					( Origin gFrontEnd )
				)
				( attribute "MATERIAL" "X6S"
					( Origin gFrontEnd )
				)
				( attribute "PACK_TYPE" "0402"
					( Origin gFrontEnd )
				)
				( attribute "PART_NUMBER" "D97712-011"
					( Origin gFrontEnd )
				)
				( attribute "PHYS_PAGE" "236"
					( Origin gFrontEnd )
				)
				( attribute "ROOM" "PVNN_PCH_STBY"
					( Origin gFrontEnd )
				)
				( attribute "ROT" "0"
					( Origin gFrontEnd )
				)
				( attribute "SEC" "1"
					( Origin gFrontEnd )
				)
				( attribute "SEC_TYPE" "0402"
					( Origin gFrontEnd )
				)
				( attribute "TOLERANCE" "10%"
					( Origin gFrontEnd )
				)
				( attribute "VALUE" "1.0UF"
					( Origin gFrontEnd )
				)
				( attribute "VER" "1"
					( Origin gFrontEnd )
				)
				( attribute "VOLTAGE" "16V"
					( Units "uVoltage" "V" 1.000000)
					( Origin gFrontEnd )
				)
				( attribute "XY" "(6775,4500)"
					( Origin gFrontEnd )
				)
				( attribute "CHIPS_PART_NAME" "CAP"
					( Origin gPackager )
				)
				( attribute "CDS_PART_NAME" "CAP_0402-1.0UF,16V,10%,X6S,D97A"
					( Origin gPackager )
				)
				( objectStatus "C7A7" )
			)
			( gate "@baseboard_fab2_lib.baseboard_fab2(sch_1):page236_i23"
				( attribute "CDS_LIB" "mstr_discrete"
					( Origin gPackager )
				)
				( attribute "CDS_LOCATION" "C3L12"
					( Origin gPackager )
				)
				( attribute "LOCATION" "C3L12"
					( Origin gFrontEnd )
				)
				( attribute "MATERIAL" "X6S"
					( Origin gFrontEnd )
				)
				( attribute "PACK_TYPE" "0805"
					( Origin gFrontEnd )
				)
				( attribute "PART_NUMBER" "C95333-007"
					( Origin gFrontEnd )
				)
				( attribute "PHYS_PAGE" "236"
					( Origin gFrontEnd )
				)
				( attribute "ROOM" "PVNN_PCH_STBY"
					( Origin gFrontEnd )
				)
				( attribute "ROT" "0"
					( Origin gFrontEnd )
				)
				( attribute "SEC" "1"
					( Origin gFrontEnd )
				)
				( attribute "SEC_TYPE" "0805"
					( Origin gFrontEnd )
				)
				( attribute "TOLERANCE" "10%"
					( Origin gFrontEnd )
				)
				( attribute "VALUE" "10UF"
					( Origin gFrontEnd )
				)
				( attribute "VER" "1"
					( Origin gFrontEnd )
				)
				( attribute "VOLTAGE" "16V"
					( Units "uVoltage" "V" 1.000000)
					( Origin gFrontEnd )
				)
				( attribute "XY" "(6525,4550)"
					( Origin gFrontEnd )
				)
				( attribute "CHIPS_PART_NAME" "CAP"
					( Origin gPackager )
				)
				( attribute "CDS_PART_NAME" "CAP_0805-10UF,16V,10%,X6S,C953A"
					( Origin gPackager )
				)
				( attribute "CDS_SEC" "1"
					( Origin gPackager )
				)
				( objectStatus "C3L12" )
			)
			( gate "@baseboard_fab2_lib.baseboard_fab2(sch_1):page236_i24"
				( attribute "CDS_LIB" "mstr_discrete"
					( Origin gPackager )
				)
				( attribute "CDS_LOCATION" "C3L11"
					( Origin gPackager )
				)
				( attribute "CDS_SEC" "1"
					( Origin gPackager )
				)
				( attribute "LOCATION" "C3L11"
					( Origin gFrontEnd )
				)
				( attribute "MATERIAL" "X6S"
					( Origin gFrontEnd )
				)
				( attribute "PACK_TYPE" "0805"
					( Origin gFrontEnd )
				)
				( attribute "PART_NUMBER" "C95333-007"
					( Origin gFrontEnd )
				)
				( attribute "PHYS_PAGE" "236"
					( Origin gFrontEnd )
				)
				( attribute "ROOM" "PVNN_PCH_STBY"
					( Origin gFrontEnd )
				)
				( attribute "ROT" "0"
					( Origin gFrontEnd )
				)
				( attribute "SEC" "1"
					( Origin gFrontEnd )
				)
				( attribute "SEC_TYPE" "0805"
					( Origin gFrontEnd )
				)
				( attribute "TOLERANCE" "10%"
					( Origin gFrontEnd )
				)
				( attribute "VALUE" "10UF"
					( Origin gFrontEnd )
				)
				( attribute "VER" "1"
					( Origin gFrontEnd )
				)
				( attribute "VOLTAGE" "16V"
					( Units "uVoltage" "V" 1.000000)
					( Origin gFrontEnd )
				)
				( attribute "XY" "(6275,4500)"
					( Origin gFrontEnd )
				)
				( attribute "CHIPS_PART_NAME" "CAP"
					( Origin gPackager )
				)
				( attribute "CDS_PART_NAME" "CAP_0805-10UF,16V,10%,X6S,C953A"
					( Origin gPackager )
				)
				( objectStatus "C3L11" )
			)
			( gate "@baseboard_fab2_lib.baseboard_fab2(sch_1):page236_i26"
				( attribute "CDS_LIB" "mstr_discrete"
					( Origin gPackager )
				)
				( attribute "CDS_LOCATION" "C3L8"
					( Origin gPackager )
				)
				( attribute "CDS_SEC" "1"
					( Origin gPackager )
				)
				( attribute "LOCATION" "C3L8"
					( Origin gFrontEnd )
				)
				( attribute "MATERIAL" "X6S"
					( Origin gFrontEnd )
				)
				( attribute "PACK_TYPE" "0805"
					( Origin gFrontEnd )
				)
				( attribute "PART_NUMBER" "C95333-007"
					( Origin gFrontEnd )
				)
				( attribute "PHYS_PAGE" "236"
					( Origin gFrontEnd )
				)
				( attribute "ROOM" "PVNN_PCH_STBY"
					( Origin gFrontEnd )
				)
				( attribute "ROT" "0"
					( Origin gFrontEnd )
				)
				( attribute "SEC" "1"
					( Origin gFrontEnd )
				)
				( attribute "SEC_TYPE" "0805"
					( Origin gFrontEnd )
				)
				( attribute "TOLERANCE" "10%"
					( Origin gFrontEnd )
				)
				( attribute "VALUE" "10UF"
					( Origin gFrontEnd )
				)
				( attribute "VER" "1"
					( Origin gFrontEnd )
				)
				( attribute "VOLTAGE" "16V"
					( Units "uVoltage" "V" 1.000000)
					( Origin gFrontEnd )
				)
				( attribute "XY" "(6000,4550)"
					( Origin gFrontEnd )
				)
				( attribute "CHIPS_PART_NAME" "CAP"
					( Origin gPackager )
				)
				( attribute "CDS_PART_NAME" "CAP_0805-10UF,16V,10%,X6S,C953A"
					( Origin gPackager )
				)
				( objectStatus "C3L8" )
			)
			( gate "@baseboard_fab2_lib.baseboard_fab2(sch_1):page236_i29"
				( attribute "CDS_LIB" "mstr_discrete"
					( Origin gPackager )
				)
				( attribute "CDS_LOCATION" "C3L9"
					( Origin gPackager )
				)
				( attribute "CDS_SEC" "1"
					( Origin gPackager )
				)
				( attribute "LOCATION" "C3L9"
					( Origin gFrontEnd )
				)
				( attribute "MATERIAL" "X6S"
					( Origin gFrontEnd )
				)
				( attribute "PACK_TYPE" "0805"
					( Origin gFrontEnd )
				)
				( attribute "PART_NUMBER" "C95333-007"
					( Origin gFrontEnd )
				)
				( attribute "PHYS_PAGE" "236"
					( Origin gFrontEnd )
				)
				( attribute "ROOM" "P1V05_PCH_STBY_VR"
					( Origin gFrontEnd )
				)
				( attribute "ROT" "0"
					( Origin gFrontEnd )
				)
				( attribute "SEC" "1"
					( Origin gFrontEnd )
				)
				( attribute "SEC_TYPE" "0805"
					( Origin gFrontEnd )
				)
				( attribute "TOLERANCE" "10%"
					( Origin gFrontEnd )
				)
				( attribute "VALUE" "10UF"
					( Origin gFrontEnd )
				)
				( attribute "VER" "1"
					( Origin gFrontEnd )
				)
				( attribute "VOLTAGE" "16V"
					( Units "uVoltage" "V" 1.000000)
					( Origin gFrontEnd )
				)
				( attribute "XY" "(6025,2875)"
					( Origin gFrontEnd )
				)
				( attribute "CHIPS_PART_NAME" "CAP"
					( Origin gPackager )
				)
				( attribute "CDS_PART_NAME" "CAP_0805-10UF,16V,10%,X6S,C953A"
					( Origin gPackager )
				)
				( objectStatus "C3L9" )
			)
			( gate "@baseboard_fab2_lib.baseboard_fab2(sch_1):page236_i31"
				( attribute "CDS_LIB" "mstr_discrete"
					( Origin gPackager )
				)
				( attribute "CDS_LOCATION" "C3L7"
					( Origin gPackager )
				)
				( attribute "CDS_SEC" "1"
					( Origin gPackager )
				)
				( attribute "LOCATION" "C3L7"
					( Origin gFrontEnd )
				)
				( attribute "MATERIAL" "X6S"
					( Origin gFrontEnd )
				)
				( attribute "PACK_TYPE" "0805"
					( Origin gFrontEnd )
				)
				( attribute "PART_NUMBER" "C95333-007"
					( Origin gFrontEnd )
				)
				( attribute "PHYS_PAGE" "236"
					( Origin gFrontEnd )
				)
				( attribute "ROOM" "P1V05_PCH_STBY_VR"
					( Origin gFrontEnd )
				)
				( attribute "ROT" "0"
					( Origin gFrontEnd )
				)
				( attribute "SEC" "1"
					( Origin gFrontEnd )
				)
				( attribute "SEC_TYPE" "0805"
					( Origin gFrontEnd )
				)
				( attribute "TOLERANCE" "10%"
					( Origin gFrontEnd )
				)
				( attribute "VALUE" "10UF"
					( Origin gFrontEnd )
				)
				( attribute "VER" "1"
					( Origin gFrontEnd )
				)
				( attribute "VOLTAGE" "16V"
					( Units "uVoltage" "V" 1.000000)
					( Origin gFrontEnd )
				)
				( attribute "XY" "(6250,2800)"
					( Origin gFrontEnd )
				)
				( attribute "CHIPS_PART_NAME" "CAP"
					( Origin gPackager )
				)
				( attribute "CDS_PART_NAME" "CAP_0805-10UF,16V,10%,X6S,C953A"
					( Origin gPackager )
				)
				( objectStatus "C3L7" )
			)
			( gate "@baseboard_fab2_lib.baseboard_fab2(sch_1):page236_i32"
				( attribute "CDS_LIB" "mstr_discrete"
					( Origin gPackager )
				)
				( attribute "CDS_LOCATION" "C3L10"
					( Origin gPackager )
				)
				( attribute "CDS_SEC" "1"
					( Origin gPackager )
				)
				( attribute "LOCATION" "C3L10"
					( Origin gFrontEnd )
				)
				( attribute "MATERIAL" "X6S"
					( Origin gFrontEnd )
				)
				( attribute "PACK_TYPE" "0805"
					( Origin gFrontEnd )
				)
				( attribute "PART_NUMBER" "C95333-007"
					( Origin gFrontEnd )
				)
				( attribute "PHYS_PAGE" "236"
					( Origin gFrontEnd )
				)
				( attribute "ROOM" "P1V05_PCH_STBY_VR"
					( Origin gFrontEnd )
				)
				( attribute "ROT" "0"
					( Origin gFrontEnd )
				)
				( attribute "SEC" "1"
					( Origin gFrontEnd )
				)
				( attribute "SEC_TYPE" "0805"
					( Origin gFrontEnd )
				)
				( attribute "TOLERANCE" "10%"
					( Origin gFrontEnd )
				)
				( attribute "VALUE" "10UF"
					( Origin gFrontEnd )
				)
				( attribute "VER" "1"
					( Origin gFrontEnd )
				)
				( attribute "VOLTAGE" "16V"
					( Units "uVoltage" "V" 1.000000)
					( Origin gFrontEnd )
				)
				( attribute "XY" "(6475,2875)"
					( Origin gFrontEnd )
				)
				( attribute "CHIPS_PART_NAME" "CAP"
					( Origin gPackager )
				)
				( attribute "CDS_PART_NAME" "CAP_0805-10UF,16V,10%,X6S,C953A"
					( Origin gPackager )
				)
				( objectStatus "C3L10" )
			)
			( gate "@baseboard_fab2_lib.baseboard_fab2(sch_1):page236_i33"
				( attribute "CDS_LIB" "mstr_discrete"
					( Origin gPackager )
				)
				( attribute "CDS_LOCATION" "C7A9"
					( Origin gPackager )
				)
				( attribute "CDS_SEC" "1"
					( Origin gPackager )
				)
				( attribute "LOCATION" "C7A9"
					( Origin gFrontEnd )
				)
				( attribute "MATERIAL" "X6S"
					( Origin gFrontEnd )
				)
				( attribute "PACK_TYPE" "0402"
					( Origin gFrontEnd )
				)
				( attribute "PART_NUMBER" "D97712-011"
					( Origin gFrontEnd )
				)
				( attribute "PHYS_PAGE" "236"
					( Origin gFrontEnd )
				)
				( attribute "ROOM" "P1V05_PCH_STBY_VR"
					( Origin gFrontEnd )
				)
				( attribute "ROT" "0"
					( Origin gFrontEnd )
				)
				( attribute "SEC" "1"
					( Origin gFrontEnd )
				)
				( attribute "SEC_TYPE" "0402"
					( Origin gFrontEnd )
				)
				( attribute "TOLERANCE" "10%"
					( Origin gFrontEnd )
				)
				( attribute "VALUE" "1.0UF"
					( Origin gFrontEnd )
				)
				( attribute "VER" "1"
					( Origin gFrontEnd )
				)
				( attribute "VOLTAGE" "16V"
					( Units "uVoltage" "V" 1.000000)
					( Origin gFrontEnd )
				)
				( attribute "XY" "(6700,2800)"
					( Origin gFrontEnd )
				)
				( attribute "CHIPS_PART_NAME" "CAP"
					( Origin gPackager )
				)
				( attribute "CDS_PART_NAME" "CAP_0402-1.0UF,16V,10%,X6S,D97A"
					( Origin gPackager )
				)
				( objectStatus "C7A9" )
			)
			( gate "@baseboard_fab2_lib.baseboard_fab2(sch_1):page236_i34"
				( attribute "CDS_LIB" "mstr_discrete"
					( Origin gPackager )
				)
				( attribute "CDS_LOCATION" "C7A44"
					( Origin gPackager )
				)
				( attribute "CDS_SEC" "1"
					( Origin gPackager )
				)
				( attribute "LOCATION" "C7A44"
					( Origin gFrontEnd )
				)
				( attribute "MATERIAL" "X7R"
					( Origin gFrontEnd )
				)
				( attribute "PACK_TYPE" "0402"
					( Origin gFrontEnd )
				)
				( attribute "PART_NUMBER" "A36096-104"
					( Origin gFrontEnd )
				)
				( attribute "PHYS_PAGE" "236"
					( Origin gFrontEnd )
				)
				( attribute "ROOM" "P1V05_PCH_STBY_VR"
					( Origin gFrontEnd )
				)
				( attribute "ROT" "2"
					( Origin gFrontEnd )
				)
				( attribute "SEC" "1"
					( Origin gFrontEnd )
				)
				( attribute "SEC_TYPE" "0402"
					( Origin gFrontEnd )
				)
				( attribute "SPOF" "TRUE"
					( Origin gFrontEnd )
				)
				( attribute "TOLERANCE" "10%"
					( Origin gFrontEnd )
				)
				( attribute "VALUE" "0.220UF"
					( Origin gFrontEnd )
				)
				( attribute "VER" "1"
					( Origin gFrontEnd )
				)
				( attribute "VOLTAGE" "16V"
					( Units "uVoltage" "V" 1.000000)
					( Origin gFrontEnd )
				)
				( attribute "XY" "(7050,2100)"
					( Origin gFrontEnd )
				)
				( attribute "CHIPS_PART_NAME" "CAP"
					( Origin gPackager )
				)
				( attribute "CDS_PART_NAME" "CAP_0402-0.220UF,16V,10%,X7R,AA"
					( Origin gPackager )
				)
				( objectStatus "C7A44" )
			)
			( gate "@baseboard_fab2_lib.baseboard_fab2(sch_1):page236_i35"
				( attribute "CDS_LIB" "dev_discrete"
					( Origin gPackager )
				)
				( attribute "CDS_LOCATION" "C7A40"
					( Origin gPackager )
				)
				( attribute "CDS_SEC" "1"
					( Origin gPackager )
				)
				( attribute "LOCATION" "C7A40"
					( Origin gFrontEnd )
				)
				( attribute "MATERIAL" "X7R"
					( Origin gFrontEnd )
				)
				( attribute "PACK_TYPE" "0402V"
					( Origin gFrontEnd )
				)
				( attribute "PART_NUMBER" "A36096-030"
					( Origin gFrontEnd )
				)
				( attribute "PHYS_PAGE" "236"
					( Origin gFrontEnd )
				)
				( attribute "ROOM" "P1V05_PCH_STBY_VR"
					( Origin gFrontEnd )
				)
				( attribute "ROT" "0"
					( Origin gFrontEnd )
				)
				( attribute "SEC" "1"
					( Origin gFrontEnd )
				)
				( attribute "SEC_TYPE" "0402V"
					( Origin gFrontEnd )
				)
				( attribute "TOLERANCE" "10%"
					( Origin gFrontEnd )
				)
				( attribute "VALUE" "0.1UF"
					( Origin gFrontEnd )
				)
				( attribute "VER" "1"
					( Origin gFrontEnd )
				)
				( attribute "VOLTAGE" "16V"
					( Units "uVoltage" "V" 1.000000)
					( Origin gFrontEnd )
				)
				( attribute "XY" "(6925,2875)"
					( Origin gFrontEnd )
				)
				( attribute "CHIPS_PART_NAME" "CAP_A"
					( Origin gPackager )
				)
				( attribute "CDS_PART_NAME" "CAP_A_0402V-0.1UF,16V,10%,X7R,A"
					( Origin gPackager )
				)
				( objectStatus "C7A40" )
			)
			( gate "@baseboard_fab2_lib.baseboard_fab2(sch_1):page236_i36"
				( attribute "CDS_LIB" "mstr_discrete"
					( Origin gPackager )
				)
				( attribute "CDS_LOCATION" "C7A10"
					( Origin gPackager )
				)
				( attribute "CDS_SEC" "1"
					( Origin gPackager )
				)
				( attribute "LOCATION" "C7A10"
					( Origin gFrontEnd )
				)
				( attribute "MATERIAL" "X6S"
					( Origin gFrontEnd )
				)
				( attribute "PACK_TYPE" "0402"
					( Origin gFrontEnd )
				)
				( attribute "PART_NUMBER" "D97712-011"
					( Origin gFrontEnd )
				)
				( attribute "PHYS_PAGE" "236"
					( Origin gFrontEnd )
				)
				( attribute "ROOM" "P1V05_PCH_STBY_VR"
					( Origin gFrontEnd )
				)
				( attribute "ROT" "0"
					( Origin gFrontEnd )
				)
				( attribute "SEC" "1"
					( Origin gFrontEnd )
				)
				( attribute "SEC_TYPE" "0402"
					( Origin gFrontEnd )
				)
				( attribute "TOLERANCE" "10%"
					( Origin gFrontEnd )
				)
				( attribute "VALUE" "1.0UF"
					( Origin gFrontEnd )
				)
				( attribute "VER" "1"
					( Origin gFrontEnd )
				)
				( attribute "VOLTAGE" "16V"
					( Units "uVoltage" "V" 1.000000)
					( Origin gFrontEnd )
				)
				( attribute "XY" "(7175,2800)"
					( Origin gFrontEnd )
				)
				( attribute "CHIPS_PART_NAME" "CAP"
					( Origin gPackager )
				)
				( attribute "CDS_PART_NAME" "CAP_0402-1.0UF,16V,10%,X6S,D97A"
					( Origin gPackager )
				)
				( objectStatus "C7A10" )
			)
			( gate "@baseboard_fab2_lib.baseboard_fab2(sch_1):page205_i83"
				( attribute "CDS_LIB" "w_hdl"
					( Origin gPackager )
				)
				( attribute "CDS_LMAN_SYM_OUTLINE" "-50,25,50,-25"
					( Origin gPackager )
				)
				( attribute "LOCATION" "C4C4"
					( Origin gFrontEnd )
				)
				( attribute "PACK_TYPE" "SMD-BCG6"
					( Origin gFrontEnd )
				)
				( attribute "PART_NUMBER" "78.10523.8FL"
					( Origin gFrontEnd )
				)
				( attribute "PHYS_PAGE" "205"
					( Origin gFrontEnd )
				)
				( attribute "ROT" "0"
					( Origin gFrontEnd )
				)
				( attribute "SEC" "1"
					( Origin gFrontEnd )
				)
				( attribute "SEC_TYPE" "SMD-BCG6"
					( Origin gFrontEnd )
				)
				( attribute "VALUE" "SC1U10V2KX-4-GP"
					( Origin gFrontEnd )
				)
				( attribute "VER" "1"
					( Origin gFrontEnd )
				)
				( attribute "XY" "(-5625,4175)"
					( Origin gFrontEnd )
				)
				( attribute "CHIPS_PART_NAME" "SC1U10V2KX-4-GP"
					( Origin gPackager )
				)
				( attribute "CDS_PART_NAME" "SC1U10V2KX-4-GP_SMD-BCG6-SC1U1A"
					( Origin gPackager )
				)
				( attribute "CDS_LOCATION" "C4C4"
					( Origin gPackager )
				)
				( attribute "CDS_SEC" "1"
					( Origin gPackager )
				)
				( attribute "ATTRIBUTE" "1UF"
					( Origin gFrontEnd )
				)
				( attribute "PACK_SIZE" "0402"
					( Origin gFrontEnd )
				)
				( attribute "RATED" "10V"
					( Origin gFrontEnd )
				)
				( attribute "TOLERANCE" "10%"
					( Origin gFrontEnd )
				)
				( objectStatus "C4C4" )
			)
			( gate "@baseboard_fab2_lib.baseboard_fab2(sch_1):page236_i39"
				( attribute "CDS_LIB" "mstr_discrete"
					( Origin gPackager )
				)
				( attribute "CDS_LOCATION" "C7A41"
					( Origin gPackager )
				)
				( attribute "CDS_SEC" "1"
					( Origin gPackager )
				)
				( attribute "LOCATION" "C7A41"
					( Origin gFrontEnd )
				)
				( attribute "MATERIAL" "X7R"
					( Origin gFrontEnd )
				)
				( attribute "PACK_TYPE" "0402"
					( Origin gFrontEnd )
				)
				( attribute "PART_NUMBER" "A36096-155"
					( Origin gFrontEnd )
				)
				( attribute "PHYS_PAGE" "236"
					( Origin gFrontEnd )
				)
				( attribute "ROOM" "P1V05_PCH_STBY_VR"
					( Origin gFrontEnd )
				)
				( attribute "ROT" "0"
					( Origin gFrontEnd )
				)
				( attribute "SEC" "1"
					( Origin gFrontEnd )
				)
				( attribute "SEC_TYPE" "0402"
					( Origin gFrontEnd )
				)
				( attribute "TOLERANCE" "10%"
					( Origin gFrontEnd )
				)
				( attribute "VALUE" "0.22UF"
					( Origin gFrontEnd )
				)
				( attribute "VER" "1"
					( Origin gFrontEnd )
				)
				( attribute "VOLTAGE" "16V"
					( Units "uVoltage" "V" 1.000000)
					( Origin gFrontEnd )
				)
				( attribute "XY" "(8000,2875)"
					( Origin gFrontEnd )
				)
				( attribute "CHIPS_PART_NAME" "CAP"
					( Origin gPackager )
				)
				( attribute "CDS_PART_NAME" "CAP_0402-0.22UF,16V,10%,X7R,A3A"
					( Origin gPackager )
				)
				( objectStatus "C7A41" )
			)
			( gate "@baseboard_fab2_lib.baseboard_fab2(sch_1):page204_i105"
				( attribute "CDS_LIB" "w_hdl"
					( Origin gPackager )
				)
				( attribute "CDS_LMAN_SYM_OUTLINE" "-75,100,75,-100"
					( Origin gPackager )
				)
				( attribute "LOCATION" "L4C1"
					( Origin gFrontEnd )
				)
				( attribute "PACK_TYPE" "DISCRET-GC2"
					( Origin gFrontEnd )
				)
				( attribute "PART_NUMBER" "068.8001N.M001"
					( Origin gFrontEnd )
				)
				( attribute "PHYS_PAGE" "204"
					( Origin gFrontEnd )
				)
				( attribute "ROT" "1"
					( Origin gFrontEnd )
				)
				( attribute "SEC" "1"
					( Origin gFrontEnd )
				)
				( attribute "SEC_TYPE" "DISCRET-GC2"
					( Origin gFrontEnd )
				)
				( attribute "VALUE" "IND-80NH-1-GP"
					( Origin gFrontEnd )
				)
				( attribute "VER" "1"
					( Origin gFrontEnd )
				)
				( attribute "XY" "(-3025,2200)"
					( Origin gFrontEnd )
				)
				( attribute "CHIPS_PART_NAME" "IND-80NH-1-GP"
					( Origin gPackager )
				)
				( attribute "CDS_PART_NAME" "IND-80NH-1-GP_DISCRET-GC2-IND-A"
					( Origin gPackager )
				)
				( attribute "CDS_LOCATION" "L4C1"
					( Origin gPackager )
				)
				( attribute "CDS_SEC" "1"
					( Origin gPackager )
				)
				( attribute "ATTRIBUTE" "80NH"
					( Origin gFrontEnd )
				)
				( attribute "PACK_SIZE" "DCR=0.22MOHM"
					( Origin gFrontEnd )
				)
				( attribute "RATED" "ISAT=50A@25C"
					( Origin gFrontEnd )
				)
				( attribute "TYPE" "IRMS=34A@DELTA_T<45C"
					( Origin gFrontEnd )
				)
				( objectStatus "L4C1" )
			)
			( gate "@baseboard_fab2_lib.baseboard_fab2(sch_1):page236_i46"
				( attribute "BOM_COST" "PROC_VRD_PVCCIO_CPU0"
					( Origin gFrontEnd )
				)
				( attribute "CDS_LIB" "mstr_discrete"
					( Origin gPackager )
				)
				( attribute "CDS_LOCATION" "C7A42"
					( Origin gPackager )
				)
				( attribute "CDS_SEC" "1"
					( Origin gPackager )
				)
				( attribute "LOCATION" "C7A42"
					( Origin gFrontEnd )
				)
				( attribute "MATERIAL" "X6S"
					( Origin gFrontEnd )
				)
				( attribute "PACK_TYPE" "0805LF"
					( Origin gFrontEnd )
				)
				( attribute "PART_NUMBER" "C95333-002"
					( Origin gFrontEnd )
				)
				( attribute "PHYS_PAGE" "236"
					( Origin gFrontEnd )
				)
				( attribute "ROOM" "P1V05_PCH_STBY_VR"
					( Origin gFrontEnd )
				)
				( attribute "ROT" "0"
					( Origin gFrontEnd )
				)
				( attribute "SEC" "1"
					( Origin gFrontEnd )
				)
				( attribute "SEC_TYPE" "0805LF"
					( Origin gFrontEnd )
				)
				( attribute "TOLERANCE" "20%"
					( Origin gFrontEnd )
				)
				( attribute "VALUE" "22UF"
					( Origin gFrontEnd )
				)
				( attribute "VER" "1"
					( Origin gFrontEnd )
				)
				( attribute "VOLTAGE" "4V"
					( Units "uVoltage" "V" 1.000000)
					( Origin gFrontEnd )
				)
				( attribute "XY" "(11650,2050)"
					( Origin gFrontEnd )
				)
				( attribute "CHIPS_PART_NAME" "CAP"
					( Origin gPackager )
				)
				( attribute "CDS_PART_NAME" "CAP_0805LF-22UF,4V,20%,X6S,C95A"
					( Origin gPackager )
				)
				( objectStatus "C7A42" )
			)
			( gate "@baseboard_fab2_lib.baseboard_fab2(sch_1):page236_i56"
				( attribute "BOM_COST" "P1V05_PCH_STBY"
					( Origin gFrontEnd )
				)
				( attribute "CDS_LIB" "mstr_discrete"
					( Origin gPackager )
				)
				( attribute "CDS_LOCATION" "R8B14"
					( Origin gPackager )
				)
				( attribute "LOCATION" "R8B14"
					( Origin gFrontEnd )
				)
				( attribute "MATERIAL" "CHIP"
					( Origin gFrontEnd )
				)
				( attribute "PACK_TYPE" "0402"
					( Origin gFrontEnd )
				)
				( attribute "PART_NUMBER" "G21497-005"
					( Origin gFrontEnd )
				)
				( attribute "PHYS_PAGE" "236"
					( Origin gFrontEnd )
				)
				( attribute "ROOM" "P1V05_PCH_STBY"
					( Origin gFrontEnd )
				)
				( attribute "ROT" "0"
					( Origin gFrontEnd )
				)
				( attribute "SEC" "1"
					( Origin gFrontEnd )
				)
				( attribute "SEC_TYPE" "0402"
					( Origin gFrontEnd )
				)
				( attribute "TOLERANCE" "5%"
					( Origin gFrontEnd )
				)
				( attribute "VALUE" "0.0"
					( Origin gFrontEnd )
				)
				( attribute "VER" "1"
					( Origin gFrontEnd )
				)
				( attribute "WATTAGE" "1/16W"
					( Origin gFrontEnd )
				)
				( attribute "XY" "(7450,1300)"
					( Origin gFrontEnd )
				)
				( attribute "CHIPS_PART_NAME" "RES"
					( Origin gPackager )
				)
				( attribute "CDS_PART_NAME" "RES_0402-0.0,5%,1/16W,CHIP,G21A"
					( Origin gPackager )
				)
				( attribute "CDS_SEC" "1"
					( Origin gPackager )
				)
				( objectStatus "R8B14" )
			)
			( gate "@baseboard_fab2_lib.baseboard_fab2(sch_1):page236_i57"
				( attribute "BOM_COST" "P1V05_PCH_STBY"
					( Origin gFrontEnd )
				)
				( attribute "CDS_LIB" "mstr_discrete"
					( Origin gPackager )
				)
				( attribute "CDS_LOCATION" "R8B15"
					( Origin gPackager )
				)
				( attribute "LOCATION" "R8B15"
					( Origin gFrontEnd )
				)
				( attribute "MATERIAL" "EMPTY"
					( Origin gFrontEnd )
				)
				( attribute "NO_XNET_CONNECTION" "1"
					( Origin gFrontEnd )
				)
				( attribute "PACK_TYPE" "0402"
					( Origin gFrontEnd )
				)
				( attribute "PART_NUMBER" "G21796-017"
					( Origin gFrontEnd )
				)
				( attribute "PHYS_PAGE" "236"
					( Origin gFrontEnd )
				)
				( attribute "ROOM" "P1V05_PCH_STBY"
					( Origin gFrontEnd )
				)
				( attribute "ROT" "0"
					( Origin gFrontEnd )
				)
				( attribute "SEC" "1"
					( Origin gFrontEnd )
				)
				( attribute "SEC_TYPE" "0402"
					( Origin gFrontEnd )
				)
				( attribute "TOLERANCE" "1%"
					( Origin gFrontEnd )
				)
				( attribute "VALUE" "100.0"
					( Origin gFrontEnd )
				)
				( attribute "VER" "2"
					( Origin gFrontEnd )
				)
				( attribute "WATTAGE" "1/16W"
					( Origin gFrontEnd )
				)
				( attribute "XY" "(7175,1050)"
					( Origin gFrontEnd )
				)
				( attribute "CHIPS_PART_NAME" "RES"
					( Origin gPackager )
				)
				( attribute "CDS_PART_NAME" "RES_0402-100.0,1%,1/16W,EMPTY,A"
					( Origin gPackager )
				)
				( attribute "CDS_SEC" "1"
					( Origin gPackager )
				)
				( objectStatus "R8B15" )
			)
			( gate "@baseboard_fab2_lib.baseboard_fab2(sch_1):page236_i59"
				( attribute "BOM_COST" "P1V05_PCH_STBY"
					( Origin gFrontEnd )
				)
				( attribute "CDS_LIB" "mstr_discrete"
					( Origin gPackager )
				)
				( attribute "CDS_LOCATION" "R8B12"
					( Origin gPackager )
				)
				( attribute "LOCATION" "R8B12"
					( Origin gFrontEnd )
				)
				( attribute "MATERIAL" "CHIP"
					( Origin gFrontEnd )
				)
				( attribute "PACK_TYPE" "0402"
					( Origin gFrontEnd )
				)
				( attribute "PART_NUMBER" "G21497-005"
					( Origin gFrontEnd )
				)
				( attribute "PHYS_PAGE" "236"
					( Origin gFrontEnd )
				)
				( attribute "ROOM" "P1V05_PCH_STBY"
					( Origin gFrontEnd )
				)
				( attribute "ROT" "0"
					( Origin gFrontEnd )
				)
				( attribute "SEC" "1"
					( Origin gFrontEnd )
				)
				( attribute "SEC_TYPE" "0402"
					( Origin gFrontEnd )
				)
				( attribute "TOLERANCE" "5%"
					( Origin gFrontEnd )
				)
				( attribute "VALUE" "0.0"
					( Origin gFrontEnd )
				)
				( attribute "VER" "1"
					( Origin gFrontEnd )
				)
				( attribute "WATTAGE" "1/16W"
					( Origin gFrontEnd )
				)
				( attribute "XY" "(7425,850)"
					( Origin gFrontEnd )
				)
				( attribute "CHIPS_PART_NAME" "RES"
					( Origin gPackager )
				)
				( attribute "CDS_PART_NAME" "RES_0402-0.0,5%,1/16W,CHIP,G21A"
					( Origin gPackager )
				)
				( attribute "CDS_SEC" "1"
					( Origin gPackager )
				)
				( objectStatus "R8B12" )
			)
			( gate "@baseboard_fab2_lib.baseboard_fab2(sch_1):page212_i126"
				( attribute "CDS_LIB" "w_hdl"
					( Origin gPackager )
				)
				( attribute "CDS_LMAN_SYM_OUTLINE" "-50,25,50,-25"
					( Origin gPackager )
				)
				( attribute "LOCATION" "C22W32"
					( Origin gFrontEnd )
				)
				( attribute "PACK_TYPE" "SMD-BCG5"
					( Origin gFrontEnd )
				)
				( attribute "PART_NUMBER" "078.22611.0811"
					( Origin gFrontEnd )
				)
				( attribute "PHYS_PAGE" "212"
					( Origin gFrontEnd )
				)
				( attribute "ROT" "0"
					( Origin gFrontEnd )
				)
				( attribute "SEC" "1"
					( Origin gFrontEnd )
				)
				( attribute "SEC_TYPE" "SMD-BCG5"
					( Origin gFrontEnd )
				)
				( attribute "VALUE" "SC22U16V5MX-4-GP"
					( Origin gFrontEnd )
				)
				( attribute "VER" "1"
					( Origin gFrontEnd )
				)
				( attribute "XY" "(2600,2175)"
					( Origin gFrontEnd )
				)
				( attribute "CHIPS_PART_NAME" "SC22U16V5MX-4-GP"
					( Origin gPackager )
				)
				( attribute "CDS_PART_NAME" "SC22U16V5MX-4-GP_SMD-BCG5-SC22A"
					( Origin gPackager )
				)
				( attribute "CDS_LOCATION" "C22W32"
					( Origin gPackager )
				)
				( attribute "CDS_SEC" "1"
					( Origin gPackager )
				)
				( attribute "ATTRIBUTE" "22UF"
					( Origin gFrontEnd )
				)
				( attribute "PACK_SIZE" "0805"
					( Origin gFrontEnd )
				)
				( attribute "RATED" "16V"
					( Origin gFrontEnd )
				)
				( attribute "TOLERANCE" "20%"
					( Origin gFrontEnd )
				)
				( attribute "TYPE" "X6S"
					( Origin gFrontEnd )
				)
				( objectStatus "C22W32" )
			)
			( gate "@baseboard_fab2_lib.baseboard_fab2(sch_1):page212_i124"
				( attribute "CDS_LIB" "w_hdl"
					( Origin gPackager )
				)
				( attribute "CDS_LMAN_SYM_OUTLINE" "-50,25,50,-25"
					( Origin gPackager )
				)
				( attribute "LOCATION" "C22W33"
					( Origin gFrontEnd )
				)
				( attribute "PACK_TYPE" "SMD-BCG5"
					( Origin gFrontEnd )
				)
				( attribute "PART_NUMBER" "078.22611.0811"
					( Origin gFrontEnd )
				)
				( attribute "PHYS_PAGE" "212"
					( Origin gFrontEnd )
				)
				( attribute "ROT" "0"
					( Origin gFrontEnd )
				)
				( attribute "SEC" "1"
					( Origin gFrontEnd )
				)
				( attribute "SEC_TYPE" "SMD-BCG5"
					( Origin gFrontEnd )
				)
				( attribute "VALUE" "SC22U16V5MX-4-GP"
					( Origin gFrontEnd )
				)
				( attribute "VER" "1"
					( Origin gFrontEnd )
				)
				( attribute "XY" "(2900,2175)"
					( Origin gFrontEnd )
				)
				( attribute "CHIPS_PART_NAME" "SC22U16V5MX-4-GP"
					( Origin gPackager )
				)
				( attribute "CDS_PART_NAME" "SC22U16V5MX-4-GP_SMD-BCG5-SC22A"
					( Origin gPackager )
				)
				( attribute "CDS_LOCATION" "C22W33"
					( Origin gPackager )
				)
				( attribute "CDS_SEC" "1"
					( Origin gPackager )
				)
				( attribute "ATTRIBUTE" "22UF"
					( Origin gFrontEnd )
				)
				( attribute "PACK_SIZE" "0805"
					( Origin gFrontEnd )
				)
				( attribute "RATED" "16V"
					( Origin gFrontEnd )
				)
				( attribute "TOLERANCE" "20%"
					( Origin gFrontEnd )
				)
				( attribute "TYPE" "X6S"
					( Origin gFrontEnd )
				)
				( objectStatus "C22W33" )
			)
			( gate "@baseboard_fab2_lib.baseboard_fab2(sch_1):page236_i71"
				( attribute "CDS_LIB" "mstr_discrete"
					( Origin gPackager )
				)
				( attribute "CDS_LOCATION" "C3L18"
					( Origin gPackager )
				)
				( attribute "CDS_SEC" "1"
					( Origin gPackager )
				)
				( attribute "LOCATION" "C3L18"
					( Origin gFrontEnd )
				)
				( attribute "MATERIAL" "ALUM"
					( Origin gFrontEnd )
				)
				( attribute "PACK_TYPE" "SM"
					( Origin gFrontEnd )
				)
				( attribute "PART_NUMBER" "699013-031"
					( Origin gFrontEnd )
				)
				( attribute "PHYS_PAGE" "236"
					( Origin gFrontEnd )
				)
				( attribute "ROOM" "PVNN_PCH_STBY"
					( Origin gFrontEnd )
				)
				( attribute "ROT" "0"
					( Origin gFrontEnd )
				)
				( attribute "SEC" "1"
					( Origin gFrontEnd )
				)
				( attribute "SEC_TYPE" "SM"
					( Origin gFrontEnd )
				)
				( attribute "TOLERANCE" "20%"
					( Origin gFrontEnd )
				)
				( attribute "VALUE" "470UF"
					( Origin gFrontEnd )
				)
				( attribute "VER" "1"
					( Origin gFrontEnd )
				)
				( attribute "VOLTAGE" "2V"
					( Units "uVoltage" "V" 1.000000)
					( Origin gFrontEnd )
				)
				( attribute "XY" "(12025,3775)"
					( Origin gFrontEnd )
				)
				( attribute "CHIPS_PART_NAME" "CAPP"
					( Origin gPackager )
				)
				( attribute "CDS_PART_NAME" "CAPP_SM-470UF,2V,20%,ALUM,6990A"
					( Origin gPackager )
				)
				( objectStatus "C3L18" )
			)
			( gate "@baseboard_fab2_lib.baseboard_fab2(sch_1):page236_i73"
				( attribute "CDS_LIB" "mstr_discrete"
					( Origin gPackager )
				)
				( attribute "CDS_LOCATION" "C3L20"
					( Origin gPackager )
				)
				( attribute "CDS_SEC" "1"
					( Origin gPackager )
				)
				( attribute "LOCATION" "C3L20"
					( Origin gFrontEnd )
				)
				( attribute "MATERIAL" "ALUM"
					( Origin gFrontEnd )
				)
				( attribute "PACK_TYPE" "SM"
					( Origin gFrontEnd )
				)
				( attribute "PART_NUMBER" "699013-031"
					( Origin gFrontEnd )
				)
				( attribute "PHYS_PAGE" "236"
					( Origin gFrontEnd )
				)
				( attribute "ROOM" "PVNN_PCH_STBY"
					( Origin gFrontEnd )
				)
				( attribute "ROT" "0"
					( Origin gFrontEnd )
				)
				( attribute "SEC" "1"
					( Origin gFrontEnd )
				)
				( attribute "SEC_TYPE" "SM"
					( Origin gFrontEnd )
				)
				( attribute "TOLERANCE" "20%"
					( Origin gFrontEnd )
				)
				( attribute "VALUE" "470UF"
					( Origin gFrontEnd )
				)
				( attribute "VER" "1"
					( Origin gFrontEnd )
				)
				( attribute "VOLTAGE" "2V"
					( Units "uVoltage" "V" 1.000000)
					( Origin gFrontEnd )
				)
				( attribute "XY" "(12325,3775)"
					( Origin gFrontEnd )
				)
				( attribute "CHIPS_PART_NAME" "CAPP"
					( Origin gPackager )
				)
				( attribute "CDS_PART_NAME" "CAPP_SM-470UF,2V,20%,ALUM,6990A"
					( Origin gPackager )
				)
				( objectStatus "C3L20" )
			)
			( gate "@baseboard_fab2_lib.baseboard_fab2(sch_1):page236_i74"
				( attribute "CDS_LIB" "mstr_discrete"
					( Origin gPackager )
				)
				( attribute "CDS_LOCATION" "C3L21"
					( Origin gPackager )
				)
				( attribute "CDS_SEC" "1"
					( Origin gPackager )
				)
				( attribute "LOCATION" "C3L21"
					( Origin gFrontEnd )
				)
				( attribute "MATERIAL" "ALUM"
					( Origin gFrontEnd )
				)
				( attribute "PACK_TYPE" "SM"
					( Origin gFrontEnd )
				)
				( attribute "PART_NUMBER" "699013-031"
					( Origin gFrontEnd )
				)
				( attribute "PHYS_PAGE" "236"
					( Origin gFrontEnd )
				)
				( attribute "ROOM" "PVNN_PCH_STBY"
					( Origin gFrontEnd )
				)
				( attribute "ROT" "0"
					( Origin gFrontEnd )
				)
				( attribute "SEC" "1"
					( Origin gFrontEnd )
				)
				( attribute "SEC_TYPE" "SM"
					( Origin gFrontEnd )
				)
				( attribute "TOLERANCE" "20%"
					( Origin gFrontEnd )
				)
				( attribute "VALUE" "470UF"
					( Origin gFrontEnd )
				)
				( attribute "VER" "1"
					( Origin gFrontEnd )
				)
				( attribute "VOLTAGE" "2V"
					( Units "uVoltage" "V" 1.000000)
					( Origin gFrontEnd )
				)
				( attribute "XY" "(12600,3775)"
					( Origin gFrontEnd )
				)
				( attribute "CHIPS_PART_NAME" "CAPP"
					( Origin gPackager )
				)
				( attribute "CDS_PART_NAME" "CAPP_SM-470UF,2V,20%,ALUM,6990A"
					( Origin gPackager )
				)
				( objectStatus "C3L21" )
			)
			( gate "@baseboard_fab2_lib.baseboard_fab2(sch_1):page236_i75"
				( attribute "CDS_LIB" "mstr_discrete"
					( Origin gPackager )
				)
				( attribute "CDS_LOCATION" "C7A27"
					( Origin gPackager )
				)
				( attribute "CDS_SEC" "1"
					( Origin gPackager )
				)
				( attribute "LOCATION" "C7A27"
					( Origin gFrontEnd )
				)
				( attribute "MATERIAL" "ALUM"
					( Origin gFrontEnd )
				)
				( attribute "PACK_TYPE" "SM"
					( Origin gFrontEnd )
				)
				( attribute "PART_NUMBER" "699013-031"
					( Origin gFrontEnd )
				)
				( attribute "PHYS_PAGE" "236"
					( Origin gFrontEnd )
				)
				( attribute "ROOM" "PVNN_PCH_STBY"
					( Origin gFrontEnd )
				)
				( attribute "ROT" "0"
					( Origin gFrontEnd )
				)
				( attribute "SEC" "1"
					( Origin gFrontEnd )
				)
				( attribute "SEC_TYPE" "SM"
					( Origin gFrontEnd )
				)
				( attribute "TOLERANCE" "20%"
					( Origin gFrontEnd )
				)
				( attribute "VALUE" "470UF"
					( Origin gFrontEnd )
				)
				( attribute "VER" "1"
					( Origin gFrontEnd )
				)
				( attribute "VOLTAGE" "2V"
					( Units "uVoltage" "V" 1.000000)
					( Origin gFrontEnd )
				)
				( attribute "XY" "(12850,3775)"
					( Origin gFrontEnd )
				)
				( attribute "CHIPS_PART_NAME" "CAPP"
					( Origin gPackager )
				)
				( attribute "CDS_PART_NAME" "CAPP_SM-470UF,2V,20%,ALUM,6990A"
					( Origin gPackager )
				)
				( objectStatus "C7A27" )
			)
			( gate "@baseboard_fab2_lib.baseboard_fab2(sch_1):page236_i76"
				( attribute "CDS_LIB" "mstr_discrete"
					( Origin gPackager )
				)
				( attribute "CDS_LOCATION" "C3L19"
					( Origin gPackager )
				)
				( attribute "CDS_SEC" "1"
					( Origin gPackager )
				)
				( attribute "LOCATION" "C3L19"
					( Origin gFrontEnd )
				)
				( attribute "MATERIAL" "ALUM"
					( Origin gFrontEnd )
				)
				( attribute "PACK_TYPE" "SM"
					( Origin gFrontEnd )
				)
				( attribute "PART_NUMBER" "699013-031"
					( Origin gFrontEnd )
				)
				( attribute "PHYS_PAGE" "236"
					( Origin gFrontEnd )
				)
				( attribute "ROOM" "P1V05_PCH_STBY"
					( Origin gFrontEnd )
				)
				( attribute "ROT" "0"
					( Origin gFrontEnd )
				)
				( attribute "SEC" "1"
					( Origin gFrontEnd )
				)
				( attribute "SEC_TYPE" "SM"
					( Origin gFrontEnd )
				)
				( attribute "TOLERANCE" "20%"
					( Origin gFrontEnd )
				)
				( attribute "VALUE" "470UF"
					( Origin gFrontEnd )
				)
				( attribute "VER" "1"
					( Origin gFrontEnd )
				)
				( attribute "VOLTAGE" "2V"
					( Units "uVoltage" "V" 1.000000)
					( Origin gFrontEnd )
				)
				( attribute "XY" "(11925,2050)"
					( Origin gFrontEnd )
				)
				( attribute "CHIPS_PART_NAME" "CAPP"
					( Origin gPackager )
				)
				( attribute "CDS_PART_NAME" "CAPP_SM-470UF,2V,20%,ALUM,6990A"
					( Origin gPackager )
				)
				( objectStatus "C3L19" )
			)
			( gate "@baseboard_fab2_lib.baseboard_fab2(sch_1):page236_i77"
				( attribute "CDS_LIB" "mstr_discrete"
					( Origin gPackager )
				)
				( attribute "CDS_LOCATION" "C2L46"
					( Origin gPackager )
				)
				( attribute "LOCATION" "C2L46"
					( Origin gFrontEnd )
				)
				( attribute "MATERIAL" "ALUM"
					( Origin gFrontEnd )
				)
				( attribute "PACK_TYPE" "SM"
					( Origin gFrontEnd )
				)
				( attribute "PART_NUMBER" "699013-031"
					( Origin gFrontEnd )
				)
				( attribute "PHYS_PAGE" "236"
					( Origin gFrontEnd )
				)
				( attribute "ROOM" "P1V05_PCH_STBY"
					( Origin gFrontEnd )
				)
				( attribute "ROT" "0"
					( Origin gFrontEnd )
				)
				( attribute "SEC" "1"
					( Origin gFrontEnd )
				)
				( attribute "TOLERANCE" "20%"
					( Origin gFrontEnd )
				)
				( attribute "VALUE" "470UF"
					( Origin gFrontEnd )
				)
				( attribute "VER" "1"
					( Origin gFrontEnd )
				)
				( attribute "VOLTAGE" "2V"
					( Units "uVoltage" "V" 1.000000)
					( Origin gFrontEnd )
				)
				( attribute "XY" "(12175,2050)"
					( Origin gFrontEnd )
				)
				( attribute "CHIPS_PART_NAME" "CAPP"
					( Origin gPackager )
				)
				( attribute "CDS_PART_NAME" "CAPP_SM-470UF,2V,20%,ALUM,6990A"
					( Origin gPackager )
				)
				( attribute "SEC_TYPE" "SM"
					( Origin gFrontEnd )
				)
				( attribute "CDS_SEC" "1"
					( Origin gPackager )
				)
				( objectStatus "C2L46" )
			)
			( gate "@baseboard_fab2_lib.baseboard_fab2(sch_1):page236_i78"
				( attribute "CDS_LIB" "mstr_discrete"
					( Origin gPackager )
				)
				( attribute "CDS_LOCATION" "C8A15"
					( Origin gPackager )
				)
				( attribute "LOCATION" "C8A15"
					( Origin gFrontEnd )
				)
				( attribute "MATERIAL" "ALUM"
					( Origin gFrontEnd )
				)
				( attribute "PACK_TYPE" "SM"
					( Origin gFrontEnd )
				)
				( attribute "PART_NUMBER" "699013-031"
					( Origin gFrontEnd )
				)
				( attribute "PHYS_PAGE" "236"
					( Origin gFrontEnd )
				)
				( attribute "ROOM" "P1V05_PCH_STBY"
					( Origin gFrontEnd )
				)
				( attribute "ROT" "0"
					( Origin gFrontEnd )
				)
				( attribute "SEC" "1"
					( Origin gFrontEnd )
				)
				( attribute "TOLERANCE" "20%"
					( Origin gFrontEnd )
				)
				( attribute "VALUE" "470UF"
					( Origin gFrontEnd )
				)
				( attribute "VER" "1"
					( Origin gFrontEnd )
				)
				( attribute "VOLTAGE" "2V"
					( Units "uVoltage" "V" 1.000000)
					( Origin gFrontEnd )
				)
				( attribute "XY" "(12425,2050)"
					( Origin gFrontEnd )
				)
				( attribute "CHIPS_PART_NAME" "CAPP"
					( Origin gPackager )
				)
				( attribute "CDS_PART_NAME" "CAPP_SM-470UF,2V,20%,ALUM,6990A"
					( Origin gPackager )
				)
				( attribute "SEC_TYPE" "SM"
					( Origin gFrontEnd )
				)
				( attribute "CDS_SEC" "1"
					( Origin gPackager )
				)
				( objectStatus "C8A15" )
			)
			( gate "@baseboard_fab2_lib.baseboard_fab2(sch_1):page236_i79"
				( attribute "CDS_LIB" "mstr_discrete"
					( Origin gPackager )
				)
				( attribute "CDS_LOCATION" "C2L25"
					( Origin gPackager )
				)
				( attribute "LOCATION" "C2L25"
					( Origin gFrontEnd )
				)
				( attribute "MATERIAL" "ALUM"
					( Origin gFrontEnd )
				)
				( attribute "PACK_TYPE" "SM"
					( Origin gFrontEnd )
				)
				( attribute "PART_NUMBER" "699013-031"
					( Origin gFrontEnd )
				)
				( attribute "PHYS_PAGE" "236"
					( Origin gFrontEnd )
				)
				( attribute "ROOM" "P1V05_PCH_STBY"
					( Origin gFrontEnd )
				)
				( attribute "ROT" "0"
					( Origin gFrontEnd )
				)
				( attribute "SEC" "1"
					( Origin gFrontEnd )
				)
				( attribute "TOLERANCE" "20%"
					( Origin gFrontEnd )
				)
				( attribute "VALUE" "470UF"
					( Origin gFrontEnd )
				)
				( attribute "VER" "1"
					( Origin gFrontEnd )
				)
				( attribute "VOLTAGE" "2V"
					( Units "uVoltage" "V" 1.000000)
					( Origin gFrontEnd )
				)
				( attribute "XY" "(12700,2050)"
					( Origin gFrontEnd )
				)
				( attribute "CHIPS_PART_NAME" "CAPP"
					( Origin gPackager )
				)
				( attribute "CDS_PART_NAME" "CAPP_SM-470UF,2V,20%,ALUM,6990A"
					( Origin gPackager )
				)
				( attribute "SEC_TYPE" "SM"
					( Origin gFrontEnd )
				)
				( attribute "CDS_SEC" "1"
					( Origin gPackager )
				)
				( objectStatus "C2L25" )
			)
			( gate "@baseboard_fab2_lib.baseboard_fab2(sch_1):page236_i90"
				( attribute "BOM_COST" "P1V05_PCH_STBY"
					( Origin gFrontEnd )
				)
				( attribute "CDS_LIB" "mstr_discrete"
					( Origin gPackager )
				)
				( attribute "CDS_LOCATION" "R7A13"
					( Origin gPackager )
				)
				( attribute "LOCATION" "R7A13"
					( Origin gFrontEnd )
				)
				( attribute "MATERIAL" "CHIP"
					( Origin gFrontEnd )
				)
				( attribute "PACK_TYPE" "0402"
					( Origin gFrontEnd )
				)
				( attribute "PART_NUMBER" "G21796-017"
					( Origin gFrontEnd )
				)
				( attribute "PHYS_PAGE" "236"
					( Origin gFrontEnd )
				)
				( attribute "ROOM" "P1V05_PCH_STBY"
					( Origin gFrontEnd )
				)
				( attribute "ROT" "0"
					( Origin gFrontEnd )
				)
				( attribute "SEC" "1"
					( Origin gFrontEnd )
				)
				( attribute "SPOF" "TRUE"
					( Origin gFrontEnd )
				)
				( attribute "TOLERANCE" "1%"
					( Origin gFrontEnd )
				)
				( attribute "VALUE" "100.0"
					( Origin gFrontEnd )
				)
				( attribute "VER" "1"
					( Origin gFrontEnd )
				)
				( attribute "WATTAGE" "1/16W"
					( Origin gFrontEnd )
				)
				( attribute "XY" "(9200,1400)"
					( Origin gFrontEnd )
				)
				( attribute "CHIPS_PART_NAME" "RES"
					( Origin gPackager )
				)
				( attribute "CDS_PART_NAME" "RES_0402-100.0,1%,1/16W,CHIP,GA"
					( Origin gPackager )
				)
				( attribute "SEC_TYPE" "0402"
					( Origin gFrontEnd )
				)
				( attribute "CDS_SEC" "1"
					( Origin gPackager )
				)
				( objectStatus "R7A13" )
			)
			( gate "@baseboard_fab2_lib.baseboard_fab2(sch_1):page236_i92"
				( attribute "BOM_COST" "P1V05_PCH_STBY"
					( Origin gFrontEnd )
				)
				( attribute "CDS_LIB" "mstr_discrete"
					( Origin gPackager )
				)
				( attribute "CDS_LOCATION" "R7A18"
					( Origin gPackager )
				)
				( attribute "LOCATION" "R7A18"
					( Origin gFrontEnd )
				)
				( attribute "MATERIAL" "CHIP"
					( Origin gFrontEnd )
				)
				( attribute "PACK_TYPE" "0402"
					( Origin gFrontEnd )
				)
				( attribute "PART_NUMBER" "G21497-005"
					( Origin gFrontEnd )
				)
				( attribute "PHYS_PAGE" "236"
					( Origin gFrontEnd )
				)
				( attribute "ROOM" "P1V05_PCH_STBY"
					( Origin gFrontEnd )
				)
				( attribute "ROT" "0"
					( Origin gFrontEnd )
				)
				( attribute "SEC" "1"
					( Origin gFrontEnd )
				)
				( attribute "SPOF" "TRUE"
					( Origin gFrontEnd )
				)
				( attribute "TOLERANCE" "5%"
					( Origin gFrontEnd )
				)
				( attribute "VALUE" "0.0"
					( Origin gFrontEnd )
				)
				( attribute "VER" "1"
					( Origin gFrontEnd )
				)
				( attribute "WATTAGE" "1/16W"
					( Origin gFrontEnd )
				)
				( attribute "XY" "(9200,950)"
					( Origin gFrontEnd )
				)
				( attribute "CHIPS_PART_NAME" "RES"
					( Origin gPackager )
				)
				( attribute "CDS_PART_NAME" "RES_0402-0.0,5%,1/16W,CHIP,G21A"
					( Origin gPackager )
				)
				( attribute "SEC_TYPE" "0402"
					( Origin gFrontEnd )
				)
				( attribute "CDS_SEC" "1"
					( Origin gPackager )
				)
				( objectStatus "R7A18" )
			)
			( gate "@baseboard_fab2_lib.baseboard_fab2(sch_1):page236_i93"
				( attribute "BOM_COST" "P1V05_PCH_STBY"
					( Origin gFrontEnd )
				)
				( attribute "CDS_LIB" "mstr_discrete"
					( Origin gPackager )
				)
				( attribute "CDS_LOCATION" "R7A19"
					( Origin gPackager )
				)
				( attribute "CDS_SEC" "1"
					( Origin gPackager )
				)
				( attribute "LOCATION" "R7A19"
					( Origin gFrontEnd )
				)
				( attribute "MATERIAL" "CHIP"
					( Origin gFrontEnd )
				)
				( attribute "NO_XNET_CONNECTION" "1"
					( Origin gFrontEnd )
				)
				( attribute "PACK_TYPE" "0402"
					( Origin gFrontEnd )
				)
				( attribute "PART_NUMBER" "G21796-066"
					( Origin gFrontEnd )
				)
				( attribute "PHYS_PAGE" "236"
					( Origin gFrontEnd )
				)
				( attribute "ROOM" "P1V05_PCH_STBY"
					( Origin gFrontEnd )
				)
				( attribute "ROT" "0"
					( Origin gFrontEnd )
				)
				( attribute "SEC" "1"
					( Origin gFrontEnd )
				)
				( attribute "SEC_TYPE" "0402"
					( Origin gFrontEnd )
				)
				( attribute "SPOF" "TRUE"
					( Origin gFrontEnd )
				)
				( attribute "TOLERANCE" "1%"
					( Origin gFrontEnd )
				)
				( attribute "VALUE" "10.0"
					( Origin gFrontEnd )
				)
				( attribute "VER" "1"
					( Origin gFrontEnd )
				)
				( attribute "WATTAGE" "1/16W"
					( Origin gFrontEnd )
				)
				( attribute "XY" "(8725,1175)"
					( Origin gFrontEnd )
				)
				( attribute "CHIPS_PART_NAME" "RES"
					( Origin gPackager )
				)
				( attribute "CDS_PART_NAME" "RES_0402-10.0,1%,1/16W,CHIP,G2A"
					( Origin gPackager )
				)
				( objectStatus "R7A19" )
			)
			( gate "@baseboard_fab2_lib.baseboard_fab2(sch_1):page236_i94"
				( attribute "BOM_COST" "P1V05_PCH_STBY"
					( Origin gFrontEnd )
				)
				( attribute "CDS_LIB" "mstr_discrete"
					( Origin gPackager )
				)
				( attribute "CDS_LOCATION" "R7A14"
					( Origin gPackager )
				)
				( attribute "CDS_SEC" "1"
					( Origin gPackager )
				)
				( attribute "LOCATION" "R7A14"
					( Origin gFrontEnd )
				)
				( attribute "MATERIAL" "CHIP"
					( Origin gFrontEnd )
				)
				( attribute "NO_XNET_CONNECTION" "1"
					( Origin gFrontEnd )
				)
				( attribute "PACK_TYPE" "0402"
					( Origin gFrontEnd )
				)
				( attribute "PART_NUMBER" "G21796-066"
					( Origin gFrontEnd )
				)
				( attribute "PHYS_PAGE" "236"
					( Origin gFrontEnd )
				)
				( attribute "ROOM" "P1V05_PCH_STBY"
					( Origin gFrontEnd )
				)
				( attribute "ROT" "0"
					( Origin gFrontEnd )
				)
				( attribute "SEC" "1"
					( Origin gFrontEnd )
				)
				( attribute "SEC_TYPE" "0402"
					( Origin gFrontEnd )
				)
				( attribute "SPOF" "TRUE"
					( Origin gFrontEnd )
				)
				( attribute "TOLERANCE" "1%"
					( Origin gFrontEnd )
				)
				( attribute "VALUE" "10.0"
					( Origin gFrontEnd )
				)
				( attribute "VER" "1"
					( Origin gFrontEnd )
				)
				( attribute "WATTAGE" "1/16W"
					( Origin gFrontEnd )
				)
				( attribute "XY" "(8750,900)"
					( Origin gFrontEnd )
				)
				( attribute "CHIPS_PART_NAME" "RES"
					( Origin gPackager )
				)
				( attribute "CDS_PART_NAME" "RES_0402-10.0,1%,1/16W,CHIP,G2A"
					( Origin gPackager )
				)
				( objectStatus "R7A14" )
			)
			( gate "@baseboard_fab2_lib.baseboard_fab2(sch_1):page236_i116"
				( attribute "CDS_LIB" "mstr_discrete"
					( Origin gPackager )
				)
				( attribute "CDS_LOCATION" "EU7A3"
					( Origin gPackager )
				)
				( attribute "CDS_SEC" "1"
					( Origin gPackager )
				)
				( attribute "LOCATION" "EU7A3"
					( Origin gFrontEnd )
				)
				( attribute "MATERIAL" "IC"
					( Origin gFrontEnd )
				)
				( attribute "NO_XNET_CONNECTION" "1"
					( Origin gFrontEnd )
				)
				( attribute "PACK_TYPE" "SM"
					( Origin gFrontEnd )
				)
				( attribute "PART_NUMBER" "H73684-001"
					( Origin gFrontEnd )
				)
				( attribute "PHYS_PAGE" "236"
					( Origin gFrontEnd )
				)
				( attribute "ROT" "0"
					( Origin gFrontEnd )
				)
				( attribute "SEC" "1"
					( Origin gFrontEnd )
				)
				( attribute "SEC_TYPE" "SM"
					( Origin gFrontEnd )
				)
				( attribute "VALUE" "IR35412"
					( Origin gFrontEnd )
				)
				( attribute "VER" "1"
					( Origin gFrontEnd )
				)
				( attribute "XY" "(9850,4275)"
					( Origin gFrontEnd )
				)
				( attribute "CHIPS_PART_NAME" "IR354XX"
					( Origin gPackager )
				)
				( attribute "CDS_PART_NAME" "IR354XX_SM-IR35412,IC,H73684-0A"
					( Origin gPackager )
				)
				( objectStatus "EU7A3" )
			)
			( gate "@baseboard_fab2_lib.baseboard_fab2(sch_1):page236_i117"
				( attribute "CDS_LIB" "mstr_discrete"
					( Origin gPackager )
				)
				( attribute "CDS_LOCATION" "EU7A2"
					( Origin gPackager )
				)
				( attribute "LOCATION" "EU7A2"
					( Origin gFrontEnd )
				)
				( attribute "MATERIAL" "IC"
					( Origin gFrontEnd )
				)
				( attribute "NO_XNET_CONNECTION" "1"
					( Origin gFrontEnd )
				)
				( attribute "PACK_TYPE" "SM"
					( Origin gFrontEnd )
				)
				( attribute "PART_NUMBER" "H73684-001"
					( Origin gFrontEnd )
				)
				( attribute "PHYS_PAGE" "236"
					( Origin gFrontEnd )
				)
				( attribute "ROT" "0"
					( Origin gFrontEnd )
				)
				( attribute "SEC" "1"
					( Origin gFrontEnd )
				)
				( attribute "SEC_TYPE" "SM"
					( Origin gFrontEnd )
				)
				( attribute "VALUE" "IR35412"
					( Origin gFrontEnd )
				)
				( attribute "VER" "1"
					( Origin gFrontEnd )
				)
				( attribute "XY" "(9875,2525)"
					( Origin gFrontEnd )
				)
				( attribute "CHIPS_PART_NAME" "IR354XX"
					( Origin gPackager )
				)
				( attribute "CDS_PART_NAME" "IR354XX_SM-IR35412,IC,H73684-0A"
					( Origin gPackager )
				)
				( attribute "CDS_SEC" "1"
					( Origin gPackager )
				)
				( objectStatus "EU7A2" )
			)
			( gate "@baseboard_fab2_lib.baseboard_fab2(sch_1):page236_i118"
				( attribute "CDS_LIB" "mstr_discrete"
					( Origin gPackager )
				)
				( attribute "CDS_LOCATION" "R3L15"
					( Origin gPackager )
				)
				( attribute "LOCATION" "R3L15"
					( Origin gFrontEnd )
				)
				( attribute "MATERIAL" "EMPTY"
					( Origin gFrontEnd )
				)
				( attribute "PACK_TYPE" "0402"
					( Origin gFrontEnd )
				)
				( attribute "PART_NUMBER" "G21796-187"
					( Origin gFrontEnd )
				)
				( attribute "PHYS_PAGE" "236"
					( Origin gFrontEnd )
				)
				( attribute "ROT" "0"
					( Origin gFrontEnd )
				)
				( attribute "SEC" "1"
					( Origin gFrontEnd )
				)
				( attribute "TOLERANCE" "1%"
					( Origin gFrontEnd )
				)
				( attribute "VALUE" "68.1K"
					( Origin gFrontEnd )
				)
				( attribute "VER" "2"
					( Origin gFrontEnd )
				)
				( attribute "WATTAGE" "1/16W"
					( Origin gFrontEnd )
				)
				( attribute "XY" "(12125,4450)"
					( Origin gFrontEnd )
				)
				( attribute "CHIPS_PART_NAME" "RES"
					( Origin gPackager )
				)
				( attribute "CDS_PART_NAME" "RES_0402-68.1K,1%,1/16W,EMPTY,A"
					( Origin gPackager )
				)
				( attribute "SEC_TYPE" "0402"
					( Origin gFrontEnd )
				)
				( attribute "CDS_SEC" "1"
					( Origin gPackager )
				)
				( objectStatus "R3L15" )
			)
			( gate "@baseboard_fab2_lib.baseboard_fab2(sch_1):page236_i120"
				( attribute "CDS_LIB" "mstr_discrete"
					( Origin gPackager )
				)
				( attribute "CDS_LOCATION" "R3L14"
					( Origin gPackager )
				)
				( attribute "LOCATION" "R3L14"
					( Origin gFrontEnd )
				)
				( attribute "MATERIAL" "EMPTY"
					( Origin gFrontEnd )
				)
				( attribute "PACK_TYPE" "0402"
					( Origin gFrontEnd )
				)
				( attribute "PART_NUMBER" "G21796-187"
					( Origin gFrontEnd )
				)
				( attribute "PHYS_PAGE" "236"
					( Origin gFrontEnd )
				)
				( attribute "ROT" "0"
					( Origin gFrontEnd )
				)
				( attribute "SEC" "1"
					( Origin gFrontEnd )
				)
				( attribute "TOLERANCE" "1%"
					( Origin gFrontEnd )
				)
				( attribute "VALUE" "68.1K"
					( Origin gFrontEnd )
				)
				( attribute "VER" "2"
					( Origin gFrontEnd )
				)
				( attribute "WATTAGE" "1/16W"
					( Origin gFrontEnd )
				)
				( attribute "XY" "(12150,2700)"
					( Origin gFrontEnd )
				)
				( attribute "CHIPS_PART_NAME" "RES"
					( Origin gPackager )
				)
				( attribute "CDS_PART_NAME" "RES_0402-68.1K,1%,1/16W,EMPTY,A"
					( Origin gPackager )
				)
				( attribute "SEC_TYPE" "0402"
					( Origin gFrontEnd )
				)
				( attribute "CDS_SEC" "1"
					( Origin gPackager )
				)
				( objectStatus "R3L14" )
			)
			( gate "@baseboard_fab2_lib.baseboard_fab2(sch_1):page237_i3"
				( attribute "BOM_COST" "P1V8_PCH_STBY_VR"
					( Origin gFrontEnd )
				)
				( attribute "CDS_LIB" "mstr_discrete"
					( Origin gPackager )
				)
				( attribute "CDS_LOCATION" "R8A10"
					( Origin gPackager )
				)
				( attribute "CDS_SEC" "1"
					( Origin gPackager )
				)
				( attribute "LOCATION" "R8A10"
					( Origin gFrontEnd )
				)
				( attribute "MATERIAL" "CHIP"
					( Origin gFrontEnd )
				)
				( attribute "PACK_TYPE" "0402"
					( Origin gFrontEnd )
				)
				( attribute "PART_NUMBER" "G21796-140"
					( Origin gFrontEnd )
				)
				( attribute "PHYS_PAGE" "237"
					( Origin gFrontEnd )
				)
				( attribute "ROOM" "P1V8_PCH_STBY_VR"
					( Origin gFrontEnd )
				)
				( attribute "ROT" "0"
					( Origin gFrontEnd )
				)
				( attribute "SEC" "1"
					( Origin gPackager )
				)
				( attribute "TOLERANCE" "1%"
					( Origin gFrontEnd )
				)
				( attribute "VALUE" "5.11K"
					( Origin gFrontEnd )
				)
				( attribute "VER" "2"
					( Origin gFrontEnd )
				)
				( attribute "WATTAGE" "1/16W"
					( Origin gFrontEnd )
				)
				( attribute "XY" "(1350,3875)"
					( Origin gFrontEnd )
				)
				( attribute "CHIPS_PART_NAME" "RES"
					( Origin gPackager )
				)
				( attribute "CDS_PART_NAME" "RES_0402-5.11K,1%,1/16W,CHIP,GA"
					( Origin gPackager )
				)
				( objectStatus "R8A10" )
			)
			( gate "@baseboard_fab2_lib.baseboard_fab2(sch_1):page237_i5"
				( attribute "BOM_COST" "P1V8_PCH_STBY_VR"
					( Origin gFrontEnd )
				)
				( attribute "CDS_LIB" "mstr_discrete"
					( Origin gPackager )
				)
				( attribute "CDS_LOCATION" "C8A11"
					( Origin gPackager )
				)
				( attribute "CDS_SEC" "1"
					( Origin gPackager )
				)
				( attribute "LOCATION" "C8A11"
					( Origin gFrontEnd )
				)
				( attribute "MATERIAL" "X7R"
					( Origin gFrontEnd )
				)
				( attribute "PACK_TYPE" "0402LF"
					( Origin gFrontEnd )
				)
				( attribute "PART_NUMBER" "A36096-046"
					( Origin gFrontEnd )
				)
				( attribute "PHYS_PAGE" "237"
					( Origin gFrontEnd )
				)
				( attribute "ROOM" "P1V8_PCH_STBY_VR"
					( Origin gFrontEnd )
				)
				( attribute "ROT" "0"
					( Origin gFrontEnd )
				)
				( attribute "SEC" "1"
					( Origin gPackager )
				)
				( attribute "TOLERANCE" "10%"
					( Origin gFrontEnd )
				)
				( attribute "VALUE" "1000PF"
					( Origin gFrontEnd )
				)
				( attribute "VER" "1"
					( Origin gFrontEnd )
				)
				( attribute "VOLTAGE" "50V"
					( Units "uVoltage" "V" 1.000000)
					( Origin gFrontEnd )
				)
				( attribute "XY" "(1350,3475)"
					( Origin gFrontEnd )
				)
				( attribute "CHIPS_PART_NAME" "CAP"
					( Origin gPackager )
				)
				( attribute "CDS_PART_NAME" "CAP_0402LF-1000PF,50V,10%,X7R,A"
					( Origin gPackager )
				)
				( objectStatus "C8A11" )
			)
			( gate "@baseboard_fab2_lib.baseboard_fab2(sch_1):page237_i12"
				( attribute "BOM_COST" "P1V8_PCH_STBY_VR"
					( Origin gFrontEnd )
				)
				( attribute "CDS_LIB" "mstr_discrete"
					( Origin gPackager )
				)
				( attribute "CDS_LOCATION" "C2L45"
					( Origin gPackager )
				)
				( attribute "CDS_SEC" "1"
					( Origin gPackager )
				)
				( attribute "LOCATION" "C2L45"
					( Origin gFrontEnd )
				)
				( attribute "MATERIAL" "X6S"
					( Origin gFrontEnd )
				)
				( attribute "PACK_TYPE" "0805"
					( Origin gFrontEnd )
				)
				( attribute "PART_NUMBER" "C95333-008"
					( Origin gFrontEnd )
				)
				( attribute "PHYS_PAGE" "237"
					( Origin gFrontEnd )
				)
				( attribute "ROOM" "P1V8_PCH_STBY_VR"
					( Origin gFrontEnd )
				)
				( attribute "ROT" "0"
					( Origin gFrontEnd )
				)
				( attribute "SEC" "1"
					( Origin gPackager )
				)
				( attribute "TOLERANCE" "20%"
					( Origin gFrontEnd )
				)
				( attribute "VALUE" "22UF"
					( Origin gFrontEnd )
				)
				( attribute "VER" "1"
					( Origin gFrontEnd )
				)
				( attribute "VOLTAGE" "6.3V"
					( Units "uVoltage" "V" 1.000000)
					( Origin gFrontEnd )
				)
				( attribute "XY" "(3375,2150)"
					( Origin gFrontEnd )
				)
				( attribute "CHIPS_PART_NAME" "CAP"
					( Origin gPackager )
				)
				( attribute "CDS_PART_NAME" "CAP_0805-22UF,6.3V,20%,X6S,C95A"
					( Origin gPackager )
				)
				( objectStatus "C2L45" )
			)
			( gate "@baseboard_fab2_lib.baseboard_fab2(sch_1):page237_i13"
				( attribute "BOM_COST" "P1V8_PCH_STBY_VR"
					( Origin gFrontEnd )
				)
				( attribute "CDS_LIB" "mstr_discrete"
					( Origin gPackager )
				)
				( attribute "CDS_LOCATION" "C8A14"
					( Origin gPackager )
				)
				( attribute "CDS_SEC" "1"
					( Origin gPackager )
				)
				( attribute "LOCATION" "C8A14"
					( Origin gFrontEnd )
				)
				( attribute "MATERIAL" "X6S"
					( Origin gFrontEnd )
				)
				( attribute "PACK_TYPE" "0805"
					( Origin gFrontEnd )
				)
				( attribute "PART_NUMBER" "C95333-008"
					( Origin gFrontEnd )
				)
				( attribute "PHYS_PAGE" "237"
					( Origin gFrontEnd )
				)
				( attribute "ROOM" "P1V8_PCH_STBY_VR"
					( Origin gFrontEnd )
				)
				( attribute "ROT" "0"
					( Origin gFrontEnd )
				)
				( attribute "SEC" "1"
					( Origin gFrontEnd )
				)
				( attribute "SEC_TYPE" "0805"
					( Origin gFrontEnd )
				)
				( attribute "TOLERANCE" "20%"
					( Origin gFrontEnd )
				)
				( attribute "VALUE" "22UF"
					( Origin gFrontEnd )
				)
				( attribute "VER" "1"
					( Origin gFrontEnd )
				)
				( attribute "VOLTAGE" "6.3V"
					( Units "uVoltage" "V" 1.000000)
					( Origin gFrontEnd )
				)
				( attribute "XY" "(3100,2200)"
					( Origin gFrontEnd )
				)
				( attribute "CHIPS_PART_NAME" "CAP"
					( Origin gPackager )
				)
				( attribute "CDS_PART_NAME" "CAP_0805-22UF,6.3V,20%,X6S,C95A"
					( Origin gPackager )
				)
				( objectStatus "C8A14" )
			)
			( gate "@baseboard_fab2_lib.baseboard_fab2(sch_1):page237_i15"
				( attribute "BOM_COST" "P1V8_PCH_STBY_VR"
					( Origin gFrontEnd )
				)
				( attribute "CDS_LIB" "mstr_discrete"
					( Origin gPackager )
				)
				( attribute "CDS_LOCATION" "R8A12"
					( Origin gPackager )
				)
				( attribute "CDS_SEC" "1"
					( Origin gPackager )
				)
				( attribute "LOCATION" "R8A12"
					( Origin gFrontEnd )
				)
				( attribute "MATERIAL" "CHIP"
					( Origin gFrontEnd )
				)
				( attribute "PACK_TYPE" "0603"
					( Origin gFrontEnd )
				)
				( attribute "PART_NUMBER" "G22026-030"
					( Origin gFrontEnd )
				)
				( attribute "PHYS_PAGE" "237"
					( Origin gFrontEnd )
				)
				( attribute "ROOM" "P1V8_PCH_STBY_VR"
					( Origin gFrontEnd )
				)
				( attribute "ROT" "0"
					( Origin gFrontEnd )
				)
				( attribute "SEC" "1"
					( Origin gFrontEnd )
				)
				( attribute "SEC_TYPE" "0603"
					( Origin gFrontEnd )
				)
				( attribute "TOLERANCE" "1%"
					( Origin gFrontEnd )
				)
				( attribute "VALUE" "475.0"
					( Origin gFrontEnd )
				)
				( attribute "VER" "2"
					( Origin gFrontEnd )
				)
				( attribute "WATTAGE" "1/10W"
					( Origin gFrontEnd )
				)
				( attribute "XY" "(2800,2125)"
					( Origin gFrontEnd )
				)
				( attribute "CHIPS_PART_NAME" "RES"
					( Origin gPackager )
				)
				( attribute "CDS_PART_NAME" "RES_0603-475.0,1%,1/10W,CHIP,GA"
					( Origin gPackager )
				)
				( objectStatus "R8A12" )
			)
			( gate "@baseboard_fab2_lib.baseboard_fab2(sch_1):page237_i29"
				( attribute "BOM_COST" "P1V8_PCH_STBY_VR"
					( Origin gFrontEnd )
				)
				( attribute "CDS_LIB" "mstr_discrete"
					( Origin gPackager )
				)
				( attribute "CDS_LOCATION" "C8A6"
					( Origin gPackager )
				)
				( attribute "CDS_SEC" "1"
					( Origin gPackager )
				)
				( attribute "LOCATION" "C8A6"
					( Origin gFrontEnd )
				)
				( attribute "MATERIAL" "X6S"
					( Origin gFrontEnd )
				)
				( attribute "PACK_TYPE" "0603"
					( Origin gFrontEnd )
				)
				( attribute "PART_NUMBER" "E15431-002"
					( Origin gFrontEnd )
				)
				( attribute "PHYS_PAGE" "237"
					( Origin gFrontEnd )
				)
				( attribute "ROOM" "P1V8_PCH_STBY_VR"
					( Origin gFrontEnd )
				)
				( attribute "ROT" "0"
					( Origin gFrontEnd )
				)
				( attribute "SEC" "1"
					( Origin gFrontEnd )
				)
				( attribute "SEC_TYPE" "0603"
					( Origin gFrontEnd )
				)
				( attribute "TOLERANCE" "20%"
					( Origin gFrontEnd )
				)
				( attribute "VALUE" "10UF"
					( Origin gFrontEnd )
				)
				( attribute "VER" "1"
					( Origin gFrontEnd )
				)
				( attribute "VOLTAGE" "6.3V"
					( Units "uVoltage" "V" 1.000000)
					( Origin gFrontEnd )
				)
				( attribute "XY" "(-1975,3150)"
					( Origin gFrontEnd )
				)
				( attribute "CHIPS_PART_NAME" "CAP"
					( Origin gPackager )
				)
				( attribute "CDS_PART_NAME" "CAP_0603-10UF,6.3V,20%,X6S,E15A"
					( Origin gPackager )
				)
				( objectStatus "C8A6" )
			)
			( gate "@baseboard_fab2_lib.baseboard_fab2(sch_1):page237_i31"
				( attribute "BOM_COST" "P1V8_PCH_STBY_VR"
					( Origin gFrontEnd )
				)
				( attribute "CDS_LIB" "mstr_discrete"
					( Origin gPackager )
				)
				( attribute "CDS_LOCATION" "C8A4"
					( Origin gPackager )
				)
				( attribute "CDS_SEC" "1"
					( Origin gPackager )
				)
				( attribute "LOCATION" "C8A4"
					( Origin gFrontEnd )
				)
				( attribute "MATERIAL" "X7R"
					( Origin gFrontEnd )
				)
				( attribute "PACK_TYPE" "0603LF"
					( Origin gFrontEnd )
				)
				( attribute "PART_NUMBER" "602433-020"
					( Origin gFrontEnd )
				)
				( attribute "PHYS_PAGE" "237"
					( Origin gFrontEnd )
				)
				( attribute "ROOM" "P1V8_PCH_STBY_VR"
					( Origin gFrontEnd )
				)
				( attribute "ROT" "0"
					( Origin gFrontEnd )
				)
				( attribute "SEC" "1"
					( Origin gFrontEnd )
				)
				( attribute "SEC_TYPE" "0603LF"
					( Origin gFrontEnd )
				)
				( attribute "TOLERANCE" "10%"
					( Origin gFrontEnd )
				)
				( attribute "VALUE" "0.1UF"
					( Origin gFrontEnd )
				)
				( attribute "VER" "1"
					( Origin gFrontEnd )
				)
				( attribute "VOLTAGE" "25V"
					( Units "uVoltage" "V" 1.000000)
					( Origin gFrontEnd )
				)
				( attribute "XY" "(-1550,3175)"
					( Origin gFrontEnd )
				)
				( attribute "CHIPS_PART_NAME" "CAP"
					( Origin gPackager )
				)
				( attribute "CDS_PART_NAME" "CAP_0603LF-0.1UF,25V,10%,X7R,6A"
					( Origin gPackager )
				)
				( objectStatus "C8A4" )
			)
			( gate "@baseboard_fab2_lib.baseboard_fab2(sch_1):page237_i55"
				( attribute "BOM_COST" "P1V8_PCH_STBY_VR"
					( Origin gFrontEnd )
				)
				( attribute "CDS_LIB" "mstr_discrete"
					( Origin gPackager )
				)
				( attribute "CDS_LOCATION" "C8A10"
					( Origin gPackager )
				)
				( attribute "CDS_SEC" "1"
					( Origin gPackager )
				)
				( attribute "LOCATION" "C8A10"
					( Origin gFrontEnd )
				)
				( attribute "MATERIAL" "EMPTY"
					( Origin gFrontEnd )
				)
				( attribute "PACK_TYPE" "0402LF"
					( Origin gFrontEnd )
				)
				( attribute "PART_NUMBER" "A36096-046"
					( Origin gFrontEnd )
				)
				( attribute "PHYS_PAGE" "237"
					( Origin gFrontEnd )
				)
				( attribute "ROOM" "P1V8_PCH_STBY_VR"
					( Origin gFrontEnd )
				)
				( attribute "ROT" "2"
					( Origin gFrontEnd )
				)
				( attribute "SEC" "1"
					( Origin gPackager )
				)
				( attribute "TOLERANCE" "10%"
					( Origin gFrontEnd )
				)
				( attribute "VALUE" "1000PF"
					( Origin gFrontEnd )
				)
				( attribute "VER" "1"
					( Origin gFrontEnd )
				)
				( attribute "VOLTAGE" "50V"
					( Units "uVoltage" "V" 1.000000)
					( Origin gFrontEnd )
				)
				( attribute "XY" "(-1500,2200)"
					( Origin gFrontEnd )
				)
				( attribute "CHIPS_PART_NAME" "CAP"
					( Origin gPackager )
				)
				( attribute "CDS_PART_NAME" "CAP_0402LF-1000PF,50V,10%,EMPTA"
					( Origin gPackager )
				)
				( objectStatus "C8A10" )
			)
			( gate "@baseboard_fab2_lib.baseboard_fab2(sch_1):page237_i77"
				( attribute "CDS_LIB" "mstr_discrete"
					( Origin gPackager )
				)
				( attribute "CDS_LOCATION" "C8A12"
					( Origin gPackager )
				)
				( attribute "CDS_SEC" "1"
					( Origin gPackager )
				)
				( attribute "LOCATION" "C8A12"
					( Origin gFrontEnd )
				)
				( attribute "MATERIAL" "X6S"
					( Origin gFrontEnd )
				)
				( attribute "PACK_TYPE" "0805"
					( Origin gFrontEnd )
				)
				( attribute "PART_NUMBER" "C95333-006"
					( Origin gFrontEnd )
				)
				( attribute "PHYS_PAGE" "237"
					( Origin gFrontEnd )
				)
				( attribute "ROOM" "P1V8_PCH_STBY_VR"
					( Origin gFrontEnd )
				)
				( attribute "ROT" "0"
					( Origin gFrontEnd )
				)
				( attribute "SEC" "1"
					( Origin gFrontEnd )
				)
				( attribute "SEC_TYPE" "0805"
					( Origin gFrontEnd )
				)
				( attribute "TOLERANCE" "20%"
					( Origin gFrontEnd )
				)
				( attribute "VALUE" "47UF"
					( Origin gFrontEnd )
				)
				( attribute "VER" "1"
					( Origin gFrontEnd )
				)
				( attribute "VOLTAGE" "4V"
					( Units "uVoltage" "V" 1.000000)
					( Origin gFrontEnd )
				)
				( attribute "XY" "(3650,2200)"
					( Origin gFrontEnd )
				)
				( attribute "CHIPS_PART_NAME" "CAP"
					( Origin gPackager )
				)
				( attribute "CDS_PART_NAME" "CAP_0805-47UF,4V,20%,X6S,C9533A"
					( Origin gPackager )
				)
				( objectStatus "C8A12" )
			)
			( gate "@baseboard_fab2_lib.baseboard_fab2(sch_1):page237_i79"
				( attribute "CDS_LIB" "mstr_discrete"
					( Origin gPackager )
				)
				( attribute "CDS_LOCATION" "C2L32"
					( Origin gPackager )
				)
				( attribute "CDS_SEC" "1"
					( Origin gPackager )
				)
				( attribute "LOCATION" "C2L32"
					( Origin gFrontEnd )
				)
				( attribute "MATERIAL" "X6S"
					( Origin gFrontEnd )
				)
				( attribute "PACK_TYPE" "0805"
					( Origin gFrontEnd )
				)
				( attribute "PART_NUMBER" "C95333-006"
					( Origin gFrontEnd )
				)
				( attribute "PHYS_PAGE" "237"
					( Origin gFrontEnd )
				)
				( attribute "ROOM" "P1V8_PCH_STBY_VR"
					( Origin gFrontEnd )
				)
				( attribute "ROT" "0"
					( Origin gFrontEnd )
				)
				( attribute "SEC" "1"
					( Origin gFrontEnd )
				)
				( attribute "SEC_TYPE" "0805"
					( Origin gFrontEnd )
				)
				( attribute "TOLERANCE" "20%"
					( Origin gFrontEnd )
				)
				( attribute "VALUE" "47UF"
					( Origin gFrontEnd )
				)
				( attribute "VER" "1"
					( Origin gFrontEnd )
				)
				( attribute "VOLTAGE" "4V"
					( Units "uVoltage" "V" 1.000000)
					( Origin gFrontEnd )
				)
				( attribute "XY" "(3900,1850)"
					( Origin gFrontEnd )
				)
				( attribute "CHIPS_PART_NAME" "CAP"
					( Origin gPackager )
				)
				( attribute "CDS_PART_NAME" "CAP_0805-47UF,4V,20%,X6S,C9533A"
					( Origin gPackager )
				)
				( objectStatus "C2L32" )
			)
			( gate "@baseboard_fab2_lib.baseboard_fab2(sch_1):page237_i80"
				( attribute "CDS_LIB" "mstr_discrete"
					( Origin gPackager )
				)
				( attribute "CDS_LOCATION" "R2L19"
					( Origin gPackager )
				)
				( attribute "CDS_SEC" "1"
					( Origin gPackager )
				)
				( attribute "LOCATION" "R2L19"
					( Origin gFrontEnd )
				)
				( attribute "MATERIAL" "CHIP"
					( Origin gFrontEnd )
				)
				( attribute "PACK_TYPE" "0402"
					( Origin gFrontEnd )
				)
				( attribute "PART_NUMBER" "G21796-048"
					( Origin gFrontEnd )
				)
				( attribute "PHYS_PAGE" "237"
					( Origin gFrontEnd )
				)
				( attribute "ROOM" "P1V8_PCH_STBY_VR"
					( Origin gFrontEnd )
				)
				( attribute "ROT" "0"
					( Origin gFrontEnd )
				)
				( attribute "SEC" "1"
					( Origin gFrontEnd )
				)
				( attribute "SEC_TYPE" "0402"
					( Origin gFrontEnd )
				)
				( attribute "TOLERANCE" "1%"
					( Origin gFrontEnd )
				)
				( attribute "VALUE" "49.9K"
					( Origin gFrontEnd )
				)
				( attribute "VER" "2"
					( Origin gFrontEnd )
				)
				( attribute "WATTAGE" "1/16W"
					( Origin gFrontEnd )
				)
				( attribute "XY" "(2325,1700)"
					( Origin gFrontEnd )
				)
				( attribute "CHIPS_PART_NAME" "RES"
					( Origin gPackager )
				)
				( attribute "CDS_PART_NAME" "RES_0402-49.9K,1%,1/16W,CHIP,GA"
					( Origin gPackager )
				)
				( objectStatus "R2L19" )
			)
			( gate "@baseboard_fab2_lib.baseboard_fab2(sch_1):page237_i81"
				( attribute "CDS_LIB" "mstr_discrete"
					( Origin gPackager )
				)
				( attribute "CDS_LOCATION" "R2L20"
					( Origin gPackager )
				)
				( attribute "CDS_SEC" "1"
					( Origin gPackager )
				)
				( attribute "LOCATION" "R2L20"
					( Origin gFrontEnd )
				)
				( attribute "MATERIAL" "CHIP"
					( Origin gFrontEnd )
				)
				( attribute "PACK_TYPE" "0402"
					( Origin gFrontEnd )
				)
				( attribute "PART_NUMBER" "G21796-327"
					( Origin gFrontEnd )
				)
				( attribute "PHYS_PAGE" "237"
					( Origin gFrontEnd )
				)
				( attribute "ROOM" "P1V8_PCH_STBY_VR"
					( Origin gFrontEnd )
				)
				( attribute "ROT" "0"
					( Origin gFrontEnd )
				)
				( attribute "SEC" "1"
					( Origin gFrontEnd )
				)
				( attribute "SEC_TYPE" "0402"
					( Origin gFrontEnd )
				)
				( attribute "TOLERANCE" "1.0%"
					( Origin gFrontEnd )
				)
				( attribute "VALUE" "63.4K"
					( Origin gFrontEnd )
				)
				( attribute "VER" "2"
					( Origin gFrontEnd )
				)
				( attribute "WATTAGE" "1/16W"
					( Origin gFrontEnd )
				)
				( attribute "XY" "(2325,2275)"
					( Origin gFrontEnd )
				)
				( attribute "CHIPS_PART_NAME" "RES"
					( Origin gPackager )
				)
				( attribute "CDS_PART_NAME" "RES_0402-63.4K,1.0%,1/16W,CHIPA"
					( Origin gPackager )
				)
				( objectStatus "R2L20" )
			)
			( gate "@baseboard_fab2_lib.baseboard_fab2(sch_1):page237_i86"
				( attribute "CDS_LIB" "mstr_vreg"
					( Origin gPackager )
				)
				( attribute "CDS_LOCATION" "EU8A2"
					( Origin gPackager )
				)
				( attribute "CDS_SEC" "1"
					( Origin gPackager )
				)
				( attribute "LOCATION" "EU8A2"
					( Origin gFrontEnd )
				)
				( attribute "MATERIAL" "IC"
					( Origin gFrontEnd )
				)
				( attribute "PACK_TYPE" "DFN"
					( Origin gFrontEnd )
				)
				( attribute "PART_NUMBER" "H65765-001"
					( Origin gFrontEnd )
				)
				( attribute "PHYS_PAGE" "237"
					( Origin gFrontEnd )
				)
				( attribute "ROOM" "P1V8_PCH_STBY_VR"
					( Origin gFrontEnd )
				)
				( attribute "ROT" "0"
					( Origin gFrontEnd )
				)
				( attribute "SEC" "1"
					( Origin gFrontEnd )
				)
				( attribute "SEC_TYPE" "DFN"
					( Origin gFrontEnd )
				)
				( attribute "VER" "1"
					( Origin gFrontEnd )
				)
				( attribute "XY" "(-50,2725)"
					( Origin gFrontEnd )
				)
				( attribute "CHIPS_PART_NAME" "RT9059"
					( Origin gPackager )
				)
				( attribute "CDS_PART_NAME" "RT9059_DFN-IC,H65765-001"
					( Origin gPackager )
				)
				( objectStatus "EU8A2" )
			)
			( gate "@baseboard_fab2_lib.baseboard_fab2(sch_1):page237_i90"
				( attribute "CDS_LIB" "mstr_discrete"
					( Origin gPackager )
				)
				( attribute "CDS_LOCATION" "R8A11"
					( Origin gPackager )
				)
				( attribute "CDS_SEC" "1"
					( Origin gPackager )
				)
				( attribute "LOCATION" "R8A11"
					( Origin gFrontEnd )
				)
				( attribute "MATERIAL" "CHIP"
					( Origin gFrontEnd )
				)
				( attribute "PACK_TYPE" "0402"
					( Origin gFrontEnd )
				)
				( attribute "PART_NUMBER" "G21796-250"
					( Origin gFrontEnd )
				)
				( attribute "PHYS_PAGE" "237"
					( Origin gFrontEnd )
				)
				( attribute "ROOM" "P1V8_PCH_STBY_VR"
					( Origin gFrontEnd )
				)
				( attribute "ROT" "0"
					( Origin gFrontEnd )
				)
				( attribute "SEC" "1"
					( Origin gFrontEnd )
				)
				( attribute "SEC_TYPE" "0402"
					( Origin gFrontEnd )
				)
				( attribute "TOLERANCE" "1.0%"
					( Origin gFrontEnd )
				)
				( attribute "VALUE" "22.1"
					( Origin gFrontEnd )
				)
				( attribute "VER" "1"
					( Origin gFrontEnd )
				)
				( attribute "WATTAGE" "1/16W"
					( Origin gFrontEnd )
				)
				( attribute "XY" "(2175,3650)"
					( Origin gFrontEnd )
				)
				( attribute "CHIPS_PART_NAME" "RES"
					( Origin gPackager )
				)
				( attribute "CDS_PART_NAME" "RES_0402-22.1,1.0%,1/16W,CHIP,A"
					( Origin gPackager )
				)
				( objectStatus "R8A11" )
			)
			( gate "@baseboard_fab2_lib.baseboard_fab2(sch_1):page238_i5"
				( attribute "BOM_COST" "P1V26_BMC_STBY_VR"
					( Origin gFrontEnd )
				)
				( attribute "CDS_LIB" "mstr_discrete"
					( Origin gPackager )
				)
				( attribute "CDS_LOCATION" "C9F9"
					( Origin gPackager )
				)
				( attribute "CDS_SEC" "1"
					( Origin gPackager )
				)
				( attribute "LOCATION" "C9F9"
					( Origin gFrontEnd )
				)
				( attribute "MATERIAL" "EMPTY"
					( Origin gFrontEnd )
				)
				( attribute "PACK_TYPE" "0402LF"
					( Origin gFrontEnd )
				)
				( attribute "PART_NUMBER" "A36096-046"
					( Origin gFrontEnd )
				)
				( attribute "PHYS_PAGE" "238"
					( Origin gFrontEnd )
				)
				( attribute "ROOM" "P1V26_BMC_STBY_VR"
					( Origin gFrontEnd )
				)
				( attribute "ROT" "2"
					( Origin gFrontEnd )
				)
				( attribute "SEC" "1"
					( Origin gPackager )
				)
				( attribute "TOLERANCE" "10%"
					( Origin gFrontEnd )
				)
				( attribute "VALUE" "1000PF"
					( Origin gFrontEnd )
				)
				( attribute "VER" "1"
					( Origin gFrontEnd )
				)
				( attribute "VOLTAGE" "50V"
					( Units "uVoltage" "V" 1.000000)
					( Origin gFrontEnd )
				)
				( attribute "XY" "(-2000,2175)"
					( Origin gFrontEnd )
				)
				( attribute "CHIPS_PART_NAME" "CAP"
					( Origin gPackager )
				)
				( attribute "CDS_PART_NAME" "CAP_0402LF-1000PF,50V,10%,EMPTA"
					( Origin gPackager )
				)
				( objectStatus "C9F9" )
			)
			( gate "@baseboard_fab2_lib.baseboard_fab2(sch_1):page238_i7"
				( attribute "BOM_COST" "P1V26_BMC_STBY_VR"
					( Origin gFrontEnd )
				)
				( attribute "CDS_LIB" "mstr_discrete"
					( Origin gPackager )
				)
				( attribute "CDS_LOCATION" "C9F3"
					( Origin gPackager )
				)
				( attribute "CDS_SEC" "1"
					( Origin gPackager )
				)
				( attribute "LOCATION" "C9F3"
					( Origin gFrontEnd )
				)
				( attribute "MATERIAL" "X6S"
					( Origin gFrontEnd )
				)
				( attribute "PACK_TYPE" "0603"
					( Origin gFrontEnd )
				)
				( attribute "PART_NUMBER" "E15431-002"
					( Origin gFrontEnd )
				)
				( attribute "PHYS_PAGE" "238"
					( Origin gFrontEnd )
				)
				( attribute "ROOM" "P1V26_BMC_STBY_VR"
					( Origin gFrontEnd )
				)
				( attribute "ROT" "0"
					( Origin gFrontEnd )
				)
				( attribute "SEC" "1"
					( Origin gFrontEnd )
				)
				( attribute "SEC_TYPE" "0603"
					( Origin gFrontEnd )
				)
				( attribute "TOLERANCE" "20%"
					( Origin gFrontEnd )
				)
				( attribute "VALUE" "10UF"
					( Origin gFrontEnd )
				)
				( attribute "VER" "1"
					( Origin gFrontEnd )
				)
				( attribute "VOLTAGE" "6.3V"
					( Units "uVoltage" "V" 1.000000)
					( Origin gFrontEnd )
				)
				( attribute "XY" "(-2500,3025)"
					( Origin gFrontEnd )
				)
				( attribute "CHIPS_PART_NAME" "CAP"
					( Origin gPackager )
				)
				( attribute "CDS_PART_NAME" "CAP_0603-10UF,6.3V,20%,X6S,E15A"
					( Origin gPackager )
				)
				( objectStatus "C9F3" )
			)
			( gate "@baseboard_fab2_lib.baseboard_fab2(sch_1):page238_i14"
				( attribute "BOM_COST" "P1V26_BMC_STBY_VR"
					( Origin gFrontEnd )
				)
				( attribute "CDS_LIB" "mstr_discrete"
					( Origin gPackager )
				)
				( attribute "CDS_LOCATION" "R9F8"
					( Origin gPackager )
				)
				( attribute "CDS_SEC" "1"
					( Origin gPackager )
				)
				( attribute "LOCATION" "R9F8"
					( Origin gFrontEnd )
				)
				( attribute "MATERIAL" "CHIP"
					( Origin gFrontEnd )
				)
				( attribute "P1V5_STBY_IBMC" "<< NULL >>"
					( Origin gFrontEnd )
				)
				( attribute "P1V5_STBY_IBMC_VR" "<< NULL >>"
					( Origin gFrontEnd )
				)
				( attribute "PACK_TYPE" "0402"
					( Origin gFrontEnd )
				)
				( attribute "PART_NUMBER" "G21796-016"
					( Origin gFrontEnd )
				)
				( attribute "PHYS_PAGE" "238"
					( Origin gFrontEnd )
				)
				( attribute "ROOM" "P1V26_BMC_STBY_VR"
					( Origin gFrontEnd )
				)
				( attribute "ROT" "1"
					( Origin gFrontEnd )
				)
				( attribute "SEC" "1"
					( Origin gFrontEnd )
				)
				( attribute "SEC_TYPE" "0402"
					( Origin gFrontEnd )
				)
				( attribute "TOLERANCE" "1%"
					( Origin gFrontEnd )
				)
				( attribute "VALUE" "10.0K"
					( Origin gFrontEnd )
				)
				( attribute "VER" "1"
					( Origin gFrontEnd )
				)
				( attribute "WATTAGE" "1/16W"
					( Origin gFrontEnd )
				)
				( attribute "XY" "(1025,2100)"
					( Origin gFrontEnd )
				)
				( attribute "CHIPS_PART_NAME" "RES"
					( Origin gPackager )
				)
				( attribute "CDS_PART_NAME" "RES_0402-10.0K,1%,1/16W,CHIP,GA"
					( Origin gPackager )
				)
				( objectStatus "R9F8" )
			)
			( gate "@baseboard_fab2_lib.baseboard_fab2(sch_1):page238_i19"
				( attribute "BOM_COST" "P1V26_BMC_STBY_VR"
					( Origin gFrontEnd )
				)
				( attribute "CDS_LIB" "mstr_discrete"
					( Origin gPackager )
				)
				( attribute "CDS_LOCATION" "C9F8"
					( Origin gPackager )
				)
				( attribute "CDS_SEC" "1"
					( Origin gPackager )
				)
				( attribute "LOCATION" "C9F8"
					( Origin gFrontEnd )
				)
				( attribute "MATERIAL" "X7R"
					( Origin gFrontEnd )
				)
				( attribute "PACK_TYPE" "0402LF"
					( Origin gFrontEnd )
				)
				( attribute "PART_NUMBER" "A36096-046"
					( Origin gFrontEnd )
				)
				( attribute "PHYS_PAGE" "238"
					( Origin gFrontEnd )
				)
				( attribute "ROOM" "P1V26_BMC_STBY_VR"
					( Origin gFrontEnd )
				)
				( attribute "ROT" "0"
					( Origin gFrontEnd )
				)
				( attribute "SEC" "1"
					( Origin gPackager )
				)
				( attribute "TOLERANCE" "10%"
					( Origin gFrontEnd )
				)
				( attribute "VALUE" "1000PF"
					( Origin gFrontEnd )
				)
				( attribute "VER" "1"
					( Origin gFrontEnd )
				)
				( attribute "VOLTAGE" "50V"
					( Units "uVoltage" "V" 1.000000)
					( Origin gFrontEnd )
				)
				( attribute "XY" "(1250,3050)"
					( Origin gFrontEnd )
				)
				( attribute "CHIPS_PART_NAME" "CAP"
					( Origin gPackager )
				)
				( attribute "CDS_PART_NAME" "CAP_0402LF-1000PF,50V,10%,X7R,A"
					( Origin gPackager )
				)
				( objectStatus "C9F8" )
			)
			( gate "@baseboard_fab2_lib.baseboard_fab2(sch_1):page238_i21"
				( attribute "BOM_COST" "P1V26_BMC_STBY_VR"
					( Origin gFrontEnd )
				)
				( attribute "CDS_LIB" "mstr_discrete"
					( Origin gPackager )
				)
				( attribute "CDS_LOCATION" "R9F13"
					( Origin gPackager )
				)
				( attribute "CDS_SEC" "1"
					( Origin gPackager )
				)
				( attribute "LOCATION" "R9F13"
					( Origin gFrontEnd )
				)
				( attribute "MATERIAL" "CHIP"
					( Origin gFrontEnd )
				)
				( attribute "P1V5_STBY_IBMC" "<< NULL >>"
					( Origin gFrontEnd )
				)
				( attribute "P1V5_STBY_IBMC_VR" "<< NULL >>"
					( Origin gFrontEnd )
				)
				( attribute "PACK_TYPE" "0402"
					( Origin gFrontEnd )
				)
				( attribute "PART_NUMBER" "G21796-016"
					( Origin gFrontEnd )
				)
				( attribute "PHYS_PAGE" "238"
					( Origin gFrontEnd )
				)
				( attribute "ROOM" "P1V26_BMC_STBY_VR"
					( Origin gFrontEnd )
				)
				( attribute "ROT" "0"
					( Origin gFrontEnd )
				)
				( attribute "SEC" "1"
					( Origin gFrontEnd )
				)
				( attribute "SEC_TYPE" "0402"
					( Origin gFrontEnd )
				)
				( attribute "TOLERANCE" "1%"
					( Origin gFrontEnd )
				)
				( attribute "VALUE" "10.0K"
					( Origin gFrontEnd )
				)
				( attribute "VER" "2"
					( Origin gFrontEnd )
				)
				( attribute "WATTAGE" "1/16W"
					( Origin gFrontEnd )
				)
				( attribute "XY" "(900,3500)"
					( Origin gFrontEnd )
				)
				( attribute "CHIPS_PART_NAME" "RES"
					( Origin gPackager )
				)
				( attribute "CDS_PART_NAME" "RES_0402-10.0K,1%,1/16W,CHIP,GA"
					( Origin gPackager )
				)
				( objectStatus "R9F13" )
			)
			( gate "@baseboard_fab2_lib.baseboard_fab2(sch_1):page238_i23"
				( attribute "BOM_COST" "P1V26_BMC_STBY_VR"
					( Origin gFrontEnd )
				)
				( attribute "CDS_LIB" "mstr_discrete"
					( Origin gPackager )
				)
				( attribute "CDS_LOCATION" "C9E10"
					( Origin gPackager )
				)
				( attribute "CDS_SEC" "1"
					( Origin gPackager )
				)
				( attribute "LOCATION" "C9E10"
					( Origin gFrontEnd )
				)
				( attribute "MATERIAL" "X6S"
					( Origin gFrontEnd )
				)
				( attribute "PACK_TYPE" "0603"
					( Origin gFrontEnd )
				)
				( attribute "PART_NUMBER" "E15431-002"
					( Origin gFrontEnd )
				)
				( attribute "PHYS_PAGE" "238"
					( Origin gFrontEnd )
				)
				( attribute "ROOM" "P1V26_BMC_STBY_VR"
					( Origin gFrontEnd )
				)
				( attribute "ROT" "0"
					( Origin gFrontEnd )
				)
				( attribute "SEC" "1"
					( Origin gFrontEnd )
				)
				( attribute "SEC_TYPE" "0603"
					( Origin gFrontEnd )
				)
				( attribute "TOLERANCE" "20%"
					( Origin gFrontEnd )
				)
				( attribute "VALUE" "10UF"
					( Origin gFrontEnd )
				)
				( attribute "VER" "1"
					( Origin gFrontEnd )
				)
				( attribute "VOLTAGE" "6.3V"
					( Units "uVoltage" "V" 1.000000)
					( Origin gFrontEnd )
				)
				( attribute "XY" "(1600,2525)"
					( Origin gFrontEnd )
				)
				( attribute "CHIPS_PART_NAME" "CAP"
					( Origin gPackager )
				)
				( attribute "CDS_PART_NAME" "CAP_0603-10UF,6.3V,20%,X6S,E15A"
					( Origin gPackager )
				)
				( objectStatus "C9E10" )
			)
			( gate "@baseboard_fab2_lib.baseboard_fab2(sch_1):page238_i30"
				( attribute "BOM_COST" "P1V26_BMC_STBY_VR"
					( Origin gFrontEnd )
				)
				( attribute "CDS_LIB" "mstr_discrete"
					( Origin gPackager )
				)
				( attribute "CDS_LOCATION" "C9F4"
					( Origin gPackager )
				)
				( attribute "CDS_SEC" "1"
					( Origin gPackager )
				)
				( attribute "LOCATION" "C9F4"
					( Origin gFrontEnd )
				)
				( attribute "MATERIAL" "X6S"
					( Origin gFrontEnd )
				)
				( attribute "PACK_TYPE" "0805LF"
					( Origin gFrontEnd )
				)
				( attribute "PART_NUMBER" "C95333-002"
					( Origin gFrontEnd )
				)
				( attribute "PHYS_PAGE" "238"
					( Origin gFrontEnd )
				)
				( attribute "ROOM" "P1V26_BMC_STBY_VR"
					( Origin gFrontEnd )
				)
				( attribute "ROT" "0"
					( Origin gFrontEnd )
				)
				( attribute "SEC" "1"
					( Origin gFrontEnd )
				)
				( attribute "SEC_TYPE" "0805LF"
					( Origin gFrontEnd )
				)
				( attribute "TOLERANCE" "20%"
					( Origin gFrontEnd )
				)
				( attribute "VALUE" "22UF"
					( Origin gFrontEnd )
				)
				( attribute "VER" "1"
					( Origin gFrontEnd )
				)
				( attribute "VOLTAGE" "4V"
					( Units "uVoltage" "V" 1.000000)
					( Origin gFrontEnd )
				)
				( attribute "XY" "(2325,2525)"
					( Origin gFrontEnd )
				)
				( attribute "CHIPS_PART_NAME" "CAP"
					( Origin gPackager )
				)
				( attribute "CDS_PART_NAME" "CAP_0805LF-22UF,4V,20%,X6S,C95A"
					( Origin gPackager )
				)
				( objectStatus "C9F4" )
			)
			( gate "@baseboard_fab2_lib.baseboard_fab2(sch_1):page238_i39"
				( attribute "CDS_LIB" "mstr_discrete"
					( Origin gPackager )
				)
				( attribute "CDS_LOCATION" "C9E11"
					( Origin gPackager )
				)
				( attribute "CDS_SEC" "1"
					( Origin gPackager )
				)
				( attribute "LOCATION" "C9E11"
					( Origin gFrontEnd )
				)
				( attribute "MATERIAL" "X6S"
					( Origin gFrontEnd )
				)
				( attribute "PACK_TYPE" "0402"
					( Origin gFrontEnd )
				)
				( attribute "PART_NUMBER" "D97712-011"
					( Origin gFrontEnd )
				)
				( attribute "PHYS_PAGE" "238"
					( Origin gFrontEnd )
				)
				( attribute "ROT" "0"
					( Origin gFrontEnd )
				)
				( attribute "SEC" "1"
					( Origin gFrontEnd )
				)
				( attribute "SEC_TYPE" "0402"
					( Origin gFrontEnd )
				)
				( attribute "TOLERANCE" "10%"
					( Origin gFrontEnd )
				)
				( attribute "VALUE" "1.0UF"
					( Origin gFrontEnd )
				)
				( attribute "VER" "1"
					( Origin gFrontEnd )
				)
				( attribute "VOLTAGE" "16V"
					( Units "uVoltage" "V" 1.000000)
					( Origin gFrontEnd )
				)
				( attribute "XY" "(-1275,2150)"
					( Origin gFrontEnd )
				)
				( attribute "CHIPS_PART_NAME" "CAP"
					( Origin gPackager )
				)
				( attribute "CDS_PART_NAME" "CAP_0402-1.0UF,16V,10%,X6S,D97A"
					( Origin gPackager )
				)
				( objectStatus "C9E11" )
			)
			( gate "@baseboard_fab2_lib.baseboard_fab2(sch_1):page238_i40"
				( attribute "CDS_LIB" "mstr_vreg"
					( Origin gPackager )
				)
				( attribute "CDS_LOCATION" "EU9F1"
					( Origin gPackager )
				)
				( attribute "CDS_SEC" "1"
					( Origin gPackager )
				)
				( attribute "LOCATION" "EU9F1"
					( Origin gFrontEnd )
				)
				( attribute "MATERIAL" "IC"
					( Origin gFrontEnd )
				)
				( attribute "PACK_TYPE" "DFN"
					( Origin gFrontEnd )
				)
				( attribute "PART_NUMBER" "H65765-001"
					( Origin gFrontEnd )
				)
				( attribute "PHYS_PAGE" "238"
					( Origin gFrontEnd )
				)
				( attribute "ROOM" "P1V26_BMC_STBY_VR"
					( Origin gFrontEnd )
				)
				( attribute "ROT" "0"
					( Origin gFrontEnd )
				)
				( attribute "SEC" "1"
					( Origin gFrontEnd )
				)
				( attribute "SEC_TYPE" "DFN"
					( Origin gFrontEnd )
				)
				( attribute "VER" "1"
					( Origin gFrontEnd )
				)
				( attribute "XY" "(-175,2700)"
					( Origin gFrontEnd )
				)
				( attribute "CHIPS_PART_NAME" "RT9059"
					( Origin gPackager )
				)
				( attribute "CDS_PART_NAME" "RT9059_DFN-IC,H65765-001"
					( Origin gPackager )
				)
				( objectStatus "EU9F1" )
			)
			( gate "@baseboard_fab2_lib.baseboard_fab2(sch_1):page238_i41"
				( attribute "CDS_LIB" "mstr_discrete"
					( Origin gPackager )
				)
				( attribute "CDS_LOCATION" "R9F11"
					( Origin gPackager )
				)
				( attribute "CDS_SEC" "1"
					( Origin gPackager )
				)
				( attribute "LOCATION" "R9F11"
					( Origin gFrontEnd )
				)
				( attribute "MATERIAL" "CHIP"
					( Origin gFrontEnd )
				)
				( attribute "PACK_TYPE" "0402"
					( Origin gFrontEnd )
				)
				( attribute "PART_NUMBER" "G21796-250"
					( Origin gFrontEnd )
				)
				( attribute "PHYS_PAGE" "238"
					( Origin gFrontEnd )
				)
				( attribute "ROOM" "P1V26_BMC_STBY_VR"
					( Origin gFrontEnd )
				)
				( attribute "ROT" "0"
					( Origin gFrontEnd )
				)
				( attribute "SEC" "1"
					( Origin gFrontEnd )
				)
				( attribute "SEC_TYPE" "0402"
					( Origin gFrontEnd )
				)
				( attribute "TOLERANCE" "1.0%"
					( Origin gFrontEnd )
				)
				( attribute "VALUE" "22.1"
					( Origin gFrontEnd )
				)
				( attribute "VER" "1"
					( Origin gFrontEnd )
				)
				( attribute "WATTAGE" "1/16W"
					( Origin gFrontEnd )
				)
				( attribute "XY" "(1850,3200)"
					( Origin gFrontEnd )
				)
				( attribute "CHIPS_PART_NAME" "RES"
					( Origin gPackager )
				)
				( attribute "CDS_PART_NAME" "RES_0402-22.1,1.0%,1/16W,CHIP,A"
					( Origin gPackager )
				)
				( objectStatus "R9F11" )
			)
			( gate "@baseboard_fab2_lib.baseboard_fab2(sch_1):page239_i4"
				( attribute "BOM_COST" "P1V538_BMC_STBY_VR"
					( Origin gFrontEnd )
				)
				( attribute "CDS_LIB" "mstr_discrete"
					( Origin gPackager )
				)
				( attribute "CDS_LOCATION" "C9F10"
					( Origin gPackager )
				)
				( attribute "CDS_SEC" "1"
					( Origin gPackager )
				)
				( attribute "LOCATION" "C9F10"
					( Origin gFrontEnd )
				)
				( attribute "MATERIAL" "X7R"
					( Origin gFrontEnd )
				)
				( attribute "PACK_TYPE" "0402LF"
					( Origin gFrontEnd )
				)
				( attribute "PART_NUMBER" "A36096-046"
					( Origin gFrontEnd )
				)
				( attribute "PHYS_PAGE" "239"
					( Origin gFrontEnd )
				)
				( attribute "ROOM" "P1V538_BMC_STBY_VR"
					( Origin gFrontEnd )
				)
				( attribute "ROT" "0"
					( Origin gFrontEnd )
				)
				( attribute "SEC" "1"
					( Origin gPackager )
				)
				( attribute "TOLERANCE" "10%"
					( Origin gFrontEnd )
				)
				( attribute "VALUE" "1000PF"
					( Origin gFrontEnd )
				)
				( attribute "VER" "1"
					( Origin gFrontEnd )
				)
				( attribute "VOLTAGE" "50V"
					( Units "uVoltage" "V" 1.000000)
					( Origin gFrontEnd )
				)
				( attribute "XY" "(10375,4150)"
					( Origin gFrontEnd )
				)
				( attribute "CHIPS_PART_NAME" "CAP"
					( Origin gPackager )
				)
				( attribute "CDS_PART_NAME" "CAP_0402LF-1000PF,50V,10%,X7R,A"
					( Origin gPackager )
				)
				( objectStatus "C9F10" )
			)
			( gate "@baseboard_fab2_lib.baseboard_fab2(sch_1):page239_i6"
				( attribute "BOM_COST" "P1V538_BMC_STBY_VR"
					( Origin gFrontEnd )
				)
				( attribute "CDS_LIB" "mstr_discrete"
					( Origin gPackager )
				)
				( attribute "CDS_LOCATION" "R9F12"
					( Origin gPackager )
				)
				( attribute "CDS_SEC" "1"
					( Origin gPackager )
				)
				( attribute "LOCATION" "R9F12"
					( Origin gFrontEnd )
				)
				( attribute "MATERIAL" "CHIP"
					( Origin gFrontEnd )
				)
				( attribute "P1V5_STBY_IBMC" "<< NULL >>"
					( Origin gFrontEnd )
				)
				( attribute "P1V5_STBY_IBMC_VR" "<< NULL >>"
					( Origin gFrontEnd )
				)
				( attribute "PACK_TYPE" "0402"
					( Origin gFrontEnd )
				)
				( attribute "PART_NUMBER" "G21796-016"
					( Origin gFrontEnd )
				)
				( attribute "PHYS_PAGE" "239"
					( Origin gFrontEnd )
				)
				( attribute "ROOM" "P1V538_BMC_STBY_VR"
					( Origin gFrontEnd )
				)
				( attribute "ROT" "0"
					( Origin gFrontEnd )
				)
				( attribute "SEC" "1"
					( Origin gFrontEnd )
				)
				( attribute "SEC_TYPE" "0402"
					( Origin gFrontEnd )
				)
				( attribute "TOLERANCE" "1%"
					( Origin gFrontEnd )
				)
				( attribute "VALUE" "10.0K"
					( Origin gFrontEnd )
				)
				( attribute "VER" "2"
					( Origin gFrontEnd )
				)
				( attribute "WATTAGE" "1/16W"
					( Origin gFrontEnd )
				)
				( attribute "XY" "(9625,4525)"
					( Origin gFrontEnd )
				)
				( attribute "CHIPS_PART_NAME" "RES"
					( Origin gPackager )
				)
				( attribute "CDS_PART_NAME" "RES_0402-10.0K,1%,1/16W,CHIP,GA"
					( Origin gPackager )
				)
				( objectStatus "R9F12" )
			)
			( gate "@baseboard_fab2_lib.baseboard_fab2(sch_1):page239_i7"
				( attribute "BOM_COST" "P1V538_BMC_STBY_VR"
					( Origin gFrontEnd )
				)
				( attribute "CDS_LIB" "mstr_discrete"
					( Origin gPackager )
				)
				( attribute "CDS_LOCATION" "C9F13"
					( Origin gPackager )
				)
				( attribute "CDS_SEC" "1"
					( Origin gPackager )
				)
				( attribute "LOCATION" "C9F13"
					( Origin gFrontEnd )
				)
				( attribute "MATERIAL" "X6S"
					( Origin gFrontEnd )
				)
				( attribute "PACK_TYPE" "0805LF"
					( Origin gFrontEnd )
				)
				( attribute "PART_NUMBER" "C95333-002"
					( Origin gFrontEnd )
				)
				( attribute "PHYS_PAGE" "239"
					( Origin gFrontEnd )
				)
				( attribute "ROOM" "P1V538_BMC_STBY_VR"
					( Origin gFrontEnd )
				)
				( attribute "ROT" "0"
					( Origin gFrontEnd )
				)
				( attribute "SEC" "1"
					( Origin gFrontEnd )
				)
				( attribute "SEC_TYPE" "0805LF"
					( Origin gFrontEnd )
				)
				( attribute "TOLERANCE" "20%"
					( Origin gFrontEnd )
				)
				( attribute "VALUE" "22UF"
					( Origin gFrontEnd )
				)
				( attribute "VER" "1"
					( Origin gFrontEnd )
				)
				( attribute "VOLTAGE" "4V"
					( Units "uVoltage" "V" 1.000000)
					( Origin gFrontEnd )
				)
				( attribute "XY" "(11725,3575)"
					( Origin gFrontEnd )
				)
				( attribute "CHIPS_PART_NAME" "CAP"
					( Origin gPackager )
				)
				( attribute "CDS_PART_NAME" "CAP_0805LF-22UF,4V,20%,X6S,C95A"
					( Origin gPackager )
				)
				( objectStatus "C9F13" )
			)
			( gate "@baseboard_fab2_lib.baseboard_fab2(sch_1):page239_i12"
				( attribute "BOM_COST" "P1V538_BMC_STBY_VR"
					( Origin gFrontEnd )
				)
				( attribute "CDS_LIB" "mstr_discrete"
					( Origin gPackager )
				)
				( attribute "CDS_LOCATION" "C1T15"
					( Origin gPackager )
				)
				( attribute "CDS_SEC" "1"
					( Origin gPackager )
				)
				( attribute "LOCATION" "C1T15"
					( Origin gFrontEnd )
				)
				( attribute "MATERIAL" "X6S"
					( Origin gFrontEnd )
				)
				( attribute "PACK_TYPE" "0603"
					( Origin gFrontEnd )
				)
				( attribute "PART_NUMBER" "E15431-002"
					( Origin gFrontEnd )
				)
				( attribute "PHYS_PAGE" "239"
					( Origin gFrontEnd )
				)
				( attribute "ROOM" "P1V538_BMC_STBY_VR"
					( Origin gFrontEnd )
				)
				( attribute "ROT" "0"
					( Origin gFrontEnd )
				)
				( attribute "SEC" "1"
					( Origin gFrontEnd )
				)
				( attribute "SEC_TYPE" "0603"
					( Origin gFrontEnd )
				)
				( attribute "TOLERANCE" "20%"
					( Origin gFrontEnd )
				)
				( attribute "VALUE" "10UF"
					( Origin gFrontEnd )
				)
				( attribute "VER" "1"
					( Origin gFrontEnd )
				)
				( attribute "VOLTAGE" "6.3V"
					( Units "uVoltage" "V" 1.000000)
					( Origin gFrontEnd )
				)
				( attribute "XY" "(10875,3625)"
					( Origin gFrontEnd )
				)
				( attribute "CHIPS_PART_NAME" "CAP"
					( Origin gPackager )
				)
				( attribute "CDS_PART_NAME" "CAP_0603-10UF,6.3V,20%,X6S,E15A"
					( Origin gPackager )
				)
				( objectStatus "C1T15" )
			)
			( gate "@baseboard_fab2_lib.baseboard_fab2(sch_1):page238_i45"
				( attribute "CDS_LIB" "w_hdl"
					( Origin gPackager )
				)
				( attribute "CDS_LMAN_SYM_OUTLINE" "-50,75,50,-75"
					( Origin gPackager )
				)
				( attribute "LOCATION" "R9F6"
					( Origin gFrontEnd )
				)
				( attribute "PACK_TYPE" "SMD-RG"
					( Origin gFrontEnd )
				)
				( attribute "PART_NUMBER" "64.44215.6DL"
					( Origin gFrontEnd )
				)
				( attribute "PHYS_PAGE" "238"
					( Origin gFrontEnd )
				)
				( attribute "ROT" "0"
					( Origin gFrontEnd )
				)
				( attribute "VALUE" "4K42R2F-GP"
					( Origin gFrontEnd )
				)
				( attribute "VER" "1"
					( Origin gFrontEnd )
				)
				( attribute "XY" "(1025,2475)"
					( Origin gFrontEnd )
				)
				( attribute "CHIPS_PART_NAME" "4K42R2F-GP"
					( Origin gPackager )
				)
				( attribute "CDS_PART_NAME" "4K42R2F-GP_SMD-RG-4K42R2F-GP,6A"
					( Origin gPackager )
				)
				( attribute "CDS_LOCATION" "R9F6"
					( Origin gPackager )
				)
				( attribute "CDS_SEC" "1"
					( Origin gPackager )
				)
				( attribute "SEC" "1"
					( Origin gPackager )
				)
				( attribute "ATTRIBUTE" "4.42KOHM"
					( Origin gFrontEnd )
				)
				( attribute "RATED" "1/16W"
					( Origin gFrontEnd )
				)
				( attribute "TOLERANCE" "1%"
					( Origin gFrontEnd )
				)
				( attribute "PACK_SIZE" "0402"
					( Origin gFrontEnd )
				)
				( objectStatus "R9F6" )
			)
			( gate "@baseboard_fab2_lib.baseboard_fab2(sch_1):page239_i22"
				( attribute "BOM_COST" "P1V538_BMC_STBY_VR"
					( Origin gFrontEnd )
				)
				( attribute "CDS_LIB" "mstr_discrete"
					( Origin gPackager )
				)
				( attribute "CDS_LOCATION" "C1T7"
					( Origin gPackager )
				)
				( attribute "CDS_SEC" "1"
					( Origin gPackager )
				)
				( attribute "LOCATION" "C1T7"
					( Origin gFrontEnd )
				)
				( attribute "MATERIAL" "X6S"
					( Origin gFrontEnd )
				)
				( attribute "PACK_TYPE" "0603"
					( Origin gFrontEnd )
				)
				( attribute "PART_NUMBER" "E15431-002"
					( Origin gFrontEnd )
				)
				( attribute "PHYS_PAGE" "239"
					( Origin gFrontEnd )
				)
				( attribute "ROOM" "P1V538_BMC_STBY_VR"
					( Origin gFrontEnd )
				)
				( attribute "ROT" "0"
					( Origin gFrontEnd )
				)
				( attribute "SEC" "1"
					( Origin gFrontEnd )
				)
				( attribute "SEC_TYPE" "0603"
					( Origin gFrontEnd )
				)
				( attribute "TOLERANCE" "20%"
					( Origin gFrontEnd )
				)
				( attribute "VALUE" "10UF"
					( Origin gFrontEnd )
				)
				( attribute "VER" "1"
					( Origin gFrontEnd )
				)
				( attribute "VOLTAGE" "6.3V"
					( Units "uVoltage" "V" 1.000000)
					( Origin gFrontEnd )
				)
				( attribute "XY" "(5750,4150)"
					( Origin gFrontEnd )
				)
				( attribute "CHIPS_PART_NAME" "CAP"
					( Origin gPackager )
				)
				( attribute "CDS_PART_NAME" "CAP_0603-10UF,6.3V,20%,X6S,E15A"
					( Origin gPackager )
				)
				( objectStatus "C1T7" )
			)
			( gate "@baseboard_fab2_lib.baseboard_fab2(sch_1):page239_i30"
				( attribute "BOM_COST" "P1V538_BMC_STBY_VR"
					( Origin gFrontEnd )
				)
				( attribute "CDS_LIB" "mstr_discrete"
					( Origin gPackager )
				)
				( attribute "CDS_LOCATION" "C9F6"
					( Origin gPackager )
				)
				( attribute "CDS_SEC" "1"
					( Origin gPackager )
				)
				( attribute "LOCATION" "C9F6"
					( Origin gFrontEnd )
				)
				( attribute "MATERIAL" "EMPTY"
					( Origin gFrontEnd )
				)
				( attribute "PACK_TYPE" "0402LF"
					( Origin gFrontEnd )
				)
				( attribute "PART_NUMBER" "A36096-046"
					( Origin gFrontEnd )
				)
				( attribute "PHYS_PAGE" "239"
					( Origin gFrontEnd )
				)
				( attribute "ROOM" "P1V538_BMC_STBY_VR"
					( Origin gFrontEnd )
				)
				( attribute "ROT" "2"
					( Origin gFrontEnd )
				)
				( attribute "SEC" "1"
					( Origin gPackager )
				)
				( attribute "TOLERANCE" "10%"
					( Origin gFrontEnd )
				)
				( attribute "VALUE" "1000PF"
					( Origin gFrontEnd )
				)
				( attribute "VER" "1"
					( Origin gFrontEnd )
				)
				( attribute "VOLTAGE" "50V"
					( Units "uVoltage" "V" 1.000000)
					( Origin gFrontEnd )
				)
				( attribute "XY" "(7050,3300)"
					( Origin gFrontEnd )
				)
				( attribute "CHIPS_PART_NAME" "CAP"
					( Origin gPackager )
				)
				( attribute "CDS_PART_NAME" "CAP_0402LF-1000PF,50V,10%,EMPTA"
					( Origin gPackager )
				)
				( objectStatus "C9F6" )
			)
			( gate "@baseboard_fab2_lib.baseboard_fab2(sch_1):page239_i70"
				( attribute "CDS_LIB" "mstr_vreg"
					( Origin gPackager )
				)
				( attribute "CDS_LOCATION" "EU9F2"
					( Origin gPackager )
				)
				( attribute "CDS_SEC" "1"
					( Origin gPackager )
				)
				( attribute "LOCATION" "EU9F2"
					( Origin gFrontEnd )
				)
				( attribute "MATERIAL" "IC"
					( Origin gFrontEnd )
				)
				( attribute "PACK_TYPE" "DFN"
					( Origin gFrontEnd )
				)
				( attribute "PART_NUMBER" "H65765-001"
					( Origin gFrontEnd )
				)
				( attribute "PHYS_PAGE" "239"
					( Origin gFrontEnd )
				)
				( attribute "ROT" "0"
					( Origin gFrontEnd )
				)
				( attribute "SEC" "1"
					( Origin gFrontEnd )
				)
				( attribute "SEC_TYPE" "DFN"
					( Origin gFrontEnd )
				)
				( attribute "VER" "1"
					( Origin gFrontEnd )
				)
				( attribute "XY" "(8850,3775)"
					( Origin gFrontEnd )
				)
				( attribute "CHIPS_PART_NAME" "RT9059"
					( Origin gPackager )
				)
				( attribute "CDS_PART_NAME" "RT9059_DFN-IC,H65765-001"
					( Origin gPackager )
				)
				( objectStatus "EU9F2" )
			)
			( gate "@baseboard_fab2_lib.baseboard_fab2(sch_1):page239_i71"
				( attribute "CDS_LIB" "dev_discrete"
					( Origin gPackager )
				)
				( attribute "CDS_LOCATION" "C9F5"
					( Origin gPackager )
				)
				( attribute "CDS_SEC" "1"
					( Origin gPackager )
				)
				( attribute "LOCATION" "C9F5"
					( Origin gFrontEnd )
				)
				( attribute "MATERIAL" "X7R"
					( Origin gFrontEnd )
				)
				( attribute "PACK_TYPE" "0402V"
					( Origin gFrontEnd )
				)
				( attribute "PART_NUMBER" "A36096-030"
					( Origin gFrontEnd )
				)
				( attribute "PHYS_PAGE" "239"
					( Origin gFrontEnd )
				)
				( attribute "ROT" "0"
					( Origin gFrontEnd )
				)
				( attribute "SEC" "1"
					( Origin gFrontEnd )
				)
				( attribute "SEC_TYPE" "0402V"
					( Origin gFrontEnd )
				)
				( attribute "TOLERANCE" "10%"
					( Origin gFrontEnd )
				)
				( attribute "VALUE" "0.1UF"
					( Origin gFrontEnd )
				)
				( attribute "VER" "1"
					( Origin gFrontEnd )
				)
				( attribute "VOLTAGE" "16V"
					( Units "uVoltage" "V" 1.000000)
					( Origin gFrontEnd )
				)
				( attribute "XY" "(7475,4125)"
					( Origin gFrontEnd )
				)
				( attribute "CHIPS_PART_NAME" "CAP_A"
					( Origin gPackager )
				)
				( attribute "CDS_PART_NAME" "CAP_A_0402V-0.1UF,16V,10%,X7R,A"
					( Origin gPackager )
				)
				( objectStatus "C9F5" )
			)
			( gate "@baseboard_fab2_lib.baseboard_fab2(sch_1):page239_i72"
				( attribute "CDS_LIB" "mstr_discrete"
					( Origin gPackager )
				)
				( attribute "CDS_LOCATION" "R1T9"
					( Origin gPackager )
				)
				( attribute "CDS_SEC" "1"
					( Origin gPackager )
				)
				( attribute "LOCATION" "R1T9"
					( Origin gFrontEnd )
				)
				( attribute "MATERIAL" "CHIP"
					( Origin gFrontEnd )
				)
				( attribute "PACK_TYPE" "0402"
					( Origin gFrontEnd )
				)
				( attribute "PART_NUMBER" "G21796-250"
					( Origin gFrontEnd )
				)
				( attribute "PHYS_PAGE" "239"
					( Origin gFrontEnd )
				)
				( attribute "ROOM" "P1V538_BMC_STBY_VR"
					( Origin gFrontEnd )
				)
				( attribute "ROT" "0"
					( Origin gFrontEnd )
				)
				( attribute "SEC" "1"
					( Origin gFrontEnd )
				)
				( attribute "SEC_TYPE" "0402"
					( Origin gFrontEnd )
				)
				( attribute "TOLERANCE" "1.0%"
					( Origin gFrontEnd )
				)
				( attribute "VALUE" "22.1"
					( Origin gFrontEnd )
				)
				( attribute "VER" "1"
					( Origin gFrontEnd )
				)
				( attribute "WATTAGE" "1/16W"
					( Origin gFrontEnd )
				)
				( attribute "XY" "(10700,4275)"
					( Origin gFrontEnd )
				)
				( attribute "CHIPS_PART_NAME" "RES"
					( Origin gPackager )
				)
				( attribute "CDS_PART_NAME" "RES_0402-22.1,1.0%,1/16W,CHIP,A"
					( Origin gPackager )
				)
				( objectStatus "R1T9" )
			)
			( gate "@baseboard_fab2_lib.baseboard_fab2(sch_1):page232_i315"
				( attribute "BOM_COST" "PVPP_KLM_VR"
					( Origin gFrontEnd )
				)
				( attribute "CDS_LIB" "mstr_discrete"
					( Origin gPackager )
				)
				( attribute "CDS_LOCATION" "R7B14"
					( Origin gPackager )
				)
				( attribute "CDS_SEC" "1"
					( Origin gPackager )
				)
				( attribute "CONFIG" "64.39015.6DL"
					( Origin gFrontEnd )
				)
				( attribute "LOCATION" "R7B14"
					( Origin gFrontEnd )
				)
				( attribute "MATERIAL" "CHIP"
					( Origin gFrontEnd )
				)
				( attribute "NEW_VALUE" "3.9K"
					( Origin gFrontEnd )
				)
				( attribute "PACK_TYPE" "0402"
					( Origin gFrontEnd )
				)
				( attribute "PART_NUMBER" "G21796-242"
					( Origin gFrontEnd )
				)
				( attribute "PHYS_PAGE" "232"
					( Origin gFrontEnd )
				)
				( attribute "ROOM" "PVPP_KLM_VR"
					( Origin gFrontEnd )
				)
				( attribute "ROT" "2"
					( Origin gFrontEnd )
				)
				( attribute "SEC" "1"
					( Origin gPackager )
				)
				( attribute "TOLERANCE" "1.0%"
					( Origin gFrontEnd )
				)
				( attribute "VALUE" "7.87K"
					( Origin gFrontEnd )
				)
				( attribute "VER" "2"
					( Origin gFrontEnd )
				)
				( attribute "WATTAGE" "1/16W"
					( Origin gFrontEnd )
				)
				( attribute "XY" "(-5100,1650)"
					( Origin gFrontEnd )
				)
				( attribute "CHIPS_PART_NAME" "RES"
					( Origin gPackager )
				)
				( attribute "CDS_PART_NAME" "RES_0402-7.87K,1.0%,1/16W,CHIPA"
					( Origin gPackager )
				)
				( objectStatus "R7B14" )
			)
			( gate "@baseboard_fab2_lib.baseboard_fab2(sch_1):page186_i357"
				( attribute "CDS_LIB" "w_hdl"
					( Origin gPackager )
				)
				( attribute "CDS_LMAN_SYM_OUTLINE" "-50,25,50,-25"
					( Origin gPackager )
				)
				( attribute "LOCATION" "C9B9"
					( Origin gFrontEnd )
				)
				( attribute "PACK_TYPE" "SMD-BCG6"
					( Origin gFrontEnd )
				)
				( attribute "PART_NUMBER" "78.10523.8FL"
					( Origin gFrontEnd )
				)
				( attribute "PHYS_PAGE" "186"
					( Origin gFrontEnd )
				)
				( attribute "ROT" "0"
					( Origin gFrontEnd )
				)
				( attribute "SEC" "1"
					( Origin gFrontEnd )
				)
				( attribute "SEC_TYPE" "SMD-BCG6"
					( Origin gFrontEnd )
				)
				( attribute "VALUE" "SC1U10V2KX-4-GP"
					( Origin gFrontEnd )
				)
				( attribute "VER" "1"
					( Origin gFrontEnd )
				)
				( attribute "XY" "(9650,3925)"
					( Origin gFrontEnd )
				)
				( attribute "CHIPS_PART_NAME" "SC1U10V2KX-4-GP"
					( Origin gPackager )
				)
				( attribute "CDS_PART_NAME" "SC1U10V2KX-4-GP_SMD-BCG6-SC1U1A"
					( Origin gPackager )
				)
				( attribute "CDS_LOCATION" "C9B9"
					( Origin gPackager )
				)
				( attribute "CDS_SEC" "1"
					( Origin gPackager )
				)
				( attribute "ATTRIBUTE" "1UF"
					( Origin gFrontEnd )
				)
				( attribute "PACK_SIZE" "0402"
					( Origin gFrontEnd )
				)
				( attribute "RATED" "10V"
					( Origin gFrontEnd )
				)
				( attribute "TOLERANCE" "10%"
					( Origin gFrontEnd )
				)
				( objectStatus "C9B9" )
			)
			( gate "@baseboard_fab2_lib.baseboard_fab2(sch_1):page240_i111"
				( attribute "BOM" "SYSB_CPLD"
					( Origin gFrontEnd )
				)
				( attribute "BOM_COST" "P3V3_STBY_VR"
					( Origin gFrontEnd )
				)
				( attribute "CDS_LIB" "mstr_discrete"
					( Origin gPackager )
				)
				( attribute "CDS_LOCATION" "R8F1"
					( Origin gPackager )
				)
				( attribute "CDS_SEC" "1"
					( Origin gPackager )
				)
				( attribute "LOCATION" "R8F1"
					( Origin gFrontEnd )
				)
				( attribute "MATERIAL" "EMPTY"
					( Origin gFrontEnd )
				)
				( attribute "PACK_TYPE" "0402"
					( Origin gFrontEnd )
				)
				( attribute "PART_NUMBER" "G21796-016"
					( Origin gFrontEnd )
				)
				( attribute "PHYS_PAGE" "240"
					( Origin gFrontEnd )
				)
				( attribute "ROOM" "P3V3_STBY_VR"
					( Origin gFrontEnd )
				)
				( attribute "ROT" "0"
					( Origin gFrontEnd )
				)
				( attribute "SEC" "1"
					( Origin gPackager )
				)
				( attribute "TOLERANCE" "1%"
					( Origin gFrontEnd )
				)
				( attribute "VALUE" "10.0K"
					( Origin gFrontEnd )
				)
				( attribute "VER" "2"
					( Origin gFrontEnd )
				)
				( attribute "WATTAGE" "1/16W"
					( Origin gFrontEnd )
				)
				( attribute "XY" "(5625,2400)"
					( Origin gFrontEnd )
				)
				( attribute "CHIPS_PART_NAME" "RES"
					( Origin gPackager )
				)
				( attribute "CDS_PART_NAME" "RES_0402-10.0K,1%,1/16W,EMPTY,A"
					( Origin gPackager )
				)
				( objectStatus "R8F1" )
			)
			( gate "@baseboard_fab2_lib.baseboard_fab2(sch_1):page240_i113"
				( attribute "BOM_COST" "P3V3_STBY_VR"
					( Origin gFrontEnd )
				)
				( attribute "CDS_LIB" "mstr_discrete"
					( Origin gPackager )
				)
				( attribute "CDS_LOCATION" "C8E17"
					( Origin gPackager )
				)
				( attribute "CDS_SEC" "1"
					( Origin gPackager )
				)
				( attribute "FIN" "VR_1P2"
					( Origin gFrontEnd )
				)
				( attribute "LOCATION" "C8E17"
					( Origin gFrontEnd )
				)
				( attribute "MATERIAL" "EMPTY"
					( Origin gFrontEnd )
				)
				( attribute "PACK_TYPE" "0402LF"
					( Origin gFrontEnd )
				)
				( attribute "PART_NUMBER" "A36096-046"
					( Origin gFrontEnd )
				)
				( attribute "PHYS_PAGE" "240"
					( Origin gFrontEnd )
				)
				( attribute "REUSE_ID" "1"
					( Origin gFrontEnd )
				)
				( attribute "ROOM" "P3V3_STBY_VR"
					( Origin gFrontEnd )
				)
				( attribute "ROT" "2"
					( Origin gFrontEnd )
				)
				( attribute "SEC" "1"
					( Origin gPackager )
				)
				( attribute "TOLERANCE" "10%"
					( Origin gFrontEnd )
				)
				( attribute "VALUE" "1000PF"
					( Origin gFrontEnd )
				)
				( attribute "VER" "1"
					( Origin gFrontEnd )
				)
				( attribute "VOLTAGE" "50V"
					( Units "uVoltage" "V" 1.000000)
					( Origin gFrontEnd )
				)
				( attribute "XY" "(6175,2475)"
					( Origin gFrontEnd )
				)
				( attribute "CHIPS_PART_NAME" "CAP"
					( Origin gPackager )
				)
				( attribute "CDS_PART_NAME" "CAP_0402LF-1000PF,50V,10%,EMPTA"
					( Origin gPackager )
				)
				( objectStatus "C8E17" )
			)
			( gate "@baseboard_fab2_lib.baseboard_fab2(sch_1):page240_i116"
				( attribute "BOM_COST" "P3V3_STBY_VR"
					( Origin gFrontEnd )
				)
				( attribute "CDS_LIB" "mstr_discrete"
					( Origin gPackager )
				)
				( attribute "CDS_LOCATION" "C8F2"
					( Origin gPackager )
				)
				( attribute "CDS_SEC" "1"
					( Origin gPackager )
				)
				( attribute "LOCATION" "C8F2"
					( Origin gFrontEnd )
				)
				( attribute "MATERIAL" "X7R"
					( Origin gFrontEnd )
				)
				( attribute "PACK_TYPE" "0402LF"
					( Origin gFrontEnd )
				)
				( attribute "PART_NUMBER" "A36096-046"
					( Origin gFrontEnd )
				)
				( attribute "PHYS_PAGE" "240"
					( Origin gFrontEnd )
				)
				( attribute "REUSE_ID" "17"
					( Origin gFrontEnd )
				)
				( attribute "ROOM" "P3V3_STBY_VR"
					( Origin gFrontEnd )
				)
				( attribute "ROT" "0"
					( Origin gFrontEnd )
				)
				( attribute "SEC" "1"
					( Origin gPackager )
				)
				( attribute "TOLERANCE" "10%"
					( Origin gFrontEnd )
				)
				( attribute "VALUE" "1000PF"
					( Origin gFrontEnd )
				)
				( attribute "VER" "1"
					( Origin gFrontEnd )
				)
				( attribute "VOLTAGE" "50V"
					( Units "uVoltage" "V" 1.000000)
					( Origin gFrontEnd )
				)
				( attribute "XY" "(6350,3350)"
					( Origin gFrontEnd )
				)
				( attribute "CHIPS_PART_NAME" "CAP"
					( Origin gPackager )
				)
				( attribute "CDS_PART_NAME" "CAP_0402LF-1000PF,50V,10%,X7R,A"
					( Origin gPackager )
				)
				( objectStatus "C8F2" )
			)
			( gate "@baseboard_fab2_lib.baseboard_fab2(sch_1):page240_i117"
				( attribute "BOM_COST" "P3V3_STBY_VR"
					( Origin gFrontEnd )
				)
				( attribute "CDS_LIB" "mstr_discrete"
					( Origin gPackager )
				)
				( attribute "CDS_LOCATION" "R8F5"
					( Origin gPackager )
				)
				( attribute "CDS_SEC" "1"
					( Origin gPackager )
				)
				( attribute "LOCATION" "R8F5"
					( Origin gFrontEnd )
				)
				( attribute "MATERIAL" "CHIP"
					( Origin gFrontEnd )
				)
				( attribute "PACK_TYPE" "0402"
					( Origin gFrontEnd )
				)
				( attribute "PART_NUMBER" "G21796-026"
					( Origin gFrontEnd )
				)
				( attribute "PHYS_PAGE" "240"
					( Origin gFrontEnd )
				)
				( attribute "REUSE_ID" "21"
					( Origin gFrontEnd )
				)
				( attribute "ROOM" "PVPP_KLM_VR"
					( Origin gFrontEnd )
				)
				( attribute "ROT" "2"
					( Origin gFrontEnd )
				)
				( attribute "SEC" "1"
					( Origin gFrontEnd )
				)
				( attribute "SEC_TYPE" "0402"
					( Origin gFrontEnd )
				)
				( attribute "TOLERANCE" "1%"
					( Origin gFrontEnd )
				)
				( attribute "VALUE" "1.00K"
					( Origin gFrontEnd )
				)
				( attribute "VER" "2"
					( Origin gFrontEnd )
				)
				( attribute "WATTAGE" "1/16W"
					( Origin gFrontEnd )
				)
				( attribute "XY" "(6275,3900)"
					( Origin gFrontEnd )
				)
				( attribute "CHIPS_PART_NAME" "RES"
					( Origin gPackager )
				)
				( attribute "CDS_PART_NAME" "RES_0402-1.00K,1%,1/16W,CHIP,GA"
					( Origin gPackager )
				)
				( objectStatus "R8F5" )
			)
			( gate "@baseboard_fab2_lib.baseboard_fab2(sch_1):page240_i125"
				( attribute "CDS_LIB" "mstr_vreg"
					( Origin gPackager )
				)
				( attribute "CDS_LOCATION" "EU8F1"
					( Origin gPackager )
				)
				( attribute "CDS_SEC" "1"
					( Origin gPackager )
				)
				( attribute "LOCATION" "EU8F1"
					( Origin gFrontEnd )
				)
				( attribute "MATERIAL" "IC"
					( Origin gFrontEnd )
				)
				( attribute "PACK_TYPE" "QFN"
					( Origin gFrontEnd )
				)
				( attribute "PART_NUMBER" "H66262-001"
					( Origin gFrontEnd )
				)
				( attribute "PHYS_PAGE" "240"
					( Origin gFrontEnd )
				)
				( attribute "ROOM" "P3V3_STBY_VR"
					( Origin gFrontEnd )
				)
				( attribute "ROT" "0"
					( Origin gFrontEnd )
				)
				( attribute "SEC" "1"
					( Origin gFrontEnd )
				)
				( attribute "SEC_TYPE" "QFN"
					( Origin gFrontEnd )
				)
				( attribute "VER" "1"
					( Origin gFrontEnd )
				)
				( attribute "XY" "(7550,2625)"
					( Origin gFrontEnd )
				)
				( attribute "CHIPS_PART_NAME" "RT8240"
					( Origin gPackager )
				)
				( attribute "CDS_PART_NAME" "RT8240_QFN-IC,H66262-001"
					( Origin gPackager )
				)
				( objectStatus "EU8F1" )
			)
			( gate "@baseboard_fab2_lib.baseboard_fab2(sch_1):page240_i127"
				( attribute "BOM_COST" "P3V3_STBY_VR"
					( Origin gFrontEnd )
				)
				( attribute "CDS_LIB" "mstr_discrete"
					( Origin gPackager )
				)
				( attribute "CDS_LOCATION" "R8E35"
					( Origin gPackager )
				)
				( attribute "CDS_SEC" "1"
					( Origin gPackager )
				)
				( attribute "LOCATION" "R8E35"
					( Origin gFrontEnd )
				)
				( attribute "MATERIAL" "CHIP"
					( Origin gFrontEnd )
				)
				( attribute "PACK_TYPE" "0402"
					( Origin gFrontEnd )
				)
				( attribute "PART_NUMBER" "G21497-005"
					( Origin gFrontEnd )
				)
				( attribute "PHYS_PAGE" "240"
					( Origin gFrontEnd )
				)
				( attribute "REUSE_ID" "13"
					( Origin gFrontEnd )
				)
				( attribute "ROOM" "P3V3_STBY_VR"
					( Origin gFrontEnd )
				)
				( attribute "ROT" "0"
					( Origin gFrontEnd )
				)
				( attribute "SEC" "1"
					( Origin gPackager )
				)
				( attribute "SPOF" "TRUE"
					( Origin gFrontEnd )
				)
				( attribute "TOLERANCE" "5%"
					( Origin gFrontEnd )
				)
				( attribute "VALUE" "0.0"
					( Origin gFrontEnd )
				)
				( attribute "VER" "1"
					( Origin gFrontEnd )
				)
				( attribute "WATTAGE" "1/16W"
					( Origin gFrontEnd )
				)
				( attribute "XY" "(7600,3425)"
					( Origin gFrontEnd )
				)
				( attribute "CHIPS_PART_NAME" "RES"
					( Origin gPackager )
				)
				( attribute "CDS_PART_NAME" "RES_0402-0.0,5%,1/16W,CHIP,G21A"
					( Origin gPackager )
				)
				( objectStatus "R8E35" )
			)
			( gate "@baseboard_fab2_lib.baseboard_fab2(sch_1):page240_i129"
				( attribute "BOM_COST" "P3V3_STBY_VR"
					( Origin gFrontEnd )
				)
				( attribute "CDS_LIB" "mstr_discrete"
					( Origin gPackager )
				)
				( attribute "CDS_LOCATION" "C8E12"
					( Origin gPackager )
				)
				( attribute "CDS_SEC" "1"
					( Origin gPackager )
				)
				( attribute "LOCATION" "C8E12"
					( Origin gFrontEnd )
				)
				( attribute "MATERIAL" "X7R"
					( Origin gFrontEnd )
				)
				( attribute "PACK_TYPE" "0603LF"
					( Origin gFrontEnd )
				)
				( attribute "PART_NUMBER" "602433-020"
					( Origin gFrontEnd )
				)
				( attribute "PHYS_PAGE" "240"
					( Origin gFrontEnd )
				)
				( attribute "REUSE_ID" "27"
					( Origin gFrontEnd )
				)
				( attribute "ROOM" "P3V3_STBY_VR"
					( Origin gFrontEnd )
				)
				( attribute "ROT" "2"
					( Origin gFrontEnd )
				)
				( attribute "SEC" "1"
					( Origin gPackager )
				)
				( attribute "SPOF" "TRUE"
					( Origin gFrontEnd )
				)
				( attribute "TOLERANCE" "10%"
					( Origin gFrontEnd )
				)
				( attribute "VALUE" "0.1UF"
					( Origin gFrontEnd )
				)
				( attribute "VER" "2"
					( Origin gFrontEnd )
				)
				( attribute "VOLTAGE" "25V"
					( Units "uVoltage" "V" 1.000000)
					( Origin gFrontEnd )
				)
				( attribute "XY" "(8300,3425)"
					( Origin gFrontEnd )
				)
				( attribute "CHIPS_PART_NAME" "CAP"
					( Origin gPackager )
				)
				( attribute "CDS_PART_NAME" "CAP_0603LF-0.1UF,25V,10%,X7R,6A"
					( Origin gPackager )
				)
				( objectStatus "C8E12" )
			)
			( gate "@baseboard_fab2_lib.baseboard_fab2(sch_1):page176_i162"
				( attribute "BOM_COST" "SM_CONTROLLER"
					( Origin gFrontEnd )
				)
				( attribute "CDS_LIB" "mstr_digital"
					( Origin gPackager )
				)
				( attribute "CDS_LOCATION" "U1W3"
					( Origin gPackager )
				)
				( attribute "CDS_SEC" "1"
					( Origin gPackager )
				)
				( attribute "LOCATION" "U1W3"
					( Origin gFrontEnd )
				)
				( attribute "MATERIAL" "IC"
					( Origin gFrontEnd )
				)
				( attribute "PACK_TYPE" "SSOP"
					( Origin gFrontEnd )
				)
				( attribute "PART_NUMBER" "G81764-001"
					( Origin gFrontEnd )
				)
				( attribute "PHYS_PAGE" "176"
					( Origin gFrontEnd )
				)
				( attribute "ROOM" "MEM"
					( Origin gFrontEnd )
				)
				( attribute "ROT" "0"
					( Origin gFrontEnd )
				)
				( attribute "SEC" "1"
					( Origin gPackager )
				)
				( attribute "VER" "1"
					( Origin gFrontEnd )
				)
				( attribute "XY" "(-4900,2000)"
					( Origin gFrontEnd )
				)
				( attribute "CHIPS_PART_NAME" "PCA9617"
					( Origin gPackager )
				)
				( attribute "CDS_PART_NAME" "PCA9617_SSOP-IC,G81764-001"
					( Origin gPackager )
				)
				( objectStatus "U1W3" )
			)
			( gate "@baseboard_fab2_lib.baseboard_fab2(sch_1):page214_i149"
				( attribute "CDS_LIB" "w_hdl"
					( Origin gPackager )
				)
				( attribute "CDS_LMAN_SYM_OUTLINE" "-50,25,50,-25"
					( Origin gPackager )
				)
				( attribute "LOCATION" "C22W13"
					( Origin gFrontEnd )
				)
				( attribute "PACK_TYPE" "SMD-BCG5"
					( Origin gFrontEnd )
				)
				( attribute "PART_NUMBER" "078.22611.0811"
					( Origin gFrontEnd )
				)
				( attribute "PHYS_PAGE" "214"
					( Origin gFrontEnd )
				)
				( attribute "ROT" "0"
					( Origin gFrontEnd )
				)
				( attribute "SEC" "1"
					( Origin gFrontEnd )
				)
				( attribute "SEC_TYPE" "SMD-BCG5"
					( Origin gFrontEnd )
				)
				( attribute "VALUE" "SC22U16V5MX-4-GP"
					( Origin gFrontEnd )
				)
				( attribute "VER" "1"
					( Origin gFrontEnd )
				)
				( attribute "XY" "(550,1200)"
					( Origin gFrontEnd )
				)
				( attribute "CHIPS_PART_NAME" "SC22U16V5MX-4-GP"
					( Origin gPackager )
				)
				( attribute "CDS_PART_NAME" "SC22U16V5MX-4-GP_SMD-BCG5-SC22A"
					( Origin gPackager )
				)
				( attribute "CDS_LOCATION" "C22W13"
					( Origin gPackager )
				)
				( attribute "CDS_SEC" "1"
					( Origin gPackager )
				)
				( attribute "ATTRIBUTE" "22UF"
					( Origin gFrontEnd )
				)
				( attribute "PACK_SIZE" "0805"
					( Origin gFrontEnd )
				)
				( attribute "RATED" "16V"
					( Origin gFrontEnd )
				)
				( attribute "TOLERANCE" "20%"
					( Origin gFrontEnd )
				)
				( attribute "TYPE" "X6S"
					( Origin gFrontEnd )
				)
				( objectStatus "C22W13" )
			)
			( gate "@baseboard_fab2_lib.baseboard_fab2(sch_1):page214_i148"
				( attribute "CDS_LIB" "w_hdl"
					( Origin gPackager )
				)
				( attribute "CDS_LMAN_SYM_OUTLINE" "-50,25,50,-25"
					( Origin gPackager )
				)
				( attribute "LOCATION" "C4E14"
					( Origin gFrontEnd )
				)
				( attribute "PACK_TYPE" "SMD-BCG5"
					( Origin gFrontEnd )
				)
				( attribute "PART_NUMBER" "078.22611.0811"
					( Origin gFrontEnd )
				)
				( attribute "PHYS_PAGE" "214"
					( Origin gFrontEnd )
				)
				( attribute "ROT" "0"
					( Origin gFrontEnd )
				)
				( attribute "SEC" "1"
					( Origin gFrontEnd )
				)
				( attribute "SEC_TYPE" "SMD-BCG5"
					( Origin gFrontEnd )
				)
				( attribute "VALUE" "SC22U16V5MX-4-GP"
					( Origin gFrontEnd )
				)
				( attribute "VER" "1"
					( Origin gFrontEnd )
				)
				( attribute "XY" "(250,1200)"
					( Origin gFrontEnd )
				)
				( attribute "CHIPS_PART_NAME" "SC22U16V5MX-4-GP"
					( Origin gPackager )
				)
				( attribute "CDS_PART_NAME" "SC22U16V5MX-4-GP_SMD-BCG5-SC22A"
					( Origin gPackager )
				)
				( attribute "CDS_LOCATION" "C4E14"
					( Origin gPackager )
				)
				( attribute "CDS_SEC" "1"
					( Origin gPackager )
				)
				( attribute "ATTRIBUTE" "22UF"
					( Origin gFrontEnd )
				)
				( attribute "PACK_SIZE" "0805"
					( Origin gFrontEnd )
				)
				( attribute "RATED" "16V"
					( Origin gFrontEnd )
				)
				( attribute "TOLERANCE" "20%"
					( Origin gFrontEnd )
				)
				( attribute "TYPE" "X6S"
					( Origin gFrontEnd )
				)
				( objectStatus "C4E14" )
			)
			( gate "@baseboard_fab2_lib.baseboard_fab2(sch_1):page240_i137"
				( attribute "BOM_COST" "P3V3_STBY_VR"
					( Origin gFrontEnd )
				)
				( attribute "CDS_LIB" "mstr_discrete"
					( Origin gPackager )
				)
				( attribute "CDS_LOCATION" "C8E10"
					( Origin gPackager )
				)
				( attribute "CDS_SEC" "1"
					( Origin gPackager )
				)
				( attribute "LOCATION" "C8E10"
					( Origin gFrontEnd )
				)
				( attribute "MATERIAL" "X6S"
					( Origin gFrontEnd )
				)
				( attribute "PACK_TYPE" "1206LF"
					( Origin gFrontEnd )
				)
				( attribute "PART_NUMBER" "D38464-005"
					( Origin gFrontEnd )
				)
				( attribute "PHYS_PAGE" "240"
					( Origin gFrontEnd )
				)
				( attribute "ROOM" "P3V3_STBY_VR"
					( Origin gFrontEnd )
				)
				( attribute "ROT" "0"
					( Origin gFrontEnd )
				)
				( attribute "SEC" "1"
					( Origin gPackager )
				)
				( attribute "TOLERANCE" "10%"
					( Origin gFrontEnd )
				)
				( attribute "VALUE" "22UF"
					( Origin gFrontEnd )
				)
				( attribute "VER" "1"
					( Origin gFrontEnd )
				)
				( attribute "VOLTAGE" "16V"
					( Units "uVoltage" "V" 1.000000)
					( Origin gFrontEnd )
				)
				( attribute "XY" "(8150,4325)"
					( Origin gFrontEnd )
				)
				( attribute "CHIPS_PART_NAME" "CAP"
					( Origin gPackager )
				)
				( attribute "CDS_PART_NAME" "CAP_1206LF-22UF,16V,10%,X6S,D3A"
					( Origin gPackager )
				)
				( objectStatus "C8E10" )
			)
			( gate "@baseboard_fab2_lib.baseboard_fab2(sch_1):page240_i139"
				( attribute "BOM_COST" "P3V3_STBY_VR"
					( Origin gFrontEnd )
				)
				( attribute "CDS_LIB" "mstr_discrete"
					( Origin gPackager )
				)
				( attribute "CDS_LOCATION" "C8E14"
					( Origin gPackager )
				)
				( attribute "CDS_SEC" "1"
					( Origin gPackager )
				)
				( attribute "FIN" "VR_1P2"
					( Origin gFrontEnd )
				)
				( attribute "LOCATION" "C8E14"
					( Origin gFrontEnd )
				)
				( attribute "MATERIAL" "X6S"
					( Origin gFrontEnd )
				)
				( attribute "PACK_TYPE" "0402"
					( Origin gFrontEnd )
				)
				( attribute "PART_NUMBER" "D97712-011"
					( Origin gFrontEnd )
				)
				( attribute "PHYS_PAGE" "240"
					( Origin gFrontEnd )
				)
				( attribute "REUSE_ID" "1"
					( Origin gFrontEnd )
				)
				( attribute "ROOM" "P3V3_STBY_VR"
					( Origin gFrontEnd )
				)
				( attribute "ROT" "0"
					( Origin gFrontEnd )
				)
				( attribute "SEC" "1"
					( Origin gPackager )
				)
				( attribute "TOLERANCE" "10%"
					( Origin gFrontEnd )
				)
				( attribute "VALUE" "1.0UF"
					( Origin gFrontEnd )
				)
				( attribute "VER" "1"
					( Origin gFrontEnd )
				)
				( attribute "VOLTAGE" "16V"
					( Units "uVoltage" "V" 1.000000)
					( Origin gFrontEnd )
				)
				( attribute "XY" "(8475,4350)"
					( Origin gFrontEnd )
				)
				( attribute "CHIPS_PART_NAME" "CAP"
					( Origin gPackager )
				)
				( attribute "CDS_PART_NAME" "CAP_0402-1.0UF,16V,10%,X6S,D97A"
					( Origin gPackager )
				)
				( objectStatus "C8E14" )
			)
			( gate "@baseboard_fab2_lib.baseboard_fab2(sch_1):page240_i140"
				( attribute "BOM_COST" "P3V3_STBY_VR"
					( Origin gFrontEnd )
				)
				( attribute "CDS_LIB" "mstr_discrete"
					( Origin gPackager )
				)
				( attribute "CDS_LOCATION" "R8E38"
					( Origin gPackager )
				)
				( attribute "CDS_SEC" "1"
					( Origin gPackager )
				)
				( attribute "LOCATION" "R8E38"
					( Origin gFrontEnd )
				)
				( attribute "MATERIAL" "CHIP"
					( Origin gFrontEnd )
				)
				( attribute "PACK_TYPE" "0402"
					( Origin gFrontEnd )
				)
				( attribute "PART_NUMBER" "G21497-005"
					( Origin gFrontEnd )
				)
				( attribute "PHYS_PAGE" "240"
					( Origin gFrontEnd )
				)
				( attribute "ROOM" "P3V3_STBY_VR"
					( Origin gFrontEnd )
				)
				( attribute "ROT" "0"
					( Origin gFrontEnd )
				)
				( attribute "SEC" "1"
					( Origin gPackager )
				)
				( attribute "TOLERANCE" "5%"
					( Origin gFrontEnd )
				)
				( attribute "VALUE" "0.0"
					( Origin gFrontEnd )
				)
				( attribute "VER" "1"
					( Origin gFrontEnd )
				)
				( attribute "WATTAGE" "1/16W"
					( Origin gFrontEnd )
				)
				( attribute "XY" "(9225,925)"
					( Origin gFrontEnd )
				)
				( attribute "CHIPS_PART_NAME" "RES"
					( Origin gPackager )
				)
				( attribute "CDS_PART_NAME" "RES_0402-0.0,5%,1/16W,CHIP,G21A"
					( Origin gPackager )
				)
				( objectStatus "R8E38" )
			)
			( gate "@baseboard_fab2_lib.baseboard_fab2(sch_1):page240_i142"
				( attribute "BOM_COST" "P3V3_STBY_VR"
					( Origin gFrontEnd )
				)
				( attribute "CDS_LIB" "mstr_discrete"
					( Origin gPackager )
				)
				( attribute "CDS_LOCATION" "R8E34"
					( Origin gPackager )
				)
				( attribute "CDS_SEC" "1"
					( Origin gPackager )
				)
				( attribute "LOCATION" "R8E34"
					( Origin gFrontEnd )
				)
				( attribute "MATERIAL" "CHIP"
					( Origin gFrontEnd )
				)
				( attribute "PACK_TYPE" "0402"
					( Origin gFrontEnd )
				)
				( attribute "PART_NUMBER" "G21796-016"
					( Origin gFrontEnd )
				)
				( attribute "PHYS_PAGE" "240"
					( Origin gFrontEnd )
				)
				( attribute "REUSE_ID" "7"
					( Origin gFrontEnd )
				)
				( attribute "ROOM" "P3V3_STBY_VR"
					( Origin gFrontEnd )
				)
				( attribute "ROT" "0"
					( Origin gFrontEnd )
				)
				( attribute "SEC" "1"
					( Origin gPackager )
				)
				( attribute "SPOF" "TRUE"
					( Origin gFrontEnd )
				)
				( attribute "TOLERANCE" "1%"
					( Origin gFrontEnd )
				)
				( attribute "VALUE" "10.0K"
					( Origin gFrontEnd )
				)
				( attribute "VER" "2"
					( Origin gFrontEnd )
				)
				( attribute "WATTAGE" "1/16W"
					( Origin gFrontEnd )
				)
				( attribute "XY" "(9475,1100)"
					( Origin gFrontEnd )
				)
				( attribute "CHIPS_PART_NAME" "RES"
					( Origin gPackager )
				)
				( attribute "CDS_PART_NAME" "RES_0402-10.0K,1%,1/16W,CHIP,GA"
					( Origin gPackager )
				)
				( objectStatus "R8E34" )
			)
			( gate "@baseboard_fab2_lib.baseboard_fab2(sch_1):page240_i143"
				( attribute "BOM_COST" "P3V3_STBY_VR"
					( Origin gFrontEnd )
				)
				( attribute "CDS_LIB" "mstr_discrete"
					( Origin gPackager )
				)
				( attribute "CDS_LOCATION" "R8E31"
					( Origin gPackager )
				)
				( attribute "CDS_SEC" "1"
					( Origin gPackager )
				)
				( attribute "LOCATION" "R8E31"
					( Origin gFrontEnd )
				)
				( attribute "MATERIAL" "CHIP"
					( Origin gFrontEnd )
				)
				( attribute "PACK_TYPE" "0402"
					( Origin gFrontEnd )
				)
				( attribute "PART_NUMBER" "G21796-114"
					( Origin gFrontEnd )
				)
				( attribute "PHYS_PAGE" "240"
					( Origin gFrontEnd )
				)
				( attribute "REUSE_ID" "9"
					( Origin gFrontEnd )
				)
				( attribute "ROOM" "P3V3_STBY_VR"
					( Origin gFrontEnd )
				)
				( attribute "ROT" "0"
					( Origin gFrontEnd )
				)
				( attribute "SEC" "1"
					( Origin gPackager )
				)
				( attribute "SPOF" "TRUE"
					( Origin gFrontEnd )
				)
				( attribute "TOLERANCE" "1%"
					( Origin gFrontEnd )
				)
				( attribute "VALUE" "23.2K"
					( Origin gFrontEnd )
				)
				( attribute "VER" "2"
					( Origin gFrontEnd )
				)
				( attribute "WATTAGE" "1/16W"
					( Origin gFrontEnd )
				)
				( attribute "XY" "(9475,1425)"
					( Origin gFrontEnd )
				)
				( attribute "CHIPS_PART_NAME" "RES"
					( Origin gPackager )
				)
				( attribute "CDS_PART_NAME" "RES_0402-23.2K,1%,1/16W,CHIP,GA"
					( Origin gPackager )
				)
				( objectStatus "R8E31" )
			)
			( gate "@baseboard_fab2_lib.baseboard_fab2(sch_1):page240_i144"
				( attribute "CDS_LIB" "mstr_discrete"
					( Origin gPackager )
				)
				( attribute "CDS_LOCATION" "R8E25"
					( Origin gPackager )
				)
				( attribute "CDS_SEC" "1"
					( Origin gPackager )
				)
				( attribute "LOCATION" "R8E25"
					( Origin gFrontEnd )
				)
				( attribute "MATERIAL" "CHIP"
					( Origin gFrontEnd )
				)
				( attribute "PACK_TYPE" "0402"
					( Origin gFrontEnd )
				)
				( attribute "PART_NUMBER" "G21497-005"
					( Origin gFrontEnd )
				)
				( attribute "PHYS_PAGE" "240"
					( Origin gFrontEnd )
				)
				( attribute "ROOM" "PVPP_KLM_VR"
					( Origin gFrontEnd )
				)
				( attribute "ROT" "5"
					( Origin gFrontEnd )
				)
				( attribute "SEC" "1"
					( Origin gFrontEnd )
				)
				( attribute "SEC_TYPE" "0402"
					( Origin gFrontEnd )
				)
				( attribute "SPOF" "TRUE"
					( Origin gFrontEnd )
				)
				( attribute "TOLERANCE" "5%"
					( Origin gFrontEnd )
				)
				( attribute "VALUE" "0.0"
					( Origin gFrontEnd )
				)
				( attribute "VER" "1"
					( Origin gFrontEnd )
				)
				( attribute "WATTAGE" "1/16W"
					( Origin gFrontEnd )
				)
				( attribute "XY" "(9525,1800)"
					( Origin gFrontEnd )
				)
				( attribute "CHIPS_PART_NAME" "RES"
					( Origin gPackager )
				)
				( attribute "CDS_PART_NAME" "RES_0402-0.0,5%,1/16W,CHIP,G21A"
					( Origin gPackager )
				)
				( objectStatus "R8E25" )
			)
			( gate "@baseboard_fab2_lib.baseboard_fab2(sch_1):page240_i146"
				( attribute "CDS_LIB" "mstr_discrete"
					( Origin gPackager )
				)
				( attribute "CDS_LOCATION" "R8F11"
					( Origin gPackager )
				)
				( attribute "CDS_SEC" "1"
					( Origin gPackager )
				)
				( attribute "LOCATION" "R8F11"
					( Origin gFrontEnd )
				)
				( attribute "MATERIAL" "CHIP"
					( Origin gFrontEnd )
				)
				( attribute "PACK_TYPE" "0402"
					( Origin gFrontEnd )
				)
				( attribute "PART_NUMBER" "G21497-005"
					( Origin gFrontEnd )
				)
				( attribute "PHYS_PAGE" "240"
					( Origin gFrontEnd )
				)
				( attribute "ROOM" "P3V3_STBY_VR"
					( Origin gFrontEnd )
				)
				( attribute "ROT" "0"
					( Origin gFrontEnd )
				)
				( attribute "SEC" "1"
					( Origin gPackager )
				)
				( attribute "TOLERANCE" "5%"
					( Origin gFrontEnd )
				)
				( attribute "VALUE" "0.0"
					( Origin gFrontEnd )
				)
				( attribute "VER" "1"
					( Origin gFrontEnd )
				)
				( attribute "WATTAGE" "1/16W"
					( Origin gFrontEnd )
				)
				( attribute "XY" "(10475,1725)"
					( Origin gFrontEnd )
				)
				( attribute "CHIPS_PART_NAME" "RES"
					( Origin gPackager )
				)
				( attribute "CDS_PART_NAME" "RES_0402-0.0,5%,1/16W,CHIP,G21A"
					( Origin gPackager )
				)
				( objectStatus "R8F11" )
			)
			( gate "@baseboard_fab2_lib.baseboard_fab2(sch_1):page240_i148"
				( attribute "BOM_COST" "P3V3_STBY_VR"
					( Origin gFrontEnd )
				)
				( attribute "CDS_LIB" "mstr_discrete"
					( Origin gPackager )
				)
				( attribute "CDS_LOCATION" "R8F3"
					( Origin gPackager )
				)
				( attribute "CDS_SEC" "1"
					( Origin gPackager )
				)
				( attribute "LOCATION" "R8F3"
					( Origin gFrontEnd )
				)
				( attribute "MATERIAL" "EMPTY"
					( Origin gFrontEnd )
				)
				( attribute "PACK_TYPE" "0402"
					( Origin gFrontEnd )
				)
				( attribute "PART_NUMBER" "G21497-016"
					( Origin gFrontEnd )
				)
				( attribute "PHYS_PAGE" "240"
					( Origin gFrontEnd )
				)
				( attribute "REUSE_ID" "29"
					( Origin gFrontEnd )
				)
				( attribute "ROOM" "P3V3_STBY_VR"
					( Origin gFrontEnd )
				)
				( attribute "ROT" "0"
					( Origin gFrontEnd )
				)
				( attribute "SEC" "1"
					( Origin gPackager )
				)
				( attribute "TOLERANCE" "5%"
					( Origin gFrontEnd )
				)
				( attribute "VALUE" "2.2"
					( Origin gFrontEnd )
				)
				( attribute "VER" "2"
					( Origin gFrontEnd )
				)
				( attribute "WATTAGE" "1/16W"
					( Origin gFrontEnd )
				)
				( attribute "XY" "(9750,3550)"
					( Origin gFrontEnd )
				)
				( attribute "CHIPS_PART_NAME" "RES"
					( Origin gPackager )
				)
				( attribute "CDS_PART_NAME" "RES_0402-2.2,5%,1/16W,EMPTY,G2A"
					( Origin gPackager )
				)
				( objectStatus "R8F3" )
			)
			( gate "@baseboard_fab2_lib.baseboard_fab2(sch_1):page240_i152"
				( attribute "BOM_COST" "P3V3_STBY_VR"
					( Origin gFrontEnd )
				)
				( attribute "CDS_LIB" "mstr_discrete"
					( Origin gPackager )
				)
				( attribute "CDS_LOCATION" "R2T4"
					( Origin gPackager )
				)
				( attribute "CDS_SEC" "1"
					( Origin gPackager )
				)
				( attribute "LOCATION" "R2T4"
					( Origin gFrontEnd )
				)
				( attribute "MATERIAL" "CHIP"
					( Origin gFrontEnd )
				)
				( attribute "PACK_TYPE" "0402"
					( Origin gFrontEnd )
				)
				( attribute "PART_NUMBER" "G85996-004"
					( Origin gFrontEnd )
				)
				( attribute "PHYS_PAGE" "240"
					( Origin gFrontEnd )
				)
				( attribute "REUSE_ID" "34"
					( Origin gFrontEnd )
				)
				( attribute "ROOM" "P3V3_STBY_VR"
					( Origin gFrontEnd )
				)
				( attribute "ROT" "0"
					( Origin gFrontEnd )
				)
				( attribute "SEC" "1"
					( Origin gPackager )
				)
				( attribute "TOLERANCE" "0.1%"
					( Origin gFrontEnd )
				)
				( attribute "VALUE" "1.0K"
					( Origin gFrontEnd )
				)
				( attribute "VER" "2"
					( Origin gFrontEnd )
				)
				( attribute "WATTAGE" "1/16W"
					( Origin gFrontEnd )
				)
				( attribute "XY" "(10750,3800)"
					( Origin gFrontEnd )
				)
				( attribute "CHIPS_PART_NAME" "RES"
					( Origin gPackager )
				)
				( attribute "CDS_PART_NAME" "RES_0402-1.0K,0.1%,1/16W,CHIP,A"
					( Origin gPackager )
				)
				( objectStatus "R2T4" )
			)
			( gate "@baseboard_fab2_lib.baseboard_fab2(sch_1):page240_i158"
				( attribute "BOM_COST" "P3V3_STBY_VR"
					( Origin gFrontEnd )
				)
				( attribute "CDS_LIB" "mstr_discrete"
					( Origin gPackager )
				)
				( attribute "CDS_LOCATION" "C2T7"
					( Origin gPackager )
				)
				( attribute "CDS_SEC" "1"
					( Origin gPackager )
				)
				( attribute "LOCATION" "C2T7"
					( Origin gFrontEnd )
				)
				( attribute "MATERIAL" "X6S"
					( Origin gFrontEnd )
				)
				( attribute "PACK_TYPE" "0805"
					( Origin gFrontEnd )
				)
				( attribute "PART_NUMBER" "C95333-008"
					( Origin gFrontEnd )
				)
				( attribute "PHYS_PAGE" "240"
					( Origin gFrontEnd )
				)
				( attribute "REUSE_ID" "33"
					( Origin gFrontEnd )
				)
				( attribute "ROOM" "P3V3_STBY_VR"
					( Origin gFrontEnd )
				)
				( attribute "ROT" "0"
					( Origin gFrontEnd )
				)
				( attribute "SEC" "1"
					( Origin gPackager )
				)
				( attribute "TOLERANCE" "20%"
					( Origin gFrontEnd )
				)
				( attribute "VALUE" "22UF"
					( Origin gFrontEnd )
				)
				( attribute "VER" "1"
					( Origin gFrontEnd )
				)
				( attribute "VOLTAGE" "6.3V"
					( Units "uVoltage" "V" 1.000000)
					( Origin gFrontEnd )
				)
				( attribute "XY" "(11950,3875)"
					( Origin gFrontEnd )
				)
				( attribute "CHIPS_PART_NAME" "CAP"
					( Origin gPackager )
				)
				( attribute "CDS_PART_NAME" "CAP_0805-22UF,6.3V,20%,X6S,C95A"
					( Origin gPackager )
				)
				( objectStatus "C2T7" )
			)
			( gate "@baseboard_fab2_lib.baseboard_fab2(sch_1):page240_i160"
				( attribute "BOM_COST" "P3V3_STBY_VR"
					( Origin gFrontEnd )
				)
				( attribute "CDS_LIB" "mstr_discrete"
					( Origin gPackager )
				)
				( attribute "CDS_LOCATION" "C2T6"
					( Origin gPackager )
				)
				( attribute "CDS_SEC" "1"
					( Origin gPackager )
				)
				( attribute "LOCATION" "C2T6"
					( Origin gFrontEnd )
				)
				( attribute "MATERIAL" "X6S"
					( Origin gFrontEnd )
				)
				( attribute "PACK_TYPE" "0805"
					( Origin gFrontEnd )
				)
				( attribute "PART_NUMBER" "C95333-008"
					( Origin gFrontEnd )
				)
				( attribute "PHYS_PAGE" "240"
					( Origin gFrontEnd )
				)
				( attribute "REUSE_ID" "33"
					( Origin gFrontEnd )
				)
				( attribute "ROOM" "P3V3_STBY_VR"
					( Origin gFrontEnd )
				)
				( attribute "ROT" "0"
					( Origin gFrontEnd )
				)
				( attribute "SEC" "1"
					( Origin gPackager )
				)
				( attribute "TOLERANCE" "20%"
					( Origin gFrontEnd )
				)
				( attribute "VALUE" "22UF"
					( Origin gFrontEnd )
				)
				( attribute "VER" "1"
					( Origin gFrontEnd )
				)
				( attribute "VOLTAGE" "6.3V"
					( Units "uVoltage" "V" 1.000000)
					( Origin gFrontEnd )
				)
				( attribute "XY" "(12175,3875)"
					( Origin gFrontEnd )
				)
				( attribute "CHIPS_PART_NAME" "CAP"
					( Origin gPackager )
				)
				( attribute "CDS_PART_NAME" "CAP_0805-22UF,6.3V,20%,X6S,C95A"
					( Origin gPackager )
				)
				( objectStatus "C2T6" )
			)
			( gate "@baseboard_fab2_lib.baseboard_fab2(sch_1):page240_i163"
				( attribute "BOM_COST" "P3V3_STBY_VR"
					( Origin gFrontEnd )
				)
				( attribute "CDS_LIB" "mstr_discrete"
					( Origin gPackager )
				)
				( attribute "CDS_LOCATION" "C8F3"
					( Origin gPackager )
				)
				( attribute "CDS_SEC" "1"
					( Origin gPackager )
				)
				( attribute "LOCATION" "C8F3"
					( Origin gFrontEnd )
				)
				( attribute "MATERIAL" "EMPTY"
					( Origin gFrontEnd )
				)
				( attribute "PACK_TYPE" "0402LF"
					( Origin gFrontEnd )
				)
				( attribute "PART_NUMBER" "A36096-091"
					( Origin gFrontEnd )
				)
				( attribute "PHYS_PAGE" "240"
					( Origin gFrontEnd )
				)
				( attribute "REUSE_ID" "26"
					( Origin gFrontEnd )
				)
				( attribute "ROOM" "P3V3_STBY_VR"
					( Origin gFrontEnd )
				)
				( attribute "ROT" "0"
					( Origin gFrontEnd )
				)
				( attribute "SEC" "1"
					( Origin gPackager )
				)
				( attribute "TOLERANCE" "10%"
					( Origin gFrontEnd )
				)
				( attribute "VALUE" "3300PF"
					( Origin gFrontEnd )
				)
				( attribute "VER" "1"
					( Origin gFrontEnd )
				)
				( attribute "VOLTAGE" "50V"
					( Units "uVoltage" "V" 1.000000)
					( Origin gFrontEnd )
				)
				( attribute "XY" "(9750,3900)"
					( Origin gFrontEnd )
				)
				( attribute "CHIPS_PART_NAME" "CAP"
					( Origin gPackager )
				)
				( attribute "CDS_PART_NAME" "CAP_0402LF-3300PF,50V,10%,EMPTA"
					( Origin gPackager )
				)
				( objectStatus "C8F3" )
			)
			( gate "@baseboard_fab2_lib.baseboard_fab2(sch_1):page240_i170"
				( attribute "CDS_LIB" "mstr_discrete"
					( Origin gPackager )
				)
				( attribute "CDS_LOCATION" "EU8E1"
					( Origin gPackager )
				)
				( attribute "CDS_SEC" "1"
					( Origin gPackager )
				)
				( attribute "LOCATION" "EU8E1"
					( Origin gFrontEnd )
				)
				( attribute "MATERIAL" "IC"
					( Origin gFrontEnd )
				)
				( attribute "PACK_TYPE" "SM"
					( Origin gFrontEnd )
				)
				( attribute "PART_NUMBER" "H66258-001"
					( Origin gFrontEnd )
				)
				( attribute "PHYS_PAGE" "240"
					( Origin gFrontEnd )
				)
				( attribute "ROOM" "P3V3_STBY_VR"
					( Origin gFrontEnd )
				)
				( attribute "ROT" "0"
					( Origin gFrontEnd )
				)
				( attribute "SEC" "1"
					( Origin gFrontEnd )
				)
				( attribute "SEC_TYPE" "SM"
					( Origin gFrontEnd )
				)
				( attribute "VER" "1"
					( Origin gFrontEnd )
				)
				( attribute "XY" "(9250,3400)"
					( Origin gFrontEnd )
				)
				( attribute "CHIPS_PART_NAME" "CSD87384M"
					( Origin gPackager )
				)
				( attribute "CDS_PART_NAME" "CSD87384M_SM-IC,H66258-001"
					( Origin gPackager )
				)
				( objectStatus "EU8E1" )
			)
			( gate "@baseboard_fab2_lib.baseboard_fab2(sch_1):page240_i171"
				( attribute "CDS_LIB" "mstr_discrete"
					( Origin gPackager )
				)
				( attribute "CDS_LOCATION" "R8F10"
					( Origin gPackager )
				)
				( attribute "CDS_SEC" "1"
					( Origin gPackager )
				)
				( attribute "LOCATION" "R8F10"
					( Origin gFrontEnd )
				)
				( attribute "MATERIAL" "CHIP"
					( Origin gFrontEnd )
				)
				( attribute "PACK_TYPE" "0402"
					( Origin gFrontEnd )
				)
				( attribute "PART_NUMBER" "G21796-250"
					( Origin gFrontEnd )
				)
				( attribute "PHYS_PAGE" "240"
					( Origin gFrontEnd )
				)
				( attribute "ROOM" "P3V3_STBY_VR"
					( Origin gFrontEnd )
				)
				( attribute "ROT" "0"
					( Origin gFrontEnd )
				)
				( attribute "SEC" "1"
					( Origin gFrontEnd )
				)
				( attribute "SEC_TYPE" "0402"
					( Origin gFrontEnd )
				)
				( attribute "TOLERANCE" "1.0%"
					( Origin gFrontEnd )
				)
				( attribute "VALUE" "22.1"
					( Origin gFrontEnd )
				)
				( attribute "VER" "1"
					( Origin gFrontEnd )
				)
				( attribute "WATTAGE" "1/16W"
					( Origin gFrontEnd )
				)
				( attribute "XY" "(7175,3825)"
					( Origin gFrontEnd )
				)
				( attribute "CHIPS_PART_NAME" "RES"
					( Origin gPackager )
				)
				( attribute "CDS_PART_NAME" "RES_0402-22.1,1.0%,1/16W,CHIP,A"
					( Origin gPackager )
				)
				( objectStatus "R8F10" )
			)
			( gate "@baseboard_fab2_lib.baseboard_fab2(sch_1):page175_i99"
				( attribute "BOM_COST" "M-SATA"
					( Origin gFrontEnd )
				)
				( attribute "CDS_LIB" "mstr_discrete"
					( Origin gPackager )
				)
				( attribute "LOCATION" "R1L19"
					( Origin gFrontEnd )
				)
				( attribute "MATERIAL" "CHIP"
					( Origin gFrontEnd )
				)
				( attribute "PACK_TYPE" "0402"
					( Origin gFrontEnd )
				)
				( attribute "PART_NUMBER" "G21796-072"
					( Origin gFrontEnd )
				)
				( attribute "PHYS_PAGE" "175"
					( Origin gFrontEnd )
				)
				( attribute "ROOM" "M-SATA"
					( Origin gFrontEnd )
				)
				( attribute "ROT" "0"
					( Origin gFrontEnd )
				)
				( attribute "TOLERANCE" "1%"
					( Origin gFrontEnd )
				)
				( attribute "VALUE" "4.75K"
					( Origin gFrontEnd )
				)
				( attribute "VER" "2"
					( Origin gFrontEnd )
				)
				( attribute "WATTAGE" "1/16W"
					( Origin gFrontEnd )
				)
				( attribute "XY" "(-5875,3075)"
					( Origin gFrontEnd )
				)
				( attribute "CHIPS_PART_NAME" "RES"
					( Origin gPackager )
				)
				( attribute "CDS_PART_NAME" "RES_0402-4.75K,1%,1/16W,CHIP,GA"
					( Origin gPackager )
				)
				( attribute "SEC" "1"
					( Origin gFrontEnd )
				)
				( attribute "SEC_TYPE" "0402"
					( Origin gFrontEnd )
				)
				( attribute "CDS_LOCATION" "R1L19"
					( Origin gPackager )
				)
				( attribute "CDS_SEC" "1"
					( Origin gPackager )
				)
				( objectStatus "R1L19" )
			)
			( gate "@baseboard_fab2_lib.baseboard_fab2(sch_1):page240_i174"
				( attribute "BOM_COST" "P3V3_STBY_VR"
					( Origin gFrontEnd )
				)
				( attribute "CDS_LIB" "mstr_discrete"
					( Origin gPackager )
				)
				( attribute "CDS_LOCATION" "C2T9"
					( Origin gPackager )
				)
				( attribute "LOCATION" "C2T9"
					( Origin gFrontEnd )
				)
				( attribute "MATERIAL" "X6S"
					( Origin gFrontEnd )
				)
				( attribute "PACK_TYPE" "0805"
					( Origin gFrontEnd )
				)
				( attribute "PART_NUMBER" "C95333-008"
					( Origin gFrontEnd )
				)
				( attribute "PHYS_PAGE" "240"
					( Origin gFrontEnd )
				)
				( attribute "REUSE_ID" "33"
					( Origin gFrontEnd )
				)
				( attribute "ROOM" "P3V3_STBY_VR"
					( Origin gFrontEnd )
				)
				( attribute "ROT" "0"
					( Origin gFrontEnd )
				)
				( attribute "SEC" "1"
					( Origin gFrontEnd )
				)
				( attribute "TOLERANCE" "20%"
					( Origin gFrontEnd )
				)
				( attribute "VALUE" "22UF"
					( Origin gFrontEnd )
				)
				( attribute "VER" "1"
					( Origin gFrontEnd )
				)
				( attribute "VOLTAGE" "6.3V"
					( Units "uVoltage" "V" 1.000000)
					( Origin gFrontEnd )
				)
				( attribute "XY" "(12425,3875)"
					( Origin gFrontEnd )
				)
				( attribute "CHIPS_PART_NAME" "CAP"
					( Origin gPackager )
				)
				( attribute "CDS_PART_NAME" "CAP_0805-22UF,6.3V,20%,X6S,C95A"
					( Origin gPackager )
				)
				( attribute "SEC_TYPE" "0805"
					( Origin gFrontEnd )
				)
				( attribute "CDS_SEC" "1"
					( Origin gPackager )
				)
				( objectStatus "C2T9" )
			)
			( gate "@baseboard_fab2_lib.baseboard_fab2(sch_1):page240_i176"
				( attribute "CDS_LIB" "mstr_discrete"
					( Origin gPackager )
				)
				( attribute "CDS_LOCATION" "R8F2"
					( Origin gPackager )
				)
				( attribute "LOCATION" "R8F2"
					( Origin gFrontEnd )
				)
				( attribute "MATERIAL" "CHIP"
					( Origin gFrontEnd )
				)
				( attribute "PACK_TYPE" "0402"
					( Origin gFrontEnd )
				)
				( attribute "PART_NUMBER" "G21497-005"
					( Origin gFrontEnd )
				)
				( attribute "PHYS_PAGE" "240"
					( Origin gFrontEnd )
				)
				( attribute "ROOM" "PVCCIN_CPU0_VR"
					( Origin gFrontEnd )
				)
				( attribute "ROT" "0"
					( Origin gFrontEnd )
				)
				( attribute "SEC" "1"
					( Origin gFrontEnd )
				)
				( attribute "TOLERANCE" "5%"
					( Origin gFrontEnd )
				)
				( attribute "VALUE" "0.0"
					( Origin gFrontEnd )
				)
				( attribute "VER" "1"
					( Origin gFrontEnd )
				)
				( attribute "WATTAGE" "1/16W"
					( Origin gFrontEnd )
				)
				( attribute "XY" "(6400,2725)"
					( Origin gFrontEnd )
				)
				( attribute "CHIPS_PART_NAME" "RES"
					( Origin gPackager )
				)
				( attribute "CDS_PART_NAME" "RES_0402-0.0,5%,1/16W,CHIP,G21A"
					( Origin gPackager )
				)
				( attribute "SEC_TYPE" "0402"
					( Origin gFrontEnd )
				)
				( attribute "CDS_SEC" "1"
					( Origin gPackager )
				)
				( objectStatus "R8F2" )
			)
			( gate "@baseboard_fab2_lib.baseboard_fab2(sch_1):page240_i177"
				( attribute "BOM_COST" "SM_CONTROLLER"
					( Origin gFrontEnd )
				)
				( attribute "CDS_LIB" "mstr_discrete"
					( Origin gPackager )
				)
				( attribute "CDS_LOCATION" "R8E40"
					( Origin gPackager )
				)
				( attribute "LOCATION" "R8E40"
					( Origin gFrontEnd )
				)
				( attribute "MATERIAL" "EMPTY"
					( Origin gFrontEnd )
				)
				( attribute "PACK_TYPE" "0402"
					( Origin gFrontEnd )
				)
				( attribute "PART_NUMBER" "G21796-010"
					( Origin gFrontEnd )
				)
				( attribute "PHYS_PAGE" "240"
					( Origin gFrontEnd )
				)
				( attribute "ROOM" "BMC"
					( Origin gFrontEnd )
				)
				( attribute "ROT" "0"
					( Origin gFrontEnd )
				)
				( attribute "SEC" "1"
					( Origin gFrontEnd )
				)
				( attribute "TOLERANCE" "1%"
					( Origin gFrontEnd )
				)
				( attribute "VALUE" "100.0K"
					( Origin gFrontEnd )
				)
				( attribute "VER" "2"
					( Origin gFrontEnd )
				)
				( attribute "WATTAGE" "1/16W"
					( Origin gFrontEnd )
				)
				( attribute "XY" "(6950,3250)"
					( Origin gFrontEnd )
				)
				( attribute "CHIPS_PART_NAME" "RES"
					( Origin gPackager )
				)
				( attribute "CDS_PART_NAME" "RES_0402-100.0K,1%,1/16W,EMPTYA"
					( Origin gPackager )
				)
				( attribute "SEC_TYPE" "0402"
					( Origin gFrontEnd )
				)
				( attribute "CDS_SEC" "1"
					( Origin gPackager )
				)
				( objectStatus "R8E40" )
			)
			( gate "@baseboard_fab2_lib.baseboard_fab2(sch_1):page227_i148"
				( attribute "CDS_LIB" "w_hdl"
					( Origin gPackager )
				)
				( attribute "CDS_LMAN_SYM_OUTLINE" "-50,25,50,-25"
					( Origin gPackager )
				)
				( attribute "LOCATION" "C1A2"
					( Origin gFrontEnd )
				)
				( attribute "PACK_TYPE" "SMD-BCG6"
					( Origin gFrontEnd )
				)
				( attribute "PART_NUMBER" "78.10523.8FL"
					( Origin gFrontEnd )
				)
				( attribute "PHYS_PAGE" "227"
					( Origin gFrontEnd )
				)
				( attribute "ROT" "0"
					( Origin gFrontEnd )
				)
				( attribute "SEC" "1"
					( Origin gFrontEnd )
				)
				( attribute "SEC_TYPE" "SMD-BCG6"
					( Origin gFrontEnd )
				)
				( attribute "VALUE" "SC1U10V2KX-4-GP"
					( Origin gFrontEnd )
				)
				( attribute "VER" "1"
					( Origin gFrontEnd )
				)
				( attribute "XY" "(-475,2475)"
					( Origin gFrontEnd )
				)
				( attribute "CHIPS_PART_NAME" "SC1U10V2KX-4-GP"
					( Origin gPackager )
				)
				( attribute "CDS_PART_NAME" "SC1U10V2KX-4-GP_SMD-BCG6-SC1U1A"
					( Origin gPackager )
				)
				( attribute "CDS_LOCATION" "C1A2"
					( Origin gPackager )
				)
				( attribute "CDS_SEC" "1"
					( Origin gPackager )
				)
				( attribute "ATTRIBUTE" "1UF"
					( Origin gFrontEnd )
				)
				( attribute "PACK_SIZE" "0402"
					( Origin gFrontEnd )
				)
				( attribute "RATED" "10V"
					( Origin gFrontEnd )
				)
				( attribute "TOLERANCE" "10%"
					( Origin gFrontEnd )
				)
				( objectStatus "C1A2" )
			)
			( gate "@baseboard_fab2_lib.baseboard_fab2(sch_1):page240_i191"
				( attribute "CDS_LIB" "w_hdl"
					( Origin gPackager )
				)
				( attribute "CDS_LMAN_SYM_OUTLINE" "-50,25,50,-25"
					( Origin gPackager )
				)
				( attribute "LOCATION" "C2R11"
					( Origin gFrontEnd )
				)
				( attribute "PACK_TYPE" "SMD-BCG5"
					( Origin gFrontEnd )
				)
				( attribute "PART_NUMBER" "078.47521.08BD"
					( Origin gFrontEnd )
				)
				( attribute "PHYS_PAGE" "240"
					( Origin gFrontEnd )
				)
				( attribute "ROT" "0"
					( Origin gFrontEnd )
				)
				( attribute "SEC" "1"
					( Origin gFrontEnd )
				)
				( attribute "SEC_TYPE" "SMD-BCG5"
					( Origin gFrontEnd )
				)
				( attribute "VALUE" "SC4D7U16V3KX-GP"
					( Origin gFrontEnd )
				)
				( attribute "VER" "1"
					( Origin gFrontEnd )
				)
				( attribute "XY" "(5500,3275)"
					( Origin gFrontEnd )
				)
				( attribute "CHIPS_PART_NAME" "SC4D7U16V3KX-GP"
					( Origin gPackager )
				)
				( attribute "CDS_PART_NAME" "SC4D7U16V3KX-GP_SMD-BCG5-SC4D7A"
					( Origin gPackager )
				)
				( attribute "CDS_LOCATION" "C2R11"
					( Origin gPackager )
				)
				( attribute "CDS_SEC" "1"
					( Origin gPackager )
				)
				( attribute "ATTRIBUTE" "4.7UF"
					( Origin gFrontEnd )
				)
				( attribute "PACK_SIZE" "0603"
					( Origin gFrontEnd )
				)
				( attribute "RATED" "16V"
					( Origin gFrontEnd )
				)
				( attribute "TOLERANCE" "10%"
					( Origin gFrontEnd )
				)
				( objectStatus "C2R11" )
			)
			( gate "@baseboard_fab2_lib.baseboard_fab2(sch_1):page241_i9"
				( attribute "BOM_COST" "P5V_STBY_VR"
					( Origin gFrontEnd )
				)
				( attribute "CDS_LIB" "mstr_discrete"
					( Origin gPackager )
				)
				( attribute "CDS_LOCATION" "R8E18"
					( Origin gPackager )
				)
				( attribute "CDS_SEC" "1"
					( Origin gPackager )
				)
				( attribute "LOCATION" "R8E18"
					( Origin gFrontEnd )
				)
				( attribute "MATERIAL" "CHIP"
					( Origin gFrontEnd )
				)
				( attribute "PACK_TYPE" "0402"
					( Origin gFrontEnd )
				)
				( attribute "PART_NUMBER" "G85996-004"
					( Origin gFrontEnd )
				)
				( attribute "PHYS_PAGE" "241"
					( Origin gFrontEnd )
				)
				( attribute "REUSE_ID" "34"
					( Origin gFrontEnd )
				)
				( attribute "ROOM" "P5V_STBY_VR"
					( Origin gFrontEnd )
				)
				( attribute "ROT" "0"
					( Origin gFrontEnd )
				)
				( attribute "SEC" "1"
					( Origin gFrontEnd )
				)
				( attribute "SEC_TYPE" "0402"
					( Origin gFrontEnd )
				)
				( attribute "TOLERANCE" "0.1%"
					( Origin gFrontEnd )
				)
				( attribute "VALUE" "1.0K"
					( Origin gFrontEnd )
				)
				( attribute "VER" "2"
					( Origin gFrontEnd )
				)
				( attribute "WATTAGE" "1/16W"
					( Origin gFrontEnd )
				)
				( attribute "XY" "(2550,3875)"
					( Origin gFrontEnd )
				)
				( attribute "CHIPS_PART_NAME" "RES"
					( Origin gPackager )
				)
				( attribute "CDS_PART_NAME" "RES_0402-1.0K,0.1%,1/16W,CHIP,A"
					( Origin gPackager )
				)
				( objectStatus "R8E18" )
			)
			( gate "@baseboard_fab2_lib.baseboard_fab2(sch_1):page241_i11"
				( attribute "BOM_COST" "P5V_STBY_VR"
					( Origin gFrontEnd )
				)
				( attribute "CDS_LIB" "mstr_discrete"
					( Origin gPackager )
				)
				( attribute "CDS_LOCATION" "R7E12"
					( Origin gPackager )
				)
				( attribute "CDS_SEC" "1"
					( Origin gPackager )
				)
				( attribute "LOCATION" "R7E12"
					( Origin gFrontEnd )
				)
				( attribute "MATERIAL" "CHIP"
					( Origin gFrontEnd )
				)
				( attribute "PACK_TYPE" "0402"
					( Origin gFrontEnd )
				)
				( attribute "PART_NUMBER" "G21796-026"
					( Origin gFrontEnd )
				)
				( attribute "PHYS_PAGE" "241"
					( Origin gFrontEnd )
				)
				( attribute "REUSE_ID" "21"
					( Origin gFrontEnd )
				)
				( attribute "ROOM" "P5V_STBY_VR"
					( Origin gFrontEnd )
				)
				( attribute "ROT" "0"
					( Origin gFrontEnd )
				)
				( attribute "SEC" "1"
					( Origin gFrontEnd )
				)
				( attribute "SEC_TYPE" "0402"
					( Origin gFrontEnd )
				)
				( attribute "TOLERANCE" "1%"
					( Origin gFrontEnd )
				)
				( attribute "VALUE" "1.00K"
					( Origin gFrontEnd )
				)
				( attribute "VER" "2"
					( Origin gFrontEnd )
				)
				( attribute "WATTAGE" "1/16W"
					( Origin gFrontEnd )
				)
				( attribute "XY" "(1225,4850)"
					( Origin gFrontEnd )
				)
				( attribute "CHIPS_PART_NAME" "RES"
					( Origin gPackager )
				)
				( attribute "CDS_PART_NAME" "RES_0402-1.00K,1%,1/16W,CHIP,GA"
					( Origin gPackager )
				)
				( objectStatus "R7E12" )
			)
			( gate "@baseboard_fab2_lib.baseboard_fab2(sch_1):page241_i12"
				( attribute "BOM_COST" "P5V_STBY_VR"
					( Origin gFrontEnd )
				)
				( attribute "CDS_LIB" "mstr_discrete"
					( Origin gPackager )
				)
				( attribute "CDS_LOCATION" "C8E6"
					( Origin gPackager )
				)
				( attribute "CDS_SEC" "1"
					( Origin gPackager )
				)
				( attribute "LOCATION" "C8E6"
					( Origin gFrontEnd )
				)
				( attribute "MATERIAL" "X7R"
					( Origin gFrontEnd )
				)
				( attribute "PACK_TYPE" "0603LF"
					( Origin gFrontEnd )
				)
				( attribute "PART_NUMBER" "602433-020"
					( Origin gFrontEnd )
				)
				( attribute "PHYS_PAGE" "241"
					( Origin gFrontEnd )
				)
				( attribute "REUSE_ID" "27"
					( Origin gFrontEnd )
				)
				( attribute "ROOM" "P5V_STBY_VR"
					( Origin gFrontEnd )
				)
				( attribute "ROT" "0"
					( Origin gFrontEnd )
				)
				( attribute "SEC" "1"
					( Origin gFrontEnd )
				)
				( attribute "SEC_TYPE" "0603LF"
					( Origin gFrontEnd )
				)
				( attribute "SPOF" "TRUE"
					( Origin gFrontEnd )
				)
				( attribute "TOLERANCE" "10%"
					( Origin gFrontEnd )
				)
				( attribute "VALUE" "0.1UF"
					( Origin gFrontEnd )
				)
				( attribute "VER" "2"
					( Origin gFrontEnd )
				)
				( attribute "VOLTAGE" "25V"
					( Units "uVoltage" "V" 1.000000)
					( Origin gFrontEnd )
				)
				( attribute "XY" "(1200,3675)"
					( Origin gFrontEnd )
				)
				( attribute "CHIPS_PART_NAME" "CAP"
					( Origin gPackager )
				)
				( attribute "CDS_PART_NAME" "CAP_0603LF-0.1UF,25V,10%,X7R,6A"
					( Origin gPackager )
				)
				( objectStatus "C8E6" )
			)
			( gate "@baseboard_fab2_lib.baseboard_fab2(sch_1):page241_i14"
				( attribute "BOM_COST" "P5V_STBY_VR"
					( Origin gFrontEnd )
				)
				( attribute "CDS_LIB" "mstr_discrete"
					( Origin gPackager )
				)
				( attribute "CDS_LOCATION" "C7E10"
					( Origin gPackager )
				)
				( attribute "CDS_SEC" "1"
					( Origin gPackager )
				)
				( attribute "LOCATION" "C7E10"
					( Origin gFrontEnd )
				)
				( attribute "MATERIAL" "X7R"
					( Origin gFrontEnd )
				)
				( attribute "PACK_TYPE" "0402LF"
					( Origin gFrontEnd )
				)
				( attribute "PART_NUMBER" "A36096-046"
					( Origin gFrontEnd )
				)
				( attribute "PHYS_PAGE" "241"
					( Origin gFrontEnd )
				)
				( attribute "REUSE_ID" "17"
					( Origin gFrontEnd )
				)
				( attribute "ROOM" "P5V_STBY_VR"
					( Origin gFrontEnd )
				)
				( attribute "ROT" "0"
					( Origin gFrontEnd )
				)
				( attribute "SEC" "1"
					( Origin gFrontEnd )
				)
				( attribute "SEC_TYPE" "0402LF"
					( Origin gFrontEnd )
				)
				( attribute "TOLERANCE" "10%"
					( Origin gFrontEnd )
				)
				( attribute "VALUE" "1000PF"
					( Origin gFrontEnd )
				)
				( attribute "VER" "1"
					( Origin gFrontEnd )
				)
				( attribute "VOLTAGE" "50V"
					( Units "uVoltage" "V" 1.000000)
					( Origin gFrontEnd )
				)
				( attribute "XY" "(1500,4400)"
					( Origin gFrontEnd )
				)
				( attribute "CHIPS_PART_NAME" "CAP"
					( Origin gPackager )
				)
				( attribute "CDS_PART_NAME" "CAP_0402LF-1000PF,50V,10%,X7R,A"
					( Origin gPackager )
				)
				( objectStatus "C7E10" )
			)
			( gate "@baseboard_fab2_lib.baseboard_fab2(sch_1):page241_i18"
				( attribute "BOM_COST" "P5V_STBY_VR"
					( Origin gFrontEnd )
				)
				( attribute "CDS_LIB" "mstr_discrete"
					( Origin gPackager )
				)
				( attribute "CDS_LOCATION" "R7E14"
					( Origin gPackager )
				)
				( attribute "CDS_SEC" "1"
					( Origin gPackager )
				)
				( attribute "LOCATION" "R7E14"
					( Origin gFrontEnd )
				)
				( attribute "MATERIAL" "CHIP"
					( Origin gFrontEnd )
				)
				( attribute "PACK_TYPE" "0402"
					( Origin gFrontEnd )
				)
				( attribute "PART_NUMBER" "G21796-224"
					( Origin gFrontEnd )
				)
				( attribute "PHYS_PAGE" "241"
					( Origin gFrontEnd )
				)
				( attribute "REUSE_ID" "8"
					( Origin gFrontEnd )
				)
				( attribute "ROOM" "P5V_STBY_VR"
					( Origin gFrontEnd )
				)
				( attribute "ROT" "0"
					( Origin gFrontEnd )
				)
				( attribute "SEC" "1"
					( Origin gFrontEnd )
				)
				( attribute "SEC_TYPE" "0402"
					( Origin gFrontEnd )
				)
				( attribute "TOLERANCE" "1%"
					( Origin gFrontEnd )
				)
				( attribute "VALUE" "75K"
					( Origin gFrontEnd )
				)
				( attribute "VER" "2"
					( Origin gFrontEnd )
				)
				( attribute "WATTAGE" "1/16W"
					( Origin gFrontEnd )
				)
				( attribute "XY" "(-825,2600)"
					( Origin gFrontEnd )
				)
				( attribute "CHIPS_PART_NAME" "RES"
					( Origin gPackager )
				)
				( attribute "CDS_PART_NAME" "RES_0402-75K,1%,1/16W,CHIP,G21A"
					( Origin gPackager )
				)
				( objectStatus "R7E14" )
			)
			( gate "@baseboard_fab2_lib.baseboard_fab2(sch_1):page241_i30"
				( attribute "BOM_COST" "P5V_STBY_VR"
					( Origin gFrontEnd )
				)
				( attribute "CDS_LIB" "mstr_discrete"
					( Origin gPackager )
				)
				( attribute "CDS_LOCATION" "C7E14"
					( Origin gPackager )
				)
				( attribute "CDS_SEC" "1"
					( Origin gPackager )
				)
				( attribute "FIN" "VR_1P2"
					( Origin gFrontEnd )
				)
				( attribute "LOCATION" "C7E14"
					( Origin gFrontEnd )
				)
				( attribute "MATERIAL" "X6S"
					( Origin gFrontEnd )
				)
				( attribute "PACK_TYPE" "0402"
					( Origin gFrontEnd )
				)
				( attribute "PART_NUMBER" "D97712-011"
					( Origin gFrontEnd )
				)
				( attribute "PHYS_PAGE" "241"
					( Origin gFrontEnd )
				)
				( attribute "REUSE_ID" "1"
					( Origin gFrontEnd )
				)
				( attribute "ROOM" "P5V_STBY_VR"
					( Origin gFrontEnd )
				)
				( attribute "ROT" "0"
					( Origin gFrontEnd )
				)
				( attribute "SEC" "1"
					( Origin gFrontEnd )
				)
				( attribute "SEC_TYPE" "0402"
					( Origin gFrontEnd )
				)
				( attribute "TOLERANCE" "10%"
					( Origin gFrontEnd )
				)
				( attribute "VALUE" "1.0UF"
					( Origin gFrontEnd )
				)
				( attribute "VER" "1"
					( Origin gFrontEnd )
				)
				( attribute "VOLTAGE" "16V"
					( Units "uVoltage" "V" 1.000000)
					( Origin gFrontEnd )
				)
				( attribute "XY" "(-1400,3850)"
					( Origin gFrontEnd )
				)
				( attribute "CHIPS_PART_NAME" "CAP"
					( Origin gPackager )
				)
				( attribute "CDS_PART_NAME" "CAP_0402-1.0UF,16V,10%,X6S,D97A"
					( Origin gPackager )
				)
				( objectStatus "C7E14" )
			)
			( gate "@baseboard_fab2_lib.baseboard_fab2(sch_1):page241_i37"
				( attribute "BOM_COST" "P5V_STBY_VR"
					( Origin gFrontEnd )
				)
				( attribute "CDS_LIB" "mstr_discrete"
					( Origin gPackager )
				)
				( attribute "CDS_LOCATION" "R7E17"
					( Origin gPackager )
				)
				( attribute "CDS_SEC" "1"
					( Origin gPackager )
				)
				( attribute "LOCATION" "R7E17"
					( Origin gFrontEnd )
				)
				( attribute "MATERIAL" "CHIP"
					( Origin gFrontEnd )
				)
				( attribute "NO_XNET_CONNECTION" "1"
					( Origin gFrontEnd )
				)
				( attribute "PACK_TYPE" "0402"
					( Origin gFrontEnd )
				)
				( attribute "PART_NUMBER" "G21497-005"
					( Origin gFrontEnd )
				)
				( attribute "PHYS_PAGE" "241"
					( Origin gFrontEnd )
				)
				( attribute "REUSE_ID" "13"
					( Origin gPackager )
				)
				( attribute "ROOM" "P5V_STBY_VR"
					( Origin gFrontEnd )
				)
				( attribute "ROT" "0"
					( Origin gFrontEnd )
				)
				( attribute "SEC" "1"
					( Origin gFrontEnd )
				)
				( attribute "SEC_TYPE" "0402"
					( Origin gFrontEnd )
				)
				( attribute "TOLERANCE" "5%"
					( Origin gFrontEnd )
				)
				( attribute "VALUE" "0.0"
					( Origin gFrontEnd )
				)
				( attribute "VER" "2"
					( Origin gFrontEnd )
				)
				( attribute "WATTAGE" "1/16W"
					( Origin gFrontEnd )
				)
				( attribute "XY" "(-1400,4200)"
					( Origin gFrontEnd )
				)
				( attribute "CHIPS_PART_NAME" "RES"
					( Origin gPackager )
				)
				( attribute "CDS_PART_NAME" "RES_0402-0.0,5%,1/16W,CHIP,G21A"
					( Origin gPackager )
				)
				( objectStatus "R7E17" )
			)
			( gate "@baseboard_fab2_lib.baseboard_fab2(sch_1):page241_i39"
				( attribute "BOM_COST" "P5V_STBY_VR"
					( Origin gFrontEnd )
				)
				( attribute "CDS_LIB" "mstr_discrete"
					( Origin gPackager )
				)
				( attribute "CDS_LOCATION" "C7E11"
					( Origin gPackager )
				)
				( attribute "CDS_SEC" "1"
					( Origin gPackager )
				)
				( attribute "LOCATION" "C7E11"
					( Origin gFrontEnd )
				)
				( attribute "MATERIAL" "X6S"
					( Origin gFrontEnd )
				)
				( attribute "PACK_TYPE" "1206LF"
					( Origin gFrontEnd )
				)
				( attribute "PART_NUMBER" "D38464-005"
					( Origin gFrontEnd )
				)
				( attribute "PHYS_PAGE" "241"
					( Origin gFrontEnd )
				)
				( attribute "ROOM" "P5V_STBY_VR"
					( Origin gFrontEnd )
				)
				( attribute "ROT" "0"
					( Origin gFrontEnd )
				)
				( attribute "SEC" "1"
					( Origin gFrontEnd )
				)
				( attribute "SEC_TYPE" "1206LF"
					( Origin gFrontEnd )
				)
				( attribute "TOLERANCE" "10%"
					( Origin gFrontEnd )
				)
				( attribute "VALUE" "22UF"
					( Origin gFrontEnd )
				)
				( attribute "VER" "1"
					( Origin gFrontEnd )
				)
				( attribute "VOLTAGE" "16V"
					( Units "uVoltage" "V" 1.000000)
					( Origin gFrontEnd )
				)
				( attribute "XY" "(-1750,4275)"
					( Origin gFrontEnd )
				)
				( attribute "CHIPS_PART_NAME" "CAP"
					( Origin gPackager )
				)
				( attribute "CDS_PART_NAME" "CAP_1206LF-22UF,16V,10%,X6S,D3A"
					( Origin gPackager )
				)
				( objectStatus "C7E11" )
			)
			( gate "@baseboard_fab2_lib.baseboard_fab2(sch_1):page241_i41"
				( attribute "BOM_COST" "P5V_STBY_VR"
					( Origin gFrontEnd )
				)
				( attribute "CDS_LIB" "mstr_discrete"
					( Origin gPackager )
				)
				( attribute "CDS_LOCATION" "C8E13"
					( Origin gPackager )
				)
				( attribute "CDS_SEC" "1"
					( Origin gPackager )
				)
				( attribute "FIN" "VR_1P2"
					( Origin gFrontEnd )
				)
				( attribute "LOCATION" "C8E13"
					( Origin gFrontEnd )
				)
				( attribute "MATERIAL" "EMPTY"
					( Origin gFrontEnd )
				)
				( attribute "PACK_TYPE" "0402LF"
					( Origin gFrontEnd )
				)
				( attribute "PART_NUMBER" "A36096-046"
					( Origin gFrontEnd )
				)
				( attribute "PHYS_PAGE" "241"
					( Origin gFrontEnd )
				)
				( attribute "REUSE_ID" "1"
					( Origin gFrontEnd )
				)
				( attribute "ROOM" "P5V_STBY_VR"
					( Origin gFrontEnd )
				)
				( attribute "ROT" "2"
					( Origin gFrontEnd )
				)
				( attribute "SEC" "1"
					( Origin gFrontEnd )
				)
				( attribute "SEC_TYPE" "0402LF"
					( Origin gFrontEnd )
				)
				( attribute "TOLERANCE" "10%"
					( Origin gFrontEnd )
				)
				( attribute "VALUE" "1000PF"
					( Origin gFrontEnd )
				)
				( attribute "VER" "1"
					( Origin gFrontEnd )
				)
				( attribute "VOLTAGE" "50V"
					( Units "uVoltage" "V" 1.000000)
					( Origin gFrontEnd )
				)
				( attribute "XY" "(-2000,3075)"
					( Origin gFrontEnd )
				)
				( attribute "CHIPS_PART_NAME" "CAP"
					( Origin gPackager )
				)
				( attribute "CDS_PART_NAME" "CAP_0402LF-1000PF,50V,10%,EMPTA"
					( Origin gPackager )
				)
				( objectStatus "C8E13" )
			)
			( gate "@baseboard_fab2_lib.baseboard_fab2(sch_1):page240_i182"
				( attribute "CDS_LIB" "w_hdl"
					( Origin gPackager )
				)
				( attribute "CDS_LMAN_SYM_OUTLINE" "-50,25,50,-25"
					( Origin gPackager )
				)
				( attribute "LOCATION" "C22W11"
					( Origin gFrontEnd )
				)
				( attribute "PACK_TYPE" "SMD-BCG5"
					( Origin gFrontEnd )
				)
				( attribute "PART_NUMBER" "078.22611.0811"
					( Origin gFrontEnd )
				)
				( attribute "PHYS_PAGE" "240"
					( Origin gFrontEnd )
				)
				( attribute "ROT" "0"
					( Origin gFrontEnd )
				)
				( attribute "SEC" "1"
					( Origin gFrontEnd )
				)
				( attribute "SEC_TYPE" "SMD-BCG5"
					( Origin gFrontEnd )
				)
				( attribute "VALUE" "SC22U16V5MX-4-GP"
					( Origin gFrontEnd )
				)
				( attribute "VER" "1"
					( Origin gFrontEnd )
				)
				( attribute "XY" "(7000,4275)"
					( Origin gFrontEnd )
				)
				( attribute "CHIPS_PART_NAME" "SC22U16V5MX-4-GP"
					( Origin gPackager )
				)
				( attribute "CDS_PART_NAME" "SC22U16V5MX-4-GP_SMD-BCG5-SC22A"
					( Origin gPackager )
				)
				( attribute "CDS_LOCATION" "C22W11"
					( Origin gPackager )
				)
				( attribute "CDS_SEC" "1"
					( Origin gPackager )
				)
				( attribute "ATTRIBUTE" "22UF"
					( Origin gFrontEnd )
				)
				( attribute "PACK_SIZE" "0805"
					( Origin gFrontEnd )
				)
				( attribute "RATED" "16V"
					( Origin gFrontEnd )
				)
				( attribute "TOLERANCE" "20%"
					( Origin gFrontEnd )
				)
				( attribute "TYPE" "X6S"
					( Origin gFrontEnd )
				)
				( objectStatus "C22W11" )
			)
			( gate "@baseboard_fab2_lib.baseboard_fab2(sch_1):page241_i50"
				( attribute "BOM_COST" "P5V_STBY_VR"
					( Origin gFrontEnd )
				)
				( attribute "CDS_LIB" "mstr_discrete"
					( Origin gPackager )
				)
				( attribute "CDS_LOCATION" "R7F1"
					( Origin gPackager )
				)
				( attribute "CDS_SEC" "1"
					( Origin gPackager )
				)
				( attribute "LOCATION" "R7F1"
					( Origin gFrontEnd )
				)
				( attribute "MATERIAL" "CHIP"
					( Origin gFrontEnd )
				)
				( attribute "PACK_TYPE" "0402"
					( Origin gFrontEnd )
				)
				( attribute "PART_NUMBER" "G21796-016"
					( Origin gFrontEnd )
				)
				( attribute "PHYS_PAGE" "241"
					( Origin gFrontEnd )
				)
				( attribute "REUSE_ID" "9"
					( Origin gFrontEnd )
				)
				( attribute "ROOM" "P5V_STBY_VR"
					( Origin gFrontEnd )
				)
				( attribute "ROT" "0"
					( Origin gFrontEnd )
				)
				( attribute "SEC" "1"
					( Origin gFrontEnd )
				)
				( attribute "SEC_TYPE" "0402"
					( Origin gFrontEnd )
				)
				( attribute "SPOF" "TRUE"
					( Origin gFrontEnd )
				)
				( attribute "TOLERANCE" "1%"
					( Origin gFrontEnd )
				)
				( attribute "VALUE" "10.0K"
					( Origin gFrontEnd )
				)
				( attribute "VER" "2"
					( Origin gFrontEnd )
				)
				( attribute "WATTAGE" "1/16W"
					( Origin gFrontEnd )
				)
				( attribute "XY" "(1750,3425)"
					( Origin gFrontEnd )
				)
				( attribute "CHIPS_PART_NAME" "RES"
					( Origin gPackager )
				)
				( attribute "CDS_PART_NAME" "RES_0402-10.0K,1%,1/16W,CHIP,GA"
					( Origin gPackager )
				)
				( objectStatus "R7F1" )
			)
			( gate "@baseboard_fab2_lib.baseboard_fab2(sch_1):page241_i51"
				( attribute "BOM_COST" "P5V_STBY_VR"
					( Origin gFrontEnd )
				)
				( attribute "CDS_LIB" "mstr_discrete"
					( Origin gPackager )
				)
				( attribute "CDS_LOCATION" "R7E16"
					( Origin gPackager )
				)
				( attribute "CDS_SEC" "1"
					( Origin gPackager )
				)
				( attribute "LOCATION" "R7E16"
					( Origin gFrontEnd )
				)
				( attribute "MATERIAL" "CHIP"
					( Origin gFrontEnd )
				)
				( attribute "PACK_TYPE" "0402"
					( Origin gFrontEnd )
				)
				( attribute "PART_NUMBER" "G21796-095"
					( Origin gFrontEnd )
				)
				( attribute "PHYS_PAGE" "241"
					( Origin gFrontEnd )
				)
				( attribute "REUSE_ID" "7"
					( Origin gFrontEnd )
				)
				( attribute "ROOM" "P5V_STBY_VR"
					( Origin gFrontEnd )
				)
				( attribute "ROT" "0"
					( Origin gFrontEnd )
				)
				( attribute "SEC" "1"
					( Origin gFrontEnd )
				)
				( attribute "SEC_TYPE" "0402"
					( Origin gFrontEnd )
				)
				( attribute "SPOF" "TRUE"
					( Origin gFrontEnd )
				)
				( attribute "TOLERANCE" "1%"
					( Origin gFrontEnd )
				)
				( attribute "VALUE" "1.37K"
					( Origin gFrontEnd )
				)
				( attribute "VER" "2"
					( Origin gFrontEnd )
				)
				( attribute "WATTAGE" "1/16W"
					( Origin gFrontEnd )
				)
				( attribute "XY" "(1750,2900)"
					( Origin gFrontEnd )
				)
				( attribute "CHIPS_PART_NAME" "RES"
					( Origin gPackager )
				)
				( attribute "CDS_PART_NAME" "RES_0402-1.37K,1%,1/16W,CHIP,GA"
					( Origin gPackager )
				)
				( objectStatus "R7E16" )
			)
			( gate "@baseboard_fab2_lib.baseboard_fab2(sch_1):page241_i53"
				( attribute "BOM_COST" "P5V_STBY_VR"
					( Origin gFrontEnd )
				)
				( attribute "CDS_LIB" "mstr_discrete"
					( Origin gPackager )
				)
				( attribute "CDS_LOCATION" "C8E16"
					( Origin gPackager )
				)
				( attribute "CDS_SEC" "1"
					( Origin gPackager )
				)
				( attribute "LOCATION" "C8E16"
					( Origin gFrontEnd )
				)
				( attribute "MATERIAL" "X7R"
					( Origin gFrontEnd )
				)
				( attribute "PACK_TYPE" "0402LF"
					( Origin gFrontEnd )
				)
				( attribute "PART_NUMBER" "A36096-065"
					( Origin gFrontEnd )
				)
				( attribute "PHYS_PAGE" "241"
					( Origin gFrontEnd )
				)
				( attribute "REUSE_ID" "4"
					( Origin gFrontEnd )
				)
				( attribute "ROOM" "P5V_STBY_VR"
					( Origin gFrontEnd )
				)
				( attribute "ROT" "0"
					( Origin gFrontEnd )
				)
				( attribute "SEC" "1"
					( Origin gFrontEnd )
				)
				( attribute "SEC_TYPE" "0402LF"
					( Origin gFrontEnd )
				)
				( attribute "TOLERANCE" "10%"
					( Origin gFrontEnd )
				)
				( attribute "VALUE" "270PF"
					( Origin gFrontEnd )
				)
				( attribute "VER" "2"
					( Origin gFrontEnd )
				)
				( attribute "VOLTAGE" "50V"
					( Units "uVoltage" "V" 1.000000)
					( Origin gFrontEnd )
				)
				( attribute "XY" "(200,2575)"
					( Origin gFrontEnd )
				)
				( attribute "CHIPS_PART_NAME" "CAP"
					( Origin gPackager )
				)
				( attribute "CDS_PART_NAME" "CAP_0402LF-270PF,50V,10%,X7R,AA"
					( Origin gPackager )
				)
				( objectStatus "C8E16" )
			)
			( gate "@baseboard_fab2_lib.baseboard_fab2(sch_1):page241_i54"
				( attribute "BOM_COST" "P5V_STBY_VR"
					( Origin gFrontEnd )
				)
				( attribute "CDS_LIB" "mstr_discrete"
					( Origin gPackager )
				)
				( attribute "CDS_LOCATION" "R8E39"
					( Origin gPackager )
				)
				( attribute "CDS_SEC" "1"
					( Origin gPackager )
				)
				( attribute "LOCATION" "R8E39"
					( Origin gFrontEnd )
				)
				( attribute "MATERIAL" "CHIP"
					( Origin gFrontEnd )
				)
				( attribute "PACK_TYPE" "0402"
					( Origin gFrontEnd )
				)
				( attribute "PART_NUMBER" "G21796-254"
					( Origin gFrontEnd )
				)
				( attribute "PHYS_PAGE" "241"
					( Origin gFrontEnd )
				)
				( attribute "REUSE_ID" "10"
					( Origin gFrontEnd )
				)
				( attribute "ROOM" "P5V_STBY_VR"
					( Origin gFrontEnd )
				)
				( attribute "ROT" "0"
					( Origin gFrontEnd )
				)
				( attribute "SEC" "1"
					( Origin gFrontEnd )
				)
				( attribute "SEC_TYPE" "0402"
					( Origin gFrontEnd )
				)
				( attribute "TOLERANCE" "1%"
					( Origin gFrontEnd )
				)
				( attribute "VALUE" "24.9K"
					( Origin gFrontEnd )
				)
				( attribute "VER" "1"
					( Origin gFrontEnd )
				)
				( attribute "WATTAGE" "1/16W"
					( Origin gFrontEnd )
				)
				( attribute "XY" "(-200,2200)"
					( Origin gFrontEnd )
				)
				( attribute "CHIPS_PART_NAME" "RES"
					( Origin gPackager )
				)
				( attribute "CDS_PART_NAME" "RES_0402-24.9K,1%,1/16W,CHIP,GA"
					( Origin gPackager )
				)
				( objectStatus "R8E39" )
			)
			( gate "@baseboard_fab2_lib.baseboard_fab2(sch_1):page241_i57"
				( attribute "BOM_COST" "P5V_STBY_VR"
					( Origin gFrontEnd )
				)
				( attribute "CDS_LIB" "mstr_discrete"
					( Origin gPackager )
				)
				( attribute "CDS_LOCATION" "C8F1"
					( Origin gPackager )
				)
				( attribute "CDS_SEC" "1"
					( Origin gPackager )
				)
				( attribute "LOCATION" "C8F1"
					( Origin gFrontEnd )
				)
				( attribute "MATERIAL" "X7R"
					( Origin gFrontEnd )
				)
				( attribute "PACK_TYPE" "0402LF"
					( Origin gFrontEnd )
				)
				( attribute "PART_NUMBER" "A36096-075"
					( Origin gFrontEnd )
				)
				( attribute "PHYS_PAGE" "241"
					( Origin gFrontEnd )
				)
				( attribute "REUSE_ID" "5"
					( Origin gFrontEnd )
				)
				( attribute "ROOM" "P5V_STBY_VR"
					( Origin gFrontEnd )
				)
				( attribute "ROT" "0"
					( Origin gFrontEnd )
				)
				( attribute "SEC" "1"
					( Origin gFrontEnd )
				)
				( attribute "SEC_TYPE" "0402LF"
					( Origin gFrontEnd )
				)
				( attribute "TOLERANCE" "10%"
					( Origin gFrontEnd )
				)
				( attribute "VALUE" "2200PF"
					( Origin gFrontEnd )
				)
				( attribute "VER" "2"
					( Origin gFrontEnd )
				)
				( attribute "VOLTAGE" "50V"
					( Units "uVoltage" "V" 1.000000)
					( Origin gFrontEnd )
				)
				( attribute "XY" "(575,2200)"
					( Origin gFrontEnd )
				)
				( attribute "CHIPS_PART_NAME" "CAP"
					( Origin gPackager )
				)
				( attribute "CDS_PART_NAME" "CAP_0402LF-2200PF,50V,10%,X7R,A"
					( Origin gPackager )
				)
				( objectStatus "C8F1" )
			)
			( gate "@baseboard_fab2_lib.baseboard_fab2(sch_1):page241_i58"
				( attribute "BOM_COST" "P5V_STBY_VR"
					( Origin gFrontEnd )
				)
				( attribute "CDS_LIB" "mstr_discrete"
					( Origin gPackager )
				)
				( attribute "CDS_LOCATION" "R7E13"
					( Origin gPackager )
				)
				( attribute "CDS_SEC" "1"
					( Origin gPackager )
				)
				( attribute "LOCATION" "R7E13"
					( Origin gFrontEnd )
				)
				( attribute "MATERIAL" "CHIP"
					( Origin gFrontEnd )
				)
				( attribute "PACK_TYPE" "0402"
					( Origin gFrontEnd )
				)
				( attribute "PART_NUMBER" "G21497-005"
					( Origin gFrontEnd )
				)
				( attribute "PHYS_PAGE" "241"
					( Origin gFrontEnd )
				)
				( attribute "REUSE_ID" "13"
					( Origin gPackager )
				)
				( attribute "ROOM" "P5V_STBY_VR"
					( Origin gFrontEnd )
				)
				( attribute "ROT" "0"
					( Origin gFrontEnd )
				)
				( attribute "SEC" "1"
					( Origin gFrontEnd )
				)
				( attribute "SEC_TYPE" "0402"
					( Origin gFrontEnd )
				)
				( attribute "SPOF" "TRUE"
					( Origin gFrontEnd )
				)
				( attribute "TOLERANCE" "5%"
					( Origin gFrontEnd )
				)
				( attribute "VALUE" "0.0"
					( Origin gFrontEnd )
				)
				( attribute "VER" "1"
					( Origin gFrontEnd )
				)
				( attribute "WATTAGE" "1/16W"
					( Origin gFrontEnd )
				)
				( attribute "XY" "(1575,1550)"
					( Origin gFrontEnd )
				)
				( attribute "CHIPS_PART_NAME" "RES"
					( Origin gPackager )
				)
				( attribute "CDS_PART_NAME" "RES_0402-0.0,5%,1/16W,CHIP,G21A"
					( Origin gPackager )
				)
				( objectStatus "R7E13" )
			)
			( gate "@baseboard_fab2_lib.baseboard_fab2(sch_1):page241_i63"
				( attribute "BOM_COST" "P5V_STBY_VR"
					( Origin gFrontEnd )
				)
				( attribute "CDS_LIB" "mstr_discrete"
					( Origin gPackager )
				)
				( attribute "CDS_LOCATION" "C8E15"
					( Origin gPackager )
				)
				( attribute "CDS_SEC" "1"
					( Origin gPackager )
				)
				( attribute "LOCATION" "C8E15"
					( Origin gFrontEnd )
				)
				( attribute "MATERIAL" "X7R"
					( Origin gFrontEnd )
				)
				( attribute "PACK_TYPE" "0402LF"
					( Origin gFrontEnd )
				)
				( attribute "PART_NUMBER" "A36096-073"
					( Origin gFrontEnd )
				)
				( attribute "PHYS_PAGE" "241"
					( Origin gFrontEnd )
				)
				( attribute "REUSE_ID" "16"
					( Origin gFrontEnd )
				)
				( attribute "ROOM" "P5V_STBY_VR"
					( Origin gFrontEnd )
				)
				( attribute "ROT" "2"
					( Origin gFrontEnd )
				)
				( attribute "SEC" "1"
					( Origin gFrontEnd )
				)
				( attribute "SEC_TYPE" "0402LF"
					( Origin gFrontEnd )
				)
				( attribute "TOLERANCE" "10%"
					( Origin gFrontEnd )
				)
				( attribute "VALUE" "0.022UF"
					( Origin gFrontEnd )
				)
				( attribute "VER" "1"
					( Origin gFrontEnd )
				)
				( attribute "VOLTAGE" "16V"
					( Units "uVoltage" "V" 1.000000)
					( Origin gFrontEnd )
				)
				( attribute "XY" "(-1025,3000)"
					( Origin gFrontEnd )
				)
				( attribute "CHIPS_PART_NAME" "CAP"
					( Origin gPackager )
				)
				( attribute "CDS_PART_NAME" "CAP_0402LF-0.022UF,16V,10%,X7RA"
					( Origin gPackager )
				)
				( objectStatus "C8E15" )
			)
			( gate "@baseboard_fab2_lib.baseboard_fab2(sch_1):page241_i78"
				( attribute "BOM_COST" "P5V_STBY_VR"
					( Origin gFrontEnd )
				)
				( attribute "CDS_LIB" "mstr_discrete"
					( Origin gPackager )
				)
				( attribute "CDS_LOCATION" "R8E37"
					( Origin gPackager )
				)
				( attribute "CDS_SEC" "1"
					( Origin gPackager )
				)
				( attribute "LOCATION" "R8E37"
					( Origin gFrontEnd )
				)
				( attribute "MATERIAL" "CHIP"
					( Origin gFrontEnd )
				)
				( attribute "PACK_TYPE" "0402"
					( Origin gFrontEnd )
				)
				( attribute "PART_NUMBER" "G21497-005"
					( Origin gFrontEnd )
				)
				( attribute "PHYS_PAGE" "241"
					( Origin gFrontEnd )
				)
				( attribute "ROOM" "P5V_STBY_VR"
					( Origin gFrontEnd )
				)
				( attribute "ROT" "0"
					( Origin gFrontEnd )
				)
				( attribute "SEC" "1"
					( Origin gFrontEnd )
				)
				( attribute "SEC_TYPE" "0402"
					( Origin gFrontEnd )
				)
				( attribute "SPOF" "TRUE"
					( Origin gFrontEnd )
				)
				( attribute "TOLERANCE" "5%"
					( Origin gFrontEnd )
				)
				( attribute "VALUE" "0.0"
					( Origin gFrontEnd )
				)
				( attribute "VER" "1"
					( Origin gFrontEnd )
				)
				( attribute "WATTAGE" "1/16W"
					( Origin gFrontEnd )
				)
				( attribute "XY" "(2075,3650)"
					( Origin gFrontEnd )
				)
				( attribute "CHIPS_PART_NAME" "RES"
					( Origin gPackager )
				)
				( attribute "CDS_PART_NAME" "RES_0402-0.0,5%,1/16W,CHIP,G21A"
					( Origin gPackager )
				)
				( objectStatus "R8E37" )
			)
			( gate "@baseboard_fab2_lib.baseboard_fab2(sch_1):page241_i82"
				( attribute "BOM_COST" "P5V_STBY_VR"
					( Origin gFrontEnd )
				)
				( attribute "CDS_LIB" "mstr_discrete"
					( Origin gPackager )
				)
				( attribute "CDS_LOCATION" "FB7E1"
					( Origin gPackager )
				)
				( attribute "LOCATION" "FB7E1"
					( Origin gFrontEnd )
				)
				( attribute "MATERIAL" "FB"
					( Origin gFrontEnd )
				)
				( attribute "PACK_TYPE" "SM"
					( Origin gFrontEnd )
				)
				( attribute "PART_NUMBER" "656554-051"
					( Origin gFrontEnd )
				)
				( attribute "PHYS_PAGE" "241"
					( Origin gFrontEnd )
				)
				( attribute "ROOM" "P5V_STBY_VR"
					( Origin gFrontEnd )
				)
				( attribute "ROT" "0"
					( Origin gFrontEnd )
				)
				( attribute "SEC" "1"
					( Origin gFrontEnd )
				)
				( attribute "VALUE" "22"
					( Origin gFrontEnd )
				)
				( attribute "VER" "1"
					( Origin gFrontEnd )
				)
				( attribute "XY" "(-3300,4675)"
					( Origin gFrontEnd )
				)
				( attribute "CHIPS_PART_NAME" "FERRITE"
					( Origin gPackager )
				)
				( attribute "CDS_PART_NAME" "FERRITE_SM-22,FB,656554-051"
					( Origin gPackager )
				)
				( attribute "SEC_TYPE" "SM"
					( Origin gFrontEnd )
				)
				( attribute "CDS_SEC" "1"
					( Origin gPackager )
				)
				( objectStatus "FB7E1" )
			)
			( gate "@baseboard_fab2_lib.baseboard_fab2(sch_1):page241_i83"
				( attribute "BOM_COST" "P5V_STBY_VR"
					( Origin gFrontEnd )
				)
				( attribute "CDS_LIB" "mstr_vreg"
					( Origin gPackager )
				)
				( attribute "CDS_LOCATION" "EU7E2"
					( Origin gPackager )
				)
				( attribute "CDS_SEC" "1"
					( Origin gPackager )
				)
				( attribute "LOCATION" "EU7E2"
					( Origin gFrontEnd )
				)
				( attribute "MATERIAL" "IC"
					( Origin gFrontEnd )
				)
				( attribute "PACK_TYPE" "LCC"
					( Origin gFrontEnd )
				)
				( attribute "PART_NUMBER" "H63269-001"
					( Origin gFrontEnd )
				)
				( attribute "PHYS_PAGE" "241"
					( Origin gFrontEnd )
				)
				( attribute "ROOM" "P5V_STBY_VR"
					( Origin gFrontEnd )
				)
				( attribute "ROT" "0"
					( Origin gFrontEnd )
				)
				( attribute "SEC" "1"
					( Origin gFrontEnd )
				)
				( attribute "SEC_TYPE" "LCC"
					( Origin gFrontEnd )
				)
				( attribute "VER" "1"
					( Origin gFrontEnd )
				)
				( attribute "XY" "(125,3575)"
					( Origin gFrontEnd )
				)
				( attribute "CHIPS_PART_NAME" "TPS54821"
					( Origin gPackager )
				)
				( attribute "CDS_PART_NAME" "TPS54821_LCC-IC,H63269-001"
					( Origin gPackager )
				)
				( objectStatus "EU7E2" )
			)
			( gate "@baseboard_fab2_lib.baseboard_fab2(sch_1):page241_i89"
				( attribute "CDS_LIB" "mstr_discrete"
					( Origin gPackager )
				)
				( attribute "CDS_LOCATION" "R7E15"
					( Origin gPackager )
				)
				( attribute "CDS_SEC" "1"
					( Origin gPackager )
				)
				( attribute "LOCATION" "R7E15"
					( Origin gFrontEnd )
				)
				( attribute "MATERIAL" "CHIP"
					( Origin gFrontEnd )
				)
				( attribute "PACK_TYPE" "0402"
					( Origin gFrontEnd )
				)
				( attribute "PART_NUMBER" "G21796-250"
					( Origin gFrontEnd )
				)
				( attribute "PHYS_PAGE" "241"
					( Origin gFrontEnd )
				)
				( attribute "ROOM" "P5V_STBY_VR"
					( Origin gFrontEnd )
				)
				( attribute "ROT" "0"
					( Origin gFrontEnd )
				)
				( attribute "SEC" "1"
					( Origin gFrontEnd )
				)
				( attribute "SEC_TYPE" "0402"
					( Origin gFrontEnd )
				)
				( attribute "TOLERANCE" "1.0%"
					( Origin gFrontEnd )
				)
				( attribute "VALUE" "22.1"
					( Origin gFrontEnd )
				)
				( attribute "VER" "1"
					( Origin gFrontEnd )
				)
				( attribute "WATTAGE" "1/16W"
					( Origin gFrontEnd )
				)
				( attribute "XY" "(2250,4625)"
					( Origin gFrontEnd )
				)
				( attribute "CHIPS_PART_NAME" "RES"
					( Origin gPackager )
				)
				( attribute "CDS_PART_NAME" "RES_0402-22.1,1.0%,1/16W,CHIP,A"
					( Origin gPackager )
				)
				( objectStatus "R7E15" )
			)
			( gate "@baseboard_fab2_lib.baseboard_fab2(sch_1):page241_i90"
				( attribute "CDS_LIB" "mstr_discrete"
					( Origin gPackager )
				)
				( attribute "CDS_LOCATION" "L8E1"
					( Origin gPackager )
				)
				( attribute "CDS_SEC" "1"
					( Origin gPackager )
				)
				( attribute "LOCATION" "L8E1"
					( Origin gFrontEnd )
				)
				( attribute "MATERIAL" "IND"
					( Origin gFrontEnd )
				)
				( attribute "PACK_TYPE" "SM"
					( Origin gFrontEnd )
				)
				( attribute "PART_NUMBER" "E98761-003"
					( Origin gFrontEnd )
				)
				( attribute "PHYS_PAGE" "241"
					( Origin gFrontEnd )
				)
				( attribute "ROT" "0"
					( Origin gFrontEnd )
				)
				( attribute "SEC" "1"
					( Origin gPackager )
				)
				( attribute "VALUE" "2.2UH"
					( Origin gFrontEnd )
				)
				( attribute "VER" "1"
					( Origin gFrontEnd )
				)
				( attribute "XY" "(2150,4050)"
					( Origin gFrontEnd )
				)
				( attribute "CHIPS_PART_NAME" "INDUCTOR"
					( Origin gPackager )
				)
				( attribute "CDS_PART_NAME" "INDUCTOR_SM-2.2UH,IND,E98761-0A"
					( Origin gPackager )
				)
				( objectStatus "L8E1" )
			)
			( gate "@baseboard_fab2_lib.baseboard_fab2(sch_1):page241_i91"
				( attribute "CDS_LIB" "mstr_discrete"
					( Origin gPackager )
				)
				( attribute "CDS_LOCATION" "R8E33"
					( Origin gPackager )
				)
				( attribute "CDS_SEC" "1"
					( Origin gPackager )
				)
				( attribute "LOCATION" "R8E33"
					( Origin gFrontEnd )
				)
				( attribute "MATERIAL" "CHIP"
					( Origin gFrontEnd )
				)
				( attribute "PACK_TYPE" "0402"
					( Origin gFrontEnd )
				)
				( attribute "PART_NUMBER" "G21497-005"
					( Origin gFrontEnd )
				)
				( attribute "PHYS_PAGE" "241"
					( Origin gFrontEnd )
				)
				( attribute "ROOM" "PVCCIN_CPU0_VR"
					( Origin gFrontEnd )
				)
				( attribute "ROT" "0"
					( Origin gFrontEnd )
				)
				( attribute "SEC" "1"
					( Origin gFrontEnd )
				)
				( attribute "SEC_TYPE" "0402"
					( Origin gFrontEnd )
				)
				( attribute "TOLERANCE" "5%"
					( Origin gFrontEnd )
				)
				( attribute "VALUE" "0.0"
					( Origin gFrontEnd )
				)
				( attribute "VER" "1"
					( Origin gFrontEnd )
				)
				( attribute "WATTAGE" "1/16W"
					( Origin gFrontEnd )
				)
				( attribute "XY" "(-1625,3475)"
					( Origin gFrontEnd )
				)
				( attribute "CHIPS_PART_NAME" "RES"
					( Origin gPackager )
				)
				( attribute "CDS_PART_NAME" "RES_0402-0.0,5%,1/16W,CHIP,G21A"
					( Origin gPackager )
				)
				( objectStatus "R8E33" )
			)
			( gate "@baseboard_fab2_lib.baseboard_fab2(sch_1):page243_i88"
				( attribute "CDS_LIB" "dev_discrete"
					( Origin gPackager )
				)
				( attribute "LOCATION" "C5G106"
					( Origin gFrontEnd )
				)
				( attribute "MATERIAL" "X6S"
					( Origin gFrontEnd )
				)
				( attribute "PACK_TYPE" "0603V"
					( Origin gFrontEnd )
				)
				( attribute "PART_NUMBER" "E15431-004"
					( Origin gFrontEnd )
				)
				( attribute "PHYS_PAGE" "243"
					( Origin gFrontEnd )
				)
				( attribute "ROOM" "PVDDQ_KLM"
					( Origin gFrontEnd )
				)
				( attribute "ROT" "0"
					( Origin gFrontEnd )
				)
				( attribute "TOLERANCE" "20%"
					( Origin gFrontEnd )
				)
				( attribute "VALUE" "22.0UF"
					( Origin gFrontEnd )
				)
				( attribute "VER" "1"
					( Origin gFrontEnd )
				)
				( attribute "VOLTAGE" "4V"
					( Units "uVoltage" "V" 1.000000)
					( Origin gFrontEnd )
				)
				( attribute "XY" "(-3800,1850)"
					( Origin gFrontEnd )
				)
				( attribute "CHIPS_PART_NAME" "CAP_A"
					( Origin gPackager )
				)
				( attribute "CDS_PART_NAME" "CAP_A_0603V-22.0UF,4V,20%,X6S,A"
					( Origin gPackager )
				)
				( attribute "CDS_LOCATION" "C5G106"
					( Origin gPackager )
				)
				( attribute "SEC" "1"
					( Origin gFrontEnd )
				)
				( attribute "SEC_TYPE" "0603V"
					( Origin gFrontEnd )
				)
				( attribute "CDS_SEC" "1"
					( Origin gPackager )
				)
				( attribute "GROUP" "PWR_MLCC_CAP"
					( Origin gFrontEnd )
				)
				( attribute "BOM_DS" "NOPOP"
					( Origin gFrontEnd )
				)
				( objectStatus "C5G106" )
			)
			( gate "@baseboard_fab2_lib.baseboard_fab2(sch_1):page243_i87"
				( attribute "CDS_LIB" "dev_discrete"
					( Origin gPackager )
				)
				( attribute "LOCATION" "C5G107"
					( Origin gFrontEnd )
				)
				( attribute "MATERIAL" "X6S"
					( Origin gFrontEnd )
				)
				( attribute "PACK_TYPE" "0603V"
					( Origin gFrontEnd )
				)
				( attribute "PART_NUMBER" "E15431-004"
					( Origin gFrontEnd )
				)
				( attribute "PHYS_PAGE" "243"
					( Origin gFrontEnd )
				)
				( attribute "ROOM" "PVDDQ_KLM"
					( Origin gFrontEnd )
				)
				( attribute "ROT" "0"
					( Origin gFrontEnd )
				)
				( attribute "TOLERANCE" "20%"
					( Origin gFrontEnd )
				)
				( attribute "VALUE" "22.0UF"
					( Origin gFrontEnd )
				)
				( attribute "VER" "1"
					( Origin gFrontEnd )
				)
				( attribute "VOLTAGE" "4V"
					( Units "uVoltage" "V" 1.000000)
					( Origin gFrontEnd )
				)
				( attribute "XY" "(-3400,1850)"
					( Origin gFrontEnd )
				)
				( attribute "CHIPS_PART_NAME" "CAP_A"
					( Origin gPackager )
				)
				( attribute "CDS_PART_NAME" "CAP_A_0603V-22.0UF,4V,20%,X6S,A"
					( Origin gPackager )
				)
				( attribute "CDS_LOCATION" "C5G107"
					( Origin gPackager )
				)
				( attribute "SEC" "1"
					( Origin gFrontEnd )
				)
				( attribute "SEC_TYPE" "0603V"
					( Origin gFrontEnd )
				)
				( attribute "CDS_SEC" "1"
					( Origin gPackager )
				)
				( attribute "GROUP" "PWR_MLCC_CAP"
					( Origin gFrontEnd )
				)
				( attribute "BOM_DS" "NOPOP"
					( Origin gFrontEnd )
				)
				( objectStatus "C5G107" )
			)
			( gate "@baseboard_fab2_lib.baseboard_fab2(sch_1):page243_i86"
				( attribute "CDS_LIB" "dev_discrete"
					( Origin gPackager )
				)
				( attribute "LOCATION" "C5G108"
					( Origin gFrontEnd )
				)
				( attribute "MATERIAL" "X6S"
					( Origin gFrontEnd )
				)
				( attribute "PACK_TYPE" "0603V"
					( Origin gFrontEnd )
				)
				( attribute "PART_NUMBER" "E15431-004"
					( Origin gFrontEnd )
				)
				( attribute "PHYS_PAGE" "243"
					( Origin gFrontEnd )
				)
				( attribute "ROOM" "PVDDQ_KLM"
					( Origin gFrontEnd )
				)
				( attribute "ROT" "0"
					( Origin gFrontEnd )
				)
				( attribute "TOLERANCE" "20%"
					( Origin gFrontEnd )
				)
				( attribute "VALUE" "22.0UF"
					( Origin gFrontEnd )
				)
				( attribute "VER" "1"
					( Origin gFrontEnd )
				)
				( attribute "VOLTAGE" "4V"
					( Units "uVoltage" "V" 1.000000)
					( Origin gFrontEnd )
				)
				( attribute "XY" "(-3000,1850)"
					( Origin gFrontEnd )
				)
				( attribute "CHIPS_PART_NAME" "CAP_A"
					( Origin gPackager )
				)
				( attribute "CDS_PART_NAME" "CAP_A_0603V-22.0UF,4V,20%,X6S,A"
					( Origin gPackager )
				)
				( attribute "CDS_LOCATION" "C5G108"
					( Origin gPackager )
				)
				( attribute "SEC" "1"
					( Origin gFrontEnd )
				)
				( attribute "SEC_TYPE" "0603V"
					( Origin gFrontEnd )
				)
				( attribute "CDS_SEC" "1"
					( Origin gPackager )
				)
				( attribute "GROUP" "PWR_MLCC_CAP"
					( Origin gFrontEnd )
				)
				( attribute "BOM_DS" "NOPOP"
					( Origin gFrontEnd )
				)
				( objectStatus "C5G108" )
			)
			( gate "@baseboard_fab2_lib.baseboard_fab2(sch_1):page243_i85"
				( attribute "CDS_LIB" "dev_discrete"
					( Origin gPackager )
				)
				( attribute "LOCATION" "C5G109"
					( Origin gFrontEnd )
				)
				( attribute "MATERIAL" "X6S"
					( Origin gFrontEnd )
				)
				( attribute "PACK_TYPE" "0603V"
					( Origin gFrontEnd )
				)
				( attribute "PART_NUMBER" "E15431-004"
					( Origin gFrontEnd )
				)
				( attribute "PHYS_PAGE" "243"
					( Origin gFrontEnd )
				)
				( attribute "ROOM" "PVDDQ_KLM"
					( Origin gFrontEnd )
				)
				( attribute "ROT" "0"
					( Origin gFrontEnd )
				)
				( attribute "TOLERANCE" "20%"
					( Origin gFrontEnd )
				)
				( attribute "VALUE" "22.0UF"
					( Origin gFrontEnd )
				)
				( attribute "VER" "1"
					( Origin gFrontEnd )
				)
				( attribute "VOLTAGE" "4V"
					( Units "uVoltage" "V" 1.000000)
					( Origin gFrontEnd )
				)
				( attribute "XY" "(-2600,1850)"
					( Origin gFrontEnd )
				)
				( attribute "CHIPS_PART_NAME" "CAP_A"
					( Origin gPackager )
				)
				( attribute "CDS_PART_NAME" "CAP_A_0603V-22.0UF,4V,20%,X6S,A"
					( Origin gPackager )
				)
				( attribute "CDS_LOCATION" "C5G109"
					( Origin gPackager )
				)
				( attribute "SEC" "1"
					( Origin gFrontEnd )
				)
				( attribute "SEC_TYPE" "0603V"
					( Origin gFrontEnd )
				)
				( attribute "CDS_SEC" "1"
					( Origin gPackager )
				)
				( attribute "GROUP" "PWR_MLCC_CAP"
					( Origin gFrontEnd )
				)
				( attribute "BOM_DS" "NOPOP"
					( Origin gFrontEnd )
				)
				( objectStatus "C5G109" )
			)
			( gate "@baseboard_fab2_lib.baseboard_fab2(sch_1):page243_i84"
				( attribute "CDS_LIB" "dev_discrete"
					( Origin gPackager )
				)
				( attribute "LOCATION" "C5G110"
					( Origin gFrontEnd )
				)
				( attribute "MATERIAL" "X6S"
					( Origin gFrontEnd )
				)
				( attribute "PACK_TYPE" "0603V"
					( Origin gFrontEnd )
				)
				( attribute "PART_NUMBER" "E15431-004"
					( Origin gFrontEnd )
				)
				( attribute "PHYS_PAGE" "243"
					( Origin gFrontEnd )
				)
				( attribute "ROOM" "PVDDQ_KLM"
					( Origin gFrontEnd )
				)
				( attribute "ROT" "0"
					( Origin gFrontEnd )
				)
				( attribute "TOLERANCE" "20%"
					( Origin gFrontEnd )
				)
				( attribute "VALUE" "22.0UF"
					( Origin gFrontEnd )
				)
				( attribute "VER" "1"
					( Origin gFrontEnd )
				)
				( attribute "VOLTAGE" "4V"
					( Units "uVoltage" "V" 1.000000)
					( Origin gFrontEnd )
				)
				( attribute "XY" "(-2200,1850)"
					( Origin gFrontEnd )
				)
				( attribute "CHIPS_PART_NAME" "CAP_A"
					( Origin gPackager )
				)
				( attribute "CDS_PART_NAME" "CAP_A_0603V-22.0UF,4V,20%,X6S,A"
					( Origin gPackager )
				)
				( attribute "CDS_LOCATION" "C5G110"
					( Origin gPackager )
				)
				( attribute "SEC" "1"
					( Origin gFrontEnd )
				)
				( attribute "SEC_TYPE" "0603V"
					( Origin gFrontEnd )
				)
				( attribute "CDS_SEC" "1"
					( Origin gPackager )
				)
				( attribute "GROUP" "PWR_MLCC_CAP"
					( Origin gFrontEnd )
				)
				( attribute "BOM_DS" "NOPOP"
					( Origin gFrontEnd )
				)
				( objectStatus "C5G110" )
			)
			( gate "@baseboard_fab2_lib.baseboard_fab2(sch_1):page243_i83"
				( attribute "CDS_LIB" "dev_discrete"
					( Origin gPackager )
				)
				( attribute "LOCATION" "C5G111"
					( Origin gFrontEnd )
				)
				( attribute "MATERIAL" "X6S"
					( Origin gFrontEnd )
				)
				( attribute "PACK_TYPE" "0603V"
					( Origin gFrontEnd )
				)
				( attribute "PART_NUMBER" "E15431-004"
					( Origin gFrontEnd )
				)
				( attribute "PHYS_PAGE" "243"
					( Origin gFrontEnd )
				)
				( attribute "ROOM" "PVDDQ_KLM"
					( Origin gFrontEnd )
				)
				( attribute "ROT" "0"
					( Origin gFrontEnd )
				)
				( attribute "TOLERANCE" "20%"
					( Origin gFrontEnd )
				)
				( attribute "VALUE" "22.0UF"
					( Origin gFrontEnd )
				)
				( attribute "VER" "1"
					( Origin gFrontEnd )
				)
				( attribute "VOLTAGE" "4V"
					( Units "uVoltage" "V" 1.000000)
					( Origin gFrontEnd )
				)
				( attribute "XY" "(-1800,1850)"
					( Origin gFrontEnd )
				)
				( attribute "CHIPS_PART_NAME" "CAP_A"
					( Origin gPackager )
				)
				( attribute "CDS_PART_NAME" "CAP_A_0603V-22.0UF,4V,20%,X6S,A"
					( Origin gPackager )
				)
				( attribute "CDS_LOCATION" "C5G111"
					( Origin gPackager )
				)
				( attribute "SEC" "1"
					( Origin gFrontEnd )
				)
				( attribute "SEC_TYPE" "0603V"
					( Origin gFrontEnd )
				)
				( attribute "CDS_SEC" "1"
					( Origin gPackager )
				)
				( attribute "GROUP" "PWR_MLCC_CAP"
					( Origin gFrontEnd )
				)
				( attribute "BOM_DS" "NOPOP"
					( Origin gFrontEnd )
				)
				( objectStatus "C5G111" )
			)
			( gate "@baseboard_fab2_lib.baseboard_fab2(sch_1):page243_i82"
				( attribute "CDS_LIB" "dev_discrete"
					( Origin gPackager )
				)
				( attribute "LOCATION" "C5G112"
					( Origin gFrontEnd )
				)
				( attribute "MATERIAL" "X6S"
					( Origin gFrontEnd )
				)
				( attribute "PACK_TYPE" "0603V"
					( Origin gFrontEnd )
				)
				( attribute "PART_NUMBER" "E15431-004"
					( Origin gFrontEnd )
				)
				( attribute "PHYS_PAGE" "243"
					( Origin gFrontEnd )
				)
				( attribute "ROOM" "PVDDQ_KLM"
					( Origin gFrontEnd )
				)
				( attribute "ROT" "0"
					( Origin gFrontEnd )
				)
				( attribute "TOLERANCE" "20%"
					( Origin gFrontEnd )
				)
				( attribute "VALUE" "22.0UF"
					( Origin gFrontEnd )
				)
				( attribute "VER" "1"
					( Origin gFrontEnd )
				)
				( attribute "VOLTAGE" "4V"
					( Units "uVoltage" "V" 1.000000)
					( Origin gFrontEnd )
				)
				( attribute "XY" "(-1400,1850)"
					( Origin gFrontEnd )
				)
				( attribute "CHIPS_PART_NAME" "CAP_A"
					( Origin gPackager )
				)
				( attribute "CDS_PART_NAME" "CAP_A_0603V-22.0UF,4V,20%,X6S,A"
					( Origin gPackager )
				)
				( attribute "CDS_LOCATION" "C5G112"
					( Origin gPackager )
				)
				( attribute "SEC" "1"
					( Origin gFrontEnd )
				)
				( attribute "SEC_TYPE" "0603V"
					( Origin gFrontEnd )
				)
				( attribute "CDS_SEC" "1"
					( Origin gPackager )
				)
				( attribute "GROUP" "PWR_MLCC_CAP"
					( Origin gFrontEnd )
				)
				( attribute "BOM_DS" "NOPOP"
					( Origin gFrontEnd )
				)
				( objectStatus "C5G112" )
			)
			( gate "@baseboard_fab2_lib.baseboard_fab2(sch_1):page243_i81"
				( attribute "CDS_LIB" "dev_discrete"
					( Origin gPackager )
				)
				( attribute "LOCATION" "C5G113"
					( Origin gFrontEnd )
				)
				( attribute "MATERIAL" "X6S"
					( Origin gFrontEnd )
				)
				( attribute "PACK_TYPE" "0603V"
					( Origin gFrontEnd )
				)
				( attribute "PART_NUMBER" "E15431-004"
					( Origin gFrontEnd )
				)
				( attribute "PHYS_PAGE" "243"
					( Origin gFrontEnd )
				)
				( attribute "ROOM" "PVDDQ_KLM"
					( Origin gFrontEnd )
				)
				( attribute "ROT" "0"
					( Origin gFrontEnd )
				)
				( attribute "TOLERANCE" "20%"
					( Origin gFrontEnd )
				)
				( attribute "VALUE" "22.0UF"
					( Origin gFrontEnd )
				)
				( attribute "VER" "1"
					( Origin gFrontEnd )
				)
				( attribute "VOLTAGE" "4V"
					( Units "uVoltage" "V" 1.000000)
					( Origin gFrontEnd )
				)
				( attribute "XY" "(-1000,1850)"
					( Origin gFrontEnd )
				)
				( attribute "CHIPS_PART_NAME" "CAP_A"
					( Origin gPackager )
				)
				( attribute "CDS_PART_NAME" "CAP_A_0603V-22.0UF,4V,20%,X6S,A"
					( Origin gPackager )
				)
				( attribute "CDS_LOCATION" "C5G113"
					( Origin gPackager )
				)
				( attribute "SEC" "1"
					( Origin gFrontEnd )
				)
				( attribute "SEC_TYPE" "0603V"
					( Origin gFrontEnd )
				)
				( attribute "CDS_SEC" "1"
					( Origin gPackager )
				)
				( attribute "GROUP" "PWR_MLCC_CAP"
					( Origin gFrontEnd )
				)
				( attribute "BOM_DS" "NOPOP"
					( Origin gFrontEnd )
				)
				( objectStatus "C5G113" )
			)
			( gate "@baseboard_fab2_lib.baseboard_fab2(sch_1):page243_i92"
				( attribute "BOM_COST" "PROC_SOCKET"
					( Origin gFrontEnd )
				)
				( attribute "CDS_LIB" "mstr_discrete"
					( Origin gPackager )
				)
				( attribute "LOCATION" "C5G117"
					( Origin gFrontEnd )
				)
				( attribute "MATERIAL" "X6S"
					( Origin gFrontEnd )
				)
				( attribute "PACK_TYPE" "0805"
					( Origin gFrontEnd )
				)
				( attribute "PART_NUMBER" "C95333-006"
					( Origin gFrontEnd )
				)
				( attribute "PHYS_PAGE" "243"
					( Origin gFrontEnd )
				)
				( attribute "ROOM" "PVCCIN_CPU0_DECAP_VR"
					( Origin gFrontEnd )
				)
				( attribute "ROT" "0"
					( Origin gFrontEnd )
				)
				( attribute "TOLERANCE" "20%"
					( Origin gFrontEnd )
				)
				( attribute "VALUE" "47UF"
					( Origin gFrontEnd )
				)
				( attribute "VER" "1"
					( Origin gFrontEnd )
				)
				( attribute "VOLTAGE" "4V"
					( Units "uVoltage" "V" 1.000000)
					( Origin gFrontEnd )
				)
				( attribute "XY" "(-7750,3750)"
					( Origin gFrontEnd )
				)
				( attribute "CHIPS_PART_NAME" "CAP"
					( Origin gPackager )
				)
				( attribute "CDS_PART_NAME" "CAP_0805-47UF,4V,20%,X6S,C9533A"
					( Origin gPackager )
				)
				( attribute "CDS_LOCATION" "C5G117"
					( Origin gPackager )
				)
				( attribute "SEC" "1"
					( Origin gFrontEnd )
				)
				( attribute "SEC_TYPE" "0805"
					( Origin gFrontEnd )
				)
				( attribute "CDS_SEC" "1"
					( Origin gPackager )
				)
				( attribute "GROUP" "PWR_MLCC_CAP"
					( Origin gFrontEnd )
				)
				( attribute "POP" "NOPOP"
					( Origin gFrontEnd )
				)
				( objectStatus "C5G117" )
			)
			( gate "@baseboard_fab2_lib.baseboard_fab2(sch_1):page243_i80"
				( attribute "CDS_LIB" "dev_discrete"
					( Origin gPackager )
				)
				( attribute "LOCATION" "C5G114"
					( Origin gFrontEnd )
				)
				( attribute "MATERIAL" "X6S"
					( Origin gFrontEnd )
				)
				( attribute "PACK_TYPE" "0603V"
					( Origin gFrontEnd )
				)
				( attribute "PART_NUMBER" "E15431-004"
					( Origin gFrontEnd )
				)
				( attribute "PHYS_PAGE" "243"
					( Origin gFrontEnd )
				)
				( attribute "ROOM" "PVDDQ_KLM"
					( Origin gFrontEnd )
				)
				( attribute "ROT" "0"
					( Origin gFrontEnd )
				)
				( attribute "TOLERANCE" "20%"
					( Origin gFrontEnd )
				)
				( attribute "VALUE" "22.0UF"
					( Origin gFrontEnd )
				)
				( attribute "VER" "1"
					( Origin gFrontEnd )
				)
				( attribute "VOLTAGE" "4V"
					( Units "uVoltage" "V" 1.000000)
					( Origin gFrontEnd )
				)
				( attribute "XY" "(-600,1850)"
					( Origin gFrontEnd )
				)
				( attribute "CHIPS_PART_NAME" "CAP_A"
					( Origin gPackager )
				)
				( attribute "CDS_PART_NAME" "CAP_A_0603V-22.0UF,4V,20%,X6S,A"
					( Origin gPackager )
				)
				( attribute "CDS_LOCATION" "C5G114"
					( Origin gPackager )
				)
				( attribute "SEC" "1"
					( Origin gFrontEnd )
				)
				( attribute "SEC_TYPE" "0603V"
					( Origin gFrontEnd )
				)
				( attribute "CDS_SEC" "1"
					( Origin gPackager )
				)
				( attribute "GROUP" "PWR_MLCC_CAP"
					( Origin gFrontEnd )
				)
				( attribute "BOM_DS" "NOPOP"
					( Origin gFrontEnd )
				)
				( objectStatus "C5G114" )
			)
			( gate "@baseboard_fab2_lib.baseboard_fab2(sch_1):page243_i79"
				( attribute "CDS_LIB" "dev_discrete"
					( Origin gPackager )
				)
				( attribute "LOCATION" "C5G97"
					( Origin gFrontEnd )
				)
				( attribute "MATERIAL" "X6S"
					( Origin gFrontEnd )
				)
				( attribute "PACK_TYPE" "0603V"
					( Origin gFrontEnd )
				)
				( attribute "PART_NUMBER" "E15431-004"
					( Origin gFrontEnd )
				)
				( attribute "PHYS_PAGE" "243"
					( Origin gFrontEnd )
				)
				( attribute "ROOM" "PVDDQ_KLM"
					( Origin gFrontEnd )
				)
				( attribute "ROT" "0"
					( Origin gFrontEnd )
				)
				( attribute "TOLERANCE" "20%"
					( Origin gFrontEnd )
				)
				( attribute "VALUE" "22.0UF"
					( Origin gFrontEnd )
				)
				( attribute "VER" "1"
					( Origin gFrontEnd )
				)
				( attribute "VOLTAGE" "4V"
					( Units "uVoltage" "V" 1.000000)
					( Origin gFrontEnd )
				)
				( attribute "XY" "(-3800,2800)"
					( Origin gFrontEnd )
				)
				( attribute "CHIPS_PART_NAME" "CAP_A"
					( Origin gPackager )
				)
				( attribute "CDS_PART_NAME" "CAP_A_0603V-22.0UF,4V,20%,X6S,A"
					( Origin gPackager )
				)
				( attribute "CDS_LOCATION" "C5G97"
					( Origin gPackager )
				)
				( attribute "SEC" "1"
					( Origin gFrontEnd )
				)
				( attribute "SEC_TYPE" "0603V"
					( Origin gFrontEnd )
				)
				( attribute "CDS_SEC" "1"
					( Origin gPackager )
				)
				( attribute "GROUP" "PWR_MLCC_CAP"
					( Origin gFrontEnd )
				)
				( attribute "BOM_DS" "NOPOP"
					( Origin gFrontEnd )
				)
				( objectStatus "C5G97" )
			)
			( gate "@baseboard_fab2_lib.baseboard_fab2(sch_1):page243_i78"
				( attribute "CDS_LIB" "dev_discrete"
					( Origin gPackager )
				)
				( attribute "LOCATION" "C5G98"
					( Origin gFrontEnd )
				)
				( attribute "MATERIAL" "X6S"
					( Origin gFrontEnd )
				)
				( attribute "PACK_TYPE" "0603V"
					( Origin gFrontEnd )
				)
				( attribute "PART_NUMBER" "E15431-004"
					( Origin gFrontEnd )
				)
				( attribute "PHYS_PAGE" "243"
					( Origin gFrontEnd )
				)
				( attribute "ROOM" "PVDDQ_KLM"
					( Origin gFrontEnd )
				)
				( attribute "ROT" "0"
					( Origin gFrontEnd )
				)
				( attribute "TOLERANCE" "20%"
					( Origin gFrontEnd )
				)
				( attribute "VALUE" "22.0UF"
					( Origin gFrontEnd )
				)
				( attribute "VER" "1"
					( Origin gFrontEnd )
				)
				( attribute "VOLTAGE" "4V"
					( Units "uVoltage" "V" 1.000000)
					( Origin gFrontEnd )
				)
				( attribute "XY" "(-3400,2800)"
					( Origin gFrontEnd )
				)
				( attribute "CHIPS_PART_NAME" "CAP_A"
					( Origin gPackager )
				)
				( attribute "CDS_PART_NAME" "CAP_A_0603V-22.0UF,4V,20%,X6S,A"
					( Origin gPackager )
				)
				( attribute "CDS_LOCATION" "C5G98"
					( Origin gPackager )
				)
				( attribute "SEC" "1"
					( Origin gFrontEnd )
				)
				( attribute "SEC_TYPE" "0603V"
					( Origin gFrontEnd )
				)
				( attribute "CDS_SEC" "1"
					( Origin gPackager )
				)
				( attribute "GROUP" "PWR_MLCC_CAP"
					( Origin gFrontEnd )
				)
				( attribute "BOM_DS" "NOPOP"
					( Origin gFrontEnd )
				)
				( objectStatus "C5G98" )
			)
			( gate "@baseboard_fab2_lib.baseboard_fab2(sch_1):page243_i77"
				( attribute "CDS_LIB" "dev_discrete"
					( Origin gPackager )
				)
				( attribute "LOCATION" "C5G99"
					( Origin gFrontEnd )
				)
				( attribute "MATERIAL" "X6S"
					( Origin gFrontEnd )
				)
				( attribute "PACK_TYPE" "0603V"
					( Origin gFrontEnd )
				)
				( attribute "PART_NUMBER" "E15431-004"
					( Origin gFrontEnd )
				)
				( attribute "PHYS_PAGE" "243"
					( Origin gFrontEnd )
				)
				( attribute "ROOM" "PVDDQ_KLM"
					( Origin gFrontEnd )
				)
				( attribute "ROT" "0"
					( Origin gFrontEnd )
				)
				( attribute "TOLERANCE" "20%"
					( Origin gFrontEnd )
				)
				( attribute "VALUE" "22.0UF"
					( Origin gFrontEnd )
				)
				( attribute "VER" "1"
					( Origin gFrontEnd )
				)
				( attribute "VOLTAGE" "4V"
					( Units "uVoltage" "V" 1.000000)
					( Origin gFrontEnd )
				)
				( attribute "XY" "(-3000,2800)"
					( Origin gFrontEnd )
				)
				( attribute "CHIPS_PART_NAME" "CAP_A"
					( Origin gPackager )
				)
				( attribute "CDS_PART_NAME" "CAP_A_0603V-22.0UF,4V,20%,X6S,A"
					( Origin gPackager )
				)
				( attribute "CDS_LOCATION" "C5G99"
					( Origin gPackager )
				)
				( attribute "SEC" "1"
					( Origin gFrontEnd )
				)
				( attribute "SEC_TYPE" "0603V"
					( Origin gFrontEnd )
				)
				( attribute "CDS_SEC" "1"
					( Origin gPackager )
				)
				( attribute "GROUP" "PWR_MLCC_CAP"
					( Origin gFrontEnd )
				)
				( attribute "BOM_DS" "NOPOP"
					( Origin gFrontEnd )
				)
				( objectStatus "C5G99" )
			)
			( gate "@baseboard_fab2_lib.baseboard_fab2(sch_1):page243_i76"
				( attribute "CDS_LIB" "dev_discrete"
					( Origin gPackager )
				)
				( attribute "LOCATION" "C5G100"
					( Origin gFrontEnd )
				)
				( attribute "MATERIAL" "X6S"
					( Origin gFrontEnd )
				)
				( attribute "PACK_TYPE" "0603V"
					( Origin gFrontEnd )
				)
				( attribute "PART_NUMBER" "E15431-004"
					( Origin gFrontEnd )
				)
				( attribute "PHYS_PAGE" "243"
					( Origin gFrontEnd )
				)
				( attribute "ROOM" "PVDDQ_KLM"
					( Origin gFrontEnd )
				)
				( attribute "ROT" "0"
					( Origin gFrontEnd )
				)
				( attribute "TOLERANCE" "20%"
					( Origin gFrontEnd )
				)
				( attribute "VALUE" "22.0UF"
					( Origin gFrontEnd )
				)
				( attribute "VER" "1"
					( Origin gFrontEnd )
				)
				( attribute "VOLTAGE" "4V"
					( Units "uVoltage" "V" 1.000000)
					( Origin gFrontEnd )
				)
				( attribute "XY" "(-2600,2800)"
					( Origin gFrontEnd )
				)
				( attribute "CHIPS_PART_NAME" "CAP_A"
					( Origin gPackager )
				)
				( attribute "CDS_PART_NAME" "CAP_A_0603V-22.0UF,4V,20%,X6S,A"
					( Origin gPackager )
				)
				( attribute "CDS_LOCATION" "C5G100"
					( Origin gPackager )
				)
				( attribute "SEC" "1"
					( Origin gFrontEnd )
				)
				( attribute "SEC_TYPE" "0603V"
					( Origin gFrontEnd )
				)
				( attribute "CDS_SEC" "1"
					( Origin gPackager )
				)
				( attribute "GROUP" "PWR_MLCC_CAP"
					( Origin gFrontEnd )
				)
				( attribute "BOM_DS" "NOPOP"
					( Origin gFrontEnd )
				)
				( objectStatus "C5G100" )
			)
			( gate "@baseboard_fab2_lib.baseboard_fab2(sch_1):page243_i75"
				( attribute "CDS_LIB" "dev_discrete"
					( Origin gPackager )
				)
				( attribute "LOCATION" "C5G101"
					( Origin gFrontEnd )
				)
				( attribute "MATERIAL" "X6S"
					( Origin gFrontEnd )
				)
				( attribute "PACK_TYPE" "0603V"
					( Origin gFrontEnd )
				)
				( attribute "PART_NUMBER" "E15431-004"
					( Origin gFrontEnd )
				)
				( attribute "PHYS_PAGE" "243"
					( Origin gFrontEnd )
				)
				( attribute "ROOM" "PVDDQ_KLM"
					( Origin gFrontEnd )
				)
				( attribute "ROT" "0"
					( Origin gFrontEnd )
				)
				( attribute "TOLERANCE" "20%"
					( Origin gFrontEnd )
				)
				( attribute "VALUE" "22.0UF"
					( Origin gFrontEnd )
				)
				( attribute "VER" "1"
					( Origin gFrontEnd )
				)
				( attribute "VOLTAGE" "4V"
					( Units "uVoltage" "V" 1.000000)
					( Origin gFrontEnd )
				)
				( attribute "XY" "(-2200,2800)"
					( Origin gFrontEnd )
				)
				( attribute "CHIPS_PART_NAME" "CAP_A"
					( Origin gPackager )
				)
				( attribute "CDS_PART_NAME" "CAP_A_0603V-22.0UF,4V,20%,X6S,A"
					( Origin gPackager )
				)
				( attribute "CDS_LOCATION" "C5G101"
					( Origin gPackager )
				)
				( attribute "SEC" "1"
					( Origin gFrontEnd )
				)
				( attribute "SEC_TYPE" "0603V"
					( Origin gFrontEnd )
				)
				( attribute "CDS_SEC" "1"
					( Origin gPackager )
				)
				( attribute "GROUP" "PWR_MLCC_CAP"
					( Origin gFrontEnd )
				)
				( attribute "BOM_DS" "NOPOP"
					( Origin gFrontEnd )
				)
				( objectStatus "C5G101" )
			)
			( gate "@baseboard_fab2_lib.baseboard_fab2(sch_1):page243_i74"
				( attribute "CDS_LIB" "dev_discrete"
					( Origin gPackager )
				)
				( attribute "LOCATION" "C5G102"
					( Origin gFrontEnd )
				)
				( attribute "MATERIAL" "X6S"
					( Origin gFrontEnd )
				)
				( attribute "PACK_TYPE" "0603V"
					( Origin gFrontEnd )
				)
				( attribute "PART_NUMBER" "E15431-004"
					( Origin gFrontEnd )
				)
				( attribute "PHYS_PAGE" "243"
					( Origin gFrontEnd )
				)
				( attribute "ROOM" "PVDDQ_KLM"
					( Origin gFrontEnd )
				)
				( attribute "ROT" "0"
					( Origin gFrontEnd )
				)
				( attribute "TOLERANCE" "20%"
					( Origin gFrontEnd )
				)
				( attribute "VALUE" "22.0UF"
					( Origin gFrontEnd )
				)
				( attribute "VER" "1"
					( Origin gFrontEnd )
				)
				( attribute "VOLTAGE" "4V"
					( Units "uVoltage" "V" 1.000000)
					( Origin gFrontEnd )
				)
				( attribute "XY" "(-1800,2800)"
					( Origin gFrontEnd )
				)
				( attribute "CHIPS_PART_NAME" "CAP_A"
					( Origin gPackager )
				)
				( attribute "CDS_PART_NAME" "CAP_A_0603V-22.0UF,4V,20%,X6S,A"
					( Origin gPackager )
				)
				( attribute "CDS_LOCATION" "C5G102"
					( Origin gPackager )
				)
				( attribute "SEC" "1"
					( Origin gFrontEnd )
				)
				( attribute "SEC_TYPE" "0603V"
					( Origin gFrontEnd )
				)
				( attribute "CDS_SEC" "1"
					( Origin gPackager )
				)
				( attribute "GROUP" "PWR_MLCC_CAP"
					( Origin gFrontEnd )
				)
				( attribute "BOM_DS" "NOPOP"
					( Origin gFrontEnd )
				)
				( objectStatus "C5G102" )
			)
			( gate "@baseboard_fab2_lib.baseboard_fab2(sch_1):page243_i73"
				( attribute "CDS_LIB" "dev_discrete"
					( Origin gPackager )
				)
				( attribute "LOCATION" "C5G105"
					( Origin gFrontEnd )
				)
				( attribute "MATERIAL" "X6S"
					( Origin gFrontEnd )
				)
				( attribute "PACK_TYPE" "0603V"
					( Origin gFrontEnd )
				)
				( attribute "PART_NUMBER" "E15431-004"
					( Origin gFrontEnd )
				)
				( attribute "PHYS_PAGE" "243"
					( Origin gFrontEnd )
				)
				( attribute "ROOM" "PVDDQ_KLM"
					( Origin gFrontEnd )
				)
				( attribute "ROT" "0"
					( Origin gFrontEnd )
				)
				( attribute "TOLERANCE" "20%"
					( Origin gFrontEnd )
				)
				( attribute "VALUE" "22.0UF"
					( Origin gFrontEnd )
				)
				( attribute "VER" "1"
					( Origin gFrontEnd )
				)
				( attribute "VOLTAGE" "4V"
					( Units "uVoltage" "V" 1.000000)
					( Origin gFrontEnd )
				)
				( attribute "XY" "(-600,2800)"
					( Origin gFrontEnd )
				)
				( attribute "CHIPS_PART_NAME" "CAP_A"
					( Origin gPackager )
				)
				( attribute "CDS_PART_NAME" "CAP_A_0603V-22.0UF,4V,20%,X6S,A"
					( Origin gPackager )
				)
				( attribute "SEC" "1"
					( Origin gFrontEnd )
				)
				( attribute "SEC_TYPE" "0603V"
					( Origin gFrontEnd )
				)
				( attribute "CDS_LOCATION" "C5G105"
					( Origin gPackager )
				)
				( attribute "CDS_SEC" "1"
					( Origin gPackager )
				)
				( attribute "GROUP" "PWR_MLCC_CAP"
					( Origin gFrontEnd )
				)
				( attribute "BOM_DS" "NOPOP"
					( Origin gFrontEnd )
				)
				( objectStatus "C5G105" )
			)
			( gate "@baseboard_fab2_lib.baseboard_fab2(sch_1):page243_i72"
				( attribute "CDS_LIB" "dev_discrete"
					( Origin gPackager )
				)
				( attribute "LOCATION" "C5G104"
					( Origin gFrontEnd )
				)
				( attribute "MATERIAL" "X6S"
					( Origin gFrontEnd )
				)
				( attribute "PACK_TYPE" "0603V"
					( Origin gFrontEnd )
				)
				( attribute "PART_NUMBER" "E15431-004"
					( Origin gFrontEnd )
				)
				( attribute "PHYS_PAGE" "243"
					( Origin gFrontEnd )
				)
				( attribute "ROOM" "PVDDQ_KLM"
					( Origin gFrontEnd )
				)
				( attribute "ROT" "0"
					( Origin gFrontEnd )
				)
				( attribute "TOLERANCE" "20%"
					( Origin gFrontEnd )
				)
				( attribute "VALUE" "22.0UF"
					( Origin gFrontEnd )
				)
				( attribute "VER" "1"
					( Origin gFrontEnd )
				)
				( attribute "VOLTAGE" "4V"
					( Units "uVoltage" "V" 1.000000)
					( Origin gFrontEnd )
				)
				( attribute "XY" "(-1000,2800)"
					( Origin gFrontEnd )
				)
				( attribute "CHIPS_PART_NAME" "CAP_A"
					( Origin gPackager )
				)
				( attribute "CDS_PART_NAME" "CAP_A_0603V-22.0UF,4V,20%,X6S,A"
					( Origin gPackager )
				)
				( attribute "CDS_LOCATION" "C5G104"
					( Origin gPackager )
				)
				( attribute "SEC" "1"
					( Origin gFrontEnd )
				)
				( attribute "SEC_TYPE" "0603V"
					( Origin gFrontEnd )
				)
				( attribute "CDS_SEC" "1"
					( Origin gPackager )
				)
				( attribute "GROUP" "PWR_MLCC_CAP"
					( Origin gFrontEnd )
				)
				( attribute "BOM_DS" "NOPOP"
					( Origin gFrontEnd )
				)
				( objectStatus "C5G104" )
			)
			( gate "@baseboard_fab2_lib.baseboard_fab2(sch_1):page243_i71"
				( attribute "CDS_LIB" "dev_discrete"
					( Origin gPackager )
				)
				( attribute "LOCATION" "C5G103"
					( Origin gFrontEnd )
				)
				( attribute "MATERIAL" "X6S"
					( Origin gFrontEnd )
				)
				( attribute "PACK_TYPE" "0603V"
					( Origin gFrontEnd )
				)
				( attribute "PART_NUMBER" "E15431-004"
					( Origin gFrontEnd )
				)
				( attribute "PHYS_PAGE" "243"
					( Origin gFrontEnd )
				)
				( attribute "ROOM" "PVDDQ_KLM"
					( Origin gFrontEnd )
				)
				( attribute "ROT" "0"
					( Origin gFrontEnd )
				)
				( attribute "TOLERANCE" "20%"
					( Origin gFrontEnd )
				)
				( attribute "VALUE" "22.0UF"
					( Origin gFrontEnd )
				)
				( attribute "VER" "1"
					( Origin gFrontEnd )
				)
				( attribute "VOLTAGE" "4V"
					( Units "uVoltage" "V" 1.000000)
					( Origin gFrontEnd )
				)
				( attribute "XY" "(-1400,2800)"
					( Origin gFrontEnd )
				)
				( attribute "CHIPS_PART_NAME" "CAP_A"
					( Origin gPackager )
				)
				( attribute "CDS_PART_NAME" "CAP_A_0603V-22.0UF,4V,20%,X6S,A"
					( Origin gPackager )
				)
				( attribute "CDS_LOCATION" "C5G103"
					( Origin gPackager )
				)
				( attribute "SEC" "1"
					( Origin gFrontEnd )
				)
				( attribute "SEC_TYPE" "0603V"
					( Origin gFrontEnd )
				)
				( attribute "CDS_SEC" "1"
					( Origin gPackager )
				)
				( attribute "GROUP" "PWR_MLCC_CAP"
					( Origin gFrontEnd )
				)
				( attribute "BOM_DS" "NOPOP"
					( Origin gFrontEnd )
				)
				( objectStatus "C5G103" )
			)
			( gate "@baseboard_fab2_lib.baseboard_fab2(sch_1):page243_i70"
				( attribute "CDS_LIB" "dev_discrete"
					( Origin gPackager )
				)
				( attribute "LOCATION" "C5G88"
					( Origin gFrontEnd )
				)
				( attribute "MATERIAL" "X6S"
					( Origin gFrontEnd )
				)
				( attribute "PACK_TYPE" "0603V"
					( Origin gFrontEnd )
				)
				( attribute "PART_NUMBER" "E15431-004"
					( Origin gFrontEnd )
				)
				( attribute "PHYS_PAGE" "243"
					( Origin gFrontEnd )
				)
				( attribute "ROOM" "PVDDQ_KLM"
					( Origin gFrontEnd )
				)
				( attribute "ROT" "0"
					( Origin gFrontEnd )
				)
				( attribute "TOLERANCE" "20%"
					( Origin gFrontEnd )
				)
				( attribute "VALUE" "22.0UF"
					( Origin gFrontEnd )
				)
				( attribute "VER" "1"
					( Origin gFrontEnd )
				)
				( attribute "VOLTAGE" "4V"
					( Units "uVoltage" "V" 1.000000)
					( Origin gFrontEnd )
				)
				( attribute "XY" "(-7750,1850)"
					( Origin gFrontEnd )
				)
				( attribute "CHIPS_PART_NAME" "CAP_A"
					( Origin gPackager )
				)
				( attribute "CDS_PART_NAME" "CAP_A_0603V-22.0UF,4V,20%,X6S,A"
					( Origin gPackager )
				)
				( attribute "CDS_LOCATION" "C5G88"
					( Origin gPackager )
				)
				( attribute "SEC" "1"
					( Origin gFrontEnd )
				)
				( attribute "SEC_TYPE" "0603V"
					( Origin gFrontEnd )
				)
				( attribute "CDS_SEC" "1"
					( Origin gPackager )
				)
				( attribute "GROUP" "PWR_MLCC_CAP"
					( Origin gFrontEnd )
				)
				( attribute "BOM_DS" "NOPOP"
					( Origin gFrontEnd )
				)
				( objectStatus "C5G88" )
			)
			( gate "@baseboard_fab2_lib.baseboard_fab2(sch_1):page243_i69"
				( attribute "CDS_LIB" "dev_discrete"
					( Origin gPackager )
				)
				( attribute "LOCATION" "C5G89"
					( Origin gFrontEnd )
				)
				( attribute "MATERIAL" "X6S"
					( Origin gFrontEnd )
				)
				( attribute "PACK_TYPE" "0603V"
					( Origin gFrontEnd )
				)
				( attribute "PART_NUMBER" "E15431-004"
					( Origin gFrontEnd )
				)
				( attribute "PHYS_PAGE" "243"
					( Origin gFrontEnd )
				)
				( attribute "ROOM" "PVDDQ_KLM"
					( Origin gFrontEnd )
				)
				( attribute "ROT" "0"
					( Origin gFrontEnd )
				)
				( attribute "TOLERANCE" "20%"
					( Origin gFrontEnd )
				)
				( attribute "VALUE" "22.0UF"
					( Origin gFrontEnd )
				)
				( attribute "VER" "1"
					( Origin gFrontEnd )
				)
				( attribute "VOLTAGE" "4V"
					( Units "uVoltage" "V" 1.000000)
					( Origin gFrontEnd )
				)
				( attribute "XY" "(-7350,1850)"
					( Origin gFrontEnd )
				)
				( attribute "CHIPS_PART_NAME" "CAP_A"
					( Origin gPackager )
				)
				( attribute "CDS_PART_NAME" "CAP_A_0603V-22.0UF,4V,20%,X6S,A"
					( Origin gPackager )
				)
				( attribute "CDS_LOCATION" "C5G89"
					( Origin gPackager )
				)
				( attribute "SEC" "1"
					( Origin gFrontEnd )
				)
				( attribute "SEC_TYPE" "0603V"
					( Origin gFrontEnd )
				)
				( attribute "CDS_SEC" "1"
					( Origin gPackager )
				)
				( attribute "GROUP" "PWR_MLCC_CAP"
					( Origin gFrontEnd )
				)
				( attribute "BOM_DS" "NOPOP"
					( Origin gFrontEnd )
				)
				( objectStatus "C5G89" )
			)
			( gate "@baseboard_fab2_lib.baseboard_fab2(sch_1):page243_i68"
				( attribute "CDS_LIB" "dev_discrete"
					( Origin gPackager )
				)
				( attribute "LOCATION" "C5G90"
					( Origin gFrontEnd )
				)
				( attribute "MATERIAL" "X6S"
					( Origin gFrontEnd )
				)
				( attribute "PACK_TYPE" "0603V"
					( Origin gFrontEnd )
				)
				( attribute "PART_NUMBER" "E15431-004"
					( Origin gFrontEnd )
				)
				( attribute "PHYS_PAGE" "243"
					( Origin gFrontEnd )
				)
				( attribute "ROOM" "PVDDQ_KLM"
					( Origin gFrontEnd )
				)
				( attribute "ROT" "0"
					( Origin gFrontEnd )
				)
				( attribute "TOLERANCE" "20%"
					( Origin gFrontEnd )
				)
				( attribute "VALUE" "22.0UF"
					( Origin gFrontEnd )
				)
				( attribute "VER" "1"
					( Origin gFrontEnd )
				)
				( attribute "VOLTAGE" "4V"
					( Units "uVoltage" "V" 1.000000)
					( Origin gFrontEnd )
				)
				( attribute "XY" "(-6950,1850)"
					( Origin gFrontEnd )
				)
				( attribute "CHIPS_PART_NAME" "CAP_A"
					( Origin gPackager )
				)
				( attribute "CDS_PART_NAME" "CAP_A_0603V-22.0UF,4V,20%,X6S,A"
					( Origin gPackager )
				)
				( attribute "CDS_LOCATION" "C5G90"
					( Origin gPackager )
				)
				( attribute "SEC" "1"
					( Origin gFrontEnd )
				)
				( attribute "SEC_TYPE" "0603V"
					( Origin gFrontEnd )
				)
				( attribute "CDS_SEC" "1"
					( Origin gPackager )
				)
				( attribute "GROUP" "PWR_MLCC_CAP"
					( Origin gFrontEnd )
				)
				( attribute "BOM_DS" "NOPOP"
					( Origin gFrontEnd )
				)
				( objectStatus "C5G90" )
			)
			( gate "@baseboard_fab2_lib.baseboard_fab2(sch_1):page243_i67"
				( attribute "CDS_LIB" "dev_discrete"
					( Origin gPackager )
				)
				( attribute "LOCATION" "C5G91"
					( Origin gFrontEnd )
				)
				( attribute "MATERIAL" "X6S"
					( Origin gFrontEnd )
				)
				( attribute "PACK_TYPE" "0603V"
					( Origin gFrontEnd )
				)
				( attribute "PART_NUMBER" "E15431-004"
					( Origin gFrontEnd )
				)
				( attribute "PHYS_PAGE" "243"
					( Origin gFrontEnd )
				)
				( attribute "ROOM" "PVDDQ_KLM"
					( Origin gFrontEnd )
				)
				( attribute "ROT" "0"
					( Origin gFrontEnd )
				)
				( attribute "TOLERANCE" "20%"
					( Origin gFrontEnd )
				)
				( attribute "VALUE" "22.0UF"
					( Origin gFrontEnd )
				)
				( attribute "VER" "1"
					( Origin gFrontEnd )
				)
				( attribute "VOLTAGE" "4V"
					( Units "uVoltage" "V" 1.000000)
					( Origin gFrontEnd )
				)
				( attribute "XY" "(-6550,1850)"
					( Origin gFrontEnd )
				)
				( attribute "CHIPS_PART_NAME" "CAP_A"
					( Origin gPackager )
				)
				( attribute "CDS_PART_NAME" "CAP_A_0603V-22.0UF,4V,20%,X6S,A"
					( Origin gPackager )
				)
				( attribute "CDS_LOCATION" "C5G91"
					( Origin gPackager )
				)
				( attribute "SEC" "1"
					( Origin gFrontEnd )
				)
				( attribute "SEC_TYPE" "0603V"
					( Origin gFrontEnd )
				)
				( attribute "CDS_SEC" "1"
					( Origin gPackager )
				)
				( attribute "GROUP" "PWR_MLCC_CAP"
					( Origin gFrontEnd )
				)
				( attribute "BOM_DS" "NOPOP"
					( Origin gFrontEnd )
				)
				( objectStatus "C5G91" )
			)
			( gate "@baseboard_fab2_lib.baseboard_fab2(sch_1):page243_i66"
				( attribute "CDS_LIB" "dev_discrete"
					( Origin gPackager )
				)
				( attribute "LOCATION" "C5G92"
					( Origin gFrontEnd )
				)
				( attribute "MATERIAL" "X6S"
					( Origin gFrontEnd )
				)
				( attribute "PACK_TYPE" "0603V"
					( Origin gFrontEnd )
				)
				( attribute "PART_NUMBER" "E15431-004"
					( Origin gFrontEnd )
				)
				( attribute "PHYS_PAGE" "243"
					( Origin gFrontEnd )
				)
				( attribute "ROOM" "PVDDQ_KLM"
					( Origin gFrontEnd )
				)
				( attribute "ROT" "0"
					( Origin gFrontEnd )
				)
				( attribute "TOLERANCE" "20%"
					( Origin gFrontEnd )
				)
				( attribute "VALUE" "22.0UF"
					( Origin gFrontEnd )
				)
				( attribute "VER" "1"
					( Origin gFrontEnd )
				)
				( attribute "VOLTAGE" "4V"
					( Units "uVoltage" "V" 1.000000)
					( Origin gFrontEnd )
				)
				( attribute "XY" "(-6150,1850)"
					( Origin gFrontEnd )
				)
				( attribute "CHIPS_PART_NAME" "CAP_A"
					( Origin gPackager )
				)
				( attribute "CDS_PART_NAME" "CAP_A_0603V-22.0UF,4V,20%,X6S,A"
					( Origin gPackager )
				)
				( attribute "CDS_LOCATION" "C5G92"
					( Origin gPackager )
				)
				( attribute "SEC" "1"
					( Origin gFrontEnd )
				)
				( attribute "SEC_TYPE" "0603V"
					( Origin gFrontEnd )
				)
				( attribute "CDS_SEC" "1"
					( Origin gPackager )
				)
				( attribute "GROUP" "PWR_MLCC_CAP"
					( Origin gFrontEnd )
				)
				( attribute "BOM_DS" "NOPOP"
					( Origin gFrontEnd )
				)
				( objectStatus "C5G92" )
			)
			( gate "@baseboard_fab2_lib.baseboard_fab2(sch_1):page243_i91"
				( attribute "BOM_COST" "PROC_SOCKET"
					( Origin gFrontEnd )
				)
				( attribute "CDS_LIB" "mstr_discrete"
					( Origin gPackager )
				)
				( attribute "LOCATION" "C5G118"
					( Origin gFrontEnd )
				)
				( attribute "MATERIAL" "X6S"
					( Origin gFrontEnd )
				)
				( attribute "PACK_TYPE" "0805"
					( Origin gFrontEnd )
				)
				( attribute "PART_NUMBER" "C95333-006"
					( Origin gFrontEnd )
				)
				( attribute "PHYS_PAGE" "243"
					( Origin gFrontEnd )
				)
				( attribute "ROOM" "PVCCIN_CPU0_DECAP_VR"
					( Origin gFrontEnd )
				)
				( attribute "ROT" "0"
					( Origin gFrontEnd )
				)
				( attribute "TOLERANCE" "20%"
					( Origin gFrontEnd )
				)
				( attribute "VALUE" "47UF"
					( Origin gFrontEnd )
				)
				( attribute "VER" "1"
					( Origin gFrontEnd )
				)
				( attribute "VOLTAGE" "4V"
					( Units "uVoltage" "V" 1.000000)
					( Origin gFrontEnd )
				)
				( attribute "XY" "(-7350,3750)"
					( Origin gFrontEnd )
				)
				( attribute "CHIPS_PART_NAME" "CAP"
					( Origin gPackager )
				)
				( attribute "CDS_PART_NAME" "CAP_0805-47UF,4V,20%,X6S,C9533A"
					( Origin gPackager )
				)
				( attribute "CDS_LOCATION" "C5G118"
					( Origin gPackager )
				)
				( attribute "SEC" "1"
					( Origin gFrontEnd )
				)
				( attribute "SEC_TYPE" "0805"
					( Origin gFrontEnd )
				)
				( attribute "CDS_SEC" "1"
					( Origin gPackager )
				)
				( attribute "GROUP" "PWR_MLCC_CAP"
					( Origin gFrontEnd )
				)
				( attribute "POP" "NOPOP"
					( Origin gFrontEnd )
				)
				( objectStatus "C5G118" )
			)
			( gate "@baseboard_fab2_lib.baseboard_fab2(sch_1):page243_i65"
				( attribute "CDS_LIB" "dev_discrete"
					( Origin gPackager )
				)
				( attribute "LOCATION" "C5G93"
					( Origin gFrontEnd )
				)
				( attribute "MATERIAL" "X6S"
					( Origin gFrontEnd )
				)
				( attribute "PACK_TYPE" "0603V"
					( Origin gFrontEnd )
				)
				( attribute "PART_NUMBER" "E15431-004"
					( Origin gFrontEnd )
				)
				( attribute "PHYS_PAGE" "243"
					( Origin gFrontEnd )
				)
				( attribute "ROOM" "PVDDQ_KLM"
					( Origin gFrontEnd )
				)
				( attribute "ROT" "0"
					( Origin gFrontEnd )
				)
				( attribute "TOLERANCE" "20%"
					( Origin gFrontEnd )
				)
				( attribute "VALUE" "22.0UF"
					( Origin gFrontEnd )
				)
				( attribute "VER" "1"
					( Origin gFrontEnd )
				)
				( attribute "VOLTAGE" "4V"
					( Units "uVoltage" "V" 1.000000)
					( Origin gFrontEnd )
				)
				( attribute "XY" "(-5750,1850)"
					( Origin gFrontEnd )
				)
				( attribute "CHIPS_PART_NAME" "CAP_A"
					( Origin gPackager )
				)
				( attribute "CDS_PART_NAME" "CAP_A_0603V-22.0UF,4V,20%,X6S,A"
					( Origin gPackager )
				)
				( attribute "CDS_LOCATION" "C5G93"
					( Origin gPackager )
				)
				( attribute "SEC" "1"
					( Origin gFrontEnd )
				)
				( attribute "SEC_TYPE" "0603V"
					( Origin gFrontEnd )
				)
				( attribute "CDS_SEC" "1"
					( Origin gPackager )
				)
				( attribute "GROUP" "PWR_MLCC_CAP"
					( Origin gFrontEnd )
				)
				( attribute "BOM_DS" "NOPOP"
					( Origin gFrontEnd )
				)
				( objectStatus "C5G93" )
			)
			( gate "@baseboard_fab2_lib.baseboard_fab2(sch_1):page243_i64"
				( attribute "CDS_LIB" "dev_discrete"
					( Origin gPackager )
				)
				( attribute "LOCATION" "C5G94"
					( Origin gFrontEnd )
				)
				( attribute "MATERIAL" "X6S"
					( Origin gFrontEnd )
				)
				( attribute "PACK_TYPE" "0603V"
					( Origin gFrontEnd )
				)
				( attribute "PART_NUMBER" "E15431-004"
					( Origin gFrontEnd )
				)
				( attribute "PHYS_PAGE" "243"
					( Origin gFrontEnd )
				)
				( attribute "ROOM" "PVDDQ_KLM"
					( Origin gFrontEnd )
				)
				( attribute "ROT" "0"
					( Origin gFrontEnd )
				)
				( attribute "TOLERANCE" "20%"
					( Origin gFrontEnd )
				)
				( attribute "VALUE" "22.0UF"
					( Origin gFrontEnd )
				)
				( attribute "VER" "1"
					( Origin gFrontEnd )
				)
				( attribute "VOLTAGE" "4V"
					( Units "uVoltage" "V" 1.000000)
					( Origin gFrontEnd )
				)
				( attribute "XY" "(-5350,1850)"
					( Origin gFrontEnd )
				)
				( attribute "CHIPS_PART_NAME" "CAP_A"
					( Origin gPackager )
				)
				( attribute "CDS_PART_NAME" "CAP_A_0603V-22.0UF,4V,20%,X6S,A"
					( Origin gPackager )
				)
				( attribute "CDS_LOCATION" "C5G94"
					( Origin gPackager )
				)
				( attribute "SEC" "1"
					( Origin gFrontEnd )
				)
				( attribute "SEC_TYPE" "0603V"
					( Origin gFrontEnd )
				)
				( attribute "CDS_SEC" "1"
					( Origin gPackager )
				)
				( attribute "GROUP" "PWR_MLCC_CAP"
					( Origin gFrontEnd )
				)
				( attribute "BOM_DS" "NOPOP"
					( Origin gFrontEnd )
				)
				( objectStatus "C5G94" )
			)
			( gate "@baseboard_fab2_lib.baseboard_fab2(sch_1):page243_i63"
				( attribute "CDS_LIB" "dev_discrete"
					( Origin gPackager )
				)
				( attribute "LOCATION" "C5G95"
					( Origin gFrontEnd )
				)
				( attribute "MATERIAL" "X6S"
					( Origin gFrontEnd )
				)
				( attribute "PACK_TYPE" "0603V"
					( Origin gFrontEnd )
				)
				( attribute "PART_NUMBER" "E15431-004"
					( Origin gFrontEnd )
				)
				( attribute "PHYS_PAGE" "243"
					( Origin gFrontEnd )
				)
				( attribute "ROOM" "PVDDQ_KLM"
					( Origin gFrontEnd )
				)
				( attribute "ROT" "0"
					( Origin gFrontEnd )
				)
				( attribute "TOLERANCE" "20%"
					( Origin gFrontEnd )
				)
				( attribute "VALUE" "22.0UF"
					( Origin gFrontEnd )
				)
				( attribute "VER" "1"
					( Origin gFrontEnd )
				)
				( attribute "VOLTAGE" "4V"
					( Units "uVoltage" "V" 1.000000)
					( Origin gFrontEnd )
				)
				( attribute "XY" "(-4950,1850)"
					( Origin gFrontEnd )
				)
				( attribute "CHIPS_PART_NAME" "CAP_A"
					( Origin gPackager )
				)
				( attribute "CDS_PART_NAME" "CAP_A_0603V-22.0UF,4V,20%,X6S,A"
					( Origin gPackager )
				)
				( attribute "CDS_LOCATION" "C5G95"
					( Origin gPackager )
				)
				( attribute "SEC" "1"
					( Origin gFrontEnd )
				)
				( attribute "SEC_TYPE" "0603V"
					( Origin gFrontEnd )
				)
				( attribute "CDS_SEC" "1"
					( Origin gPackager )
				)
				( attribute "GROUP" "PWR_MLCC_CAP"
					( Origin gFrontEnd )
				)
				( attribute "BOM_DS" "NOPOP"
					( Origin gFrontEnd )
				)
				( objectStatus "C5G95" )
			)
			( gate "@baseboard_fab2_lib.baseboard_fab2(sch_1):page243_i90"
				( attribute "BOM_COST" "PROC_SOCKET"
					( Origin gFrontEnd )
				)
				( attribute "CDS_LIB" "mstr_discrete"
					( Origin gPackager )
				)
				( attribute "LOCATION" "C5G116"
					( Origin gFrontEnd )
				)
				( attribute "MATERIAL" "X6S"
					( Origin gFrontEnd )
				)
				( attribute "PACK_TYPE" "0805"
					( Origin gFrontEnd )
				)
				( attribute "PART_NUMBER" "C95333-006"
					( Origin gFrontEnd )
				)
				( attribute "PHYS_PAGE" "243"
					( Origin gFrontEnd )
				)
				( attribute "ROOM" "PVCCIN_CPU0_DECAP_VR"
					( Origin gFrontEnd )
				)
				( attribute "ROT" "0"
					( Origin gFrontEnd )
				)
				( attribute "TOLERANCE" "20%"
					( Origin gFrontEnd )
				)
				( attribute "VALUE" "47UF"
					( Origin gFrontEnd )
				)
				( attribute "VER" "1"
					( Origin gFrontEnd )
				)
				( attribute "VOLTAGE" "4V"
					( Units "uVoltage" "V" 1.000000)
					( Origin gFrontEnd )
				)
				( attribute "XY" "(-3400,3775)"
					( Origin gFrontEnd )
				)
				( attribute "CHIPS_PART_NAME" "CAP"
					( Origin gPackager )
				)
				( attribute "CDS_PART_NAME" "CAP_0805-47UF,4V,20%,X6S,C9533A"
					( Origin gPackager )
				)
				( attribute "CDS_LOCATION" "C5G116"
					( Origin gPackager )
				)
				( attribute "SEC" "1"
					( Origin gFrontEnd )
				)
				( attribute "SEC_TYPE" "0805"
					( Origin gFrontEnd )
				)
				( attribute "CDS_SEC" "1"
					( Origin gPackager )
				)
				( attribute "GROUP" "PWR_MLCC_CAP"
					( Origin gFrontEnd )
				)
				( attribute "POP" "NOPOP"
					( Origin gFrontEnd )
				)
				( objectStatus "C5G116" )
			)
			( gate "@baseboard_fab2_lib.baseboard_fab2(sch_1):page243_i62"
				( attribute "CDS_LIB" "dev_discrete"
					( Origin gPackager )
				)
				( attribute "LOCATION" "C5G96"
					( Origin gFrontEnd )
				)
				( attribute "MATERIAL" "X6S"
					( Origin gFrontEnd )
				)
				( attribute "PACK_TYPE" "0603V"
					( Origin gFrontEnd )
				)
				( attribute "PART_NUMBER" "E15431-004"
					( Origin gFrontEnd )
				)
				( attribute "PHYS_PAGE" "243"
					( Origin gFrontEnd )
				)
				( attribute "ROOM" "PVDDQ_KLM"
					( Origin gFrontEnd )
				)
				( attribute "ROT" "0"
					( Origin gFrontEnd )
				)
				( attribute "TOLERANCE" "20%"
					( Origin gFrontEnd )
				)
				( attribute "VALUE" "22.0UF"
					( Origin gFrontEnd )
				)
				( attribute "VER" "1"
					( Origin gFrontEnd )
				)
				( attribute "VOLTAGE" "4V"
					( Units "uVoltage" "V" 1.000000)
					( Origin gFrontEnd )
				)
				( attribute "XY" "(-4550,1850)"
					( Origin gFrontEnd )
				)
				( attribute "CHIPS_PART_NAME" "CAP_A"
					( Origin gPackager )
				)
				( attribute "CDS_PART_NAME" "CAP_A_0603V-22.0UF,4V,20%,X6S,A"
					( Origin gPackager )
				)
				( attribute "CDS_LOCATION" "C5G96"
					( Origin gPackager )
				)
				( attribute "SEC" "1"
					( Origin gFrontEnd )
				)
				( attribute "SEC_TYPE" "0603V"
					( Origin gFrontEnd )
				)
				( attribute "CDS_SEC" "1"
					( Origin gPackager )
				)
				( attribute "GROUP" "PWR_MLCC_CAP"
					( Origin gFrontEnd )
				)
				( attribute "BOM_DS" "NOPOP"
					( Origin gFrontEnd )
				)
				( objectStatus "C5G96" )
			)
			( gate "@baseboard_fab2_lib.baseboard_fab2(sch_1):page243_i61"
				( attribute "CDS_LIB" "dev_discrete"
					( Origin gPackager )
				)
				( attribute "LOCATION" "C5G80"
					( Origin gFrontEnd )
				)
				( attribute "MATERIAL" "X6S"
					( Origin gFrontEnd )
				)
				( attribute "PACK_TYPE" "0603V"
					( Origin gFrontEnd )
				)
				( attribute "PART_NUMBER" "E15431-004"
					( Origin gFrontEnd )
				)
				( attribute "PHYS_PAGE" "243"
					( Origin gFrontEnd )
				)
				( attribute "ROOM" "PVDDQ_KLM"
					( Origin gFrontEnd )
				)
				( attribute "ROT" "0"
					( Origin gFrontEnd )
				)
				( attribute "TOLERANCE" "20%"
					( Origin gFrontEnd )
				)
				( attribute "VALUE" "22.0UF"
					( Origin gFrontEnd )
				)
				( attribute "VER" "1"
					( Origin gFrontEnd )
				)
				( attribute "VOLTAGE" "4V"
					( Units "uVoltage" "V" 1.000000)
					( Origin gFrontEnd )
				)
				( attribute "XY" "(-7350,2800)"
					( Origin gFrontEnd )
				)
				( attribute "CHIPS_PART_NAME" "CAP_A"
					( Origin gPackager )
				)
				( attribute "CDS_PART_NAME" "CAP_A_0603V-22.0UF,4V,20%,X6S,A"
					( Origin gPackager )
				)
				( attribute "CDS_LOCATION" "C5G80"
					( Origin gPackager )
				)
				( attribute "SEC" "1"
					( Origin gFrontEnd )
				)
				( attribute "SEC_TYPE" "0603V"
					( Origin gFrontEnd )
				)
				( attribute "CDS_SEC" "1"
					( Origin gPackager )
				)
				( attribute "GROUP" "PWR_MLCC_CAP"
					( Origin gFrontEnd )
				)
				( attribute "BOM_DS" "NOPOP"
					( Origin gFrontEnd )
				)
				( objectStatus "C5G80" )
			)
			( gate "@baseboard_fab2_lib.baseboard_fab2(sch_1):page243_i60"
				( attribute "CDS_LIB" "dev_discrete"
					( Origin gPackager )
				)
				( attribute "LOCATION" "C5G81"
					( Origin gFrontEnd )
				)
				( attribute "MATERIAL" "X6S"
					( Origin gFrontEnd )
				)
				( attribute "PACK_TYPE" "0603V"
					( Origin gFrontEnd )
				)
				( attribute "PART_NUMBER" "E15431-004"
					( Origin gFrontEnd )
				)
				( attribute "PHYS_PAGE" "243"
					( Origin gFrontEnd )
				)
				( attribute "ROOM" "PVDDQ_KLM"
					( Origin gFrontEnd )
				)
				( attribute "ROT" "0"
					( Origin gFrontEnd )
				)
				( attribute "TOLERANCE" "20%"
					( Origin gFrontEnd )
				)
				( attribute "VALUE" "22.0UF"
					( Origin gFrontEnd )
				)
				( attribute "VER" "1"
					( Origin gFrontEnd )
				)
				( attribute "VOLTAGE" "4V"
					( Units "uVoltage" "V" 1.000000)
					( Origin gFrontEnd )
				)
				( attribute "XY" "(-6950,2800)"
					( Origin gFrontEnd )
				)
				( attribute "CHIPS_PART_NAME" "CAP_A"
					( Origin gPackager )
				)
				( attribute "CDS_PART_NAME" "CAP_A_0603V-22.0UF,4V,20%,X6S,A"
					( Origin gPackager )
				)
				( attribute "CDS_LOCATION" "C5G81"
					( Origin gPackager )
				)
				( attribute "SEC" "1"
					( Origin gFrontEnd )
				)
				( attribute "SEC_TYPE" "0603V"
					( Origin gFrontEnd )
				)
				( attribute "CDS_SEC" "1"
					( Origin gPackager )
				)
				( attribute "GROUP" "PWR_MLCC_CAP"
					( Origin gFrontEnd )
				)
				( attribute "BOM_DS" "NOPOP"
					( Origin gFrontEnd )
				)
				( objectStatus "C5G81" )
			)
			( gate "@baseboard_fab2_lib.baseboard_fab2(sch_1):page243_i59"
				( attribute "CDS_LIB" "dev_discrete"
					( Origin gPackager )
				)
				( attribute "LOCATION" "C5G82"
					( Origin gFrontEnd )
				)
				( attribute "MATERIAL" "X6S"
					( Origin gFrontEnd )
				)
				( attribute "PACK_TYPE" "0603V"
					( Origin gFrontEnd )
				)
				( attribute "PART_NUMBER" "E15431-004"
					( Origin gFrontEnd )
				)
				( attribute "PHYS_PAGE" "243"
					( Origin gFrontEnd )
				)
				( attribute "ROOM" "PVDDQ_KLM"
					( Origin gFrontEnd )
				)
				( attribute "ROT" "0"
					( Origin gFrontEnd )
				)
				( attribute "TOLERANCE" "20%"
					( Origin gFrontEnd )
				)
				( attribute "VALUE" "22.0UF"
					( Origin gFrontEnd )
				)
				( attribute "VER" "1"
					( Origin gFrontEnd )
				)
				( attribute "VOLTAGE" "4V"
					( Units "uVoltage" "V" 1.000000)
					( Origin gFrontEnd )
				)
				( attribute "XY" "(-6550,2800)"
					( Origin gFrontEnd )
				)
				( attribute "CHIPS_PART_NAME" "CAP_A"
					( Origin gPackager )
				)
				( attribute "CDS_PART_NAME" "CAP_A_0603V-22.0UF,4V,20%,X6S,A"
					( Origin gPackager )
				)
				( attribute "CDS_LOCATION" "C5G82"
					( Origin gPackager )
				)
				( attribute "SEC" "1"
					( Origin gFrontEnd )
				)
				( attribute "SEC_TYPE" "0603V"
					( Origin gFrontEnd )
				)
				( attribute "CDS_SEC" "1"
					( Origin gPackager )
				)
				( attribute "GROUP" "PWR_MLCC_CAP"
					( Origin gFrontEnd )
				)
				( attribute "BOM_DS" "NOPOP"
					( Origin gFrontEnd )
				)
				( objectStatus "C5G82" )
			)
			( gate "@baseboard_fab2_lib.baseboard_fab2(sch_1):page243_i58"
				( attribute "CDS_LIB" "dev_discrete"
					( Origin gPackager )
				)
				( attribute "LOCATION" "C5G83"
					( Origin gFrontEnd )
				)
				( attribute "MATERIAL" "X6S"
					( Origin gFrontEnd )
				)
				( attribute "PACK_TYPE" "0603V"
					( Origin gFrontEnd )
				)
				( attribute "PART_NUMBER" "E15431-004"
					( Origin gFrontEnd )
				)
				( attribute "PHYS_PAGE" "243"
					( Origin gFrontEnd )
				)
				( attribute "ROOM" "PVDDQ_KLM"
					( Origin gFrontEnd )
				)
				( attribute "ROT" "0"
					( Origin gFrontEnd )
				)
				( attribute "TOLERANCE" "20%"
					( Origin gFrontEnd )
				)
				( attribute "VALUE" "22.0UF"
					( Origin gFrontEnd )
				)
				( attribute "VER" "1"
					( Origin gFrontEnd )
				)
				( attribute "VOLTAGE" "4V"
					( Units "uVoltage" "V" 1.000000)
					( Origin gFrontEnd )
				)
				( attribute "XY" "(-6150,2800)"
					( Origin gFrontEnd )
				)
				( attribute "CHIPS_PART_NAME" "CAP_A"
					( Origin gPackager )
				)
				( attribute "CDS_PART_NAME" "CAP_A_0603V-22.0UF,4V,20%,X6S,A"
					( Origin gPackager )
				)
				( attribute "CDS_LOCATION" "C5G83"
					( Origin gPackager )
				)
				( attribute "SEC" "1"
					( Origin gFrontEnd )
				)
				( attribute "SEC_TYPE" "0603V"
					( Origin gFrontEnd )
				)
				( attribute "CDS_SEC" "1"
					( Origin gPackager )
				)
				( attribute "GROUP" "PWR_MLCC_CAP"
					( Origin gFrontEnd )
				)
				( attribute "BOM_DS" "NOPOP"
					( Origin gFrontEnd )
				)
				( objectStatus "C5G83" )
			)
			( gate "@baseboard_fab2_lib.baseboard_fab2(sch_1):page243_i57"
				( attribute "CDS_LIB" "dev_discrete"
					( Origin gPackager )
				)
				( attribute "LOCATION" "C5G84"
					( Origin gFrontEnd )
				)
				( attribute "MATERIAL" "X6S"
					( Origin gFrontEnd )
				)
				( attribute "PACK_TYPE" "0603V"
					( Origin gFrontEnd )
				)
				( attribute "PART_NUMBER" "E15431-004"
					( Origin gFrontEnd )
				)
				( attribute "PHYS_PAGE" "243"
					( Origin gFrontEnd )
				)
				( attribute "ROOM" "PVDDQ_KLM"
					( Origin gFrontEnd )
				)
				( attribute "ROT" "0"
					( Origin gFrontEnd )
				)
				( attribute "TOLERANCE" "20%"
					( Origin gFrontEnd )
				)
				( attribute "VALUE" "22.0UF"
					( Origin gFrontEnd )
				)
				( attribute "VER" "1"
					( Origin gFrontEnd )
				)
				( attribute "VOLTAGE" "4V"
					( Units "uVoltage" "V" 1.000000)
					( Origin gFrontEnd )
				)
				( attribute "XY" "(-5750,2800)"
					( Origin gFrontEnd )
				)
				( attribute "CHIPS_PART_NAME" "CAP_A"
					( Origin gPackager )
				)
				( attribute "CDS_PART_NAME" "CAP_A_0603V-22.0UF,4V,20%,X6S,A"
					( Origin gPackager )
				)
				( attribute "CDS_LOCATION" "C5G84"
					( Origin gPackager )
				)
				( attribute "SEC" "1"
					( Origin gFrontEnd )
				)
				( attribute "SEC_TYPE" "0603V"
					( Origin gFrontEnd )
				)
				( attribute "CDS_SEC" "1"
					( Origin gPackager )
				)
				( attribute "GROUP" "PWR_MLCC_CAP"
					( Origin gFrontEnd )
				)
				( attribute "BOM_DS" "NOPOP"
					( Origin gFrontEnd )
				)
				( objectStatus "C5G84" )
			)
			( gate "@baseboard_fab2_lib.baseboard_fab2(sch_1):page243_i56"
				( attribute "CDS_LIB" "dev_discrete"
					( Origin gPackager )
				)
				( attribute "LOCATION" "C5G85"
					( Origin gFrontEnd )
				)
				( attribute "MATERIAL" "X6S"
					( Origin gFrontEnd )
				)
				( attribute "PACK_TYPE" "0603V"
					( Origin gFrontEnd )
				)
				( attribute "PART_NUMBER" "E15431-004"
					( Origin gFrontEnd )
				)
				( attribute "PHYS_PAGE" "243"
					( Origin gFrontEnd )
				)
				( attribute "ROOM" "PVDDQ_KLM"
					( Origin gFrontEnd )
				)
				( attribute "ROT" "0"
					( Origin gFrontEnd )
				)
				( attribute "TOLERANCE" "20%"
					( Origin gFrontEnd )
				)
				( attribute "VALUE" "22.0UF"
					( Origin gFrontEnd )
				)
				( attribute "VER" "1"
					( Origin gFrontEnd )
				)
				( attribute "VOLTAGE" "4V"
					( Units "uVoltage" "V" 1.000000)
					( Origin gFrontEnd )
				)
				( attribute "XY" "(-5350,2800)"
					( Origin gFrontEnd )
				)
				( attribute "CHIPS_PART_NAME" "CAP_A"
					( Origin gPackager )
				)
				( attribute "CDS_PART_NAME" "CAP_A_0603V-22.0UF,4V,20%,X6S,A"
					( Origin gPackager )
				)
				( attribute "CDS_LOCATION" "C5G85"
					( Origin gPackager )
				)
				( attribute "SEC" "1"
					( Origin gFrontEnd )
				)
				( attribute "SEC_TYPE" "0603V"
					( Origin gFrontEnd )
				)
				( attribute "CDS_SEC" "1"
					( Origin gPackager )
				)
				( attribute "GROUP" "PWR_MLCC_CAP"
					( Origin gFrontEnd )
				)
				( attribute "BOM_DS" "NOPOP"
					( Origin gFrontEnd )
				)
				( objectStatus "C5G85" )
			)
			( gate "@baseboard_fab2_lib.baseboard_fab2(sch_1):page243_i55"
				( attribute "CDS_LIB" "dev_discrete"
					( Origin gPackager )
				)
				( attribute "LOCATION" "C5G86"
					( Origin gFrontEnd )
				)
				( attribute "MATERIAL" "X6S"
					( Origin gFrontEnd )
				)
				( attribute "PACK_TYPE" "0603V"
					( Origin gFrontEnd )
				)
				( attribute "PART_NUMBER" "E15431-004"
					( Origin gFrontEnd )
				)
				( attribute "PHYS_PAGE" "243"
					( Origin gFrontEnd )
				)
				( attribute "ROOM" "PVDDQ_KLM"
					( Origin gFrontEnd )
				)
				( attribute "ROT" "0"
					( Origin gFrontEnd )
				)
				( attribute "TOLERANCE" "20%"
					( Origin gFrontEnd )
				)
				( attribute "VALUE" "22.0UF"
					( Origin gFrontEnd )
				)
				( attribute "VER" "1"
					( Origin gFrontEnd )
				)
				( attribute "VOLTAGE" "4V"
					( Units "uVoltage" "V" 1.000000)
					( Origin gFrontEnd )
				)
				( attribute "XY" "(-4950,2800)"
					( Origin gFrontEnd )
				)
				( attribute "CHIPS_PART_NAME" "CAP_A"
					( Origin gPackager )
				)
				( attribute "CDS_PART_NAME" "CAP_A_0603V-22.0UF,4V,20%,X6S,A"
					( Origin gPackager )
				)
				( attribute "CDS_LOCATION" "C5G86"
					( Origin gPackager )
				)
				( attribute "SEC" "1"
					( Origin gFrontEnd )
				)
				( attribute "SEC_TYPE" "0603V"
					( Origin gFrontEnd )
				)
				( attribute "CDS_SEC" "1"
					( Origin gPackager )
				)
				( attribute "GROUP" "PWR_MLCC_CAP"
					( Origin gFrontEnd )
				)
				( attribute "BOM_DS" "NOPOP"
					( Origin gFrontEnd )
				)
				( objectStatus "C5G86" )
			)
			( gate "@baseboard_fab2_lib.baseboard_fab2(sch_1):page243_i54"
				( attribute "CDS_LIB" "dev_discrete"
					( Origin gPackager )
				)
				( attribute "LOCATION" "C5G87"
					( Origin gFrontEnd )
				)
				( attribute "MATERIAL" "X6S"
					( Origin gFrontEnd )
				)
				( attribute "PACK_TYPE" "0603V"
					( Origin gFrontEnd )
				)
				( attribute "PART_NUMBER" "E15431-004"
					( Origin gFrontEnd )
				)
				( attribute "PHYS_PAGE" "243"
					( Origin gFrontEnd )
				)
				( attribute "ROOM" "PVDDQ_KLM"
					( Origin gFrontEnd )
				)
				( attribute "ROT" "0"
					( Origin gFrontEnd )
				)
				( attribute "TOLERANCE" "20%"
					( Origin gFrontEnd )
				)
				( attribute "VALUE" "22.0UF"
					( Origin gFrontEnd )
				)
				( attribute "VER" "1"
					( Origin gFrontEnd )
				)
				( attribute "VOLTAGE" "4V"
					( Units "uVoltage" "V" 1.000000)
					( Origin gFrontEnd )
				)
				( attribute "XY" "(-4550,2775)"
					( Origin gFrontEnd )
				)
				( attribute "CHIPS_PART_NAME" "CAP_A"
					( Origin gPackager )
				)
				( attribute "CDS_PART_NAME" "CAP_A_0603V-22.0UF,4V,20%,X6S,A"
					( Origin gPackager )
				)
				( attribute "CDS_LOCATION" "C5G87"
					( Origin gPackager )
				)
				( attribute "SEC" "1"
					( Origin gFrontEnd )
				)
				( attribute "SEC_TYPE" "0603V"
					( Origin gFrontEnd )
				)
				( attribute "CDS_SEC" "1"
					( Origin gPackager )
				)
				( attribute "GROUP" "PWR_MLCC_CAP"
					( Origin gFrontEnd )
				)
				( attribute "BOM_DS" "NOPOP"
					( Origin gFrontEnd )
				)
				( objectStatus "C5G87" )
			)
			( gate "@baseboard_fab2_lib.baseboard_fab2(sch_1):page243_i53"
				( attribute "CDS_LIB" "dev_discrete"
					( Origin gPackager )
				)
				( attribute "LOCATION" "C5G79"
					( Origin gFrontEnd )
				)
				( attribute "MATERIAL" "X6S"
					( Origin gFrontEnd )
				)
				( attribute "PACK_TYPE" "0603V"
					( Origin gFrontEnd )
				)
				( attribute "PART_NUMBER" "E15431-004"
					( Origin gFrontEnd )
				)
				( attribute "PHYS_PAGE" "243"
					( Origin gFrontEnd )
				)
				( attribute "ROOM" "PVDDQ_KLM"
					( Origin gFrontEnd )
				)
				( attribute "ROT" "0"
					( Origin gFrontEnd )
				)
				( attribute "TOLERANCE" "20%"
					( Origin gFrontEnd )
				)
				( attribute "VALUE" "22.0UF"
					( Origin gFrontEnd )
				)
				( attribute "VER" "1"
					( Origin gFrontEnd )
				)
				( attribute "VOLTAGE" "4V"
					( Units "uVoltage" "V" 1.000000)
					( Origin gFrontEnd )
				)
				( attribute "XY" "(-7750,2800)"
					( Origin gFrontEnd )
				)
				( attribute "CHIPS_PART_NAME" "CAP_A"
					( Origin gPackager )
				)
				( attribute "CDS_PART_NAME" "CAP_A_0603V-22.0UF,4V,20%,X6S,A"
					( Origin gPackager )
				)
				( attribute "CDS_LOCATION" "C5G79"
					( Origin gPackager )
				)
				( attribute "SEC" "1"
					( Origin gFrontEnd )
				)
				( attribute "SEC_TYPE" "0603V"
					( Origin gFrontEnd )
				)
				( attribute "CDS_SEC" "1"
					( Origin gPackager )
				)
				( attribute "GROUP" "PWR_MLCC_CAP"
					( Origin gFrontEnd )
				)
				( attribute "BOM_DS" "NOPOP"
					( Origin gFrontEnd )
				)
				( objectStatus "C5G79" )
			)
			( gate "@baseboard_fab2_lib.baseboard_fab2(sch_1):page219_i138"
				( attribute "CDS_LIB" "mstr_discrete"
					( Origin gPackager )
				)
				( attribute "LOCATION" "CT47"
					( Origin gFrontEnd )
				)
				( attribute "MATERIAL" "X7R"
					( Origin gFrontEnd )
				)
				( attribute "PACK_TYPE" "0402LF"
					( Origin gFrontEnd )
				)
				( attribute "PART_NUMBER" "A36096-046"
					( Origin gFrontEnd )
				)
				( attribute "PHYS_PAGE" "219"
					( Origin gFrontEnd )
				)
				( attribute "POP" "NOPOP"
					( Origin gFrontEnd )
				)
				( attribute "ROOM" "VDDQ_KLM_PWR_VR"
					( Origin gFrontEnd )
				)
				( attribute "ROT" "0"
					( Origin gFrontEnd )
				)
				( attribute "TOLERANCE" "10%"
					( Origin gFrontEnd )
				)
				( attribute "VALUE" "1000PF"
					( Origin gFrontEnd )
				)
				( attribute "VER" "1"
					( Origin gFrontEnd )
				)
				( attribute "VOLTAGE" "50V"
					( Units "uVoltage" "V" 1.000000)
					( Origin gFrontEnd )
				)
				( attribute "XY" "(2875,-600)"
					( Origin gFrontEnd )
				)
				( attribute "CHIPS_PART_NAME" "CAP"
					( Origin gPackager )
				)
				( attribute "CDS_PART_NAME" "CAP_0402LF-1000PF,50V,10%,X7R,A"
					( Origin gPackager )
				)
				( attribute "CDS_LOCATION" "CT47"
					( Origin gPackager )
				)
				( attribute "SEC" "1"
					( Origin gFrontEnd )
				)
				( attribute "SEC_TYPE" "0402LF"
					( Origin gFrontEnd )
				)
				( attribute "CDS_SEC" "1"
					( Origin gPackager )
				)
				( attribute "BOM_SS" "NOPOP"
					( Origin gFrontEnd )
				)
				( objectStatus "CT47" )
			)
			( gate "@baseboard_fab2_lib.baseboard_fab2(sch_1):page203_i119"
				( attribute "CDS_LIB" "mstr_discrete"
					( Origin gPackager )
				)
				( attribute "LOCATION" "CT41"
					( Origin gFrontEnd )
				)
				( attribute "MATERIAL" "X7R"
					( Origin gFrontEnd )
				)
				( attribute "PACK_TYPE" "0402LF"
					( Origin gFrontEnd )
				)
				( attribute "PART_NUMBER" "A36096-046"
					( Origin gFrontEnd )
				)
				( attribute "PHYS_PAGE" "203"
					( Origin gFrontEnd )
				)
				( attribute "POP" "NOPOP"
					( Origin gFrontEnd )
				)
				( attribute "ROOM" "VDDQ_KLM_PWR_VR"
					( Origin gFrontEnd )
				)
				( attribute "ROT" "0"
					( Origin gFrontEnd )
				)
				( attribute "TOLERANCE" "10%"
					( Origin gFrontEnd )
				)
				( attribute "VALUE" "1000PF"
					( Origin gFrontEnd )
				)
				( attribute "VER" "1"
					( Origin gFrontEnd )
				)
				( attribute "VOLTAGE" "50V"
					( Units "uVoltage" "V" 1.000000)
					( Origin gFrontEnd )
				)
				( attribute "XY" "(-1975,800)"
					( Origin gFrontEnd )
				)
				( attribute "CHIPS_PART_NAME" "CAP"
					( Origin gPackager )
				)
				( attribute "CDS_PART_NAME" "CAP_0402LF-1000PF,50V,10%,X7R,A"
					( Origin gPackager )
				)
				( attribute "CDS_LOCATION" "CT41"
					( Origin gPackager )
				)
				( attribute "SEC" "1"
					( Origin gFrontEnd )
				)
				( attribute "SEC_TYPE" "0402LF"
					( Origin gFrontEnd )
				)
				( attribute "CDS_SEC" "1"
					( Origin gPackager )
				)
				( objectStatus "CT41" )
			)
			( gate "@baseboard_fab2_lib.baseboard_fab2(sch_1):page203_i118"
				( attribute "CDS_LIB" "mstr_discrete"
					( Origin gPackager )
				)
				( attribute "LOCATION" "CT38"
					( Origin gFrontEnd )
				)
				( attribute "MATERIAL" "X7R"
					( Origin gFrontEnd )
				)
				( attribute "PACK_TYPE" "0402LF"
					( Origin gFrontEnd )
				)
				( attribute "PART_NUMBER" "A36096-046"
					( Origin gFrontEnd )
				)
				( attribute "PHYS_PAGE" "203"
					( Origin gFrontEnd )
				)
				( attribute "POP" "NOPOP"
					( Origin gFrontEnd )
				)
				( attribute "ROOM" "VDDQ_KLM_PWR_VR"
					( Origin gFrontEnd )
				)
				( attribute "ROT" "0"
					( Origin gFrontEnd )
				)
				( attribute "TOLERANCE" "10%"
					( Origin gFrontEnd )
				)
				( attribute "VALUE" "1000PF"
					( Origin gFrontEnd )
				)
				( attribute "VER" "1"
					( Origin gFrontEnd )
				)
				( attribute "VOLTAGE" "50V"
					( Units "uVoltage" "V" 1.000000)
					( Origin gFrontEnd )
				)
				( attribute "XY" "(-1950,3500)"
					( Origin gFrontEnd )
				)
				( attribute "CHIPS_PART_NAME" "CAP"
					( Origin gPackager )
				)
				( attribute "CDS_PART_NAME" "CAP_0402LF-1000PF,50V,10%,X7R,A"
					( Origin gPackager )
				)
				( attribute "CDS_LOCATION" "CT38"
					( Origin gPackager )
				)
				( attribute "SEC" "1"
					( Origin gFrontEnd )
				)
				( attribute "SEC_TYPE" "0402LF"
					( Origin gFrontEnd )
				)
				( attribute "CDS_SEC" "1"
					( Origin gPackager )
				)
				( objectStatus "CT38" )
			)
			( gate "@baseboard_fab2_lib.baseboard_fab2(sch_1):page242_i53"
				( attribute "CDS_LIB" "dev_discrete"
					( Origin gPackager )
				)
				( attribute "LOCATION" "C5G41"
					( Origin gFrontEnd )
				)
				( attribute "MATERIAL" "X6S"
					( Origin gFrontEnd )
				)
				( attribute "PACK_TYPE" "0603V"
					( Origin gFrontEnd )
				)
				( attribute "PART_NUMBER" "E15431-004"
					( Origin gFrontEnd )
				)
				( attribute "PHYS_PAGE" "242"
					( Origin gFrontEnd )
				)
				( attribute "ROOM" "PVDDQ_KLM"
					( Origin gFrontEnd )
				)
				( attribute "ROT" "0"
					( Origin gFrontEnd )
				)
				( attribute "TOLERANCE" "20%"
					( Origin gFrontEnd )
				)
				( attribute "VALUE" "22.0UF"
					( Origin gFrontEnd )
				)
				( attribute "VER" "1"
					( Origin gFrontEnd )
				)
				( attribute "VOLTAGE" "4V"
					( Units "uVoltage" "V" 1.000000)
					( Origin gFrontEnd )
				)
				( attribute "XY" "(-7750,2800)"
					( Origin gFrontEnd )
				)
				( attribute "CHIPS_PART_NAME" "CAP_A"
					( Origin gPackager )
				)
				( attribute "CDS_PART_NAME" "CAP_A_0603V-22.0UF,4V,20%,X6S,A"
					( Origin gPackager )
				)
				( attribute "CDS_LOCATION" "C5G41"
					( Origin gPackager )
				)
				( attribute "SEC" "1"
					( Origin gFrontEnd )
				)
				( attribute "SEC_TYPE" "0603V"
					( Origin gFrontEnd )
				)
				( attribute "CDS_SEC" "1"
					( Origin gPackager )
				)
				( attribute "GROUP" "PWR_MLCC_CAP"
					( Origin gFrontEnd )
				)
				( attribute "BOM_DS" "NOPOP"
					( Origin gFrontEnd )
				)
				( objectStatus "C5G41" )
			)
			( gate "@baseboard_fab2_lib.baseboard_fab2(sch_1):page242_i54"
				( attribute "CDS_LIB" "dev_discrete"
					( Origin gPackager )
				)
				( attribute "LOCATION" "C5G42"
					( Origin gFrontEnd )
				)
				( attribute "MATERIAL" "X6S"
					( Origin gFrontEnd )
				)
				( attribute "PACK_TYPE" "0603V"
					( Origin gFrontEnd )
				)
				( attribute "PART_NUMBER" "E15431-004"
					( Origin gFrontEnd )
				)
				( attribute "PHYS_PAGE" "242"
					( Origin gFrontEnd )
				)
				( attribute "ROOM" "PVDDQ_KLM"
					( Origin gFrontEnd )
				)
				( attribute "ROT" "0"
					( Origin gFrontEnd )
				)
				( attribute "TOLERANCE" "20%"
					( Origin gFrontEnd )
				)
				( attribute "VALUE" "22.0UF"
					( Origin gFrontEnd )
				)
				( attribute "VER" "1"
					( Origin gFrontEnd )
				)
				( attribute "VOLTAGE" "4V"
					( Units "uVoltage" "V" 1.000000)
					( Origin gFrontEnd )
				)
				( attribute "XY" "(-7350,2800)"
					( Origin gFrontEnd )
				)
				( attribute "CHIPS_PART_NAME" "CAP_A"
					( Origin gPackager )
				)
				( attribute "CDS_PART_NAME" "CAP_A_0603V-22.0UF,4V,20%,X6S,A"
					( Origin gPackager )
				)
				( attribute "CDS_LOCATION" "C5G42"
					( Origin gPackager )
				)
				( attribute "SEC" "1"
					( Origin gFrontEnd )
				)
				( attribute "SEC_TYPE" "0603V"
					( Origin gFrontEnd )
				)
				( attribute "CDS_SEC" "1"
					( Origin gPackager )
				)
				( attribute "GROUP" "PWR_MLCC_CAP"
					( Origin gFrontEnd )
				)
				( attribute "BOM_DS" "NOPOP"
					( Origin gFrontEnd )
				)
				( objectStatus "C5G42" )
			)
			( gate "@baseboard_fab2_lib.baseboard_fab2(sch_1):page242_i55"
				( attribute "CDS_LIB" "dev_discrete"
					( Origin gPackager )
				)
				( attribute "LOCATION" "C5G44"
					( Origin gFrontEnd )
				)
				( attribute "MATERIAL" "X6S"
					( Origin gFrontEnd )
				)
				( attribute "PACK_TYPE" "0603V"
					( Origin gFrontEnd )
				)
				( attribute "PART_NUMBER" "E15431-004"
					( Origin gFrontEnd )
				)
				( attribute "PHYS_PAGE" "242"
					( Origin gFrontEnd )
				)
				( attribute "ROOM" "PVDDQ_KLM"
					( Origin gFrontEnd )
				)
				( attribute "ROT" "0"
					( Origin gFrontEnd )
				)
				( attribute "TOLERANCE" "20%"
					( Origin gFrontEnd )
				)
				( attribute "VALUE" "22.0UF"
					( Origin gFrontEnd )
				)
				( attribute "VER" "1"
					( Origin gFrontEnd )
				)
				( attribute "VOLTAGE" "4V"
					( Units "uVoltage" "V" 1.000000)
					( Origin gFrontEnd )
				)
				( attribute "XY" "(-6550,2800)"
					( Origin gFrontEnd )
				)
				( attribute "CHIPS_PART_NAME" "CAP_A"
					( Origin gPackager )
				)
				( attribute "CDS_PART_NAME" "CAP_A_0603V-22.0UF,4V,20%,X6S,A"
					( Origin gPackager )
				)
				( attribute "SEC" "1"
					( Origin gFrontEnd )
				)
				( attribute "SEC_TYPE" "0603V"
					( Origin gFrontEnd )
				)
				( attribute "CDS_LOCATION" "C5G44"
					( Origin gPackager )
				)
				( attribute "CDS_SEC" "1"
					( Origin gPackager )
				)
				( attribute "GROUP" "PWR_MLCC_CAP"
					( Origin gFrontEnd )
				)
				( attribute "BOM_DS" "NOPOP"
					( Origin gFrontEnd )
				)
				( objectStatus "C5G44" )
			)
			( gate "@baseboard_fab2_lib.baseboard_fab2(sch_1):page242_i56"
				( attribute "CDS_LIB" "dev_discrete"
					( Origin gPackager )
				)
				( attribute "LOCATION" "C5G43"
					( Origin gFrontEnd )
				)
				( attribute "MATERIAL" "X6S"
					( Origin gFrontEnd )
				)
				( attribute "PACK_TYPE" "0603V"
					( Origin gFrontEnd )
				)
				( attribute "PART_NUMBER" "E15431-004"
					( Origin gFrontEnd )
				)
				( attribute "PHYS_PAGE" "242"
					( Origin gFrontEnd )
				)
				( attribute "ROOM" "PVDDQ_KLM"
					( Origin gFrontEnd )
				)
				( attribute "ROT" "0"
					( Origin gFrontEnd )
				)
				( attribute "TOLERANCE" "20%"
					( Origin gFrontEnd )
				)
				( attribute "VALUE" "22.0UF"
					( Origin gFrontEnd )
				)
				( attribute "VER" "1"
					( Origin gFrontEnd )
				)
				( attribute "VOLTAGE" "4V"
					( Units "uVoltage" "V" 1.000000)
					( Origin gFrontEnd )
				)
				( attribute "XY" "(-6950,2800)"
					( Origin gFrontEnd )
				)
				( attribute "CHIPS_PART_NAME" "CAP_A"
					( Origin gPackager )
				)
				( attribute "CDS_PART_NAME" "CAP_A_0603V-22.0UF,4V,20%,X6S,A"
					( Origin gPackager )
				)
				( attribute "CDS_LOCATION" "C5G43"
					( Origin gPackager )
				)
				( attribute "SEC" "1"
					( Origin gFrontEnd )
				)
				( attribute "SEC_TYPE" "0603V"
					( Origin gFrontEnd )
				)
				( attribute "CDS_SEC" "1"
					( Origin gPackager )
				)
				( attribute "GROUP" "PWR_MLCC_CAP"
					( Origin gFrontEnd )
				)
				( attribute "BOM_DS" "NOPOP"
					( Origin gFrontEnd )
				)
				( objectStatus "C5G43" )
			)
			( gate "@baseboard_fab2_lib.baseboard_fab2(sch_1):page242_i57"
				( attribute "CDS_LIB" "dev_discrete"
					( Origin gPackager )
				)
				( attribute "LOCATION" "C5G48"
					( Origin gFrontEnd )
				)
				( attribute "MATERIAL" "X6S"
					( Origin gFrontEnd )
				)
				( attribute "PACK_TYPE" "0603V"
					( Origin gFrontEnd )
				)
				( attribute "PART_NUMBER" "E15431-004"
					( Origin gFrontEnd )
				)
				( attribute "PHYS_PAGE" "242"
					( Origin gFrontEnd )
				)
				( attribute "ROOM" "PVDDQ_KLM"
					( Origin gFrontEnd )
				)
				( attribute "ROT" "0"
					( Origin gFrontEnd )
				)
				( attribute "TOLERANCE" "20%"
					( Origin gFrontEnd )
				)
				( attribute "VALUE" "22.0UF"
					( Origin gFrontEnd )
				)
				( attribute "VER" "1"
					( Origin gFrontEnd )
				)
				( attribute "VOLTAGE" "4V"
					( Units "uVoltage" "V" 1.000000)
					( Origin gFrontEnd )
				)
				( attribute "XY" "(-4950,2800)"
					( Origin gFrontEnd )
				)
				( attribute "CHIPS_PART_NAME" "CAP_A"
					( Origin gPackager )
				)
				( attribute "CDS_PART_NAME" "CAP_A_0603V-22.0UF,4V,20%,X6S,A"
					( Origin gPackager )
				)
				( attribute "SEC" "1"
					( Origin gFrontEnd )
				)
				( attribute "SEC_TYPE" "0603V"
					( Origin gFrontEnd )
				)
				( attribute "CDS_LOCATION" "C5G48"
					( Origin gPackager )
				)
				( attribute "CDS_SEC" "1"
					( Origin gPackager )
				)
				( attribute "GROUP" "PWR_MLCC_CAP"
					( Origin gFrontEnd )
				)
				( attribute "BOM_DS" "NOPOP"
					( Origin gFrontEnd )
				)
				( objectStatus "C5G48" )
			)
			( gate "@baseboard_fab2_lib.baseboard_fab2(sch_1):page242_i58"
				( attribute "CDS_LIB" "dev_discrete"
					( Origin gPackager )
				)
				( attribute "LOCATION" "C5G47"
					( Origin gFrontEnd )
				)
				( attribute "MATERIAL" "X6S"
					( Origin gFrontEnd )
				)
				( attribute "PACK_TYPE" "0603V"
					( Origin gFrontEnd )
				)
				( attribute "PART_NUMBER" "E15431-004"
					( Origin gFrontEnd )
				)
				( attribute "PHYS_PAGE" "242"
					( Origin gFrontEnd )
				)
				( attribute "ROOM" "PVDDQ_KLM"
					( Origin gFrontEnd )
				)
				( attribute "ROT" "0"
					( Origin gFrontEnd )
				)
				( attribute "TOLERANCE" "20%"
					( Origin gFrontEnd )
				)
				( attribute "VALUE" "22.0UF"
					( Origin gFrontEnd )
				)
				( attribute "VER" "1"
					( Origin gFrontEnd )
				)
				( attribute "VOLTAGE" "4V"
					( Units "uVoltage" "V" 1.000000)
					( Origin gFrontEnd )
				)
				( attribute "XY" "(-5350,2800)"
					( Origin gFrontEnd )
				)
				( attribute "CHIPS_PART_NAME" "CAP_A"
					( Origin gPackager )
				)
				( attribute "CDS_PART_NAME" "CAP_A_0603V-22.0UF,4V,20%,X6S,A"
					( Origin gPackager )
				)
				( attribute "SEC" "1"
					( Origin gFrontEnd )
				)
				( attribute "SEC_TYPE" "0603V"
					( Origin gFrontEnd )
				)
				( attribute "CDS_LOCATION" "C5G47"
					( Origin gPackager )
				)
				( attribute "CDS_SEC" "1"
					( Origin gPackager )
				)
				( attribute "GROUP" "PWR_MLCC_CAP"
					( Origin gFrontEnd )
				)
				( attribute "BOM_DS" "NOPOP"
					( Origin gFrontEnd )
				)
				( objectStatus "C5G47" )
			)
			( gate "@baseboard_fab2_lib.baseboard_fab2(sch_1):page242_i59"
				( attribute "CDS_LIB" "dev_discrete"
					( Origin gPackager )
				)
				( attribute "LOCATION" "C5G46"
					( Origin gFrontEnd )
				)
				( attribute "MATERIAL" "X6S"
					( Origin gFrontEnd )
				)
				( attribute "PACK_TYPE" "0603V"
					( Origin gFrontEnd )
				)
				( attribute "PART_NUMBER" "E15431-004"
					( Origin gFrontEnd )
				)
				( attribute "PHYS_PAGE" "242"
					( Origin gFrontEnd )
				)
				( attribute "ROOM" "PVDDQ_KLM"
					( Origin gFrontEnd )
				)
				( attribute "ROT" "0"
					( Origin gFrontEnd )
				)
				( attribute "TOLERANCE" "20%"
					( Origin gFrontEnd )
				)
				( attribute "VALUE" "22.0UF"
					( Origin gFrontEnd )
				)
				( attribute "VER" "1"
					( Origin gFrontEnd )
				)
				( attribute "VOLTAGE" "4V"
					( Units "uVoltage" "V" 1.000000)
					( Origin gFrontEnd )
				)
				( attribute "XY" "(-5750,2800)"
					( Origin gFrontEnd )
				)
				( attribute "CHIPS_PART_NAME" "CAP_A"
					( Origin gPackager )
				)
				( attribute "CDS_PART_NAME" "CAP_A_0603V-22.0UF,4V,20%,X6S,A"
					( Origin gPackager )
				)
				( attribute "SEC" "1"
					( Origin gFrontEnd )
				)
				( attribute "SEC_TYPE" "0603V"
					( Origin gFrontEnd )
				)
				( attribute "CDS_LOCATION" "C5G46"
					( Origin gPackager )
				)
				( attribute "CDS_SEC" "1"
					( Origin gPackager )
				)
				( attribute "GROUP" "PWR_MLCC_CAP"
					( Origin gFrontEnd )
				)
				( attribute "BOM_DS" "NOPOP"
					( Origin gFrontEnd )
				)
				( objectStatus "C5G46" )
			)
			( gate "@baseboard_fab2_lib.baseboard_fab2(sch_1):page242_i60"
				( attribute "CDS_LIB" "dev_discrete"
					( Origin gPackager )
				)
				( attribute "LOCATION" "C5G45"
					( Origin gFrontEnd )
				)
				( attribute "MATERIAL" "X6S"
					( Origin gFrontEnd )
				)
				( attribute "PACK_TYPE" "0603V"
					( Origin gFrontEnd )
				)
				( attribute "PART_NUMBER" "E15431-004"
					( Origin gFrontEnd )
				)
				( attribute "PHYS_PAGE" "242"
					( Origin gFrontEnd )
				)
				( attribute "ROOM" "PVDDQ_KLM"
					( Origin gFrontEnd )
				)
				( attribute "ROT" "0"
					( Origin gFrontEnd )
				)
				( attribute "TOLERANCE" "20%"
					( Origin gFrontEnd )
				)
				( attribute "VALUE" "22.0UF"
					( Origin gFrontEnd )
				)
				( attribute "VER" "1"
					( Origin gFrontEnd )
				)
				( attribute "VOLTAGE" "4V"
					( Units "uVoltage" "V" 1.000000)
					( Origin gFrontEnd )
				)
				( attribute "XY" "(-6150,2800)"
					( Origin gFrontEnd )
				)
				( attribute "CHIPS_PART_NAME" "CAP_A"
					( Origin gPackager )
				)
				( attribute "CDS_PART_NAME" "CAP_A_0603V-22.0UF,4V,20%,X6S,A"
					( Origin gPackager )
				)
				( attribute "SEC" "1"
					( Origin gFrontEnd )
				)
				( attribute "SEC_TYPE" "0603V"
					( Origin gFrontEnd )
				)
				( attribute "CDS_LOCATION" "C5G45"
					( Origin gPackager )
				)
				( attribute "CDS_SEC" "1"
					( Origin gPackager )
				)
				( attribute "GROUP" "PWR_MLCC_CAP"
					( Origin gFrontEnd )
				)
				( attribute "BOM_DS" "NOPOP"
					( Origin gFrontEnd )
				)
				( objectStatus "C5G45" )
			)
			( gate "@baseboard_fab2_lib.baseboard_fab2(sch_1):page242_i61"
				( attribute "CDS_LIB" "dev_discrete"
					( Origin gPackager )
				)
				( attribute "LOCATION" "C5G49"
					( Origin gFrontEnd )
				)
				( attribute "MATERIAL" "X6S"
					( Origin gFrontEnd )
				)
				( attribute "PACK_TYPE" "0603V"
					( Origin gFrontEnd )
				)
				( attribute "PART_NUMBER" "E15431-004"
					( Origin gFrontEnd )
				)
				( attribute "PHYS_PAGE" "242"
					( Origin gFrontEnd )
				)
				( attribute "ROOM" "PVDDQ_KLM"
					( Origin gFrontEnd )
				)
				( attribute "ROT" "0"
					( Origin gFrontEnd )
				)
				( attribute "TOLERANCE" "20%"
					( Origin gFrontEnd )
				)
				( attribute "VALUE" "22.0UF"
					( Origin gFrontEnd )
				)
				( attribute "VER" "1"
					( Origin gFrontEnd )
				)
				( attribute "VOLTAGE" "4V"
					( Units "uVoltage" "V" 1.000000)
					( Origin gFrontEnd )
				)
				( attribute "XY" "(-4550,2800)"
					( Origin gFrontEnd )
				)
				( attribute "CHIPS_PART_NAME" "CAP_A"
					( Origin gPackager )
				)
				( attribute "CDS_PART_NAME" "CAP_A_0603V-22.0UF,4V,20%,X6S,A"
					( Origin gPackager )
				)
				( attribute "SEC" "1"
					( Origin gFrontEnd )
				)
				( attribute "SEC_TYPE" "0603V"
					( Origin gFrontEnd )
				)
				( attribute "CDS_LOCATION" "C5G49"
					( Origin gPackager )
				)
				( attribute "CDS_SEC" "1"
					( Origin gPackager )
				)
				( attribute "GROUP" "PWR_MLCC_CAP"
					( Origin gFrontEnd )
				)
				( attribute "BOM_DS" "NOPOP"
					( Origin gFrontEnd )
				)
				( objectStatus "C5G49" )
			)
			( gate "@baseboard_fab2_lib.baseboard_fab2(sch_1):page242_i62"
				( attribute "CDS_LIB" "dev_discrete"
					( Origin gPackager )
				)
				( attribute "LOCATION" "C5G54"
					( Origin gFrontEnd )
				)
				( attribute "MATERIAL" "X6S"
					( Origin gFrontEnd )
				)
				( attribute "PACK_TYPE" "0603V"
					( Origin gFrontEnd )
				)
				( attribute "PART_NUMBER" "E15431-004"
					( Origin gFrontEnd )
				)
				( attribute "PHYS_PAGE" "242"
					( Origin gFrontEnd )
				)
				( attribute "ROOM" "PVDDQ_KLM"
					( Origin gFrontEnd )
				)
				( attribute "ROT" "0"
					( Origin gFrontEnd )
				)
				( attribute "TOLERANCE" "20%"
					( Origin gFrontEnd )
				)
				( attribute "VALUE" "22.0UF"
					( Origin gFrontEnd )
				)
				( attribute "VER" "1"
					( Origin gFrontEnd )
				)
				( attribute "VOLTAGE" "4V"
					( Units "uVoltage" "V" 1.000000)
					( Origin gFrontEnd )
				)
				( attribute "XY" "(-6150,1850)"
					( Origin gFrontEnd )
				)
				( attribute "CHIPS_PART_NAME" "CAP_A"
					( Origin gPackager )
				)
				( attribute "CDS_PART_NAME" "CAP_A_0603V-22.0UF,4V,20%,X6S,A"
					( Origin gPackager )
				)
				( attribute "SEC" "1"
					( Origin gFrontEnd )
				)
				( attribute "SEC_TYPE" "0603V"
					( Origin gFrontEnd )
				)
				( attribute "CDS_LOCATION" "C5G54"
					( Origin gPackager )
				)
				( attribute "CDS_SEC" "1"
					( Origin gPackager )
				)
				( attribute "GROUP" "PWR_MLCC_CAP"
					( Origin gFrontEnd )
				)
				( attribute "BOM_DS" "NOPOP"
					( Origin gFrontEnd )
				)
				( objectStatus "C5G54" )
			)
			( gate "@baseboard_fab2_lib.baseboard_fab2(sch_1):page242_i63"
				( attribute "CDS_LIB" "dev_discrete"
					( Origin gPackager )
				)
				( attribute "LOCATION" "C5G58"
					( Origin gFrontEnd )
				)
				( attribute "MATERIAL" "X6S"
					( Origin gFrontEnd )
				)
				( attribute "PACK_TYPE" "0603V"
					( Origin gFrontEnd )
				)
				( attribute "PART_NUMBER" "E15431-004"
					( Origin gFrontEnd )
				)
				( attribute "PHYS_PAGE" "242"
					( Origin gFrontEnd )
				)
				( attribute "ROOM" "PVDDQ_KLM"
					( Origin gFrontEnd )
				)
				( attribute "ROT" "0"
					( Origin gFrontEnd )
				)
				( attribute "TOLERANCE" "20%"
					( Origin gFrontEnd )
				)
				( attribute "VALUE" "22.0UF"
					( Origin gFrontEnd )
				)
				( attribute "VER" "1"
					( Origin gFrontEnd )
				)
				( attribute "VOLTAGE" "4V"
					( Units "uVoltage" "V" 1.000000)
					( Origin gFrontEnd )
				)
				( attribute "XY" "(-4550,1850)"
					( Origin gFrontEnd )
				)
				( attribute "CHIPS_PART_NAME" "CAP_A"
					( Origin gPackager )
				)
				( attribute "CDS_PART_NAME" "CAP_A_0603V-22.0UF,4V,20%,X6S,A"
					( Origin gPackager )
				)
				( attribute "SEC" "1"
					( Origin gFrontEnd )
				)
				( attribute "SEC_TYPE" "0603V"
					( Origin gFrontEnd )
				)
				( attribute "CDS_LOCATION" "C5G58"
					( Origin gPackager )
				)
				( attribute "CDS_SEC" "1"
					( Origin gPackager )
				)
				( attribute "GROUP" "PWR_MLCC_CAP"
					( Origin gFrontEnd )
				)
				( attribute "BOM_DS" "NOPOP"
					( Origin gFrontEnd )
				)
				( objectStatus "C5G58" )
			)
			( gate "@baseboard_fab2_lib.baseboard_fab2(sch_1):page242_i64"
				( attribute "CDS_LIB" "dev_discrete"
					( Origin gPackager )
				)
				( attribute "LOCATION" "C5G57"
					( Origin gFrontEnd )
				)
				( attribute "MATERIAL" "X6S"
					( Origin gFrontEnd )
				)
				( attribute "PACK_TYPE" "0603V"
					( Origin gFrontEnd )
				)
				( attribute "PART_NUMBER" "E15431-004"
					( Origin gFrontEnd )
				)
				( attribute "PHYS_PAGE" "242"
					( Origin gFrontEnd )
				)
				( attribute "ROOM" "PVDDQ_KLM"
					( Origin gFrontEnd )
				)
				( attribute "ROT" "0"
					( Origin gFrontEnd )
				)
				( attribute "TOLERANCE" "20%"
					( Origin gFrontEnd )
				)
				( attribute "VALUE" "22.0UF"
					( Origin gFrontEnd )
				)
				( attribute "VER" "1"
					( Origin gFrontEnd )
				)
				( attribute "VOLTAGE" "4V"
					( Units "uVoltage" "V" 1.000000)
					( Origin gFrontEnd )
				)
				( attribute "XY" "(-4950,1850)"
					( Origin gFrontEnd )
				)
				( attribute "CHIPS_PART_NAME" "CAP_A"
					( Origin gPackager )
				)
				( attribute "CDS_PART_NAME" "CAP_A_0603V-22.0UF,4V,20%,X6S,A"
					( Origin gPackager )
				)
				( attribute "SEC" "1"
					( Origin gFrontEnd )
				)
				( attribute "SEC_TYPE" "0603V"
					( Origin gFrontEnd )
				)
				( attribute "CDS_LOCATION" "C5G57"
					( Origin gPackager )
				)
				( attribute "CDS_SEC" "1"
					( Origin gPackager )
				)
				( attribute "GROUP" "PWR_MLCC_CAP"
					( Origin gFrontEnd )
				)
				( attribute "BOM_DS" "NOPOP"
					( Origin gFrontEnd )
				)
				( objectStatus "C5G57" )
			)
			( gate "@baseboard_fab2_lib.baseboard_fab2(sch_1):page242_i65"
				( attribute "CDS_LIB" "dev_discrete"
					( Origin gPackager )
				)
				( attribute "LOCATION" "C5G56"
					( Origin gFrontEnd )
				)
				( attribute "MATERIAL" "X6S"
					( Origin gFrontEnd )
				)
				( attribute "PACK_TYPE" "0603V"
					( Origin gFrontEnd )
				)
				( attribute "PART_NUMBER" "E15431-004"
					( Origin gFrontEnd )
				)
				( attribute "PHYS_PAGE" "242"
					( Origin gFrontEnd )
				)
				( attribute "ROOM" "PVDDQ_KLM"
					( Origin gFrontEnd )
				)
				( attribute "ROT" "0"
					( Origin gFrontEnd )
				)
				( attribute "TOLERANCE" "20%"
					( Origin gFrontEnd )
				)
				( attribute "VALUE" "22.0UF"
					( Origin gFrontEnd )
				)
				( attribute "VER" "1"
					( Origin gFrontEnd )
				)
				( attribute "VOLTAGE" "4V"
					( Units "uVoltage" "V" 1.000000)
					( Origin gFrontEnd )
				)
				( attribute "XY" "(-5350,1850)"
					( Origin gFrontEnd )
				)
				( attribute "CHIPS_PART_NAME" "CAP_A"
					( Origin gPackager )
				)
				( attribute "CDS_PART_NAME" "CAP_A_0603V-22.0UF,4V,20%,X6S,A"
					( Origin gPackager )
				)
				( attribute "SEC" "1"
					( Origin gFrontEnd )
				)
				( attribute "SEC_TYPE" "0603V"
					( Origin gFrontEnd )
				)
				( attribute "CDS_LOCATION" "C5G56"
					( Origin gPackager )
				)
				( attribute "CDS_SEC" "1"
					( Origin gPackager )
				)
				( attribute "GROUP" "PWR_MLCC_CAP"
					( Origin gFrontEnd )
				)
				( attribute "BOM_DS" "NOPOP"
					( Origin gFrontEnd )
				)
				( objectStatus "C5G56" )
			)
			( gate "@baseboard_fab2_lib.baseboard_fab2(sch_1):page242_i66"
				( attribute "CDS_LIB" "dev_discrete"
					( Origin gPackager )
				)
				( attribute "LOCATION" "C5G55"
					( Origin gFrontEnd )
				)
				( attribute "MATERIAL" "X6S"
					( Origin gFrontEnd )
				)
				( attribute "PACK_TYPE" "0603V"
					( Origin gFrontEnd )
				)
				( attribute "PART_NUMBER" "E15431-004"
					( Origin gFrontEnd )
				)
				( attribute "PHYS_PAGE" "242"
					( Origin gFrontEnd )
				)
				( attribute "ROOM" "PVDDQ_KLM"
					( Origin gFrontEnd )
				)
				( attribute "ROT" "0"
					( Origin gFrontEnd )
				)
				( attribute "TOLERANCE" "20%"
					( Origin gFrontEnd )
				)
				( attribute "VALUE" "22.0UF"
					( Origin gFrontEnd )
				)
				( attribute "VER" "1"
					( Origin gFrontEnd )
				)
				( attribute "VOLTAGE" "4V"
					( Units "uVoltage" "V" 1.000000)
					( Origin gFrontEnd )
				)
				( attribute "XY" "(-5750,1850)"
					( Origin gFrontEnd )
				)
				( attribute "CHIPS_PART_NAME" "CAP_A"
					( Origin gPackager )
				)
				( attribute "CDS_PART_NAME" "CAP_A_0603V-22.0UF,4V,20%,X6S,A"
					( Origin gPackager )
				)
				( attribute "SEC" "1"
					( Origin gFrontEnd )
				)
				( attribute "SEC_TYPE" "0603V"
					( Origin gFrontEnd )
				)
				( attribute "CDS_LOCATION" "C5G55"
					( Origin gPackager )
				)
				( attribute "CDS_SEC" "1"
					( Origin gPackager )
				)
				( attribute "GROUP" "PWR_MLCC_CAP"
					( Origin gFrontEnd )
				)
				( attribute "BOM_DS" "NOPOP"
					( Origin gFrontEnd )
				)
				( objectStatus "C5G55" )
			)
			( gate "@baseboard_fab2_lib.baseboard_fab2(sch_1):page242_i67"
				( attribute "CDS_LIB" "dev_discrete"
					( Origin gPackager )
				)
				( attribute "LOCATION" "C5G53"
					( Origin gFrontEnd )
				)
				( attribute "MATERIAL" "X6S"
					( Origin gFrontEnd )
				)
				( attribute "PACK_TYPE" "0603V"
					( Origin gFrontEnd )
				)
				( attribute "PART_NUMBER" "E15431-004"
					( Origin gFrontEnd )
				)
				( attribute "PHYS_PAGE" "242"
					( Origin gFrontEnd )
				)
				( attribute "ROOM" "PVDDQ_KLM"
					( Origin gFrontEnd )
				)
				( attribute "ROT" "0"
					( Origin gFrontEnd )
				)
				( attribute "TOLERANCE" "20%"
					( Origin gFrontEnd )
				)
				( attribute "VALUE" "22.0UF"
					( Origin gFrontEnd )
				)
				( attribute "VER" "1"
					( Origin gFrontEnd )
				)
				( attribute "VOLTAGE" "4V"
					( Units "uVoltage" "V" 1.000000)
					( Origin gFrontEnd )
				)
				( attribute "XY" "(-6550,1850)"
					( Origin gFrontEnd )
				)
				( attribute "CHIPS_PART_NAME" "CAP_A"
					( Origin gPackager )
				)
				( attribute "CDS_PART_NAME" "CAP_A_0603V-22.0UF,4V,20%,X6S,A"
					( Origin gPackager )
				)
				( attribute "SEC" "1"
					( Origin gFrontEnd )
				)
				( attribute "SEC_TYPE" "0603V"
					( Origin gFrontEnd )
				)
				( attribute "CDS_LOCATION" "C5G53"
					( Origin gPackager )
				)
				( attribute "CDS_SEC" "1"
					( Origin gPackager )
				)
				( attribute "GROUP" "PWR_MLCC_CAP"
					( Origin gFrontEnd )
				)
				( attribute "BOM_DS" "NOPOP"
					( Origin gFrontEnd )
				)
				( objectStatus "C5G53" )
			)
			( gate "@baseboard_fab2_lib.baseboard_fab2(sch_1):page242_i68"
				( attribute "CDS_LIB" "dev_discrete"
					( Origin gPackager )
				)
				( attribute "LOCATION" "C5G52"
					( Origin gFrontEnd )
				)
				( attribute "MATERIAL" "X6S"
					( Origin gFrontEnd )
				)
				( attribute "PACK_TYPE" "0603V"
					( Origin gFrontEnd )
				)
				( attribute "PART_NUMBER" "E15431-004"
					( Origin gFrontEnd )
				)
				( attribute "PHYS_PAGE" "242"
					( Origin gFrontEnd )
				)
				( attribute "ROOM" "PVDDQ_KLM"
					( Origin gFrontEnd )
				)
				( attribute "ROT" "0"
					( Origin gFrontEnd )
				)
				( attribute "TOLERANCE" "20%"
					( Origin gFrontEnd )
				)
				( attribute "VALUE" "22.0UF"
					( Origin gFrontEnd )
				)
				( attribute "VER" "1"
					( Origin gFrontEnd )
				)
				( attribute "VOLTAGE" "4V"
					( Units "uVoltage" "V" 1.000000)
					( Origin gFrontEnd )
				)
				( attribute "XY" "(-6950,1850)"
					( Origin gFrontEnd )
				)
				( attribute "CHIPS_PART_NAME" "CAP_A"
					( Origin gPackager )
				)
				( attribute "CDS_PART_NAME" "CAP_A_0603V-22.0UF,4V,20%,X6S,A"
					( Origin gPackager )
				)
				( attribute "CDS_LOCATION" "C5G52"
					( Origin gPackager )
				)
				( attribute "SEC" "1"
					( Origin gFrontEnd )
				)
				( attribute "SEC_TYPE" "0603V"
					( Origin gFrontEnd )
				)
				( attribute "CDS_SEC" "1"
					( Origin gPackager )
				)
				( attribute "GROUP" "PWR_MLCC_CAP"
					( Origin gFrontEnd )
				)
				( attribute "BOM_DS" "NOPOP"
					( Origin gFrontEnd )
				)
				( objectStatus "C5G52" )
			)
			( gate "@baseboard_fab2_lib.baseboard_fab2(sch_1):page242_i69"
				( attribute "CDS_LIB" "dev_discrete"
					( Origin gPackager )
				)
				( attribute "LOCATION" "C5G51"
					( Origin gFrontEnd )
				)
				( attribute "MATERIAL" "X6S"
					( Origin gFrontEnd )
				)
				( attribute "PACK_TYPE" "0603V"
					( Origin gFrontEnd )
				)
				( attribute "PART_NUMBER" "E15431-004"
					( Origin gFrontEnd )
				)
				( attribute "PHYS_PAGE" "242"
					( Origin gFrontEnd )
				)
				( attribute "ROOM" "PVDDQ_KLM"
					( Origin gFrontEnd )
				)
				( attribute "ROT" "0"
					( Origin gFrontEnd )
				)
				( attribute "TOLERANCE" "20%"
					( Origin gFrontEnd )
				)
				( attribute "VALUE" "22.0UF"
					( Origin gFrontEnd )
				)
				( attribute "VER" "1"
					( Origin gFrontEnd )
				)
				( attribute "VOLTAGE" "4V"
					( Units "uVoltage" "V" 1.000000)
					( Origin gFrontEnd )
				)
				( attribute "XY" "(-7350,1850)"
					( Origin gFrontEnd )
				)
				( attribute "CHIPS_PART_NAME" "CAP_A"
					( Origin gPackager )
				)
				( attribute "CDS_PART_NAME" "CAP_A_0603V-22.0UF,4V,20%,X6S,A"
					( Origin gPackager )
				)
				( attribute "CDS_LOCATION" "C5G51"
					( Origin gPackager )
				)
				( attribute "SEC" "1"
					( Origin gFrontEnd )
				)
				( attribute "SEC_TYPE" "0603V"
					( Origin gFrontEnd )
				)
				( attribute "CDS_SEC" "1"
					( Origin gPackager )
				)
				( attribute "GROUP" "PWR_MLCC_CAP"
					( Origin gFrontEnd )
				)
				( attribute "BOM_DS" "NOPOP"
					( Origin gFrontEnd )
				)
				( objectStatus "C5G51" )
			)
			( gate "@baseboard_fab2_lib.baseboard_fab2(sch_1):page242_i70"
				( attribute "CDS_LIB" "dev_discrete"
					( Origin gPackager )
				)
				( attribute "LOCATION" "C5G50"
					( Origin gFrontEnd )
				)
				( attribute "MATERIAL" "X6S"
					( Origin gFrontEnd )
				)
				( attribute "PACK_TYPE" "0603V"
					( Origin gFrontEnd )
				)
				( attribute "PART_NUMBER" "E15431-004"
					( Origin gFrontEnd )
				)
				( attribute "PHYS_PAGE" "242"
					( Origin gFrontEnd )
				)
				( attribute "ROOM" "PVDDQ_KLM"
					( Origin gFrontEnd )
				)
				( attribute "ROT" "0"
					( Origin gFrontEnd )
				)
				( attribute "TOLERANCE" "20%"
					( Origin gFrontEnd )
				)
				( attribute "VALUE" "22.0UF"
					( Origin gFrontEnd )
				)
				( attribute "VER" "1"
					( Origin gFrontEnd )
				)
				( attribute "VOLTAGE" "4V"
					( Units "uVoltage" "V" 1.000000)
					( Origin gFrontEnd )
				)
				( attribute "XY" "(-7750,1850)"
					( Origin gFrontEnd )
				)
				( attribute "CHIPS_PART_NAME" "CAP_A"
					( Origin gPackager )
				)
				( attribute "CDS_PART_NAME" "CAP_A_0603V-22.0UF,4V,20%,X6S,A"
					( Origin gPackager )
				)
				( attribute "CDS_LOCATION" "C5G50"
					( Origin gPackager )
				)
				( attribute "SEC" "1"
					( Origin gFrontEnd )
				)
				( attribute "SEC_TYPE" "0603V"
					( Origin gFrontEnd )
				)
				( attribute "CDS_SEC" "1"
					( Origin gPackager )
				)
				( attribute "GROUP" "PWR_MLCC_CAP"
					( Origin gFrontEnd )
				)
				( attribute "BOM_DS" "NOPOP"
					( Origin gFrontEnd )
				)
				( objectStatus "C5G50" )
			)
			( gate "@baseboard_fab2_lib.baseboard_fab2(sch_1):page242_i71"
				( attribute "CDS_LIB" "dev_discrete"
					( Origin gPackager )
				)
				( attribute "LOCATION" "C5G67"
					( Origin gFrontEnd )
				)
				( attribute "MATERIAL" "X6S"
					( Origin gFrontEnd )
				)
				( attribute "PACK_TYPE" "0603V"
					( Origin gFrontEnd )
				)
				( attribute "PART_NUMBER" "E15431-004"
					( Origin gFrontEnd )
				)
				( attribute "PHYS_PAGE" "242"
					( Origin gFrontEnd )
				)
				( attribute "ROOM" "PVDDQ_KLM"
					( Origin gFrontEnd )
				)
				( attribute "ROT" "0"
					( Origin gFrontEnd )
				)
				( attribute "TOLERANCE" "20%"
					( Origin gFrontEnd )
				)
				( attribute "VALUE" "22.0UF"
					( Origin gFrontEnd )
				)
				( attribute "VER" "1"
					( Origin gFrontEnd )
				)
				( attribute "VOLTAGE" "4V"
					( Units "uVoltage" "V" 1.000000)
					( Origin gFrontEnd )
				)
				( attribute "XY" "(-600,2800)"
					( Origin gFrontEnd )
				)
				( attribute "CHIPS_PART_NAME" "CAP_A"
					( Origin gPackager )
				)
				( attribute "CDS_PART_NAME" "CAP_A_0603V-22.0UF,4V,20%,X6S,A"
					( Origin gPackager )
				)
				( attribute "CDS_LOCATION" "C5G67"
					( Origin gPackager )
				)
				( attribute "SEC" "1"
					( Origin gFrontEnd )
				)
				( attribute "SEC_TYPE" "0603V"
					( Origin gFrontEnd )
				)
				( attribute "CDS_SEC" "1"
					( Origin gPackager )
				)
				( attribute "GROUP" "PWR_MLCC_CAP"
					( Origin gFrontEnd )
				)
				( attribute "BOM_DS" "NOPOP"
					( Origin gFrontEnd )
				)
				( objectStatus "C5G67" )
			)
			( gate "@baseboard_fab2_lib.baseboard_fab2(sch_1):page242_i72"
				( attribute "CDS_LIB" "dev_discrete"
					( Origin gPackager )
				)
				( attribute "LOCATION" "C5G66"
					( Origin gFrontEnd )
				)
				( attribute "MATERIAL" "X6S"
					( Origin gFrontEnd )
				)
				( attribute "PACK_TYPE" "0603V"
					( Origin gFrontEnd )
				)
				( attribute "PART_NUMBER" "E15431-004"
					( Origin gFrontEnd )
				)
				( attribute "PHYS_PAGE" "242"
					( Origin gFrontEnd )
				)
				( attribute "ROOM" "PVDDQ_KLM"
					( Origin gFrontEnd )
				)
				( attribute "ROT" "0"
					( Origin gFrontEnd )
				)
				( attribute "TOLERANCE" "20%"
					( Origin gFrontEnd )
				)
				( attribute "VALUE" "22.0UF"
					( Origin gFrontEnd )
				)
				( attribute "VER" "1"
					( Origin gFrontEnd )
				)
				( attribute "VOLTAGE" "4V"
					( Units "uVoltage" "V" 1.000000)
					( Origin gFrontEnd )
				)
				( attribute "XY" "(-1000,2800)"
					( Origin gFrontEnd )
				)
				( attribute "CHIPS_PART_NAME" "CAP_A"
					( Origin gPackager )
				)
				( attribute "CDS_PART_NAME" "CAP_A_0603V-22.0UF,4V,20%,X6S,A"
					( Origin gPackager )
				)
				( attribute "CDS_LOCATION" "C5G66"
					( Origin gPackager )
				)
				( attribute "SEC" "1"
					( Origin gFrontEnd )
				)
				( attribute "SEC_TYPE" "0603V"
					( Origin gFrontEnd )
				)
				( attribute "CDS_SEC" "1"
					( Origin gPackager )
				)
				( attribute "GROUP" "PWR_MLCC_CAP"
					( Origin gFrontEnd )
				)
				( attribute "BOM_DS" "NOPOP"
					( Origin gFrontEnd )
				)
				( objectStatus "C5G66" )
			)
			( gate "@baseboard_fab2_lib.baseboard_fab2(sch_1):page242_i73"
				( attribute "CDS_LIB" "dev_discrete"
					( Origin gPackager )
				)
				( attribute "LOCATION" "C5G65"
					( Origin gFrontEnd )
				)
				( attribute "MATERIAL" "X6S"
					( Origin gFrontEnd )
				)
				( attribute "PACK_TYPE" "0603V"
					( Origin gFrontEnd )
				)
				( attribute "PART_NUMBER" "E15431-004"
					( Origin gFrontEnd )
				)
				( attribute "PHYS_PAGE" "242"
					( Origin gFrontEnd )
				)
				( attribute "ROOM" "PVDDQ_KLM"
					( Origin gFrontEnd )
				)
				( attribute "ROT" "0"
					( Origin gFrontEnd )
				)
				( attribute "TOLERANCE" "20%"
					( Origin gFrontEnd )
				)
				( attribute "VALUE" "22.0UF"
					( Origin gFrontEnd )
				)
				( attribute "VER" "1"
					( Origin gFrontEnd )
				)
				( attribute "VOLTAGE" "4V"
					( Units "uVoltage" "V" 1.000000)
					( Origin gFrontEnd )
				)
				( attribute "XY" "(-1400,2800)"
					( Origin gFrontEnd )
				)
				( attribute "CHIPS_PART_NAME" "CAP_A"
					( Origin gPackager )
				)
				( attribute "CDS_PART_NAME" "CAP_A_0603V-22.0UF,4V,20%,X6S,A"
					( Origin gPackager )
				)
				( attribute "CDS_LOCATION" "C5G65"
					( Origin gPackager )
				)
				( attribute "SEC" "1"
					( Origin gFrontEnd )
				)
				( attribute "SEC_TYPE" "0603V"
					( Origin gFrontEnd )
				)
				( attribute "CDS_SEC" "1"
					( Origin gPackager )
				)
				( attribute "GROUP" "PWR_MLCC_CAP"
					( Origin gFrontEnd )
				)
				( attribute "BOM_DS" "NOPOP"
					( Origin gFrontEnd )
				)
				( objectStatus "C5G65" )
			)
			( gate "@baseboard_fab2_lib.baseboard_fab2(sch_1):page242_i74"
				( attribute "CDS_LIB" "dev_discrete"
					( Origin gPackager )
				)
				( attribute "LOCATION" "C5G64"
					( Origin gFrontEnd )
				)
				( attribute "MATERIAL" "X6S"
					( Origin gFrontEnd )
				)
				( attribute "PACK_TYPE" "0603V"
					( Origin gFrontEnd )
				)
				( attribute "PART_NUMBER" "E15431-004"
					( Origin gFrontEnd )
				)
				( attribute "PHYS_PAGE" "242"
					( Origin gFrontEnd )
				)
				( attribute "ROOM" "PVDDQ_KLM"
					( Origin gFrontEnd )
				)
				( attribute "ROT" "0"
					( Origin gFrontEnd )
				)
				( attribute "TOLERANCE" "20%"
					( Origin gFrontEnd )
				)
				( attribute "VALUE" "22.0UF"
					( Origin gFrontEnd )
				)
				( attribute "VER" "1"
					( Origin gFrontEnd )
				)
				( attribute "VOLTAGE" "4V"
					( Units "uVoltage" "V" 1.000000)
					( Origin gFrontEnd )
				)
				( attribute "XY" "(-1800,2800)"
					( Origin gFrontEnd )
				)
				( attribute "CHIPS_PART_NAME" "CAP_A"
					( Origin gPackager )
				)
				( attribute "CDS_PART_NAME" "CAP_A_0603V-22.0UF,4V,20%,X6S,A"
					( Origin gPackager )
				)
				( attribute "CDS_LOCATION" "C5G64"
					( Origin gPackager )
				)
				( attribute "SEC" "1"
					( Origin gFrontEnd )
				)
				( attribute "SEC_TYPE" "0603V"
					( Origin gFrontEnd )
				)
				( attribute "CDS_SEC" "1"
					( Origin gPackager )
				)
				( attribute "GROUP" "PWR_MLCC_CAP"
					( Origin gFrontEnd )
				)
				( attribute "BOM_DS" "NOPOP"
					( Origin gFrontEnd )
				)
				( objectStatus "C5G64" )
			)
			( gate "@baseboard_fab2_lib.baseboard_fab2(sch_1):page242_i75"
				( attribute "CDS_LIB" "dev_discrete"
					( Origin gPackager )
				)
				( attribute "LOCATION" "C5G63"
					( Origin gFrontEnd )
				)
				( attribute "MATERIAL" "X6S"
					( Origin gFrontEnd )
				)
				( attribute "PACK_TYPE" "0603V"
					( Origin gFrontEnd )
				)
				( attribute "PART_NUMBER" "E15431-004"
					( Origin gFrontEnd )
				)
				( attribute "PHYS_PAGE" "242"
					( Origin gFrontEnd )
				)
				( attribute "ROOM" "PVDDQ_KLM"
					( Origin gFrontEnd )
				)
				( attribute "ROT" "0"
					( Origin gFrontEnd )
				)
				( attribute "TOLERANCE" "20%"
					( Origin gFrontEnd )
				)
				( attribute "VALUE" "22.0UF"
					( Origin gFrontEnd )
				)
				( attribute "VER" "1"
					( Origin gFrontEnd )
				)
				( attribute "VOLTAGE" "4V"
					( Units "uVoltage" "V" 1.000000)
					( Origin gFrontEnd )
				)
				( attribute "XY" "(-2200,2800)"
					( Origin gFrontEnd )
				)
				( attribute "CHIPS_PART_NAME" "CAP_A"
					( Origin gPackager )
				)
				( attribute "CDS_PART_NAME" "CAP_A_0603V-22.0UF,4V,20%,X6S,A"
					( Origin gPackager )
				)
				( attribute "CDS_LOCATION" "C5G63"
					( Origin gPackager )
				)
				( attribute "SEC" "1"
					( Origin gFrontEnd )
				)
				( attribute "SEC_TYPE" "0603V"
					( Origin gFrontEnd )
				)
				( attribute "CDS_SEC" "1"
					( Origin gPackager )
				)
				( attribute "GROUP" "PWR_MLCC_CAP"
					( Origin gFrontEnd )
				)
				( attribute "BOM_DS" "NOPOP"
					( Origin gFrontEnd )
				)
				( objectStatus "C5G63" )
			)
			( gate "@baseboard_fab2_lib.baseboard_fab2(sch_1):page242_i76"
				( attribute "CDS_LIB" "dev_discrete"
					( Origin gPackager )
				)
				( attribute "LOCATION" "C5G62"
					( Origin gFrontEnd )
				)
				( attribute "MATERIAL" "X6S"
					( Origin gFrontEnd )
				)
				( attribute "PACK_TYPE" "0603V"
					( Origin gFrontEnd )
				)
				( attribute "PART_NUMBER" "E15431-004"
					( Origin gFrontEnd )
				)
				( attribute "PHYS_PAGE" "242"
					( Origin gFrontEnd )
				)
				( attribute "ROOM" "PVDDQ_KLM"
					( Origin gFrontEnd )
				)
				( attribute "ROT" "0"
					( Origin gFrontEnd )
				)
				( attribute "TOLERANCE" "20%"
					( Origin gFrontEnd )
				)
				( attribute "VALUE" "22.0UF"
					( Origin gFrontEnd )
				)
				( attribute "VER" "1"
					( Origin gFrontEnd )
				)
				( attribute "VOLTAGE" "4V"
					( Units "uVoltage" "V" 1.000000)
					( Origin gFrontEnd )
				)
				( attribute "XY" "(-2600,2800)"
					( Origin gFrontEnd )
				)
				( attribute "CHIPS_PART_NAME" "CAP_A"
					( Origin gPackager )
				)
				( attribute "CDS_PART_NAME" "CAP_A_0603V-22.0UF,4V,20%,X6S,A"
					( Origin gPackager )
				)
				( attribute "CDS_LOCATION" "C5G62"
					( Origin gPackager )
				)
				( attribute "SEC" "1"
					( Origin gFrontEnd )
				)
				( attribute "SEC_TYPE" "0603V"
					( Origin gFrontEnd )
				)
				( attribute "CDS_SEC" "1"
					( Origin gPackager )
				)
				( attribute "GROUP" "PWR_MLCC_CAP"
					( Origin gFrontEnd )
				)
				( attribute "BOM_DS" "NOPOP"
					( Origin gFrontEnd )
				)
				( objectStatus "C5G62" )
			)
			( gate "@baseboard_fab2_lib.baseboard_fab2(sch_1):page242_i77"
				( attribute "CDS_LIB" "dev_discrete"
					( Origin gPackager )
				)
				( attribute "LOCATION" "C5G61"
					( Origin gFrontEnd )
				)
				( attribute "MATERIAL" "X6S"
					( Origin gFrontEnd )
				)
				( attribute "PACK_TYPE" "0603V"
					( Origin gFrontEnd )
				)
				( attribute "PART_NUMBER" "E15431-004"
					( Origin gFrontEnd )
				)
				( attribute "PHYS_PAGE" "242"
					( Origin gFrontEnd )
				)
				( attribute "ROOM" "PVDDQ_KLM"
					( Origin gFrontEnd )
				)
				( attribute "ROT" "0"
					( Origin gFrontEnd )
				)
				( attribute "TOLERANCE" "20%"
					( Origin gFrontEnd )
				)
				( attribute "VALUE" "22.0UF"
					( Origin gFrontEnd )
				)
				( attribute "VER" "1"
					( Origin gFrontEnd )
				)
				( attribute "VOLTAGE" "4V"
					( Units "uVoltage" "V" 1.000000)
					( Origin gFrontEnd )
				)
				( attribute "XY" "(-3000,2800)"
					( Origin gFrontEnd )
				)
				( attribute "CHIPS_PART_NAME" "CAP_A"
					( Origin gPackager )
				)
				( attribute "CDS_PART_NAME" "CAP_A_0603V-22.0UF,4V,20%,X6S,A"
					( Origin gPackager )
				)
				( attribute "CDS_LOCATION" "C5G61"
					( Origin gPackager )
				)
				( attribute "SEC" "1"
					( Origin gFrontEnd )
				)
				( attribute "SEC_TYPE" "0603V"
					( Origin gFrontEnd )
				)
				( attribute "CDS_SEC" "1"
					( Origin gPackager )
				)
				( attribute "GROUP" "PWR_MLCC_CAP"
					( Origin gFrontEnd )
				)
				( attribute "BOM_DS" "NOPOP"
					( Origin gFrontEnd )
				)
				( objectStatus "C5G61" )
			)
			( gate "@baseboard_fab2_lib.baseboard_fab2(sch_1):page242_i78"
				( attribute "CDS_LIB" "dev_discrete"
					( Origin gPackager )
				)
				( attribute "LOCATION" "C5G60"
					( Origin gFrontEnd )
				)
				( attribute "MATERIAL" "X6S"
					( Origin gFrontEnd )
				)
				( attribute "PACK_TYPE" "0603V"
					( Origin gFrontEnd )
				)
				( attribute "PART_NUMBER" "E15431-004"
					( Origin gFrontEnd )
				)
				( attribute "PHYS_PAGE" "242"
					( Origin gFrontEnd )
				)
				( attribute "ROOM" "PVDDQ_KLM"
					( Origin gFrontEnd )
				)
				( attribute "ROT" "0"
					( Origin gFrontEnd )
				)
				( attribute "TOLERANCE" "20%"
					( Origin gFrontEnd )
				)
				( attribute "VALUE" "22.0UF"
					( Origin gFrontEnd )
				)
				( attribute "VER" "1"
					( Origin gFrontEnd )
				)
				( attribute "VOLTAGE" "4V"
					( Units "uVoltage" "V" 1.000000)
					( Origin gFrontEnd )
				)
				( attribute "XY" "(-3400,2800)"
					( Origin gFrontEnd )
				)
				( attribute "CHIPS_PART_NAME" "CAP_A"
					( Origin gPackager )
				)
				( attribute "CDS_PART_NAME" "CAP_A_0603V-22.0UF,4V,20%,X6S,A"
					( Origin gPackager )
				)
				( attribute "CDS_LOCATION" "C5G60"
					( Origin gPackager )
				)
				( attribute "SEC" "1"
					( Origin gFrontEnd )
				)
				( attribute "SEC_TYPE" "0603V"
					( Origin gFrontEnd )
				)
				( attribute "CDS_SEC" "1"
					( Origin gPackager )
				)
				( attribute "GROUP" "PWR_MLCC_CAP"
					( Origin gFrontEnd )
				)
				( attribute "BOM_DS" "NOPOP"
					( Origin gFrontEnd )
				)
				( objectStatus "C5G60" )
			)
			( gate "@baseboard_fab2_lib.baseboard_fab2(sch_1):page242_i79"
				( attribute "CDS_LIB" "dev_discrete"
					( Origin gPackager )
				)
				( attribute "LOCATION" "C5G59"
					( Origin gFrontEnd )
				)
				( attribute "MATERIAL" "X6S"
					( Origin gFrontEnd )
				)
				( attribute "PACK_TYPE" "0603V"
					( Origin gFrontEnd )
				)
				( attribute "PART_NUMBER" "E15431-004"
					( Origin gFrontEnd )
				)
				( attribute "PHYS_PAGE" "242"
					( Origin gFrontEnd )
				)
				( attribute "ROOM" "PVDDQ_KLM"
					( Origin gFrontEnd )
				)
				( attribute "ROT" "0"
					( Origin gFrontEnd )
				)
				( attribute "TOLERANCE" "20%"
					( Origin gFrontEnd )
				)
				( attribute "VALUE" "22.0UF"
					( Origin gFrontEnd )
				)
				( attribute "VER" "1"
					( Origin gFrontEnd )
				)
				( attribute "VOLTAGE" "4V"
					( Units "uVoltage" "V" 1.000000)
					( Origin gFrontEnd )
				)
				( attribute "XY" "(-3800,2800)"
					( Origin gFrontEnd )
				)
				( attribute "CHIPS_PART_NAME" "CAP_A"
					( Origin gPackager )
				)
				( attribute "CDS_PART_NAME" "CAP_A_0603V-22.0UF,4V,20%,X6S,A"
					( Origin gPackager )
				)
				( attribute "CDS_LOCATION" "C5G59"
					( Origin gPackager )
				)
				( attribute "SEC" "1"
					( Origin gFrontEnd )
				)
				( attribute "SEC_TYPE" "0603V"
					( Origin gFrontEnd )
				)
				( attribute "CDS_SEC" "1"
					( Origin gPackager )
				)
				( attribute "GROUP" "PWR_MLCC_CAP"
					( Origin gFrontEnd )
				)
				( attribute "BOM_DS" "NOPOP"
					( Origin gFrontEnd )
				)
				( objectStatus "C5G59" )
			)
			( gate "@baseboard_fab2_lib.baseboard_fab2(sch_1):page242_i80"
				( attribute "CDS_LIB" "dev_discrete"
					( Origin gPackager )
				)
				( attribute "LOCATION" "C5G76"
					( Origin gFrontEnd )
				)
				( attribute "MATERIAL" "X6S"
					( Origin gFrontEnd )
				)
				( attribute "PACK_TYPE" "0603V"
					( Origin gFrontEnd )
				)
				( attribute "PART_NUMBER" "E15431-004"
					( Origin gFrontEnd )
				)
				( attribute "PHYS_PAGE" "242"
					( Origin gFrontEnd )
				)
				( attribute "ROOM" "PVDDQ_KLM"
					( Origin gFrontEnd )
				)
				( attribute "ROT" "0"
					( Origin gFrontEnd )
				)
				( attribute "TOLERANCE" "20%"
					( Origin gFrontEnd )
				)
				( attribute "VALUE" "22.0UF"
					( Origin gFrontEnd )
				)
				( attribute "VER" "1"
					( Origin gFrontEnd )
				)
				( attribute "VOLTAGE" "4V"
					( Units "uVoltage" "V" 1.000000)
					( Origin gFrontEnd )
				)
				( attribute "XY" "(-600,1850)"
					( Origin gFrontEnd )
				)
				( attribute "CHIPS_PART_NAME" "CAP_A"
					( Origin gPackager )
				)
				( attribute "CDS_PART_NAME" "CAP_A_0603V-22.0UF,4V,20%,X6S,A"
					( Origin gPackager )
				)
				( attribute "CDS_LOCATION" "C5G76"
					( Origin gPackager )
				)
				( attribute "SEC" "1"
					( Origin gFrontEnd )
				)
				( attribute "SEC_TYPE" "0603V"
					( Origin gFrontEnd )
				)
				( attribute "CDS_SEC" "1"
					( Origin gPackager )
				)
				( attribute "GROUP" "PWR_MLCC_CAP"
					( Origin gFrontEnd )
				)
				( attribute "BOM_DS" "NOPOP"
					( Origin gFrontEnd )
				)
				( objectStatus "C5G76" )
			)
			( gate "@baseboard_fab2_lib.baseboard_fab2(sch_1):page242_i81"
				( attribute "CDS_LIB" "dev_discrete"
					( Origin gPackager )
				)
				( attribute "LOCATION" "C5G75"
					( Origin gFrontEnd )
				)
				( attribute "MATERIAL" "X6S"
					( Origin gFrontEnd )
				)
				( attribute "PACK_TYPE" "0603V"
					( Origin gFrontEnd )
				)
				( attribute "PART_NUMBER" "E15431-004"
					( Origin gFrontEnd )
				)
				( attribute "PHYS_PAGE" "242"
					( Origin gFrontEnd )
				)
				( attribute "ROOM" "PVDDQ_KLM"
					( Origin gFrontEnd )
				)
				( attribute "ROT" "0"
					( Origin gFrontEnd )
				)
				( attribute "TOLERANCE" "20%"
					( Origin gFrontEnd )
				)
				( attribute "VALUE" "22.0UF"
					( Origin gFrontEnd )
				)
				( attribute "VER" "1"
					( Origin gFrontEnd )
				)
				( attribute "VOLTAGE" "4V"
					( Units "uVoltage" "V" 1.000000)
					( Origin gFrontEnd )
				)
				( attribute "XY" "(-1000,1850)"
					( Origin gFrontEnd )
				)
				( attribute "CHIPS_PART_NAME" "CAP_A"
					( Origin gPackager )
				)
				( attribute "CDS_PART_NAME" "CAP_A_0603V-22.0UF,4V,20%,X6S,A"
					( Origin gPackager )
				)
				( attribute "CDS_LOCATION" "C5G75"
					( Origin gPackager )
				)
				( attribute "SEC" "1"
					( Origin gFrontEnd )
				)
				( attribute "SEC_TYPE" "0603V"
					( Origin gFrontEnd )
				)
				( attribute "CDS_SEC" "1"
					( Origin gPackager )
				)
				( attribute "GROUP" "PWR_MLCC_CAP"
					( Origin gFrontEnd )
				)
				( attribute "BOM_DS" "NOPOP"
					( Origin gFrontEnd )
				)
				( objectStatus "C5G75" )
			)
			( gate "@baseboard_fab2_lib.baseboard_fab2(sch_1):page242_i82"
				( attribute "CDS_LIB" "dev_discrete"
					( Origin gPackager )
				)
				( attribute "LOCATION" "C5G74"
					( Origin gFrontEnd )
				)
				( attribute "MATERIAL" "X6S"
					( Origin gFrontEnd )
				)
				( attribute "PACK_TYPE" "0603V"
					( Origin gFrontEnd )
				)
				( attribute "PART_NUMBER" "E15431-004"
					( Origin gFrontEnd )
				)
				( attribute "PHYS_PAGE" "242"
					( Origin gFrontEnd )
				)
				( attribute "ROOM" "PVDDQ_KLM"
					( Origin gFrontEnd )
				)
				( attribute "ROT" "0"
					( Origin gFrontEnd )
				)
				( attribute "TOLERANCE" "20%"
					( Origin gFrontEnd )
				)
				( attribute "VALUE" "22.0UF"
					( Origin gFrontEnd )
				)
				( attribute "VER" "1"
					( Origin gFrontEnd )
				)
				( attribute "VOLTAGE" "4V"
					( Units "uVoltage" "V" 1.000000)
					( Origin gFrontEnd )
				)
				( attribute "XY" "(-1400,1850)"
					( Origin gFrontEnd )
				)
				( attribute "CHIPS_PART_NAME" "CAP_A"
					( Origin gPackager )
				)
				( attribute "CDS_PART_NAME" "CAP_A_0603V-22.0UF,4V,20%,X6S,A"
					( Origin gPackager )
				)
				( attribute "CDS_LOCATION" "C5G74"
					( Origin gPackager )
				)
				( attribute "SEC" "1"
					( Origin gFrontEnd )
				)
				( attribute "SEC_TYPE" "0603V"
					( Origin gFrontEnd )
				)
				( attribute "CDS_SEC" "1"
					( Origin gPackager )
				)
				( attribute "GROUP" "PWR_MLCC_CAP"
					( Origin gFrontEnd )
				)
				( attribute "BOM_DS" "NOPOP"
					( Origin gFrontEnd )
				)
				( objectStatus "C5G74" )
			)
			( gate "@baseboard_fab2_lib.baseboard_fab2(sch_1):page242_i83"
				( attribute "CDS_LIB" "dev_discrete"
					( Origin gPackager )
				)
				( attribute "LOCATION" "C5G73"
					( Origin gFrontEnd )
				)
				( attribute "MATERIAL" "X6S"
					( Origin gFrontEnd )
				)
				( attribute "PACK_TYPE" "0603V"
					( Origin gFrontEnd )
				)
				( attribute "PART_NUMBER" "E15431-004"
					( Origin gFrontEnd )
				)
				( attribute "PHYS_PAGE" "242"
					( Origin gFrontEnd )
				)
				( attribute "ROOM" "PVDDQ_KLM"
					( Origin gFrontEnd )
				)
				( attribute "ROT" "0"
					( Origin gFrontEnd )
				)
				( attribute "TOLERANCE" "20%"
					( Origin gFrontEnd )
				)
				( attribute "VALUE" "22.0UF"
					( Origin gFrontEnd )
				)
				( attribute "VER" "1"
					( Origin gFrontEnd )
				)
				( attribute "VOLTAGE" "4V"
					( Units "uVoltage" "V" 1.000000)
					( Origin gFrontEnd )
				)
				( attribute "XY" "(-1800,1850)"
					( Origin gFrontEnd )
				)
				( attribute "CHIPS_PART_NAME" "CAP_A"
					( Origin gPackager )
				)
				( attribute "CDS_PART_NAME" "CAP_A_0603V-22.0UF,4V,20%,X6S,A"
					( Origin gPackager )
				)
				( attribute "CDS_LOCATION" "C5G73"
					( Origin gPackager )
				)
				( attribute "SEC" "1"
					( Origin gFrontEnd )
				)
				( attribute "SEC_TYPE" "0603V"
					( Origin gFrontEnd )
				)
				( attribute "CDS_SEC" "1"
					( Origin gPackager )
				)
				( attribute "GROUP" "PWR_MLCC_CAP"
					( Origin gFrontEnd )
				)
				( attribute "BOM_DS" "NOPOP"
					( Origin gFrontEnd )
				)
				( objectStatus "C5G73" )
			)
			( gate "@baseboard_fab2_lib.baseboard_fab2(sch_1):page242_i84"
				( attribute "CDS_LIB" "dev_discrete"
					( Origin gPackager )
				)
				( attribute "LOCATION" "C5G72"
					( Origin gFrontEnd )
				)
				( attribute "MATERIAL" "X6S"
					( Origin gFrontEnd )
				)
				( attribute "PACK_TYPE" "0603V"
					( Origin gFrontEnd )
				)
				( attribute "PART_NUMBER" "E15431-004"
					( Origin gFrontEnd )
				)
				( attribute "PHYS_PAGE" "242"
					( Origin gFrontEnd )
				)
				( attribute "ROOM" "PVDDQ_KLM"
					( Origin gFrontEnd )
				)
				( attribute "ROT" "0"
					( Origin gFrontEnd )
				)
				( attribute "TOLERANCE" "20%"
					( Origin gFrontEnd )
				)
				( attribute "VALUE" "22.0UF"
					( Origin gFrontEnd )
				)
				( attribute "VER" "1"
					( Origin gFrontEnd )
				)
				( attribute "VOLTAGE" "4V"
					( Units "uVoltage" "V" 1.000000)
					( Origin gFrontEnd )
				)
				( attribute "XY" "(-2200,1850)"
					( Origin gFrontEnd )
				)
				( attribute "CHIPS_PART_NAME" "CAP_A"
					( Origin gPackager )
				)
				( attribute "CDS_PART_NAME" "CAP_A_0603V-22.0UF,4V,20%,X6S,A"
					( Origin gPackager )
				)
				( attribute "CDS_LOCATION" "C5G72"
					( Origin gPackager )
				)
				( attribute "SEC" "1"
					( Origin gFrontEnd )
				)
				( attribute "SEC_TYPE" "0603V"
					( Origin gFrontEnd )
				)
				( attribute "CDS_SEC" "1"
					( Origin gPackager )
				)
				( attribute "GROUP" "PWR_MLCC_CAP"
					( Origin gFrontEnd )
				)
				( attribute "BOM_DS" "NOPOP"
					( Origin gFrontEnd )
				)
				( objectStatus "C5G72" )
			)
			( gate "@baseboard_fab2_lib.baseboard_fab2(sch_1):page242_i85"
				( attribute "CDS_LIB" "dev_discrete"
					( Origin gPackager )
				)
				( attribute "LOCATION" "C5G71"
					( Origin gFrontEnd )
				)
				( attribute "MATERIAL" "X6S"
					( Origin gFrontEnd )
				)
				( attribute "PACK_TYPE" "0603V"
					( Origin gFrontEnd )
				)
				( attribute "PART_NUMBER" "E15431-004"
					( Origin gFrontEnd )
				)
				( attribute "PHYS_PAGE" "242"
					( Origin gFrontEnd )
				)
				( attribute "ROOM" "PVDDQ_KLM"
					( Origin gFrontEnd )
				)
				( attribute "ROT" "0"
					( Origin gFrontEnd )
				)
				( attribute "TOLERANCE" "20%"
					( Origin gFrontEnd )
				)
				( attribute "VALUE" "22.0UF"
					( Origin gFrontEnd )
				)
				( attribute "VER" "1"
					( Origin gFrontEnd )
				)
				( attribute "VOLTAGE" "4V"
					( Units "uVoltage" "V" 1.000000)
					( Origin gFrontEnd )
				)
				( attribute "XY" "(-2600,1850)"
					( Origin gFrontEnd )
				)
				( attribute "CHIPS_PART_NAME" "CAP_A"
					( Origin gPackager )
				)
				( attribute "CDS_PART_NAME" "CAP_A_0603V-22.0UF,4V,20%,X6S,A"
					( Origin gPackager )
				)
				( attribute "CDS_LOCATION" "C5G71"
					( Origin gPackager )
				)
				( attribute "SEC" "1"
					( Origin gFrontEnd )
				)
				( attribute "SEC_TYPE" "0603V"
					( Origin gFrontEnd )
				)
				( attribute "CDS_SEC" "1"
					( Origin gPackager )
				)
				( attribute "GROUP" "PWR_MLCC_CAP"
					( Origin gFrontEnd )
				)
				( attribute "BOM_DS" "NOPOP"
					( Origin gFrontEnd )
				)
				( objectStatus "C5G71" )
			)
			( gate "@baseboard_fab2_lib.baseboard_fab2(sch_1):page242_i86"
				( attribute "CDS_LIB" "dev_discrete"
					( Origin gPackager )
				)
				( attribute "LOCATION" "C5G70"
					( Origin gFrontEnd )
				)
				( attribute "MATERIAL" "X6S"
					( Origin gFrontEnd )
				)
				( attribute "PACK_TYPE" "0603V"
					( Origin gFrontEnd )
				)
				( attribute "PART_NUMBER" "E15431-004"
					( Origin gFrontEnd )
				)
				( attribute "PHYS_PAGE" "242"
					( Origin gFrontEnd )
				)
				( attribute "ROOM" "PVDDQ_KLM"
					( Origin gFrontEnd )
				)
				( attribute "ROT" "0"
					( Origin gFrontEnd )
				)
				( attribute "TOLERANCE" "20%"
					( Origin gFrontEnd )
				)
				( attribute "VALUE" "22.0UF"
					( Origin gFrontEnd )
				)
				( attribute "VER" "1"
					( Origin gFrontEnd )
				)
				( attribute "VOLTAGE" "4V"
					( Units "uVoltage" "V" 1.000000)
					( Origin gFrontEnd )
				)
				( attribute "XY" "(-3000,1850)"
					( Origin gFrontEnd )
				)
				( attribute "CHIPS_PART_NAME" "CAP_A"
					( Origin gPackager )
				)
				( attribute "CDS_PART_NAME" "CAP_A_0603V-22.0UF,4V,20%,X6S,A"
					( Origin gPackager )
				)
				( attribute "CDS_LOCATION" "C5G70"
					( Origin gPackager )
				)
				( attribute "SEC" "1"
					( Origin gFrontEnd )
				)
				( attribute "SEC_TYPE" "0603V"
					( Origin gFrontEnd )
				)
				( attribute "CDS_SEC" "1"
					( Origin gPackager )
				)
				( attribute "GROUP" "PWR_MLCC_CAP"
					( Origin gFrontEnd )
				)
				( attribute "BOM_DS" "NOPOP"
					( Origin gFrontEnd )
				)
				( objectStatus "C5G70" )
			)
			( gate "@baseboard_fab2_lib.baseboard_fab2(sch_1):page242_i87"
				( attribute "CDS_LIB" "dev_discrete"
					( Origin gPackager )
				)
				( attribute "LOCATION" "C5G69"
					( Origin gFrontEnd )
				)
				( attribute "MATERIAL" "X6S"
					( Origin gFrontEnd )
				)
				( attribute "PACK_TYPE" "0603V"
					( Origin gFrontEnd )
				)
				( attribute "PART_NUMBER" "E15431-004"
					( Origin gFrontEnd )
				)
				( attribute "PHYS_PAGE" "242"
					( Origin gFrontEnd )
				)
				( attribute "ROOM" "PVDDQ_KLM"
					( Origin gFrontEnd )
				)
				( attribute "ROT" "0"
					( Origin gFrontEnd )
				)
				( attribute "TOLERANCE" "20%"
					( Origin gFrontEnd )
				)
				( attribute "VALUE" "22.0UF"
					( Origin gFrontEnd )
				)
				( attribute "VER" "1"
					( Origin gFrontEnd )
				)
				( attribute "VOLTAGE" "4V"
					( Units "uVoltage" "V" 1.000000)
					( Origin gFrontEnd )
				)
				( attribute "XY" "(-3400,1850)"
					( Origin gFrontEnd )
				)
				( attribute "CHIPS_PART_NAME" "CAP_A"
					( Origin gPackager )
				)
				( attribute "CDS_PART_NAME" "CAP_A_0603V-22.0UF,4V,20%,X6S,A"
					( Origin gPackager )
				)
				( attribute "CDS_LOCATION" "C5G69"
					( Origin gPackager )
				)
				( attribute "SEC" "1"
					( Origin gFrontEnd )
				)
				( attribute "SEC_TYPE" "0603V"
					( Origin gFrontEnd )
				)
				( attribute "CDS_SEC" "1"
					( Origin gPackager )
				)
				( attribute "GROUP" "PWR_MLCC_CAP"
					( Origin gFrontEnd )
				)
				( attribute "BOM_DS" "NOPOP"
					( Origin gFrontEnd )
				)
				( objectStatus "C5G69" )
			)
			( gate "@baseboard_fab2_lib.baseboard_fab2(sch_1):page242_i88"
				( attribute "CDS_LIB" "dev_discrete"
					( Origin gPackager )
				)
				( attribute "LOCATION" "C5G68"
					( Origin gFrontEnd )
				)
				( attribute "MATERIAL" "X6S"
					( Origin gFrontEnd )
				)
				( attribute "PACK_TYPE" "0603V"
					( Origin gFrontEnd )
				)
				( attribute "PART_NUMBER" "E15431-004"
					( Origin gFrontEnd )
				)
				( attribute "PHYS_PAGE" "242"
					( Origin gFrontEnd )
				)
				( attribute "ROOM" "PVDDQ_KLM"
					( Origin gFrontEnd )
				)
				( attribute "ROT" "0"
					( Origin gFrontEnd )
				)
				( attribute "TOLERANCE" "20%"
					( Origin gFrontEnd )
				)
				( attribute "VALUE" "22.0UF"
					( Origin gFrontEnd )
				)
				( attribute "VER" "1"
					( Origin gFrontEnd )
				)
				( attribute "VOLTAGE" "4V"
					( Units "uVoltage" "V" 1.000000)
					( Origin gFrontEnd )
				)
				( attribute "XY" "(-3800,1850)"
					( Origin gFrontEnd )
				)
				( attribute "CHIPS_PART_NAME" "CAP_A"
					( Origin gPackager )
				)
				( attribute "CDS_PART_NAME" "CAP_A_0603V-22.0UF,4V,20%,X6S,A"
					( Origin gPackager )
				)
				( attribute "CDS_LOCATION" "C5G68"
					( Origin gPackager )
				)
				( attribute "SEC" "1"
					( Origin gFrontEnd )
				)
				( attribute "SEC_TYPE" "0603V"
					( Origin gFrontEnd )
				)
				( attribute "CDS_SEC" "1"
					( Origin gPackager )
				)
				( attribute "GROUP" "PWR_MLCC_CAP"
					( Origin gFrontEnd )
				)
				( attribute "BOM_DS" "NOPOP"
					( Origin gFrontEnd )
				)
				( objectStatus "C5G68" )
			)
			( gate "@baseboard_fab2_lib.baseboard_fab2(sch_1):page207_i100"
				( attribute "BOM_COST" "NT_GBE_BASE"
					( Origin gFrontEnd )
				)
				( attribute "CDS_LIB" "mstr_discrete"
					( Origin gPackager )
				)
				( attribute "LOCATION" "RT17"
					( Origin gFrontEnd )
				)
				( attribute "MATERIAL" "CHIP"
					( Origin gFrontEnd )
				)
				( attribute "PACK_TYPE" "0603"
					( Origin gFrontEnd )
				)
				( attribute "PART_NUMBER" "G22178-002"
					( Origin gFrontEnd )
				)
				( attribute "PHYS_PAGE" "207"
					( Origin gFrontEnd )
				)
				( attribute "ROOM" "NIC_SPRV"
					( Origin gFrontEnd )
				)
				( attribute "ROT" "0"
					( Origin gFrontEnd )
				)
				( attribute "TOLERANCE" "5.0%"
					( Origin gFrontEnd )
				)
				( attribute "VALUE" "0"
					( Origin gFrontEnd )
				)
				( attribute "VER" "1"
					( Origin gFrontEnd )
				)
				( attribute "WATTAGE" "1/10W"
					( Origin gFrontEnd )
				)
				( attribute "XY" "(-4700,1025)"
					( Origin gFrontEnd )
				)
				( attribute "CHIPS_PART_NAME" "RES"
					( Origin gPackager )
				)
				( attribute "CDS_PART_NAME" "RES_0603-0,5.0%,1/10W,CHIP,G22A"
					( Origin gPackager )
				)
				( attribute "CDS_LOCATION" "RT17"
					( Origin gPackager )
				)
				( attribute "SEC" "1"
					( Origin gFrontEnd )
				)
				( attribute "SEC_TYPE" "0603"
					( Origin gFrontEnd )
				)
				( attribute "CDS_SEC" "1"
					( Origin gPackager )
				)
				( objectStatus "RT17" )
			)
			( gate "@baseboard_fab2_lib.baseboard_fab2(sch_1):page202_i70"
				( attribute "CDS_LIB" "dev_discrete"
					( Origin gPackager )
				)
				( attribute "LOCATION" "CT1"
					( Origin gFrontEnd )
				)
				( attribute "MATERIAL" "X7R"
					( Origin gFrontEnd )
				)
				( attribute "PACK_TYPE" "0402V"
					( Origin gFrontEnd )
				)
				( attribute "PART_NUMBER" "A36096-030"
					( Origin gFrontEnd )
				)
				( attribute "PHYS_PAGE" "202"
					( Origin gFrontEnd )
				)
				( attribute "ROOM" "PVCCIN_CPU0_PWR_VR"
					( Origin gFrontEnd )
				)
				( attribute "ROT" "0"
					( Origin gFrontEnd )
				)
				( attribute "TOLERANCE" "10%"
					( Origin gFrontEnd )
				)
				( attribute "VALUE" "0.1UF"
					( Origin gFrontEnd )
				)
				( attribute "VER" "1"
					( Origin gFrontEnd )
				)
				( attribute "VOLTAGE" "16V"
					( Units "uVoltage" "V" 1.000000)
					( Origin gFrontEnd )
				)
				( attribute "XY" "(-4125,3300)"
					( Origin gFrontEnd )
				)
				( attribute "CHIPS_PART_NAME" "CAP_A"
					( Origin gPackager )
				)
				( attribute "CDS_PART_NAME" "CAP_A_0402V-0.1UF,16V,10%,X7R,A"
					( Origin gPackager )
				)
				( attribute "CDS_LOCATION" "CT1"
					( Origin gPackager )
				)
				( attribute "SEC" "1"
					( Origin gFrontEnd )
				)
				( attribute "SEC_TYPE" "0402V"
					( Origin gFrontEnd )
				)
				( attribute "CDS_SEC" "1"
					( Origin gPackager )
				)
				( attribute "POP" "NOPOP"
					( Origin gFrontEnd )
				)
				( objectStatus "CT1" )
			)
			( gate "@baseboard_fab2_lib.baseboard_fab2(sch_1):page204_i114"
				( attribute "ATTRIBUTE" "1 OHM"
					( Origin gFrontEnd )
				)
				( attribute "CDS_LIB" "w_hdl"
					( Origin gPackager )
				)
				( attribute "CDS_LMAN_SYM_OUTLINE" "-50,75,50,-75"
					( Origin gPackager )
				)
				( attribute "LOCATION" "RT24"
					( Origin gFrontEnd )
				)
				( attribute "PACK_TYPE" "RCL_GP"
					( Origin gFrontEnd )
				)
				( attribute "PART_NUMBER" "64.1R005.55L"
					( Origin gFrontEnd )
				)
				( attribute "PHYS_PAGE" "204"
					( Origin gFrontEnd )
				)
				( attribute "POP" "NOPOP"
					( Origin gFrontEnd )
				)
				( attribute "RATED" "1/10W"
					( Origin gFrontEnd )
				)
				( attribute "ROT" "0"
					( Origin gFrontEnd )
				)
				( attribute "SEC" "1"
					( Origin gFrontEnd )
				)
				( attribute "SEC_TYPE" "RCL_GP"
					( Origin gFrontEnd )
				)
				( attribute "TOLERANCE" "1%"
					( Origin gFrontEnd )
				)
				( attribute "VALUE" "1R3F-GP"
					( Origin gFrontEnd )
				)
				( attribute "VER" "1"
					( Origin gFrontEnd )
				)
				( attribute "XY" "(-1975,3175)"
					( Origin gFrontEnd )
				)
				( attribute "CHIPS_PART_NAME" "1R3F-GP"
					( Origin gPackager )
				)
				( attribute "CDS_PART_NAME" "1R3F-GP_RCL_GP-1R3F-GP,64.1R00A"
					( Origin gPackager )
				)
				( attribute "PACK_SIZE" "0603"
					( Origin gFrontEnd )
				)
				( attribute "CDS_LOCATION" "RT24"
					( Origin gPackager )
				)
				( attribute "CDS_SEC" "1"
					( Origin gPackager )
				)
				( objectStatus "RT24" )
			)
			( gate "@baseboard_fab2_lib.baseboard_fab2(sch_1):page204_i97"
				( attribute "CDS_LIB" "mstr_discrete"
					( Origin gPackager )
				)
				( attribute "LOCATION" "CT35"
					( Origin gFrontEnd )
				)
				( attribute "MATERIAL" "X7R"
					( Origin gFrontEnd )
				)
				( attribute "PACK_TYPE" "0402LF"
					( Origin gFrontEnd )
				)
				( attribute "PART_NUMBER" "A36096-046"
					( Origin gFrontEnd )
				)
				( attribute "PHYS_PAGE" "204"
					( Origin gFrontEnd )
				)
				( attribute "POP" "NOPOP"
					( Origin gFrontEnd )
				)
				( attribute "ROOM" "VDDQ_KLM_PWR_VR"
					( Origin gFrontEnd )
				)
				( attribute "ROT" "0"
					( Origin gFrontEnd )
				)
				( attribute "TOLERANCE" "10%"
					( Origin gFrontEnd )
				)
				( attribute "VALUE" "1000PF"
					( Origin gFrontEnd )
				)
				( attribute "VER" "1"
					( Origin gFrontEnd )
				)
				( attribute "VOLTAGE" "50V"
					( Units "uVoltage" "V" 1.000000)
					( Origin gFrontEnd )
				)
				( attribute "XY" "(-1975,3475)"
					( Origin gFrontEnd )
				)
				( attribute "CHIPS_PART_NAME" "CAP"
					( Origin gPackager )
				)
				( attribute "CDS_PART_NAME" "CAP_0402LF-1000PF,50V,10%,X7R,A"
					( Origin gPackager )
				)
				( attribute "CDS_LOCATION" "CT35"
					( Origin gPackager )
				)
				( attribute "SEC" "1"
					( Origin gFrontEnd )
				)
				( attribute "SEC_TYPE" "0402LF"
					( Origin gFrontEnd )
				)
				( attribute "CDS_SEC" "1"
					( Origin gPackager )
				)
				( objectStatus "CT35" )
			)
			( gate "@baseboard_fab2_lib.baseboard_fab2(sch_1):page202_i78"
				( attribute "CDS_LIB" "mstr_discrete"
					( Origin gPackager )
				)
				( attribute "CDS_LOCATION" "CT2"
					( Origin gPackager )
				)
				( attribute "LOCATION" "CT2"
					( Origin gFrontEnd )
				)
				( attribute "MATERIAL" "X7R"
					( Origin gFrontEnd )
				)
				( attribute "PACK_TYPE" "0402LF"
					( Origin gFrontEnd )
				)
				( attribute "PART_NUMBER" "A36096-046"
					( Origin gFrontEnd )
				)
				( attribute "PHYS_PAGE" "202"
					( Origin gFrontEnd )
				)
				( attribute "ROOM" "VDDQ_KLM_PWR_VR"
					( Origin gFrontEnd )
				)
				( attribute "ROT" "0"
					( Origin gFrontEnd )
				)
				( attribute "SEC" "1"
					( Origin gFrontEnd )
				)
				( attribute "SEC_TYPE" "0402LF"
					( Origin gFrontEnd )
				)
				( attribute "TOLERANCE" "10%"
					( Origin gFrontEnd )
				)
				( attribute "VALUE" "1000PF"
					( Origin gFrontEnd )
				)
				( attribute "VER" "1"
					( Origin gFrontEnd )
				)
				( attribute "VOLTAGE" "50V"
					( Units "uVoltage" "V" 1.000000)
					( Origin gFrontEnd )
				)
				( attribute "XY" "(-2350,3875)"
					( Origin gFrontEnd )
				)
				( attribute "CHIPS_PART_NAME" "CAP"
					( Origin gPackager )
				)
				( attribute "CDS_PART_NAME" "CAP_0402LF-1000PF,50V,10%,X7R,A"
					( Origin gPackager )
				)
				( attribute "CDS_SEC" "1"
					( Origin gPackager )
				)
				( attribute "POP" "NOPOP"
					( Origin gFrontEnd )
				)
				( objectStatus "CT2" )
			)
			( gate "@baseboard_fab2_lib.baseboard_fab2(sch_1):page202_i81"
				( attribute "CDS_LIB" "dev_discrete"
					( Origin gPackager )
				)
				( attribute "LOCATION" "CT6"
					( Origin gFrontEnd )
				)
				( attribute "MATERIAL" "X7R"
					( Origin gFrontEnd )
				)
				( attribute "PACK_TYPE" "0402V"
					( Origin gFrontEnd )
				)
				( attribute "PART_NUMBER" "A36096-030"
					( Origin gFrontEnd )
				)
				( attribute "PHYS_PAGE" "202"
					( Origin gFrontEnd )
				)
				( attribute "ROOM" "PVCCIN_CPU0_PWR_VR"
					( Origin gFrontEnd )
				)
				( attribute "ROT" "0"
					( Origin gFrontEnd )
				)
				( attribute "TOLERANCE" "10%"
					( Origin gFrontEnd )
				)
				( attribute "VALUE" "0.1UF"
					( Origin gFrontEnd )
				)
				( attribute "VER" "1"
					( Origin gFrontEnd )
				)
				( attribute "VOLTAGE" "16V"
					( Units "uVoltage" "V" 1.000000)
					( Origin gFrontEnd )
				)
				( attribute "XY" "(-4175,675)"
					( Origin gFrontEnd )
				)
				( attribute "CHIPS_PART_NAME" "CAP_A"
					( Origin gPackager )
				)
				( attribute "CDS_PART_NAME" "CAP_A_0402V-0.1UF,16V,10%,X7R,A"
					( Origin gPackager )
				)
				( attribute "SEC" "1"
					( Origin gFrontEnd )
				)
				( attribute "SEC_TYPE" "0402V"
					( Origin gFrontEnd )
				)
				( attribute "CDS_LOCATION" "CT6"
					( Origin gPackager )
				)
				( attribute "CDS_SEC" "1"
					( Origin gPackager )
				)
				( attribute "POP" "NOPOP"
					( Origin gFrontEnd )
				)
				( objectStatus "CT6" )
			)
			( gate "@baseboard_fab2_lib.baseboard_fab2(sch_1):page207_i96"
				( attribute "CDS_LIB" "mstr_discrete"
					( Origin gPackager )
				)
				( attribute "LOCATION" "CT27"
					( Origin gFrontEnd )
				)
				( attribute "MATERIAL" "X7R"
					( Origin gFrontEnd )
				)
				( attribute "PACK_TYPE" "0402LF"
					( Origin gFrontEnd )
				)
				( attribute "PART_NUMBER" "A36096-046"
					( Origin gFrontEnd )
				)
				( attribute "PHYS_PAGE" "207"
					( Origin gFrontEnd )
				)
				( attribute "POP" "NOPOP"
					( Origin gFrontEnd )
				)
				( attribute "ROOM" "VDDQ_KLM_PWR_VR"
					( Origin gFrontEnd )
				)
				( attribute "ROT" "0"
					( Origin gFrontEnd )
				)
				( attribute "TOLERANCE" "10%"
					( Origin gFrontEnd )
				)
				( attribute "VALUE" "1000PF"
					( Origin gFrontEnd )
				)
				( attribute "VER" "1"
					( Origin gFrontEnd )
				)
				( attribute "VOLTAGE" "50V"
					( Units "uVoltage" "V" 1.000000)
					( Origin gFrontEnd )
				)
				( attribute "XY" "(-1925,825)"
					( Origin gFrontEnd )
				)
				( attribute "CHIPS_PART_NAME" "CAP"
					( Origin gPackager )
				)
				( attribute "CDS_PART_NAME" "CAP_0402LF-1000PF,50V,10%,X7R,A"
					( Origin gPackager )
				)
				( attribute "CDS_LOCATION" "CT27"
					( Origin gPackager )
				)
				( attribute "SEC" "1"
					( Origin gFrontEnd )
				)
				( attribute "SEC_TYPE" "0402LF"
					( Origin gFrontEnd )
				)
				( attribute "CDS_SEC" "1"
					( Origin gPackager )
				)
				( objectStatus "CT27" )
			)
			( gate "@baseboard_fab2_lib.baseboard_fab2(sch_1):page227_i109"
				( attribute "CDS_LIB" "dev_discrete"
					( Origin gPackager )
				)
				( attribute "LOCATION" "CT7"
					( Origin gFrontEnd )
				)
				( attribute "MATERIAL" "X7R"
					( Origin gFrontEnd )
				)
				( attribute "PACK_TYPE" "0402V"
					( Origin gFrontEnd )
				)
				( attribute "PART_NUMBER" "A36096-030"
					( Origin gFrontEnd )
				)
				( attribute "PHYS_PAGE" "227"
					( Origin gFrontEnd )
				)
				( attribute "ROOM" "PVCCIN_CPU0_PWR_VR"
					( Origin gFrontEnd )
				)
				( attribute "ROT" "0"
					( Origin gFrontEnd )
				)
				( attribute "TOLERANCE" "10%"
					( Origin gFrontEnd )
				)
				( attribute "VALUE" "0.1UF"
					( Origin gFrontEnd )
				)
				( attribute "VER" "1"
					( Origin gFrontEnd )
				)
				( attribute "VOLTAGE" "16V"
					( Units "uVoltage" "V" 1.000000)
					( Origin gFrontEnd )
				)
				( attribute "XY" "(1150,1725)"
					( Origin gFrontEnd )
				)
				( attribute "CHIPS_PART_NAME" "CAP_A"
					( Origin gPackager )
				)
				( attribute "CDS_PART_NAME" "CAP_A_0402V-0.1UF,16V,10%,X7R,A"
					( Origin gPackager )
				)
				( attribute "CDS_LOCATION" "CT7"
					( Origin gPackager )
				)
				( attribute "SEC" "1"
					( Origin gFrontEnd )
				)
				( attribute "SEC_TYPE" "0402V"
					( Origin gFrontEnd )
				)
				( attribute "CDS_SEC" "1"
					( Origin gPackager )
				)
				( attribute "POP" "NOPOP"
					( Origin gFrontEnd )
				)
				( objectStatus "CT7" )
			)
			( gate "@baseboard_fab2_lib.baseboard_fab2(sch_1):page216_i136"
				( attribute "CDS_LIB" "mstr_discrete"
					( Origin gPackager )
				)
				( attribute "LOCATION" "CT53"
					( Origin gFrontEnd )
				)
				( attribute "MATERIAL" "X7R"
					( Origin gFrontEnd )
				)
				( attribute "PACK_TYPE" "0402LF"
					( Origin gFrontEnd )
				)
				( attribute "PART_NUMBER" "A36096-046"
					( Origin gFrontEnd )
				)
				( attribute "PHYS_PAGE" "216"
					( Origin gFrontEnd )
				)
				( attribute "POP" "NOPOP"
					( Origin gFrontEnd )
				)
				( attribute "ROOM" "VDDQ_KLM_PWR_VR"
					( Origin gFrontEnd )
				)
				( attribute "ROT" "0"
					( Origin gFrontEnd )
				)
				( attribute "TOLERANCE" "10%"
					( Origin gFrontEnd )
				)
				( attribute "VALUE" "1000PF"
					( Origin gFrontEnd )
				)
				( attribute "VER" "1"
					( Origin gFrontEnd )
				)
				( attribute "VOLTAGE" "50V"
					( Units "uVoltage" "V" 1.000000)
					( Origin gFrontEnd )
				)
				( attribute "XY" "(2900,-525)"
					( Origin gFrontEnd )
				)
				( attribute "CHIPS_PART_NAME" "CAP"
					( Origin gPackager )
				)
				( attribute "CDS_PART_NAME" "CAP_0402LF-1000PF,50V,10%,X7R,A"
					( Origin gPackager )
				)
				( attribute "CDS_LOCATION" "CT53"
					( Origin gPackager )
				)
				( attribute "SEC" "1"
					( Origin gFrontEnd )
				)
				( attribute "SEC_TYPE" "0402LF"
					( Origin gFrontEnd )
				)
				( attribute "CDS_SEC" "1"
					( Origin gPackager )
				)
				( attribute "BOM_SS" "NOPOP"
					( Origin gFrontEnd )
				)
				( objectStatus "CT53" )
			)
			( gate "@baseboard_fab2_lib.baseboard_fab2(sch_1):page227_i114"
				( attribute "CDS_LIB" "mstr_discrete"
					( Origin gPackager )
				)
				( attribute "LOCATION" "CT8"
					( Origin gFrontEnd )
				)
				( attribute "MATERIAL" "X7R"
					( Origin gFrontEnd )
				)
				( attribute "PACK_TYPE" "0402LF"
					( Origin gFrontEnd )
				)
				( attribute "PART_NUMBER" "A36096-046"
					( Origin gFrontEnd )
				)
				( attribute "PHYS_PAGE" "227"
					( Origin gFrontEnd )
				)
				( attribute "ROOM" "VDDQ_KLM_PWR_VR"
					( Origin gFrontEnd )
				)
				( attribute "ROT" "0"
					( Origin gFrontEnd )
				)
				( attribute "TOLERANCE" "10%"
					( Origin gFrontEnd )
				)
				( attribute "VALUE" "1000PF"
					( Origin gFrontEnd )
				)
				( attribute "VER" "1"
					( Origin gFrontEnd )
				)
				( attribute "VOLTAGE" "50V"
					( Units "uVoltage" "V" 1.000000)
					( Origin gFrontEnd )
				)
				( attribute "XY" "(3050,2200)"
					( Origin gFrontEnd )
				)
				( attribute "CHIPS_PART_NAME" "CAP"
					( Origin gPackager )
				)
				( attribute "CDS_PART_NAME" "CAP_0402LF-1000PF,50V,10%,X7R,A"
					( Origin gPackager )
				)
				( attribute "CDS_LOCATION" "CT8"
					( Origin gPackager )
				)
				( attribute "SEC" "1"
					( Origin gFrontEnd )
				)
				( attribute "POP" "NOPOP"
					( Origin gFrontEnd )
				)
				( attribute "SEC_TYPE" "0402LF"
					( Origin gFrontEnd )
				)
				( attribute "CDS_SEC" "1"
					( Origin gPackager )
				)
				( objectStatus "CT8" )
			)
			( gate "@baseboard_fab2_lib.baseboard_fab2(sch_1):page227_i119"
				( attribute "CDS_LIB" "mstr_discrete"
					( Origin gPackager )
				)
				( attribute "LOCATION" "CT10"
					( Origin gFrontEnd )
				)
				( attribute "MATERIAL" "X7R"
					( Origin gFrontEnd )
				)
				( attribute "PACK_TYPE" "0402LF"
					( Origin gFrontEnd )
				)
				( attribute "PART_NUMBER" "A36096-046"
					( Origin gFrontEnd )
				)
				( attribute "PHYS_PAGE" "227"
					( Origin gFrontEnd )
				)
				( attribute "ROOM" "VDDQ_KLM_PWR_VR"
					( Origin gFrontEnd )
				)
				( attribute "ROT" "0"
					( Origin gFrontEnd )
				)
				( attribute "TOLERANCE" "10%"
					( Origin gFrontEnd )
				)
				( attribute "VALUE" "1000PF"
					( Origin gFrontEnd )
				)
				( attribute "VER" "1"
					( Origin gFrontEnd )
				)
				( attribute "VOLTAGE" "50V"
					( Units "uVoltage" "V" 1.000000)
					( Origin gFrontEnd )
				)
				( attribute "XY" "(2950,25)"
					( Origin gFrontEnd )
				)
				( attribute "CHIPS_PART_NAME" "CAP"
					( Origin gPackager )
				)
				( attribute "CDS_PART_NAME" "CAP_0402LF-1000PF,50V,10%,X7R,A"
					( Origin gPackager )
				)
				( attribute "CDS_LOCATION" "CT10"
					( Origin gPackager )
				)
				( attribute "SEC" "1"
					( Origin gFrontEnd )
				)
				( attribute "POP" "NOPOP"
					( Origin gFrontEnd )
				)
				( attribute "SEC_TYPE" "0402LF"
					( Origin gFrontEnd )
				)
				( attribute "CDS_SEC" "1"
					( Origin gPackager )
				)
				( attribute "BOM_SS" "NOPOP"
					( Origin gFrontEnd )
				)
				( objectStatus "CT10" )
			)
			( gate "@baseboard_fab2_lib.baseboard_fab2(sch_1):page227_i122"
				( attribute "CDS_LIB" "dev_discrete"
					( Origin gPackager )
				)
				( attribute "LOCATION" "CT12"
					( Origin gFrontEnd )
				)
				( attribute "MATERIAL" "X7R"
					( Origin gFrontEnd )
				)
				( attribute "PACK_TYPE" "0402V"
					( Origin gFrontEnd )
				)
				( attribute "PART_NUMBER" "A36096-030"
					( Origin gFrontEnd )
				)
				( attribute "PHYS_PAGE" "227"
					( Origin gFrontEnd )
				)
				( attribute "ROOM" "PVCCIN_CPU0_PWR_VR"
					( Origin gFrontEnd )
				)
				( attribute "ROT" "0"
					( Origin gFrontEnd )
				)
				( attribute "TOLERANCE" "10%"
					( Origin gFrontEnd )
				)
				( attribute "VALUE" "0.1UF"
					( Origin gFrontEnd )
				)
				( attribute "VER" "1"
					( Origin gFrontEnd )
				)
				( attribute "VOLTAGE" "16V"
					( Units "uVoltage" "V" 1.000000)
					( Origin gFrontEnd )
				)
				( attribute "XY" "(1150,-800)"
					( Origin gFrontEnd )
				)
				( attribute "CHIPS_PART_NAME" "CAP_A"
					( Origin gPackager )
				)
				( attribute "CDS_PART_NAME" "CAP_A_0402V-0.1UF,16V,10%,X7R,A"
					( Origin gPackager )
				)
				( attribute "CDS_LOCATION" "CT12"
					( Origin gPackager )
				)
				( attribute "SEC" "1"
					( Origin gFrontEnd )
				)
				( attribute "SEC_TYPE" "0402V"
					( Origin gFrontEnd )
				)
				( attribute "CDS_SEC" "1"
					( Origin gPackager )
				)
				( attribute "POP" "NOPOP"
					( Origin gFrontEnd )
				)
				( attribute "BOM_SS" "NOPOP"
					( Origin gFrontEnd )
				)
				( objectStatus "CT12" )
			)
			( gate "@baseboard_fab2_lib.baseboard_fab2(sch_1):page210_i66"
				( attribute "CDS_LIB" "mstr_discrete"
					( Origin gPackager )
				)
				( attribute "LOCATION" "CT56"
					( Origin gFrontEnd )
				)
				( attribute "MATERIAL" "X7R"
					( Origin gFrontEnd )
				)
				( attribute "PACK_TYPE" "0402LF"
					( Origin gFrontEnd )
				)
				( attribute "PART_NUMBER" "A36096-046"
					( Origin gFrontEnd )
				)
				( attribute "PHYS_PAGE" "210"
					( Origin gFrontEnd )
				)
				( attribute "POP" "NOPOP"
					( Origin gFrontEnd )
				)
				( attribute "ROOM" "VDDQ_KLM_PWR_VR"
					( Origin gFrontEnd )
				)
				( attribute "ROT" "0"
					( Origin gFrontEnd )
				)
				( attribute "TOLERANCE" "10%"
					( Origin gFrontEnd )
				)
				( attribute "VALUE" "1000PF"
					( Origin gFrontEnd )
				)
				( attribute "VER" "1"
					( Origin gFrontEnd )
				)
				( attribute "VOLTAGE" "50V"
					( Units "uVoltage" "V" 1.000000)
					( Origin gFrontEnd )
				)
				( attribute "XY" "(-2500,3150)"
					( Origin gFrontEnd )
				)
				( attribute "CHIPS_PART_NAME" "CAP"
					( Origin gPackager )
				)
				( attribute "CDS_PART_NAME" "CAP_0402LF-1000PF,50V,10%,X7R,A"
					( Origin gPackager )
				)
				( attribute "CDS_LOCATION" "CT56"
					( Origin gPackager )
				)
				( attribute "SEC" "1"
					( Origin gFrontEnd )
				)
				( attribute "SEC_TYPE" "0402LF"
					( Origin gFrontEnd )
				)
				( attribute "CDS_SEC" "1"
					( Origin gPackager )
				)
				( objectStatus "CT56" )
			)
			( gate "@baseboard_fab2_lib.baseboard_fab2(sch_1):page209_i62"
				( attribute "CDS_LIB" "dev_discrete"
					( Origin gPackager )
				)
				( attribute "LOCATION" "CT13"
					( Origin gFrontEnd )
				)
				( attribute "MATERIAL" "X7R"
					( Origin gFrontEnd )
				)
				( attribute "PACK_TYPE" "0402V"
					( Origin gFrontEnd )
				)
				( attribute "PART_NUMBER" "A36096-030"
					( Origin gFrontEnd )
				)
				( attribute "PHYS_PAGE" "209"
					( Origin gFrontEnd )
				)
				( attribute "ROOM" "PVCCIN_CPU0_PWR_VR"
					( Origin gFrontEnd )
				)
				( attribute "ROT" "0"
					( Origin gFrontEnd )
				)
				( attribute "TOLERANCE" "10%"
					( Origin gFrontEnd )
				)
				( attribute "VALUE" "0.1UF"
					( Origin gFrontEnd )
				)
				( attribute "VER" "1"
					( Origin gFrontEnd )
				)
				( attribute "VOLTAGE" "16V"
					( Units "uVoltage" "V" 1.000000)
					( Origin gFrontEnd )
				)
				( attribute "XY" "(-3950,3275)"
					( Origin gFrontEnd )
				)
				( attribute "CHIPS_PART_NAME" "CAP_A"
					( Origin gPackager )
				)
				( attribute "CDS_PART_NAME" "CAP_A_0402V-0.1UF,16V,10%,X7R,A"
					( Origin gPackager )
				)
				( attribute "CDS_LOCATION" "CT13"
					( Origin gPackager )
				)
				( attribute "SEC" "1"
					( Origin gFrontEnd )
				)
				( attribute "SEC_TYPE" "0402V"
					( Origin gFrontEnd )
				)
				( attribute "CDS_SEC" "1"
					( Origin gPackager )
				)
				( attribute "POP" "NOPOP"
					( Origin gFrontEnd )
				)
				( objectStatus "CT13" )
			)
			( gate "@baseboard_fab2_lib.baseboard_fab2(sch_1):page207_i95"
				( attribute "CDS_LIB" "mstr_discrete"
					( Origin gPackager )
				)
				( attribute "LOCATION" "CT23"
					( Origin gFrontEnd )
				)
				( attribute "MATERIAL" "X7R"
					( Origin gFrontEnd )
				)
				( attribute "PACK_TYPE" "0402LF"
					( Origin gFrontEnd )
				)
				( attribute "PART_NUMBER" "A36096-046"
					( Origin gFrontEnd )
				)
				( attribute "PHYS_PAGE" "207"
					( Origin gFrontEnd )
				)
				( attribute "POP" "NOPOP"
					( Origin gFrontEnd )
				)
				( attribute "ROOM" "VDDQ_KLM_PWR_VR"
					( Origin gFrontEnd )
				)
				( attribute "ROT" "0"
					( Origin gFrontEnd )
				)
				( attribute "TOLERANCE" "10%"
					( Origin gFrontEnd )
				)
				( attribute "VALUE" "1000PF"
					( Origin gFrontEnd )
				)
				( attribute "VER" "1"
					( Origin gFrontEnd )
				)
				( attribute "VOLTAGE" "50V"
					( Units "uVoltage" "V" 1.000000)
					( Origin gFrontEnd )
				)
				( attribute "XY" "(-2225,3400)"
					( Origin gFrontEnd )
				)
				( attribute "CHIPS_PART_NAME" "CAP"
					( Origin gPackager )
				)
				( attribute "CDS_PART_NAME" "CAP_0402LF-1000PF,50V,10%,X7R,A"
					( Origin gPackager )
				)
				( attribute "CDS_LOCATION" "CT23"
					( Origin gPackager )
				)
				( attribute "SEC" "1"
					( Origin gFrontEnd )
				)
				( attribute "SEC_TYPE" "0402LF"
					( Origin gFrontEnd )
				)
				( attribute "CDS_SEC" "1"
					( Origin gPackager )
				)
				( objectStatus "CT23" )
			)
			( gate "@baseboard_fab2_lib.baseboard_fab2(sch_1):page224_i156"
				( attribute "ATTRIBUTE" "1 OHM"
					( Origin gFrontEnd )
				)
				( attribute "CDS_LIB" "w_hdl"
					( Origin gPackager )
				)
				( attribute "CDS_LMAN_SYM_OUTLINE" "-50,75,50,-75"
					( Origin gPackager )
				)
				( attribute "LOCATION" "RT20"
					( Origin gFrontEnd )
				)
				( attribute "PACK_TYPE" "RCL_GP"
					( Origin gFrontEnd )
				)
				( attribute "PART_NUMBER" "64.1R005.55L"
					( Origin gFrontEnd )
				)
				( attribute "PHYS_PAGE" "224"
					( Origin gFrontEnd )
				)
				( attribute "POP" "NOPOP"
					( Origin gFrontEnd )
				)
				( attribute "RATED" "1/10W"
					( Origin gFrontEnd )
				)
				( attribute "ROT" "0"
					( Origin gFrontEnd )
				)
				( attribute "SEC" "1"
					( Origin gFrontEnd )
				)
				( attribute "SEC_TYPE" "RCL_GP"
					( Origin gFrontEnd )
				)
				( attribute "TOLERANCE" "1%"
					( Origin gFrontEnd )
				)
				( attribute "VALUE" "1R3F-GP"
					( Origin gFrontEnd )
				)
				( attribute "VER" "1"
					( Origin gFrontEnd )
				)
				( attribute "XY" "(2900,1475)"
					( Origin gFrontEnd )
				)
				( attribute "CHIPS_PART_NAME" "1R3F-GP"
					( Origin gPackager )
				)
				( attribute "CDS_PART_NAME" "1R3F-GP_RCL_GP-1R3F-GP,64.1R00A"
					( Origin gPackager )
				)
				( attribute "PACK_SIZE" "0603"
					( Origin gFrontEnd )
				)
				( attribute "CDS_LOCATION" "RT20"
					( Origin gPackager )
				)
				( attribute "CDS_SEC" "1"
					( Origin gPackager )
				)
				( objectStatus "RT20" )
			)
			( gate "@baseboard_fab2_lib.baseboard_fab2(sch_1):page209_i67"
				( attribute "CDS_LIB" "mstr_discrete"
					( Origin gPackager )
				)
				( attribute "LOCATION" "CT15"
					( Origin gFrontEnd )
				)
				( attribute "MATERIAL" "X7R"
					( Origin gFrontEnd )
				)
				( attribute "PACK_TYPE" "0402LF"
					( Origin gFrontEnd )
				)
				( attribute "PART_NUMBER" "A36096-046"
					( Origin gFrontEnd )
				)
				( attribute "PHYS_PAGE" "209"
					( Origin gFrontEnd )
				)
				( attribute "ROOM" "VDDQ_KLM_PWR_VR"
					( Origin gFrontEnd )
				)
				( attribute "ROT" "0"
					( Origin gFrontEnd )
				)
				( attribute "TOLERANCE" "10%"
					( Origin gFrontEnd )
				)
				( attribute "VALUE" "1000PF"
					( Origin gFrontEnd )
				)
				( attribute "VER" "1"
					( Origin gFrontEnd )
				)
				( attribute "VOLTAGE" "50V"
					( Units "uVoltage" "V" 1.000000)
					( Origin gFrontEnd )
				)
				( attribute "XY" "(-1950,3825)"
					( Origin gFrontEnd )
				)
				( attribute "CHIPS_PART_NAME" "CAP"
					( Origin gPackager )
				)
				( attribute "CDS_PART_NAME" "CAP_0402LF-1000PF,50V,10%,X7R,A"
					( Origin gPackager )
				)
				( attribute "CDS_LOCATION" "CT15"
					( Origin gPackager )
				)
				( attribute "SEC" "1"
					( Origin gFrontEnd )
				)
				( attribute "POP" "NOPOP"
					( Origin gFrontEnd )
				)
				( attribute "SEC_TYPE" "0402LF"
					( Origin gFrontEnd )
				)
				( attribute "CDS_SEC" "1"
					( Origin gPackager )
				)
				( objectStatus "CT15" )
			)
			( gate "@baseboard_fab2_lib.baseboard_fab2(sch_1):page208_i80"
				( attribute "CDS_LIB" "dev_discrete"
					( Origin gPackager )
				)
				( attribute "LOCATION" "CT16"
					( Origin gFrontEnd )
				)
				( attribute "MATERIAL" "X7R"
					( Origin gFrontEnd )
				)
				( attribute "PACK_TYPE" "0402V"
					( Origin gFrontEnd )
				)
				( attribute "PART_NUMBER" "A36096-030"
					( Origin gFrontEnd )
				)
				( attribute "PHYS_PAGE" "208"
					( Origin gFrontEnd )
				)
				( attribute "ROOM" "PVCCIN_CPU0_PWR_VR"
					( Origin gFrontEnd )
				)
				( attribute "ROT" "0"
					( Origin gFrontEnd )
				)
				( attribute "TOLERANCE" "10%"
					( Origin gFrontEnd )
				)
				( attribute "VALUE" "0.1UF"
					( Origin gFrontEnd )
				)
				( attribute "VER" "1"
					( Origin gFrontEnd )
				)
				( attribute "VOLTAGE" "16V"
					( Units "uVoltage" "V" 1.000000)
					( Origin gFrontEnd )
				)
				( attribute "XY" "(-3975,3375)"
					( Origin gFrontEnd )
				)
				( attribute "CHIPS_PART_NAME" "CAP_A"
					( Origin gPackager )
				)
				( attribute "CDS_PART_NAME" "CAP_A_0402V-0.1UF,16V,10%,X7R,A"
					( Origin gPackager )
				)
				( attribute "CDS_LOCATION" "CT16"
					( Origin gPackager )
				)
				( attribute "SEC" "1"
					( Origin gFrontEnd )
				)
				( attribute "SEC_TYPE" "0402V"
					( Origin gFrontEnd )
				)
				( attribute "CDS_SEC" "1"
					( Origin gPackager )
				)
				( attribute "POP" "NOPOP"
					( Origin gFrontEnd )
				)
				( objectStatus "CT16" )
			)
			( gate "@baseboard_fab2_lib.baseboard_fab2(sch_1):page208_i82"
				( attribute "CDS_LIB" "mstr_discrete"
					( Origin gPackager )
				)
				( attribute "LOCATION" "CTI7"
					( Origin gFrontEnd )
				)
				( attribute "MATERIAL" "X7R"
					( Origin gFrontEnd )
				)
				( attribute "PACK_TYPE" "0402LF"
					( Origin gFrontEnd )
				)
				( attribute "PART_NUMBER" "A36096-046"
					( Origin gFrontEnd )
				)
				( attribute "PHYS_PAGE" "208"
					( Origin gFrontEnd )
				)
				( attribute "ROOM" "VDDQ_KLM_PWR_VR"
					( Origin gFrontEnd )
				)
				( attribute "ROT" "0"
					( Origin gFrontEnd )
				)
				( attribute "TOLERANCE" "10%"
					( Origin gFrontEnd )
				)
				( attribute "VALUE" "1000PF"
					( Origin gFrontEnd )
				)
				( attribute "VER" "1"
					( Origin gFrontEnd )
				)
				( attribute "VOLTAGE" "50V"
					( Units "uVoltage" "V" 1.000000)
					( Origin gFrontEnd )
				)
				( attribute "XY" "(-2050,3900)"
					( Origin gFrontEnd )
				)
				( attribute "CHIPS_PART_NAME" "CAP"
					( Origin gPackager )
				)
				( attribute "CDS_PART_NAME" "CAP_0402LF-1000PF,50V,10%,X7R,A"
					( Origin gPackager )
				)
				( attribute "POP" "NOPOP"
					( Origin gFrontEnd )
				)
				( attribute "CDS_LOCATION" "CTI7"
					( Origin gPackager )
				)
				( attribute "SEC" "1"
					( Origin gFrontEnd )
				)
				( attribute "SEC_TYPE" "0402LF"
					( Origin gFrontEnd )
				)
				( attribute "CDS_SEC" "1"
					( Origin gPackager )
				)
				( objectStatus "CTI7" )
			)
			( gate "@baseboard_fab2_lib.baseboard_fab2(sch_1):page208_i87"
				( attribute "CDS_LIB" "dev_discrete"
					( Origin gPackager )
				)
				( attribute "LOCATION" "CT21"
					( Origin gFrontEnd )
				)
				( attribute "MATERIAL" "X7R"
					( Origin gFrontEnd )
				)
				( attribute "PACK_TYPE" "0402V"
					( Origin gFrontEnd )
				)
				( attribute "PART_NUMBER" "A36096-030"
					( Origin gFrontEnd )
				)
				( attribute "PHYS_PAGE" "208"
					( Origin gFrontEnd )
				)
				( attribute "ROOM" "PVCCIN_CPU0_PWR_VR"
					( Origin gFrontEnd )
				)
				( attribute "ROT" "0"
					( Origin gFrontEnd )
				)
				( attribute "TOLERANCE" "10%"
					( Origin gFrontEnd )
				)
				( attribute "VALUE" "0.1UF"
					( Origin gFrontEnd )
				)
				( attribute "VER" "1"
					( Origin gFrontEnd )
				)
				( attribute "VOLTAGE" "16V"
					( Units "uVoltage" "V" 1.000000)
					( Origin gFrontEnd )
				)
				( attribute "XY" "(-3850,775)"
					( Origin gFrontEnd )
				)
				( attribute "CHIPS_PART_NAME" "CAP_A"
					( Origin gPackager )
				)
				( attribute "CDS_PART_NAME" "CAP_A_0402V-0.1UF,16V,10%,X7R,A"
					( Origin gPackager )
				)
				( attribute "CDS_LOCATION" "CT21"
					( Origin gPackager )
				)
				( attribute "SEC" "1"
					( Origin gFrontEnd )
				)
				( attribute "SEC_TYPE" "0402V"
					( Origin gFrontEnd )
				)
				( attribute "CDS_SEC" "1"
					( Origin gPackager )
				)
				( attribute "POP" "NOPOP"
					( Origin gFrontEnd )
				)
				( objectStatus "CT21" )
			)
			( gate "@baseboard_fab2_lib.baseboard_fab2(sch_1):page208_i90"
				( attribute "CDS_LIB" "mstr_discrete"
					( Origin gPackager )
				)
				( attribute "LOCATION" "CT19"
					( Origin gFrontEnd )
				)
				( attribute "MATERIAL" "X7R"
					( Origin gFrontEnd )
				)
				( attribute "PACK_TYPE" "0402LF"
					( Origin gFrontEnd )
				)
				( attribute "PART_NUMBER" "A36096-046"
					( Origin gFrontEnd )
				)
				( attribute "PHYS_PAGE" "208"
					( Origin gFrontEnd )
				)
				( attribute "ROOM" "VDDQ_KLM_PWR_VR"
					( Origin gFrontEnd )
				)
				( attribute "ROT" "0"
					( Origin gFrontEnd )
				)
				( attribute "TOLERANCE" "10%"
					( Origin gFrontEnd )
				)
				( attribute "VALUE" "1000PF"
					( Origin gFrontEnd )
				)
				( attribute "VER" "1"
					( Origin gFrontEnd )
				)
				( attribute "VOLTAGE" "50V"
					( Units "uVoltage" "V" 1.000000)
					( Origin gFrontEnd )
				)
				( attribute "XY" "(-2000,1300)"
					( Origin gFrontEnd )
				)
				( attribute "CHIPS_PART_NAME" "CAP"
					( Origin gPackager )
				)
				( attribute "CDS_PART_NAME" "CAP_0402LF-1000PF,50V,10%,X7R,A"
					( Origin gPackager )
				)
				( attribute "CDS_LOCATION" "CT19"
					( Origin gPackager )
				)
				( attribute "SEC" "1"
					( Origin gFrontEnd )
				)
				( attribute "POP" "NOPOP"
					( Origin gFrontEnd )
				)
				( attribute "SEC_TYPE" "0402LF"
					( Origin gFrontEnd )
				)
				( attribute "CDS_SEC" "1"
					( Origin gPackager )
				)
				( objectStatus "CT19" )
			)
			( gate "@baseboard_fab2_lib.baseboard_fab2(sch_1):page212_i144"
				( attribute "ATTRIBUTE" "1 OHM"
					( Origin gFrontEnd )
				)
				( attribute "CDS_LIB" "w_hdl"
					( Origin gPackager )
				)
				( attribute "CDS_LMAN_SYM_OUTLINE" "-50,75,50,-75"
					( Origin gPackager )
				)
				( attribute "LOCATION" "RT48"
					( Origin gFrontEnd )
				)
				( attribute "PACK_TYPE" "RCL_GP"
					( Origin gFrontEnd )
				)
				( attribute "PART_NUMBER" "64.1R005.55L"
					( Origin gFrontEnd )
				)
				( attribute "PHYS_PAGE" "212"
					( Origin gFrontEnd )
				)
				( attribute "POP" "NOPOP"
					( Origin gFrontEnd )
				)
				( attribute "RATED" "1/10W"
					( Origin gFrontEnd )
				)
				( attribute "ROT" "0"
					( Origin gFrontEnd )
				)
				( attribute "SEC" "1"
					( Origin gFrontEnd )
				)
				( attribute "SEC_TYPE" "RCL_GP"
					( Origin gFrontEnd )
				)
				( attribute "TOLERANCE" "1%"
					( Origin gFrontEnd )
				)
				( attribute "VALUE" "1R3F-GP"
					( Origin gFrontEnd )
				)
				( attribute "VER" "1"
					( Origin gFrontEnd )
				)
				( attribute "XY" "(2625,3100)"
					( Origin gFrontEnd )
				)
				( attribute "CHIPS_PART_NAME" "1R3F-GP"
					( Origin gPackager )
				)
				( attribute "CDS_PART_NAME" "1R3F-GP_RCL_GP-1R3F-GP,64.1R00A"
					( Origin gPackager )
				)
				( attribute "PACK_SIZE" "0603"
					( Origin gFrontEnd )
				)
				( attribute "CDS_LOCATION" "RT48"
					( Origin gPackager )
				)
				( attribute "CDS_SEC" "1"
					( Origin gPackager )
				)
				( objectStatus "RT48" )
			)
			( gate "@baseboard_fab2_lib.baseboard_fab2(sch_1):page207_i71"
				( attribute "CDS_LIB" "dev_discrete"
					( Origin gPackager )
				)
				( attribute "LOCATION" "CT24"
					( Origin gFrontEnd )
				)
				( attribute "MATERIAL" "X7R"
					( Origin gFrontEnd )
				)
				( attribute "PACK_TYPE" "0402V"
					( Origin gFrontEnd )
				)
				( attribute "PART_NUMBER" "A36096-030"
					( Origin gFrontEnd )
				)
				( attribute "PHYS_PAGE" "207"
					( Origin gFrontEnd )
				)
				( attribute "ROOM" "PVCCIN_CPU0_PWR_VR"
					( Origin gFrontEnd )
				)
				( attribute "ROT" "0"
					( Origin gFrontEnd )
				)
				( attribute "TOLERANCE" "10%"
					( Origin gFrontEnd )
				)
				( attribute "VALUE" "0.1UF"
					( Origin gFrontEnd )
				)
				( attribute "VER" "1"
					( Origin gFrontEnd )
				)
				( attribute "VOLTAGE" "16V"
					( Units "uVoltage" "V" 1.000000)
					( Origin gFrontEnd )
				)
				( attribute "XY" "(-3850,3350)"
					( Origin gFrontEnd )
				)
				( attribute "CHIPS_PART_NAME" "CAP_A"
					( Origin gPackager )
				)
				( attribute "CDS_PART_NAME" "CAP_A_0402V-0.1UF,16V,10%,X7R,A"
					( Origin gPackager )
				)
				( attribute "CDS_LOCATION" "CT24"
					( Origin gPackager )
				)
				( attribute "SEC" "1"
					( Origin gFrontEnd )
				)
				( attribute "SEC_TYPE" "0402V"
					( Origin gFrontEnd )
				)
				( attribute "CDS_SEC" "1"
					( Origin gPackager )
				)
				( attribute "POP" "NOPOP"
					( Origin gFrontEnd )
				)
				( objectStatus "CT24" )
			)
			( gate "@baseboard_fab2_lib.baseboard_fab2(sch_1):page207_i74"
				( attribute "CDS_LIB" "mstr_discrete"
					( Origin gPackager )
				)
				( attribute "LOCATION" "CT22"
					( Origin gFrontEnd )
				)
				( attribute "MATERIAL" "X7R"
					( Origin gFrontEnd )
				)
				( attribute "PACK_TYPE" "0402LF"
					( Origin gFrontEnd )
				)
				( attribute "PART_NUMBER" "A36096-046"
					( Origin gFrontEnd )
				)
				( attribute "PHYS_PAGE" "207"
					( Origin gFrontEnd )
				)
				( attribute "ROOM" "VDDQ_KLM_PWR_VR"
					( Origin gFrontEnd )
				)
				( attribute "ROT" "0"
					( Origin gFrontEnd )
				)
				( attribute "TOLERANCE" "10%"
					( Origin gFrontEnd )
				)
				( attribute "VALUE" "1000PF"
					( Origin gFrontEnd )
				)
				( attribute "VER" "1"
					( Origin gFrontEnd )
				)
				( attribute "VOLTAGE" "50V"
					( Units "uVoltage" "V" 1.000000)
					( Origin gFrontEnd )
				)
				( attribute "XY" "(-2125,3850)"
					( Origin gFrontEnd )
				)
				( attribute "CHIPS_PART_NAME" "CAP"
					( Origin gPackager )
				)
				( attribute "CDS_PART_NAME" "CAP_0402LF-1000PF,50V,10%,X7R,A"
					( Origin gPackager )
				)
				( attribute "CDS_LOCATION" "CT22"
					( Origin gPackager )
				)
				( attribute "SEC" "1"
					( Origin gFrontEnd )
				)
				( attribute "POP" "NOPOP"
					( Origin gFrontEnd )
				)
				( attribute "SEC_TYPE" "0402LF"
					( Origin gFrontEnd )
				)
				( attribute "CDS_SEC" "1"
					( Origin gPackager )
				)
				( objectStatus "CT22" )
			)
			( gate "@baseboard_fab2_lib.baseboard_fab2(sch_1):page216_i151"
				( attribute "ATTRIBUTE" "1 OHM"
					( Origin gFrontEnd )
				)
				( attribute "CDS_LIB" "w_hdl"
					( Origin gPackager )
				)
				( attribute "CDS_LMAN_SYM_OUTLINE" "-50,75,50,-75"
					( Origin gPackager )
				)
				( attribute "LOCATION" "RT34"
					( Origin gFrontEnd )
				)
				( attribute "PACK_TYPE" "RCL_GP"
					( Origin gFrontEnd )
				)
				( attribute "PART_NUMBER" "64.1R005.55L"
					( Origin gFrontEnd )
				)
				( attribute "PHYS_PAGE" "216"
					( Origin gFrontEnd )
				)
				( attribute "POP" "NOPOP"
					( Origin gFrontEnd )
				)
				( attribute "RATED" "1/10W"
					( Origin gFrontEnd )
				)
				( attribute "ROT" "0"
					( Origin gFrontEnd )
				)
				( attribute "SEC" "1"
					( Origin gFrontEnd )
				)
				( attribute "SEC_TYPE" "RCL_GP"
					( Origin gFrontEnd )
				)
				( attribute "TOLERANCE" "1%"
					( Origin gFrontEnd )
				)
				( attribute "VALUE" "1R3F-GP"
					( Origin gFrontEnd )
				)
				( attribute "VER" "1"
					( Origin gFrontEnd )
				)
				( attribute "XY" "(2900,1500)"
					( Origin gFrontEnd )
				)
				( attribute "CHIPS_PART_NAME" "1R3F-GP"
					( Origin gPackager )
				)
				( attribute "CDS_PART_NAME" "1R3F-GP_RCL_GP-1R3F-GP,64.1R00A"
					( Origin gPackager )
				)
				( attribute "PACK_SIZE" "0603"
					( Origin gFrontEnd )
				)
				( attribute "CDS_LOCATION" "RT34"
					( Origin gPackager )
				)
				( attribute "CDS_SEC" "1"
					( Origin gPackager )
				)
				( objectStatus "RT34" )
			)
			( gate "@baseboard_fab2_lib.baseboard_fab2(sch_1):page214_i143"
				( attribute "CDS_LIB" "mstr_discrete"
					( Origin gPackager )
				)
				( attribute "LOCATION" "CT62"
					( Origin gFrontEnd )
				)
				( attribute "MATERIAL" "X7R"
					( Origin gFrontEnd )
				)
				( attribute "PACK_TYPE" "0402LF"
					( Origin gFrontEnd )
				)
				( attribute "PART_NUMBER" "A36096-046"
					( Origin gFrontEnd )
				)
				( attribute "PHYS_PAGE" "214"
					( Origin gFrontEnd )
				)
				( attribute "POP" "NOPOP"
					( Origin gFrontEnd )
				)
				( attribute "ROOM" "VDDQ_KLM_PWR_VR"
					( Origin gFrontEnd )
				)
				( attribute "ROT" "0"
					( Origin gFrontEnd )
				)
				( attribute "TOLERANCE" "10%"
					( Origin gFrontEnd )
				)
				( attribute "VALUE" "1000PF"
					( Origin gFrontEnd )
				)
				( attribute "VER" "1"
					( Origin gFrontEnd )
				)
				( attribute "VOLTAGE" "50V"
					( Units "uVoltage" "V" 1.000000)
					( Origin gFrontEnd )
				)
				( attribute "XY" "(2200,3450)"
					( Origin gFrontEnd )
				)
				( attribute "CHIPS_PART_NAME" "CAP"
					( Origin gPackager )
				)
				( attribute "CDS_PART_NAME" "CAP_0402LF-1000PF,50V,10%,X7R,A"
					( Origin gPackager )
				)
				( attribute "CDS_LOCATION" "CT62"
					( Origin gPackager )
				)
				( attribute "SEC" "1"
					( Origin gFrontEnd )
				)
				( attribute "SEC_TYPE" "0402LF"
					( Origin gFrontEnd )
				)
				( attribute "CDS_SEC" "1"
					( Origin gPackager )
				)
				( objectStatus "CT62" )
			)
			( gate "@baseboard_fab2_lib.baseboard_fab2(sch_1):page224_i117"
				( attribute "CDS_LIB" "dev_discrete"
					( Origin gPackager )
				)
				( attribute "LOCATION" "CT30"
					( Origin gFrontEnd )
				)
				( attribute "MATERIAL" "X7R"
					( Origin gFrontEnd )
				)
				( attribute "PACK_TYPE" "0402V"
					( Origin gFrontEnd )
				)
				( attribute "PART_NUMBER" "A36096-030"
					( Origin gFrontEnd )
				)
				( attribute "PHYS_PAGE" "224"
					( Origin gFrontEnd )
				)
				( attribute "ROOM" "PVCCIN_CPU0_PWR_VR"
					( Origin gFrontEnd )
				)
				( attribute "ROT" "0"
					( Origin gFrontEnd )
				)
				( attribute "TOLERANCE" "10%"
					( Origin gFrontEnd )
				)
				( attribute "VALUE" "0.1UF"
					( Origin gFrontEnd )
				)
				( attribute "VER" "1"
					( Origin gFrontEnd )
				)
				( attribute "VOLTAGE" "16V"
					( Units "uVoltage" "V" 1.000000)
					( Origin gFrontEnd )
				)
				( attribute "XY" "(1050,1725)"
					( Origin gFrontEnd )
				)
				( attribute "CHIPS_PART_NAME" "CAP_A"
					( Origin gPackager )
				)
				( attribute "CDS_PART_NAME" "CAP_A_0402V-0.1UF,16V,10%,X7R,A"
					( Origin gPackager )
				)
				( attribute "CDS_LOCATION" "CT30"
					( Origin gPackager )
				)
				( attribute "SEC" "1"
					( Origin gFrontEnd )
				)
				( attribute "SEC_TYPE" "0402V"
					( Origin gFrontEnd )
				)
				( attribute "CDS_SEC" "1"
					( Origin gPackager )
				)
				( attribute "POP" "NOPOP"
					( Origin gFrontEnd )
				)
				( objectStatus "CT30" )
			)
			( gate "@baseboard_fab2_lib.baseboard_fab2(sch_1):page236_i149"
				( attribute "CDS_LIB" "mstr_discrete"
					( Origin gPackager )
				)
				( attribute "LOCATION" "CT65"
					( Origin gFrontEnd )
				)
				( attribute "MATERIAL" "X7R"
					( Origin gFrontEnd )
				)
				( attribute "PACK_TYPE" "0402LF"
					( Origin gFrontEnd )
				)
				( attribute "PART_NUMBER" "A36096-046"
					( Origin gFrontEnd )
				)
				( attribute "PHYS_PAGE" "236"
					( Origin gFrontEnd )
				)
				( attribute "POP" "NOPOP"
					( Origin gFrontEnd )
				)
				( attribute "ROOM" "VDDQ_KLM_PWR_VR"
					( Origin gFrontEnd )
				)
				( attribute "ROT" "0"
					( Origin gFrontEnd )
				)
				( attribute "TOLERANCE" "10%"
					( Origin gFrontEnd )
				)
				( attribute "VALUE" "1000PF"
					( Origin gFrontEnd )
				)
				( attribute "VER" "1"
					( Origin gFrontEnd )
				)
				( attribute "VOLTAGE" "50V"
					( Units "uVoltage" "V" 1.000000)
					( Origin gFrontEnd )
				)
				( attribute "XY" "(10550,3850)"
					( Origin gFrontEnd )
				)
				( attribute "CHIPS_PART_NAME" "CAP"
					( Origin gPackager )
				)
				( attribute "CDS_PART_NAME" "CAP_0402LF-1000PF,50V,10%,X7R,A"
					( Origin gPackager )
				)
				( attribute "CDS_LOCATION" "CT65"
					( Origin gPackager )
				)
				( attribute "SEC" "1"
					( Origin gFrontEnd )
				)
				( attribute "SEC_TYPE" "0402LF"
					( Origin gFrontEnd )
				)
				( attribute "CDS_SEC" "1"
					( Origin gPackager )
				)
				( objectStatus "CT65" )
			)
			( gate "@baseboard_fab2_lib.baseboard_fab2(sch_1):page224_i122"
				( attribute "CDS_LIB" "mstr_discrete"
					( Origin gPackager )
				)
				( attribute "LOCATION" "CT28"
					( Origin gFrontEnd )
				)
				( attribute "MATERIAL" "X7R"
					( Origin gFrontEnd )
				)
				( attribute "PACK_TYPE" "0402LF"
					( Origin gFrontEnd )
				)
				( attribute "PART_NUMBER" "A36096-046"
					( Origin gFrontEnd )
				)
				( attribute "PHYS_PAGE" "224"
					( Origin gFrontEnd )
				)
				( attribute "ROOM" "VDDQ_KLM_PWR_VR"
					( Origin gFrontEnd )
				)
				( attribute "ROT" "0"
					( Origin gFrontEnd )
				)
				( attribute "TOLERANCE" "10%"
					( Origin gFrontEnd )
				)
				( attribute "VALUE" "1000PF"
					( Origin gFrontEnd )
				)
				( attribute "VER" "1"
					( Origin gFrontEnd )
				)
				( attribute "VOLTAGE" "50V"
					( Units "uVoltage" "V" 1.000000)
					( Origin gFrontEnd )
				)
				( attribute "XY" "(2950,2225)"
					( Origin gFrontEnd )
				)
				( attribute "CHIPS_PART_NAME" "CAP"
					( Origin gPackager )
				)
				( attribute "CDS_PART_NAME" "CAP_0402LF-1000PF,50V,10%,X7R,A"
					( Origin gPackager )
				)
				( attribute "CDS_LOCATION" "CT28"
					( Origin gPackager )
				)
				( attribute "SEC" "1"
					( Origin gFrontEnd )
				)
				( attribute "POP" "NOPOP"
					( Origin gFrontEnd )
				)
				( attribute "SEC_TYPE" "0402LF"
					( Origin gFrontEnd )
				)
				( attribute "CDS_SEC" "1"
					( Origin gPackager )
				)
				( objectStatus "CT28" )
			)
			( gate "@baseboard_fab2_lib.baseboard_fab2(sch_1):page224_i124"
				( attribute "CDS_LIB" "dev_discrete"
					( Origin gPackager )
				)
				( attribute "LOCATION" "CT31"
					( Origin gFrontEnd )
				)
				( attribute "MATERIAL" "X7R"
					( Origin gFrontEnd )
				)
				( attribute "PACK_TYPE" "0402V"
					( Origin gFrontEnd )
				)
				( attribute "PART_NUMBER" "A36096-030"
					( Origin gFrontEnd )
				)
				( attribute "PHYS_PAGE" "224"
					( Origin gFrontEnd )
				)
				( attribute "ROOM" "PVCCIN_CPU0_PWR_VR"
					( Origin gFrontEnd )
				)
				( attribute "ROT" "0"
					( Origin gFrontEnd )
				)
				( attribute "TOLERANCE" "10%"
					( Origin gFrontEnd )
				)
				( attribute "VALUE" "0.1UF"
					( Origin gFrontEnd )
				)
				( attribute "VER" "1"
					( Origin gFrontEnd )
				)
				( attribute "VOLTAGE" "16V"
					( Units "uVoltage" "V" 1.000000)
					( Origin gFrontEnd )
				)
				( attribute "XY" "(1150,-625)"
					( Origin gFrontEnd )
				)
				( attribute "CHIPS_PART_NAME" "CAP_A"
					( Origin gPackager )
				)
				( attribute "CDS_PART_NAME" "CAP_A_0402V-0.1UF,16V,10%,X7R,A"
					( Origin gPackager )
				)
				( attribute "CDS_LOCATION" "CT31"
					( Origin gPackager )
				)
				( attribute "SEC" "1"
					( Origin gFrontEnd )
				)
				( attribute "SEC_TYPE" "0402V"
					( Origin gFrontEnd )
				)
				( attribute "CDS_SEC" "1"
					( Origin gPackager )
				)
				( attribute "POP" "NOPOP"
					( Origin gFrontEnd )
				)
				( attribute "BOM_SS" "NOPOP"
					( Origin gFrontEnd )
				)
				( objectStatus "CT31" )
			)
			( gate "@baseboard_fab2_lib.baseboard_fab2(sch_1):page236_i150"
				( attribute "CDS_LIB" "mstr_discrete"
					( Origin gPackager )
				)
				( attribute "LOCATION" "CT68"
					( Origin gFrontEnd )
				)
				( attribute "MATERIAL" "X7R"
					( Origin gFrontEnd )
				)
				( attribute "PACK_TYPE" "0402LF"
					( Origin gFrontEnd )
				)
				( attribute "PART_NUMBER" "A36096-046"
					( Origin gFrontEnd )
				)
				( attribute "PHYS_PAGE" "236"
					( Origin gFrontEnd )
				)
				( attribute "POP" "NOPOP"
					( Origin gFrontEnd )
				)
				( attribute "ROOM" "VDDQ_KLM_PWR_VR"
					( Origin gFrontEnd )
				)
				( attribute "ROT" "0"
					( Origin gFrontEnd )
				)
				( attribute "TOLERANCE" "10%"
					( Origin gFrontEnd )
				)
				( attribute "VALUE" "1000PF"
					( Origin gFrontEnd )
				)
				( attribute "VER" "1"
					( Origin gFrontEnd )
				)
				( attribute "VOLTAGE" "50V"
					( Units "uVoltage" "V" 1.000000)
					( Origin gFrontEnd )
				)
				( attribute "XY" "(11050,2150)"
					( Origin gFrontEnd )
				)
				( attribute "CHIPS_PART_NAME" "CAP"
					( Origin gPackager )
				)
				( attribute "CDS_PART_NAME" "CAP_0402LF-1000PF,50V,10%,X7R,A"
					( Origin gPackager )
				)
				( attribute "CDS_LOCATION" "CT68"
					( Origin gPackager )
				)
				( attribute "SEC" "1"
					( Origin gFrontEnd )
				)
				( attribute "SEC_TYPE" "0402LF"
					( Origin gFrontEnd )
				)
				( attribute "CDS_SEC" "1"
					( Origin gPackager )
				)
				( objectStatus "CT68" )
			)
			( gate "@baseboard_fab2_lib.baseboard_fab2(sch_1):page224_i130"
				( attribute "CDS_LIB" "mstr_discrete"
					( Origin gPackager )
				)
				( attribute "LOCATION" "CT32"
					( Origin gFrontEnd )
				)
				( attribute "MATERIAL" "X7R"
					( Origin gFrontEnd )
				)
				( attribute "PACK_TYPE" "0402LF"
					( Origin gFrontEnd )
				)
				( attribute "PART_NUMBER" "A36096-046"
					( Origin gFrontEnd )
				)
				( attribute "PHYS_PAGE" "224"
					( Origin gFrontEnd )
				)
				( attribute "ROOM" "VDDQ_KLM_PWR_VR"
					( Origin gFrontEnd )
				)
				( attribute "ROT" "0"
					( Origin gFrontEnd )
				)
				( attribute "TOLERANCE" "10%"
					( Origin gFrontEnd )
				)
				( attribute "VALUE" "1000PF"
					( Origin gFrontEnd )
				)
				( attribute "VER" "1"
					( Origin gFrontEnd )
				)
				( attribute "VOLTAGE" "50V"
					( Units "uVoltage" "V" 1.000000)
					( Origin gFrontEnd )
				)
				( attribute "XY" "(3050,-75)"
					( Origin gFrontEnd )
				)
				( attribute "CHIPS_PART_NAME" "CAP"
					( Origin gPackager )
				)
				( attribute "CDS_PART_NAME" "CAP_0402LF-1000PF,50V,10%,X7R,A"
					( Origin gPackager )
				)
				( attribute "CDS_LOCATION" "CT32"
					( Origin gPackager )
				)
				( attribute "SEC" "1"
					( Origin gFrontEnd )
				)
				( attribute "POP" "NOPOP"
					( Origin gFrontEnd )
				)
				( attribute "SEC_TYPE" "0402LF"
					( Origin gFrontEnd )
				)
				( attribute "CDS_SEC" "1"
					( Origin gPackager )
				)
				( attribute "BOM_SS" "NOPOP"
					( Origin gFrontEnd )
				)
				( objectStatus "CT32" )
			)
			( gate "@baseboard_fab2_lib.baseboard_fab2(sch_1):page204_i85"
				( attribute "CDS_LIB" "dev_discrete"
					( Origin gPackager )
				)
				( attribute "LOCATION" "CT36"
					( Origin gFrontEnd )
				)
				( attribute "MATERIAL" "X7R"
					( Origin gFrontEnd )
				)
				( attribute "PACK_TYPE" "0402V"
					( Origin gFrontEnd )
				)
				( attribute "PART_NUMBER" "A36096-030"
					( Origin gFrontEnd )
				)
				( attribute "PHYS_PAGE" "204"
					( Origin gFrontEnd )
				)
				( attribute "ROOM" "PVCCIN_CPU0_PWR_VR"
					( Origin gFrontEnd )
				)
				( attribute "ROT" "0"
					( Origin gFrontEnd )
				)
				( attribute "TOLERANCE" "10%"
					( Origin gFrontEnd )
				)
				( attribute "VALUE" "0.1UF"
					( Origin gFrontEnd )
				)
				( attribute "VER" "1"
					( Origin gFrontEnd )
				)
				( attribute "VOLTAGE" "16V"
					( Units "uVoltage" "V" 1.000000)
					( Origin gFrontEnd )
				)
				( attribute "XY" "(-3850,3425)"
					( Origin gFrontEnd )
				)
				( attribute "CHIPS_PART_NAME" "CAP_A"
					( Origin gPackager )
				)
				( attribute "CDS_PART_NAME" "CAP_A_0402V-0.1UF,16V,10%,X7R,A"
					( Origin gPackager )
				)
				( attribute "CDS_LOCATION" "CT36"
					( Origin gPackager )
				)
				( attribute "SEC" "1"
					( Origin gFrontEnd )
				)
				( attribute "SEC_TYPE" "0402V"
					( Origin gFrontEnd )
				)
				( attribute "CDS_SEC" "1"
					( Origin gPackager )
				)
				( attribute "POP" "NOPOP"
					( Origin gFrontEnd )
				)
				( objectStatus "CT36" )
			)
			( gate "@baseboard_fab2_lib.baseboard_fab2(sch_1):page208_i108"
				( attribute "BOM_COST" "NT_GBE_BASE"
					( Origin gFrontEnd )
				)
				( attribute "CDS_LIB" "mstr_discrete"
					( Origin gPackager )
				)
				( attribute "LOCATION" "RT11"
					( Origin gFrontEnd )
				)
				( attribute "MATERIAL" "CHIP"
					( Origin gFrontEnd )
				)
				( attribute "PACK_TYPE" "0603"
					( Origin gFrontEnd )
				)
				( attribute "PART_NUMBER" "G22178-002"
					( Origin gFrontEnd )
				)
				( attribute "PHYS_PAGE" "208"
					( Origin gFrontEnd )
				)
				( attribute "ROOM" "NIC_SPRV"
					( Origin gFrontEnd )
				)
				( attribute "ROT" "0"
					( Origin gFrontEnd )
				)
				( attribute "TOLERANCE" "5.0%"
					( Origin gFrontEnd )
				)
				( attribute "VALUE" "0"
					( Origin gFrontEnd )
				)
				( attribute "VER" "1"
					( Origin gFrontEnd )
				)
				( attribute "WATTAGE" "1/10W"
					( Origin gFrontEnd )
				)
				( attribute "XY" "(-4975,3700)"
					( Origin gFrontEnd )
				)
				( attribute "CHIPS_PART_NAME" "RES"
					( Origin gPackager )
				)
				( attribute "CDS_PART_NAME" "RES_0603-0,5.0%,1/10W,CHIP,G22A"
					( Origin gPackager )
				)
				( attribute "CDS_LOCATION" "RT11"
					( Origin gPackager )
				)
				( attribute "SEC" "1"
					( Origin gFrontEnd )
				)
				( attribute "SEC_TYPE" "0603"
					( Origin gFrontEnd )
				)
				( attribute "CDS_SEC" "1"
					( Origin gPackager )
				)
				( objectStatus "RT11" )
			)
			( gate "@baseboard_fab2_lib.baseboard_fab2(sch_1):page204_i88"
				( attribute "CDS_LIB" "mstr_discrete"
					( Origin gPackager )
				)
				( attribute "LOCATION" "CT34"
					( Origin gFrontEnd )
				)
				( attribute "MATERIAL" "X7R"
					( Origin gFrontEnd )
				)
				( attribute "PACK_TYPE" "0402LF"
					( Origin gFrontEnd )
				)
				( attribute "PART_NUMBER" "A36096-046"
					( Origin gFrontEnd )
				)
				( attribute "PHYS_PAGE" "204"
					( Origin gFrontEnd )
				)
				( attribute "ROOM" "VDDQ_KLM_PWR_VR"
					( Origin gFrontEnd )
				)
				( attribute "ROT" "0"
					( Origin gFrontEnd )
				)
				( attribute "TOLERANCE" "10%"
					( Origin gFrontEnd )
				)
				( attribute "VALUE" "1000PF"
					( Origin gFrontEnd )
				)
				( attribute "VER" "1"
					( Origin gFrontEnd )
				)
				( attribute "VOLTAGE" "50V"
					( Units "uVoltage" "V" 1.000000)
					( Origin gFrontEnd )
				)
				( attribute "XY" "(-2075,3950)"
					( Origin gFrontEnd )
				)
				( attribute "CHIPS_PART_NAME" "CAP"
					( Origin gPackager )
				)
				( attribute "CDS_PART_NAME" "CAP_0402LF-1000PF,50V,10%,X7R,A"
					( Origin gPackager )
				)
				( attribute "CDS_LOCATION" "CT34"
					( Origin gPackager )
				)
				( attribute "SEC" "1"
					( Origin gFrontEnd )
				)
				( attribute "POP" "NOPOP"
					( Origin gFrontEnd )
				)
				( attribute "SEC_TYPE" "0402LF"
					( Origin gFrontEnd )
				)
				( attribute "CDS_SEC" "1"
					( Origin gPackager )
				)
				( objectStatus "CT34" )
			)
			( gate "@baseboard_fab2_lib.baseboard_fab2(sch_1):page242_i89"
				( attribute "BOM_COST" "PROC_SOCKET"
					( Origin gFrontEnd )
				)
				( attribute "CDS_LIB" "mstr_discrete"
					( Origin gPackager )
				)
				( attribute "LOCATION" "C5G77"
					( Origin gFrontEnd )
				)
				( attribute "MATERIAL" "X6S"
					( Origin gFrontEnd )
				)
				( attribute "PACK_TYPE" "0805"
					( Origin gFrontEnd )
				)
				( attribute "PART_NUMBER" "C95333-006"
					( Origin gFrontEnd )
				)
				( attribute "PHYS_PAGE" "242"
					( Origin gFrontEnd )
				)
				( attribute "ROOM" "PVCCIN_CPU0_DECAP_VR"
					( Origin gFrontEnd )
				)
				( attribute "ROT" "0"
					( Origin gFrontEnd )
				)
				( attribute "TOLERANCE" "20%"
					( Origin gFrontEnd )
				)
				( attribute "VALUE" "47UF"
					( Origin gFrontEnd )
				)
				( attribute "VER" "1"
					( Origin gFrontEnd )
				)
				( attribute "VOLTAGE" "4V"
					( Units "uVoltage" "V" 1.000000)
					( Origin gFrontEnd )
				)
				( attribute "XY" "(-3800,3775)"
					( Origin gFrontEnd )
				)
				( attribute "CHIPS_PART_NAME" "CAP"
					( Origin gPackager )
				)
				( attribute "CDS_PART_NAME" "CAP_0805-47UF,4V,20%,X6S,C9533A"
					( Origin gPackager )
				)
				( attribute "CDS_LOCATION" "C5G77"
					( Origin gPackager )
				)
				( attribute "SEC" "1"
					( Origin gFrontEnd )
				)
				( attribute "SEC_TYPE" "0805"
					( Origin gFrontEnd )
				)
				( attribute "CDS_SEC" "1"
					( Origin gPackager )
				)
				( attribute "GROUP" "PWR_MLCC_CAP"
					( Origin gFrontEnd )
				)
				( attribute "POP" "NOPOP"
					( Origin gFrontEnd )
				)
				( objectStatus "C5G77" )
			)
			( gate "@baseboard_fab2_lib.baseboard_fab2(sch_1):page210_i74"
				( attribute "ATTRIBUTE" "1 OHM"
					( Origin gFrontEnd )
				)
				( attribute "CDS_LIB" "w_hdl"
					( Origin gPackager )
				)
				( attribute "CDS_LMAN_SYM_OUTLINE" "-50,75,50,-75"
					( Origin gPackager )
				)
				( attribute "LOCATION" "RT38"
					( Origin gFrontEnd )
				)
				( attribute "PACK_TYPE" "RCL_GP"
					( Origin gFrontEnd )
				)
				( attribute "PART_NUMBER" "64.1R005.55L"
					( Origin gFrontEnd )
				)
				( attribute "PHYS_PAGE" "210"
					( Origin gFrontEnd )
				)
				( attribute "POP" "NOPOP"
					( Origin gFrontEnd )
				)
				( attribute "RATED" "1/10W"
					( Origin gFrontEnd )
				)
				( attribute "ROT" "0"
					( Origin gFrontEnd )
				)
				( attribute "SEC" "1"
					( Origin gFrontEnd )
				)
				( attribute "SEC_TYPE" "RCL_GP"
					( Origin gFrontEnd )
				)
				( attribute "TOLERANCE" "1%"
					( Origin gFrontEnd )
				)
				( attribute "VALUE" "1R3F-GP"
					( Origin gFrontEnd )
				)
				( attribute "VER" "1"
					( Origin gFrontEnd )
				)
				( attribute "XY" "(-2500,2825)"
					( Origin gFrontEnd )
				)
				( attribute "CHIPS_PART_NAME" "1R3F-GP"
					( Origin gPackager )
				)
				( attribute "CDS_PART_NAME" "1R3F-GP_RCL_GP-1R3F-GP,64.1R00A"
					( Origin gPackager )
				)
				( attribute "PACK_SIZE" "0603"
					( Origin gFrontEnd )
				)
				( attribute "CDS_LOCATION" "RT38"
					( Origin gPackager )
				)
				( attribute "CDS_SEC" "1"
					( Origin gPackager )
				)
				( objectStatus "RT38" )
			)
			( gate "@baseboard_fab2_lib.baseboard_fab2(sch_1):page203_i93"
				( attribute "CDS_LIB" "dev_discrete"
					( Origin gPackager )
				)
				( attribute "LOCATION" "CT40"
					( Origin gFrontEnd )
				)
				( attribute "MATERIAL" "X7R"
					( Origin gFrontEnd )
				)
				( attribute "PACK_TYPE" "0402V"
					( Origin gFrontEnd )
				)
				( attribute "PART_NUMBER" "A36096-030"
					( Origin gFrontEnd )
				)
				( attribute "PHYS_PAGE" "203"
					( Origin gFrontEnd )
				)
				( attribute "ROOM" "PVCCIN_CPU0_PWR_VR"
					( Origin gFrontEnd )
				)
				( attribute "ROT" "0"
					( Origin gFrontEnd )
				)
				( attribute "TOLERANCE" "10%"
					( Origin gFrontEnd )
				)
				( attribute "VALUE" "0.1UF"
					( Origin gFrontEnd )
				)
				( attribute "VER" "1"
					( Origin gFrontEnd )
				)
				( attribute "VOLTAGE" "16V"
					( Units "uVoltage" "V" 1.000000)
					( Origin gFrontEnd )
				)
				( attribute "XY" "(-3900,700)"
					( Origin gFrontEnd )
				)
				( attribute "CHIPS_PART_NAME" "CAP_A"
					( Origin gPackager )
				)
				( attribute "CDS_PART_NAME" "CAP_A_0402V-0.1UF,16V,10%,X7R,A"
					( Origin gPackager )
				)
				( attribute "CDS_LOCATION" "CT40"
					( Origin gPackager )
				)
				( attribute "SEC" "1"
					( Origin gFrontEnd )
				)
				( attribute "SEC_TYPE" "0402V"
					( Origin gFrontEnd )
				)
				( attribute "CDS_SEC" "1"
					( Origin gPackager )
				)
				( attribute "POP" "NOPOP"
					( Origin gFrontEnd )
				)
				( objectStatus "CT40" )
			)
			( gate "@baseboard_fab2_lib.baseboard_fab2(sch_1):page227_i139"
				( attribute "BOM_COST" "NT_GBE_BASE"
					( Origin gFrontEnd )
				)
				( attribute "CDS_LIB" "mstr_discrete"
					( Origin gPackager )
				)
				( attribute "LOCATION" "RT8"
					( Origin gFrontEnd )
				)
				( attribute "MATERIAL" "CHIP"
					( Origin gFrontEnd )
				)
				( attribute "PACK_TYPE" "0603"
					( Origin gFrontEnd )
				)
				( attribute "PART_NUMBER" "G22178-002"
					( Origin gFrontEnd )
				)
				( attribute "PHYS_PAGE" "227"
					( Origin gFrontEnd )
				)
				( attribute "ROOM" "NIC_SPRV"
					( Origin gFrontEnd )
				)
				( attribute "ROT" "0"
					( Origin gFrontEnd )
				)
				( attribute "TOLERANCE" "5.0%"
					( Origin gFrontEnd )
				)
				( attribute "VALUE" "0"
					( Origin gFrontEnd )
				)
				( attribute "VER" "1"
					( Origin gFrontEnd )
				)
				( attribute "WATTAGE" "1/10W"
					( Origin gFrontEnd )
				)
				( attribute "XY" "(225,-250)"
					( Origin gFrontEnd )
				)
				( attribute "CHIPS_PART_NAME" "RES"
					( Origin gPackager )
				)
				( attribute "CDS_PART_NAME" "RES_0603-0,5.0%,1/10W,CHIP,G22A"
					( Origin gPackager )
				)
				( attribute "CDS_LOCATION" "RT8"
					( Origin gPackager )
				)
				( attribute "SEC" "1"
					( Origin gFrontEnd )
				)
				( attribute "SEC_TYPE" "0603"
					( Origin gFrontEnd )
				)
				( attribute "CDS_SEC" "1"
					( Origin gPackager )
				)
				( attribute "BOM_SS" "NOPOP"
					( Origin gFrontEnd )
				)
				( objectStatus "RT8" )
			)
			( gate "@baseboard_fab2_lib.baseboard_fab2(sch_1):page203_i96"
				( attribute "CDS_LIB" "dev_discrete"
					( Origin gPackager )
				)
				( attribute "LOCATION" "CT39"
					( Origin gFrontEnd )
				)
				( attribute "MATERIAL" "X7R"
					( Origin gFrontEnd )
				)
				( attribute "PACK_TYPE" "0402V"
					( Origin gFrontEnd )
				)
				( attribute "PART_NUMBER" "A36096-030"
					( Origin gFrontEnd )
				)
				( attribute "PHYS_PAGE" "203"
					( Origin gFrontEnd )
				)
				( attribute "ROOM" "PVCCIN_CPU0_PWR_VR"
					( Origin gFrontEnd )
				)
				( attribute "ROT" "0"
					( Origin gFrontEnd )
				)
				( attribute "TOLERANCE" "10%"
					( Origin gFrontEnd )
				)
				( attribute "VALUE" "0.1UF"
					( Origin gFrontEnd )
				)
				( attribute "VER" "1"
					( Origin gFrontEnd )
				)
				( attribute "VOLTAGE" "16V"
					( Units "uVoltage" "V" 1.000000)
					( Origin gFrontEnd )
				)
				( attribute "XY" "(-3900,3400)"
					( Origin gFrontEnd )
				)
				( attribute "CHIPS_PART_NAME" "CAP_A"
					( Origin gPackager )
				)
				( attribute "CDS_PART_NAME" "CAP_A_0402V-0.1UF,16V,10%,X7R,A"
					( Origin gPackager )
				)
				( attribute "CDS_LOCATION" "CT39"
					( Origin gPackager )
				)
				( attribute "SEC" "1"
					( Origin gFrontEnd )
				)
				( attribute "SEC_TYPE" "0402V"
					( Origin gFrontEnd )
				)
				( attribute "CDS_SEC" "1"
					( Origin gPackager )
				)
				( attribute "POP" "NOPOP"
					( Origin gFrontEnd )
				)
				( objectStatus "CT39" )
			)
			( gate "@baseboard_fab2_lib.baseboard_fab2(sch_1):page227_i138"
				( attribute "BOM_COST" "NT_GBE_BASE"
					( Origin gFrontEnd )
				)
				( attribute "CDS_LIB" "mstr_discrete"
					( Origin gPackager )
				)
				( attribute "LOCATION" "RT5"
					( Origin gFrontEnd )
				)
				( attribute "MATERIAL" "CHIP"
					( Origin gFrontEnd )
				)
				( attribute "PACK_TYPE" "0603"
					( Origin gFrontEnd )
				)
				( attribute "PART_NUMBER" "G22178-002"
					( Origin gFrontEnd )
				)
				( attribute "PHYS_PAGE" "227"
					( Origin gFrontEnd )
				)
				( attribute "ROOM" "NIC_SPRV"
					( Origin gFrontEnd )
				)
				( attribute "ROT" "0"
					( Origin gFrontEnd )
				)
				( attribute "TOLERANCE" "5.0%"
					( Origin gFrontEnd )
				)
				( attribute "VALUE" "0"
					( Origin gFrontEnd )
				)
				( attribute "VER" "1"
					( Origin gFrontEnd )
				)
				( attribute "WATTAGE" "1/10W"
					( Origin gFrontEnd )
				)
				( attribute "XY" "(100,2025)"
					( Origin gFrontEnd )
				)
				( attribute "CHIPS_PART_NAME" "RES"
					( Origin gPackager )
				)
				( attribute "CDS_PART_NAME" "RES_0603-0,5.0%,1/10W,CHIP,G22A"
					( Origin gPackager )
				)
				( attribute "CDS_LOCATION" "RT5"
					( Origin gPackager )
				)
				( attribute "SEC" "1"
					( Origin gFrontEnd )
				)
				( attribute "SEC_TYPE" "0603"
					( Origin gFrontEnd )
				)
				( attribute "CDS_SEC" "1"
					( Origin gPackager )
				)
				( objectStatus "RT5" )
			)
			( gate "@baseboard_fab2_lib.baseboard_fab2(sch_1):page203_i99"
				( attribute "CDS_LIB" "mstr_discrete"
					( Origin gPackager )
				)
				( attribute "LOCATION" "CT37"
					( Origin gFrontEnd )
				)
				( attribute "MATERIAL" "X7R"
					( Origin gFrontEnd )
				)
				( attribute "PACK_TYPE" "0402LF"
					( Origin gFrontEnd )
				)
				( attribute "PART_NUMBER" "A36096-046"
					( Origin gFrontEnd )
				)
				( attribute "PHYS_PAGE" "203"
					( Origin gFrontEnd )
				)
				( attribute "ROOM" "VDDQ_KLM_PWR_VR"
					( Origin gFrontEnd )
				)
				( attribute "ROT" "0"
					( Origin gFrontEnd )
				)
				( attribute "TOLERANCE" "10%"
					( Origin gFrontEnd )
				)
				( attribute "VALUE" "1000PF"
					( Origin gFrontEnd )
				)
				( attribute "VER" "1"
					( Origin gFrontEnd )
				)
				( attribute "VOLTAGE" "50V"
					( Units "uVoltage" "V" 1.000000)
					( Origin gFrontEnd )
				)
				( attribute "XY" "(-1975,3950)"
					( Origin gFrontEnd )
				)
				( attribute "CHIPS_PART_NAME" "CAP"
					( Origin gPackager )
				)
				( attribute "CDS_PART_NAME" "CAP_0402LF-1000PF,50V,10%,X7R,A"
					( Origin gPackager )
				)
				( attribute "CDS_LOCATION" "CT37"
					( Origin gPackager )
				)
				( attribute "SEC" "1"
					( Origin gFrontEnd )
				)
				( attribute "POP" "NOPOP"
					( Origin gFrontEnd )
				)
				( attribute "SEC_TYPE" "0402LF"
					( Origin gFrontEnd )
				)
				( attribute "CDS_SEC" "1"
					( Origin gPackager )
				)
				( objectStatus "CT37" )
			)
			( gate "@baseboard_fab2_lib.baseboard_fab2(sch_1):page242_i90"
				( attribute "BOM_COST" "PROC_SOCKET"
					( Origin gFrontEnd )
				)
				( attribute "CDS_LIB" "mstr_discrete"
					( Origin gPackager )
				)
				( attribute "LOCATION" "C5G22"
					( Origin gFrontEnd )
				)
				( attribute "MATERIAL" "X6S"
					( Origin gFrontEnd )
				)
				( attribute "PACK_TYPE" "0805"
					( Origin gFrontEnd )
				)
				( attribute "PART_NUMBER" "C95333-006"
					( Origin gFrontEnd )
				)
				( attribute "PHYS_PAGE" "242"
					( Origin gFrontEnd )
				)
				( attribute "ROOM" "PVCCIN_CPU0_DECAP_VR"
					( Origin gFrontEnd )
				)
				( attribute "ROT" "0"
					( Origin gFrontEnd )
				)
				( attribute "TOLERANCE" "20%"
					( Origin gFrontEnd )
				)
				( attribute "VALUE" "47UF"
					( Origin gFrontEnd )
				)
				( attribute "VER" "1"
					( Origin gFrontEnd )
				)
				( attribute "VOLTAGE" "4V"
					( Units "uVoltage" "V" 1.000000)
					( Origin gFrontEnd )
				)
				( attribute "XY" "(-7350,3775)"
					( Origin gFrontEnd )
				)
				( attribute "CHIPS_PART_NAME" "CAP"
					( Origin gPackager )
				)
				( attribute "CDS_PART_NAME" "CAP_0805-47UF,4V,20%,X6S,C9533A"
					( Origin gPackager )
				)
				( attribute "SEC" "1"
					( Origin gFrontEnd )
				)
				( attribute "SEC_TYPE" "0805"
					( Origin gFrontEnd )
				)
				( attribute "CDS_LOCATION" "C5G22"
					( Origin gPackager )
				)
				( attribute "CDS_SEC" "1"
					( Origin gPackager )
				)
				( attribute "GROUP" "PWR_MLCC_CAP"
					( Origin gFrontEnd )
				)
				( attribute "POP" "NOPOP"
					( Origin gFrontEnd )
				)
				( objectStatus "C5G22" )
			)
			( gate "@baseboard_fab2_lib.baseboard_fab2(sch_1):page224_i157"
				( attribute "ATTRIBUTE" "1 OHM"
					( Origin gFrontEnd )
				)
				( attribute "CDS_LIB" "w_hdl"
					( Origin gPackager )
				)
				( attribute "CDS_LMAN_SYM_OUTLINE" "-50,75,50,-75"
					( Origin gPackager )
				)
				( attribute "LOCATION" "RT22"
					( Origin gFrontEnd )
				)
				( attribute "PACK_TYPE" "RCL_GP"
					( Origin gFrontEnd )
				)
				( attribute "PART_NUMBER" "64.1R005.55L"
					( Origin gFrontEnd )
				)
				( attribute "PHYS_PAGE" "224"
					( Origin gFrontEnd )
				)
				( attribute "POP" "NOPOP"
					( Origin gFrontEnd )
				)
				( attribute "RATED" "1/10W"
					( Origin gFrontEnd )
				)
				( attribute "ROT" "0"
					( Origin gFrontEnd )
				)
				( attribute "SEC" "1"
					( Origin gFrontEnd )
				)
				( attribute "SEC_TYPE" "RCL_GP"
					( Origin gFrontEnd )
				)
				( attribute "TOLERANCE" "1%"
					( Origin gFrontEnd )
				)
				( attribute "VALUE" "1R3F-GP"
					( Origin gFrontEnd )
				)
				( attribute "VER" "1"
					( Origin gFrontEnd )
				)
				( attribute "XY" "(3250,-925)"
					( Origin gFrontEnd )
				)
				( attribute "CHIPS_PART_NAME" "1R3F-GP"
					( Origin gPackager )
				)
				( attribute "CDS_PART_NAME" "1R3F-GP_RCL_GP-1R3F-GP,64.1R00A"
					( Origin gPackager )
				)
				( attribute "PACK_SIZE" "0603"
					( Origin gFrontEnd )
				)
				( attribute "CDS_LOCATION" "RT22"
					( Origin gPackager )
				)
				( attribute "CDS_SEC" "1"
					( Origin gPackager )
				)
				( attribute "BOM_SS" "NOPOP"
					( Origin gFrontEnd )
				)
				( objectStatus "RT22" )
			)
			( gate "@baseboard_fab2_lib.baseboard_fab2(sch_1):page209_i90"
				( attribute "ATTRIBUTE" "1 OHM"
					( Origin gFrontEnd )
				)
				( attribute "CDS_LIB" "w_hdl"
					( Origin gPackager )
				)
				( attribute "CDS_LMAN_SYM_OUTLINE" "-50,75,50,-75"
					( Origin gPackager )
				)
				( attribute "LOCATION" "RT10"
					( Origin gFrontEnd )
				)
				( attribute "PACK_TYPE" "RCL_GP"
					( Origin gFrontEnd )
				)
				( attribute "PART_NUMBER" "64.1R005.55L"
					( Origin gFrontEnd )
				)
				( attribute "PHYS_PAGE" "209"
					( Origin gFrontEnd )
				)
				( attribute "POP" "NOPOP"
					( Origin gFrontEnd )
				)
				( attribute "RATED" "1/10W"
					( Origin gFrontEnd )
				)
				( attribute "ROT" "0"
					( Origin gFrontEnd )
				)
				( attribute "SEC" "1"
					( Origin gFrontEnd )
				)
				( attribute "SEC_TYPE" "RCL_GP"
					( Origin gFrontEnd )
				)
				( attribute "TOLERANCE" "1%"
					( Origin gFrontEnd )
				)
				( attribute "VALUE" "1R3F-GP"
					( Origin gFrontEnd )
				)
				( attribute "VER" "1"
					( Origin gFrontEnd )
				)
				( attribute "XY" "(-2400,2975)"
					( Origin gFrontEnd )
				)
				( attribute "CHIPS_PART_NAME" "1R3F-GP"
					( Origin gPackager )
				)
				( attribute "CDS_PART_NAME" "1R3F-GP_RCL_GP-1R3F-GP,64.1R00A"
					( Origin gPackager )
				)
				( attribute "PACK_SIZE" "0603"
					( Origin gFrontEnd )
				)
				( attribute "CDS_LOCATION" "RT10"
					( Origin gPackager )
				)
				( attribute "CDS_SEC" "1"
					( Origin gPackager )
				)
				( objectStatus "RT10" )
			)
			( gate "@baseboard_fab2_lib.baseboard_fab2(sch_1):page205_i76"
				( attribute "CDS_LIB" "mstr_discrete"
					( Origin gPackager )
				)
				( attribute "LOCATION" "CT59"
					( Origin gFrontEnd )
				)
				( attribute "MATERIAL" "X7R"
					( Origin gFrontEnd )
				)
				( attribute "PACK_TYPE" "0402LF"
					( Origin gFrontEnd )
				)
				( attribute "PART_NUMBER" "A36096-046"
					( Origin gFrontEnd )
				)
				( attribute "PHYS_PAGE" "205"
					( Origin gFrontEnd )
				)
				( attribute "POP" "NOPOP"
					( Origin gFrontEnd )
				)
				( attribute "ROOM" "VDDQ_KLM_PWR_VR"
					( Origin gFrontEnd )
				)
				( attribute "ROT" "0"
					( Origin gFrontEnd )
				)
				( attribute "TOLERANCE" "10%"
					( Origin gFrontEnd )
				)
				( attribute "VALUE" "1000PF"
					( Origin gFrontEnd )
				)
				( attribute "VER" "1"
					( Origin gFrontEnd )
				)
				( attribute "VOLTAGE" "50V"
					( Units "uVoltage" "V" 1.000000)
					( Origin gFrontEnd )
				)
				( attribute "XY" "(-2050,3475)"
					( Origin gFrontEnd )
				)
				( attribute "CHIPS_PART_NAME" "CAP"
					( Origin gPackager )
				)
				( attribute "CDS_PART_NAME" "CAP_0402LF-1000PF,50V,10%,X7R,A"
					( Origin gPackager )
				)
				( attribute "CDS_LOCATION" "CT59"
					( Origin gPackager )
				)
				( attribute "SEC" "1"
					( Origin gFrontEnd )
				)
				( attribute "SEC_TYPE" "0402LF"
					( Origin gFrontEnd )
				)
				( attribute "CDS_SEC" "1"
					( Origin gPackager )
				)
				( objectStatus "CT59" )
			)
			( gate "@baseboard_fab2_lib.baseboard_fab2(sch_1):page203_i108"
				( attribute "CDS_LIB" "mstr_discrete"
					( Origin gPackager )
				)
				( attribute "LOCATION" "CT42"
					( Origin gFrontEnd )
				)
				( attribute "MATERIAL" "X7R"
					( Origin gFrontEnd )
				)
				( attribute "PACK_TYPE" "0402LF"
					( Origin gFrontEnd )
				)
				( attribute "PART_NUMBER" "A36096-046"
					( Origin gFrontEnd )
				)
				( attribute "PHYS_PAGE" "203"
					( Origin gFrontEnd )
				)
				( attribute "ROOM" "VDDQ_KLM_PWR_VR"
					( Origin gFrontEnd )
				)
				( attribute "ROT" "0"
					( Origin gFrontEnd )
				)
				( attribute "TOLERANCE" "10%"
					( Origin gFrontEnd )
				)
				( attribute "VALUE" "1000PF"
					( Origin gFrontEnd )
				)
				( attribute "VER" "1"
					( Origin gFrontEnd )
				)
				( attribute "VOLTAGE" "50V"
					( Units "uVoltage" "V" 1.000000)
					( Origin gFrontEnd )
				)
				( attribute "XY" "(-1925,1275)"
					( Origin gFrontEnd )
				)
				( attribute "CHIPS_PART_NAME" "CAP"
					( Origin gPackager )
				)
				( attribute "CDS_PART_NAME" "CAP_0402LF-1000PF,50V,10%,X7R,A"
					( Origin gPackager )
				)
				( attribute "CDS_LOCATION" "CT42"
					( Origin gPackager )
				)
				( attribute "SEC" "1"
					( Origin gFrontEnd )
				)
				( attribute "POP" "NOPOP"
					( Origin gFrontEnd )
				)
				( attribute "SEC_TYPE" "0402LF"
					( Origin gFrontEnd )
				)
				( attribute "CDS_SEC" "1"
					( Origin gPackager )
				)
				( objectStatus "CT42" )
			)
			( gate "@baseboard_fab2_lib.baseboard_fab2(sch_1):page219_i113"
				( attribute "CDS_LIB" "dev_discrete"
					( Origin gPackager )
				)
				( attribute "LOCATION" "CT46"
					( Origin gFrontEnd )
				)
				( attribute "MATERIAL" "X7R"
					( Origin gFrontEnd )
				)
				( attribute "PACK_TYPE" "0402V"
					( Origin gFrontEnd )
				)
				( attribute "PART_NUMBER" "A36096-030"
					( Origin gFrontEnd )
				)
				( attribute "PHYS_PAGE" "219"
					( Origin gFrontEnd )
				)
				( attribute "ROOM" "PVCCIN_CPU0_PWR_VR"
					( Origin gFrontEnd )
				)
				( attribute "ROT" "0"
					( Origin gFrontEnd )
				)
				( attribute "TOLERANCE" "10%"
					( Origin gFrontEnd )
				)
				( attribute "VALUE" "0.1UF"
					( Origin gFrontEnd )
				)
				( attribute "VER" "1"
					( Origin gFrontEnd )
				)
				( attribute "VOLTAGE" "16V"
					( Units "uVoltage" "V" 1.000000)
					( Origin gFrontEnd )
				)
				( attribute "XY" "(1075,-625)"
					( Origin gFrontEnd )
				)
				( attribute "CHIPS_PART_NAME" "CAP_A"
					( Origin gPackager )
				)
				( attribute "CDS_PART_NAME" "CAP_A_0402V-0.1UF,16V,10%,X7R,A"
					( Origin gPackager )
				)
				( attribute "CDS_LOCATION" "CT46"
					( Origin gPackager )
				)
				( attribute "SEC" "1"
					( Origin gFrontEnd )
				)
				( attribute "SEC_TYPE" "0402V"
					( Origin gFrontEnd )
				)
				( attribute "CDS_SEC" "1"
					( Origin gPackager )
				)
				( attribute "POP" "NOPOP"
					( Origin gFrontEnd )
				)
				( attribute "BOM_SS" "NOPOP"
					( Origin gFrontEnd )
				)
				( objectStatus "CT46" )
			)
			( gate "@baseboard_fab2_lib.baseboard_fab2(sch_1):page224_i145"
				( attribute "BOM_COST" "NT_GBE_BASE"
					( Origin gFrontEnd )
				)
				( attribute "CDS_LIB" "mstr_discrete"
					( Origin gPackager )
				)
				( attribute "LOCATION" "RT21"
					( Origin gFrontEnd )
				)
				( attribute "MATERIAL" "CHIP"
					( Origin gFrontEnd )
				)
				( attribute "PACK_TYPE" "0603"
					( Origin gFrontEnd )
				)
				( attribute "PART_NUMBER" "G22178-002"
					( Origin gFrontEnd )
				)
				( attribute "PHYS_PAGE" "224"
					( Origin gFrontEnd )
				)
				( attribute "ROOM" "NIC_SPRV"
					( Origin gFrontEnd )
				)
				( attribute "ROT" "0"
					( Origin gFrontEnd )
				)
				( attribute "TOLERANCE" "5.0%"
					( Origin gFrontEnd )
				)
				( attribute "VALUE" "0"
					( Origin gFrontEnd )
				)
				( attribute "VER" "1"
					( Origin gFrontEnd )
				)
				( attribute "WATTAGE" "1/10W"
					( Origin gFrontEnd )
				)
				( attribute "XY" "(275,-325)"
					( Origin gFrontEnd )
				)
				( attribute "CHIPS_PART_NAME" "RES"
					( Origin gPackager )
				)
				( attribute "CDS_PART_NAME" "RES_0603-0,5.0%,1/10W,CHIP,G22A"
					( Origin gPackager )
				)
				( attribute "CDS_LOCATION" "RT21"
					( Origin gPackager )
				)
				( attribute "SEC" "1"
					( Origin gFrontEnd )
				)
				( attribute "SEC_TYPE" "0603"
					( Origin gFrontEnd )
				)
				( attribute "CDS_SEC" "1"
					( Origin gPackager )
				)
				( attribute "BOM_SS" "NOPOP"
					( Origin gFrontEnd )
				)
				( objectStatus "RT21" )
			)
			( gate "@baseboard_fab2_lib.baseboard_fab2(sch_1):page219_i116"
				( attribute "CDS_LIB" "dev_discrete"
					( Origin gPackager )
				)
				( attribute "LOCATION" "CT45"
					( Origin gFrontEnd )
				)
				( attribute "MATERIAL" "X7R"
					( Origin gFrontEnd )
				)
				( attribute "PACK_TYPE" "0402V"
					( Origin gFrontEnd )
				)
				( attribute "PART_NUMBER" "A36096-030"
					( Origin gFrontEnd )
				)
				( attribute "PHYS_PAGE" "219"
					( Origin gFrontEnd )
				)
				( attribute "ROOM" "PVCCIN_CPU0_PWR_VR"
					( Origin gFrontEnd )
				)
				( attribute "ROT" "0"
					( Origin gFrontEnd )
				)
				( attribute "TOLERANCE" "10%"
					( Origin gFrontEnd )
				)
				( attribute "VALUE" "0.1UF"
					( Origin gFrontEnd )
				)
				( attribute "VER" "1"
					( Origin gFrontEnd )
				)
				( attribute "VOLTAGE" "16V"
					( Units "uVoltage" "V" 1.000000)
					( Origin gFrontEnd )
				)
				( attribute "XY" "(1025,1625)"
					( Origin gFrontEnd )
				)
				( attribute "CHIPS_PART_NAME" "CAP_A"
					( Origin gPackager )
				)
				( attribute "CDS_PART_NAME" "CAP_A_0402V-0.1UF,16V,10%,X7R,A"
					( Origin gPackager )
				)
				( attribute "CDS_LOCATION" "CT45"
					( Origin gPackager )
				)
				( attribute "SEC" "1"
					( Origin gFrontEnd )
				)
				( attribute "SEC_TYPE" "0402V"
					( Origin gFrontEnd )
				)
				( attribute "CDS_SEC" "1"
					( Origin gPackager )
				)
				( attribute "POP" "NOPOP"
					( Origin gFrontEnd )
				)
				( objectStatus "CT45" )
			)
			( gate "@baseboard_fab2_lib.baseboard_fab2(sch_1):page224_i144"
				( attribute "BOM_COST" "NT_GBE_BASE"
					( Origin gFrontEnd )
				)
				( attribute "CDS_LIB" "mstr_discrete"
					( Origin gPackager )
				)
				( attribute "LOCATION" "RT19"
					( Origin gFrontEnd )
				)
				( attribute "MATERIAL" "CHIP"
					( Origin gFrontEnd )
				)
				( attribute "PACK_TYPE" "0603"
					( Origin gFrontEnd )
				)
				( attribute "PART_NUMBER" "G22178-002"
					( Origin gFrontEnd )
				)
				( attribute "PHYS_PAGE" "224"
					( Origin gFrontEnd )
				)
				( attribute "ROOM" "NIC_SPRV"
					( Origin gFrontEnd )
				)
				( attribute "ROT" "0"
					( Origin gFrontEnd )
				)
				( attribute "TOLERANCE" "5.0%"
					( Origin gFrontEnd )
				)
				( attribute "VALUE" "0"
					( Origin gFrontEnd )
				)
				( attribute "VER" "1"
					( Origin gFrontEnd )
				)
				( attribute "WATTAGE" "1/10W"
					( Origin gFrontEnd )
				)
				( attribute "XY" "(100,2000)"
					( Origin gFrontEnd )
				)
				( attribute "CHIPS_PART_NAME" "RES"
					( Origin gPackager )
				)
				( attribute "CDS_PART_NAME" "RES_0603-0,5.0%,1/10W,CHIP,G22A"
					( Origin gPackager )
				)
				( attribute "CDS_LOCATION" "RT19"
					( Origin gPackager )
				)
				( attribute "SEC" "1"
					( Origin gFrontEnd )
				)
				( attribute "SEC_TYPE" "0603"
					( Origin gFrontEnd )
				)
				( attribute "CDS_SEC" "1"
					( Origin gPackager )
				)
				( objectStatus "RT19" )
			)
			( gate "@baseboard_fab2_lib.baseboard_fab2(sch_1):page219_i119"
				( attribute "CDS_LIB" "mstr_discrete"
					( Origin gPackager )
				)
				( attribute "LOCATION" "CT48"
					( Origin gFrontEnd )
				)
				( attribute "MATERIAL" "X7R"
					( Origin gFrontEnd )
				)
				( attribute "PACK_TYPE" "0402LF"
					( Origin gFrontEnd )
				)
				( attribute "PART_NUMBER" "A36096-046"
					( Origin gFrontEnd )
				)
				( attribute "PHYS_PAGE" "219"
					( Origin gFrontEnd )
				)
				( attribute "ROOM" "VDDQ_KLM_PWR_VR"
					( Origin gFrontEnd )
				)
				( attribute "ROT" "0"
					( Origin gFrontEnd )
				)
				( attribute "TOLERANCE" "10%"
					( Origin gFrontEnd )
				)
				( attribute "VALUE" "1000PF"
					( Origin gFrontEnd )
				)
				( attribute "VER" "1"
					( Origin gFrontEnd )
				)
				( attribute "VOLTAGE" "50V"
					( Units "uVoltage" "V" 1.000000)
					( Origin gFrontEnd )
				)
				( attribute "XY" "(3075,-100)"
					( Origin gFrontEnd )
				)
				( attribute "CHIPS_PART_NAME" "CAP"
					( Origin gPackager )
				)
				( attribute "CDS_PART_NAME" "CAP_0402LF-1000PF,50V,10%,X7R,A"
					( Origin gPackager )
				)
				( attribute "CDS_LOCATION" "CT48"
					( Origin gPackager )
				)
				( attribute "SEC" "1"
					( Origin gFrontEnd )
				)
				( attribute "POP" "NOPOP"
					( Origin gFrontEnd )
				)
				( attribute "SEC_TYPE" "0402LF"
					( Origin gFrontEnd )
				)
				( attribute "CDS_SEC" "1"
					( Origin gPackager )
				)
				( attribute "BOM_SS" "NOPOP"
					( Origin gFrontEnd )
				)
				( objectStatus "CT48" )
			)
			( gate "@baseboard_fab2_lib.baseboard_fab2(sch_1):page227_i134"
				( attribute "CDS_LIB" "mstr_discrete"
					( Origin gPackager )
				)
				( attribute "LOCATION" "CT9"
					( Origin gFrontEnd )
				)
				( attribute "MATERIAL" "X7R"
					( Origin gFrontEnd )
				)
				( attribute "PACK_TYPE" "0402LF"
					( Origin gFrontEnd )
				)
				( attribute "PART_NUMBER" "A36096-046"
					( Origin gFrontEnd )
				)
				( attribute "PHYS_PAGE" "227"
					( Origin gFrontEnd )
				)
				( attribute "POP" "NOPOP"
					( Origin gFrontEnd )
				)
				( attribute "ROOM" "VDDQ_KLM_PWR_VR"
					( Origin gFrontEnd )
				)
				( attribute "ROT" "0"
					( Origin gFrontEnd )
				)
				( attribute "TOLERANCE" "10%"
					( Origin gFrontEnd )
				)
				( attribute "VALUE" "1000PF"
					( Origin gFrontEnd )
				)
				( attribute "VER" "1"
					( Origin gFrontEnd )
				)
				( attribute "VOLTAGE" "50V"
					( Units "uVoltage" "V" 1.000000)
					( Origin gFrontEnd )
				)
				( attribute "XY" "(2825,1750)"
					( Origin gFrontEnd )
				)
				( attribute "CHIPS_PART_NAME" "CAP"
					( Origin gPackager )
				)
				( attribute "CDS_PART_NAME" "CAP_0402LF-1000PF,50V,10%,X7R,A"
					( Origin gPackager )
				)
				( attribute "CDS_LOCATION" "CT9"
					( Origin gPackager )
				)
				( attribute "SEC" "1"
					( Origin gFrontEnd )
				)
				( attribute "SEC_TYPE" "0402LF"
					( Origin gFrontEnd )
				)
				( attribute "CDS_SEC" "1"
					( Origin gPackager )
				)
				( objectStatus "CT9" )
			)
			( gate "@baseboard_fab2_lib.baseboard_fab2(sch_1):page219_i124"
				( attribute "CDS_LIB" "mstr_discrete"
					( Origin gPackager )
				)
				( attribute "LOCATION" "CT43"
					( Origin gFrontEnd )
				)
				( attribute "MATERIAL" "X7R"
					( Origin gFrontEnd )
				)
				( attribute "PACK_TYPE" "0402LF"
					( Origin gFrontEnd )
				)
				( attribute "PART_NUMBER" "A36096-046"
					( Origin gFrontEnd )
				)
				( attribute "PHYS_PAGE" "219"
					( Origin gFrontEnd )
				)
				( attribute "ROOM" "VDDQ_KLM_PWR_VR"
					( Origin gFrontEnd )
				)
				( attribute "ROT" "0"
					( Origin gFrontEnd )
				)
				( attribute "TOLERANCE" "10%"
					( Origin gFrontEnd )
				)
				( attribute "VALUE" "1000PF"
					( Origin gFrontEnd )
				)
				( attribute "VER" "1"
					( Origin gFrontEnd )
				)
				( attribute "VOLTAGE" "50V"
					( Units "uVoltage" "V" 1.000000)
					( Origin gFrontEnd )
				)
				( attribute "XY" "(2900,2125)"
					( Origin gFrontEnd )
				)
				( attribute "CHIPS_PART_NAME" "CAP"
					( Origin gPackager )
				)
				( attribute "CDS_PART_NAME" "CAP_0402LF-1000PF,50V,10%,X7R,A"
					( Origin gPackager )
				)
				( attribute "CDS_LOCATION" "CT43"
					( Origin gPackager )
				)
				( attribute "SEC" "1"
					( Origin gFrontEnd )
				)
				( attribute "POP" "NOPOP"
					( Origin gFrontEnd )
				)
				( attribute "SEC_TYPE" "0402LF"
					( Origin gFrontEnd )
				)
				( attribute "CDS_SEC" "1"
					( Origin gPackager )
				)
				( objectStatus "CT43" )
			)
			( gate "@baseboard_fab2_lib.baseboard_fab2(sch_1):page227_i135"
				( attribute "CDS_LIB" "mstr_discrete"
					( Origin gPackager )
				)
				( attribute "LOCATION" "CT11"
					( Origin gFrontEnd )
				)
				( attribute "MATERIAL" "X7R"
					( Origin gFrontEnd )
				)
				( attribute "PACK_TYPE" "0402LF"
					( Origin gFrontEnd )
				)
				( attribute "PART_NUMBER" "A36096-046"
					( Origin gFrontEnd )
				)
				( attribute "PHYS_PAGE" "227"
					( Origin gFrontEnd )
				)
				( attribute "POP" "NOPOP"
					( Origin gFrontEnd )
				)
				( attribute "ROOM" "VDDQ_KLM_PWR_VR"
					( Origin gFrontEnd )
				)
				( attribute "ROT" "0"
					( Origin gFrontEnd )
				)
				( attribute "TOLERANCE" "10%"
					( Origin gFrontEnd )
				)
				( attribute "VALUE" "1000PF"
					( Origin gFrontEnd )
				)
				( attribute "VER" "1"
					( Origin gFrontEnd )
				)
				( attribute "VOLTAGE" "50V"
					( Units "uVoltage" "V" 1.000000)
					( Origin gFrontEnd )
				)
				( attribute "XY" "(2925,-475)"
					( Origin gFrontEnd )
				)
				( attribute "CHIPS_PART_NAME" "CAP"
					( Origin gPackager )
				)
				( attribute "CDS_PART_NAME" "CAP_0402LF-1000PF,50V,10%,X7R,A"
					( Origin gPackager )
				)
				( attribute "CDS_LOCATION" "CT11"
					( Origin gPackager )
				)
				( attribute "SEC" "1"
					( Origin gFrontEnd )
				)
				( attribute "SEC_TYPE" "0402LF"
					( Origin gFrontEnd )
				)
				( attribute "CDS_SEC" "1"
					( Origin gPackager )
				)
				( attribute "BOM_SS" "NOPOP"
					( Origin gFrontEnd )
				)
				( objectStatus "CT11" )
			)
			( gate "@baseboard_fab2_lib.baseboard_fab2(sch_1):page216_i108"
				( attribute "CDS_LIB" "dev_discrete"
					( Origin gPackager )
				)
				( attribute "LOCATION" "CT51"
					( Origin gFrontEnd )
				)
				( attribute "MATERIAL" "X7R"
					( Origin gFrontEnd )
				)
				( attribute "PACK_TYPE" "0402V"
					( Origin gFrontEnd )
				)
				( attribute "PART_NUMBER" "A36096-030"
					( Origin gFrontEnd )
				)
				( attribute "PHYS_PAGE" "216"
					( Origin gFrontEnd )
				)
				( attribute "ROOM" "PVCCIN_CPU0_PWR_VR"
					( Origin gFrontEnd )
				)
				( attribute "ROT" "0"
					( Origin gFrontEnd )
				)
				( attribute "TOLERANCE" "10%"
					( Origin gFrontEnd )
				)
				( attribute "VALUE" "0.1UF"
					( Origin gFrontEnd )
				)
				( attribute "VER" "1"
					( Origin gFrontEnd )
				)
				( attribute "VOLTAGE" "16V"
					( Units "uVoltage" "V" 1.000000)
					( Origin gFrontEnd )
				)
				( attribute "XY" "(1025,1800)"
					( Origin gFrontEnd )
				)
				( attribute "CHIPS_PART_NAME" "CAP_A"
					( Origin gPackager )
				)
				( attribute "CDS_PART_NAME" "CAP_A_0402V-0.1UF,16V,10%,X7R,A"
					( Origin gPackager )
				)
				( attribute "CDS_LOCATION" "CT51"
					( Origin gPackager )
				)
				( attribute "SEC" "1"
					( Origin gFrontEnd )
				)
				( attribute "SEC_TYPE" "0402V"
					( Origin gFrontEnd )
				)
				( attribute "CDS_SEC" "1"
					( Origin gPackager )
				)
				( attribute "POP" "NOPOP"
					( Origin gFrontEnd )
				)
				( objectStatus "CT51" )
			)
			( gate "@baseboard_fab2_lib.baseboard_fab2(sch_1):page216_i128"
				( attribute "CDS_LIB" "mstr_discrete"
					( Origin gPackager )
				)
				( attribute "CDS_LOCATION" "C7G38"
					( Origin gPackager )
				)
				( attribute "CDS_SEC" "1"
					( Origin gPackager )
				)
				( attribute "LOCATION" "C7G38"
					( Origin gFrontEnd )
				)
				( attribute "MATERIAL" "X7R"
					( Origin gFrontEnd )
				)
				( attribute "PACK_TYPE" "0402"
					( Origin gFrontEnd )
				)
				( attribute "PART_NUMBER" "A36096-104"
					( Origin gFrontEnd )
				)
				( attribute "PHYS_PAGE" "216"
					( Origin gFrontEnd )
				)
				( attribute "ROOM" "VDDQ_ABC_PWR_VR"
					( Origin gFrontEnd )
				)
				( attribute "ROT" "2"
					( Origin gFrontEnd )
				)
				( attribute "SEC" "1"
					( Origin gFrontEnd )
				)
				( attribute "SEC_TYPE" "0402"
					( Origin gFrontEnd )
				)
				( attribute "SPOF" "TRUE"
					( Origin gFrontEnd )
				)
				( attribute "TOLERANCE" "10%"
					( Origin gFrontEnd )
				)
				( attribute "VALUE" "0.220UF"
					( Origin gFrontEnd )
				)
				( attribute "VER" "1"
					( Origin gFrontEnd )
				)
				( attribute "VOLTAGE" "16V"
					( Units "uVoltage" "V" 1.000000)
					( Origin gFrontEnd )
				)
				( attribute "XY" "(-800,-425)"
					( Origin gFrontEnd )
				)
				( attribute "CHIPS_PART_NAME" "CAP"
					( Origin gPackager )
				)
				( attribute "CDS_PART_NAME" "CAP_0402-0.220UF,16V,10%,X7R,AA"
					( Origin gPackager )
				)
				( attribute "BOM_SS" "NOPOP"
					( Origin gFrontEnd )
				)
				( objectStatus "C7G38" )
			)
			( gate "@baseboard_fab2_lib.baseboard_fab2(sch_1):page216_i111"
				( attribute "CDS_LIB" "dev_discrete"
					( Origin gPackager )
				)
				( attribute "LOCATION" "CT52"
					( Origin gFrontEnd )
				)
				( attribute "MATERIAL" "X7R"
					( Origin gFrontEnd )
				)
				( attribute "PACK_TYPE" "0402V"
					( Origin gFrontEnd )
				)
				( attribute "PART_NUMBER" "A36096-030"
					( Origin gFrontEnd )
				)
				( attribute "PHYS_PAGE" "216"
					( Origin gFrontEnd )
				)
				( attribute "ROOM" "PVCCIN_CPU0_PWR_VR"
					( Origin gFrontEnd )
				)
				( attribute "ROT" "0"
					( Origin gFrontEnd )
				)
				( attribute "TOLERANCE" "10%"
					( Origin gFrontEnd )
				)
				( attribute "VALUE" "0.1UF"
					( Origin gFrontEnd )
				)
				( attribute "VER" "1"
					( Origin gFrontEnd )
				)
				( attribute "VOLTAGE" "16V"
					( Units "uVoltage" "V" 1.000000)
					( Origin gFrontEnd )
				)
				( attribute "XY" "(1125,-950)"
					( Origin gFrontEnd )
				)
				( attribute "CHIPS_PART_NAME" "CAP_A"
					( Origin gPackager )
				)
				( attribute "CDS_PART_NAME" "CAP_A_0402V-0.1UF,16V,10%,X7R,A"
					( Origin gPackager )
				)
				( attribute "CDS_LOCATION" "CT52"
					( Origin gPackager )
				)
				( attribute "SEC" "1"
					( Origin gFrontEnd )
				)
				( attribute "SEC_TYPE" "0402V"
					( Origin gFrontEnd )
				)
				( attribute "CDS_SEC" "1"
					( Origin gPackager )
				)
				( attribute "POP" "NOPOP"
					( Origin gFrontEnd )
				)
				( attribute "BOM_SS" "NOPOP"
					( Origin gFrontEnd )
				)
				( objectStatus "CT52" )
			)
			( gate "@baseboard_fab2_lib.baseboard_fab2(sch_1):page214_i145"
				( attribute "BOM_COST" "NT_GBE_BASE"
					( Origin gFrontEnd )
				)
				( attribute "CDS_LIB" "mstr_discrete"
					( Origin gPackager )
				)
				( attribute "LOCATION" "RT41"
					( Origin gFrontEnd )
				)
				( attribute "MATERIAL" "CHIP"
					( Origin gFrontEnd )
				)
				( attribute "PACK_TYPE" "0603"
					( Origin gFrontEnd )
				)
				( attribute "PART_NUMBER" "G22178-002"
					( Origin gFrontEnd )
				)
				( attribute "PHYS_PAGE" "214"
					( Origin gFrontEnd )
				)
				( attribute "ROOM" "NIC_SPRV"
					( Origin gFrontEnd )
				)
				( attribute "ROT" "0"
					( Origin gFrontEnd )
				)
				( attribute "TOLERANCE" "5.0%"
					( Origin gFrontEnd )
				)
				( attribute "VALUE" "0"
					( Origin gFrontEnd )
				)
				( attribute "VER" "1"
					( Origin gFrontEnd )
				)
				( attribute "WATTAGE" "1/10W"
					( Origin gFrontEnd )
				)
				( attribute "XY" "(-675,3700)"
					( Origin gFrontEnd )
				)
				( attribute "CHIPS_PART_NAME" "RES"
					( Origin gPackager )
				)
				( attribute "CDS_PART_NAME" "RES_0603-0,5.0%,1/10W,CHIP,G22A"
					( Origin gPackager )
				)
				( attribute "CDS_LOCATION" "RT41"
					( Origin gPackager )
				)
				( attribute "SEC" "1"
					( Origin gFrontEnd )
				)
				( attribute "SEC_TYPE" "0603"
					( Origin gFrontEnd )
				)
				( attribute "CDS_SEC" "1"
					( Origin gPackager )
				)
				( objectStatus "RT41" )
			)
			( gate "@baseboard_fab2_lib.baseboard_fab2(sch_1):page219_i154"
				( attribute "ATTRIBUTE" "1 OHM"
					( Origin gFrontEnd )
				)
				( attribute "CDS_LIB" "w_hdl"
					( Origin gPackager )
				)
				( attribute "CDS_LMAN_SYM_OUTLINE" "-50,75,50,-75"
					( Origin gPackager )
				)
				( attribute "LOCATION" "RT32"
					( Origin gFrontEnd )
				)
				( attribute "PACK_TYPE" "RCL_GP"
					( Origin gFrontEnd )
				)
				( attribute "PART_NUMBER" "64.1R005.55L"
					( Origin gFrontEnd )
				)
				( attribute "PHYS_PAGE" "219"
					( Origin gFrontEnd )
				)
				( attribute "POP" "NOPOP"
					( Origin gFrontEnd )
				)
				( attribute "RATED" "1/10W"
					( Origin gFrontEnd )
				)
				( attribute "ROT" "0"
					( Origin gFrontEnd )
				)
				( attribute "SEC" "1"
					( Origin gFrontEnd )
				)
				( attribute "SEC_TYPE" "RCL_GP"
					( Origin gFrontEnd )
				)
				( attribute "TOLERANCE" "1%"
					( Origin gFrontEnd )
				)
				( attribute "VALUE" "1R3F-GP"
					( Origin gFrontEnd )
				)
				( attribute "VER" "1"
					( Origin gFrontEnd )
				)
				( attribute "XY" "(2875,-925)"
					( Origin gFrontEnd )
				)
				( attribute "CHIPS_PART_NAME" "1R3F-GP"
					( Origin gPackager )
				)
				( attribute "CDS_PART_NAME" "1R3F-GP_RCL_GP-1R3F-GP,64.1R00A"
					( Origin gPackager )
				)
				( attribute "PACK_SIZE" "0603"
					( Origin gFrontEnd )
				)
				( attribute "CDS_LOCATION" "RT32"
					( Origin gPackager )
				)
				( attribute "CDS_SEC" "1"
					( Origin gPackager )
				)
				( attribute "BOM_SS" "NOPOP"
					( Origin gFrontEnd )
				)
				( objectStatus "RT32" )
			)
			( gate "@baseboard_fab2_lib.baseboard_fab2(sch_1):page216_i118"
				( attribute "CDS_LIB" "mstr_discrete"
					( Origin gPackager )
				)
				( attribute "LOCATION" "CT49"
					( Origin gFrontEnd )
				)
				( attribute "MATERIAL" "X7R"
					( Origin gFrontEnd )
				)
				( attribute "PACK_TYPE" "0402LF"
					( Origin gFrontEnd )
				)
				( attribute "PART_NUMBER" "A36096-046"
					( Origin gFrontEnd )
				)
				( attribute "PHYS_PAGE" "216"
					( Origin gFrontEnd )
				)
				( attribute "ROOM" "VDDQ_KLM_PWR_VR"
					( Origin gFrontEnd )
				)
				( attribute "ROT" "0"
					( Origin gFrontEnd )
				)
				( attribute "TOLERANCE" "10%"
					( Origin gFrontEnd )
				)
				( attribute "VALUE" "1000PF"
					( Origin gFrontEnd )
				)
				( attribute "VER" "1"
					( Origin gFrontEnd )
				)
				( attribute "VOLTAGE" "50V"
					( Units "uVoltage" "V" 1.000000)
					( Origin gFrontEnd )
				)
				( attribute "XY" "(3000,2375)"
					( Origin gFrontEnd )
				)
				( attribute "CHIPS_PART_NAME" "CAP"
					( Origin gPackager )
				)
				( attribute "CDS_PART_NAME" "CAP_0402LF-1000PF,50V,10%,X7R,A"
					( Origin gPackager )
				)
				( attribute "CDS_LOCATION" "CT49"
					( Origin gPackager )
				)
				( attribute "SEC" "1"
					( Origin gFrontEnd )
				)
				( attribute "POP" "NOPOP"
					( Origin gFrontEnd )
				)
				( attribute "SEC_TYPE" "0402LF"
					( Origin gFrontEnd )
				)
				( attribute "CDS_SEC" "1"
					( Origin gPackager )
				)
				( objectStatus "CT49" )
			)
			( gate "@baseboard_fab2_lib.baseboard_fab2(sch_1):page224_i140"
				( attribute "CDS_LIB" "mstr_discrete"
					( Origin gPackager )
				)
				( attribute "LOCATION" "CT29"
					( Origin gFrontEnd )
				)
				( attribute "MATERIAL" "X7R"
					( Origin gFrontEnd )
				)
				( attribute "PACK_TYPE" "0402LF"
					( Origin gFrontEnd )
				)
				( attribute "PART_NUMBER" "A36096-046"
					( Origin gFrontEnd )
				)
				( attribute "PHYS_PAGE" "224"
					( Origin gFrontEnd )
				)
				( attribute "POP" "NOPOP"
					( Origin gFrontEnd )
				)
				( attribute "ROOM" "VDDQ_KLM_PWR_VR"
					( Origin gFrontEnd )
				)
				( attribute "ROT" "0"
					( Origin gFrontEnd )
				)
				( attribute "TOLERANCE" "10%"
					( Origin gFrontEnd )
				)
				( attribute "VALUE" "1000PF"
					( Origin gFrontEnd )
				)
				( attribute "VER" "1"
					( Origin gFrontEnd )
				)
				( attribute "VOLTAGE" "50V"
					( Units "uVoltage" "V" 1.000000)
					( Origin gFrontEnd )
				)
				( attribute "XY" "(2900,1800)"
					( Origin gFrontEnd )
				)
				( attribute "CHIPS_PART_NAME" "CAP"
					( Origin gPackager )
				)
				( attribute "CDS_PART_NAME" "CAP_0402LF-1000PF,50V,10%,X7R,A"
					( Origin gPackager )
				)
				( attribute "CDS_LOCATION" "CT29"
					( Origin gPackager )
				)
				( attribute "SEC" "1"
					( Origin gFrontEnd )
				)
				( attribute "SEC_TYPE" "0402LF"
					( Origin gFrontEnd )
				)
				( attribute "CDS_SEC" "1"
					( Origin gPackager )
				)
				( objectStatus "CT29" )
			)
			( gate "@baseboard_fab2_lib.baseboard_fab2(sch_1):page216_i121"
				( attribute "CDS_LIB" "mstr_discrete"
					( Origin gPackager )
				)
				( attribute "LOCATION" "CT54"
					( Origin gFrontEnd )
				)
				( attribute "MATERIAL" "X7R"
					( Origin gFrontEnd )
				)
				( attribute "PACK_TYPE" "0402LF"
					( Origin gFrontEnd )
				)
				( attribute "PART_NUMBER" "A36096-046"
					( Origin gFrontEnd )
				)
				( attribute "PHYS_PAGE" "216"
					( Origin gFrontEnd )
				)
				( attribute "ROOM" "VDDQ_KLM_PWR_VR"
					( Origin gFrontEnd )
				)
				( attribute "ROT" "0"
					( Origin gFrontEnd )
				)
				( attribute "TOLERANCE" "10%"
					( Origin gFrontEnd )
				)
				( attribute "VALUE" "1000PF"
					( Origin gFrontEnd )
				)
				( attribute "VER" "1"
					( Origin gFrontEnd )
				)
				( attribute "VOLTAGE" "50V"
					( Units "uVoltage" "V" 1.000000)
					( Origin gFrontEnd )
				)
				( attribute "XY" "(2900,-75)"
					( Origin gFrontEnd )
				)
				( attribute "CHIPS_PART_NAME" "CAP"
					( Origin gPackager )
				)
				( attribute "CDS_PART_NAME" "CAP_0402LF-1000PF,50V,10%,X7R,A"
					( Origin gPackager )
				)
				( attribute "CDS_LOCATION" "CT54"
					( Origin gPackager )
				)
				( attribute "SEC" "1"
					( Origin gFrontEnd )
				)
				( attribute "POP" "NOPOP"
					( Origin gFrontEnd )
				)
				( attribute "SEC_TYPE" "0402LF"
					( Origin gFrontEnd )
				)
				( attribute "CDS_SEC" "1"
					( Origin gPackager )
				)
				( attribute "BOM_SS" "NOPOP"
					( Origin gFrontEnd )
				)
				( objectStatus "CT54" )
			)
			( gate "@baseboard_fab2_lib.baseboard_fab2(sch_1):page224_i141"
				( attribute "CDS_LIB" "mstr_discrete"
					( Origin gPackager )
				)
				( attribute "LOCATION" "CT33"
					( Origin gFrontEnd )
				)
				( attribute "MATERIAL" "X7R"
					( Origin gFrontEnd )
				)
				( attribute "PACK_TYPE" "0402LF"
					( Origin gFrontEnd )
				)
				( attribute "PART_NUMBER" "A36096-046"
					( Origin gFrontEnd )
				)
				( attribute "PHYS_PAGE" "224"
					( Origin gFrontEnd )
				)
				( attribute "POP" "NOPOP"
					( Origin gFrontEnd )
				)
				( attribute "ROOM" "VDDQ_KLM_PWR_VR"
					( Origin gFrontEnd )
				)
				( attribute "ROT" "0"
					( Origin gFrontEnd )
				)
				( attribute "TOLERANCE" "10%"
					( Origin gFrontEnd )
				)
				( attribute "VALUE" "1000PF"
					( Origin gFrontEnd )
				)
				( attribute "VER" "1"
					( Origin gFrontEnd )
				)
				( attribute "VOLTAGE" "50V"
					( Units "uVoltage" "V" 1.000000)
					( Origin gFrontEnd )
				)
				( attribute "XY" "(3250,-625)"
					( Origin gFrontEnd )
				)
				( attribute "CHIPS_PART_NAME" "CAP"
					( Origin gPackager )
				)
				( attribute "CDS_PART_NAME" "CAP_0402LF-1000PF,50V,10%,X7R,A"
					( Origin gPackager )
				)
				( attribute "CDS_LOCATION" "CT33"
					( Origin gPackager )
				)
				( attribute "SEC" "1"
					( Origin gFrontEnd )
				)
				( attribute "SEC_TYPE" "0402LF"
					( Origin gFrontEnd )
				)
				( attribute "CDS_SEC" "1"
					( Origin gPackager )
				)
				( attribute "BOM_SS" "NOPOP"
					( Origin gFrontEnd )
				)
				( objectStatus "CT33" )
			)
			( gate "@baseboard_fab2_lib.baseboard_fab2(sch_1):page212_i120"
				( attribute "BOM_COST" "NT_GBE_BASE"
					( Origin gFrontEnd )
				)
				( attribute "CDS_LIB" "mstr_discrete"
					( Origin gPackager )
				)
				( attribute "LOCATION" "RT47"
					( Origin gFrontEnd )
				)
				( attribute "MATERIAL" "CHIP"
					( Origin gFrontEnd )
				)
				( attribute "PACK_TYPE" "0603"
					( Origin gFrontEnd )
				)
				( attribute "PART_NUMBER" "G22178-002"
					( Origin gFrontEnd )
				)
				( attribute "PHYS_PAGE" "212"
					( Origin gFrontEnd )
				)
				( attribute "ROOM" "NIC_SPRV"
					( Origin gFrontEnd )
				)
				( attribute "ROT" "0"
					( Origin gFrontEnd )
				)
				( attribute "TOLERANCE" "5.0%"
					( Origin gFrontEnd )
				)
				( attribute "VALUE" "0"
					( Origin gFrontEnd )
				)
				( attribute "VER" "1"
					( Origin gFrontEnd )
				)
				( attribute "WATTAGE" "1/10W"
					( Origin gFrontEnd )
				)
				( attribute "XY" "(-475,3750)"
					( Origin gFrontEnd )
				)
				( attribute "CHIPS_PART_NAME" "RES"
					( Origin gPackager )
				)
				( attribute "CDS_PART_NAME" "RES_0603-0,5.0%,1/10W,CHIP,G22A"
					( Origin gPackager )
				)
				( attribute "CDS_LOCATION" "RT47"
					( Origin gPackager )
				)
				( attribute "SEC" "1"
					( Origin gFrontEnd )
				)
				( attribute "SEC_TYPE" "0603"
					( Origin gFrontEnd )
				)
				( attribute "CDS_SEC" "1"
					( Origin gPackager )
				)
				( objectStatus "RT47" )
			)
			( gate "@baseboard_fab2_lib.baseboard_fab2(sch_1):page208_i104"
				( attribute "CDS_LIB" "mstr_discrete"
					( Origin gPackager )
				)
				( attribute "LOCATION" "CT18"
					( Origin gFrontEnd )
				)
				( attribute "MATERIAL" "X7R"
					( Origin gFrontEnd )
				)
				( attribute "PACK_TYPE" "0402LF"
					( Origin gFrontEnd )
				)
				( attribute "PART_NUMBER" "A36096-046"
					( Origin gFrontEnd )
				)
				( attribute "PHYS_PAGE" "208"
					( Origin gFrontEnd )
				)
				( attribute "POP" "NOPOP"
					( Origin gFrontEnd )
				)
				( attribute "ROOM" "VDDQ_KLM_PWR_VR"
					( Origin gFrontEnd )
				)
				( attribute "ROT" "0"
					( Origin gFrontEnd )
				)
				( attribute "TOLERANCE" "10%"
					( Origin gFrontEnd )
				)
				( attribute "VALUE" "1000PF"
					( Origin gFrontEnd )
				)
				( attribute "VER" "1"
					( Origin gFrontEnd )
				)
				( attribute "VOLTAGE" "50V"
					( Units "uVoltage" "V" 1.000000)
					( Origin gFrontEnd )
				)
				( attribute "XY" "(-2225,3500)"
					( Origin gFrontEnd )
				)
				( attribute "CHIPS_PART_NAME" "CAP"
					( Origin gPackager )
				)
				( attribute "CDS_PART_NAME" "CAP_0402LF-1000PF,50V,10%,X7R,A"
					( Origin gPackager )
				)
				( attribute "CDS_LOCATION" "CT18"
					( Origin gPackager )
				)
				( attribute "SEC" "1"
					( Origin gFrontEnd )
				)
				( attribute "SEC_TYPE" "0402LF"
					( Origin gFrontEnd )
				)
				( attribute "CDS_SEC" "1"
					( Origin gPackager )
				)
				( objectStatus "CT18" )
			)
			( gate "@baseboard_fab2_lib.baseboard_fab2(sch_1):page236_i183"
				( attribute "ATTRIBUTE" "1 OHM"
					( Origin gFrontEnd )
				)
				( attribute "CDS_LIB" "w_hdl"
					( Origin gPackager )
				)
				( attribute "CDS_LMAN_SYM_OUTLINE" "-50,75,50,-75"
					( Origin gPackager )
				)
				( attribute "LOCATION" "RT45"
					( Origin gFrontEnd )
				)
				( attribute "PACK_TYPE" "RCL_GP"
					( Origin gFrontEnd )
				)
				( attribute "PART_NUMBER" "64.1R005.55L"
					( Origin gFrontEnd )
				)
				( attribute "PHYS_PAGE" "236"
					( Origin gFrontEnd )
				)
				( attribute "POP" "NOPOP"
					( Origin gFrontEnd )
				)
				( attribute "RATED" "1/10W"
					( Origin gFrontEnd )
				)
				( attribute "ROT" "0"
					( Origin gFrontEnd )
				)
				( attribute "SEC" "1"
					( Origin gFrontEnd )
				)
				( attribute "SEC_TYPE" "RCL_GP"
					( Origin gFrontEnd )
				)
				( attribute "TOLERANCE" "1%"
					( Origin gFrontEnd )
				)
				( attribute "VALUE" "1R3F-GP"
					( Origin gFrontEnd )
				)
				( attribute "VER" "1"
					( Origin gFrontEnd )
				)
				( attribute "XY" "(11050,1850)"
					( Origin gFrontEnd )
				)
				( attribute "CHIPS_PART_NAME" "1R3F-GP"
					( Origin gPackager )
				)
				( attribute "CDS_PART_NAME" "1R3F-GP_RCL_GP-1R3F-GP,64.1R00A"
					( Origin gPackager )
				)
				( attribute "PACK_SIZE" "0603"
					( Origin gFrontEnd )
				)
				( attribute "CDS_LOCATION" "RT45"
					( Origin gPackager )
				)
				( attribute "CDS_SEC" "1"
					( Origin gPackager )
				)
				( objectStatus "RT45" )
			)
			( gate "@baseboard_fab2_lib.baseboard_fab2(sch_1):page210_i60"
				( attribute "CDS_LIB" "mstr_discrete"
					( Origin gPackager )
				)
				( attribute "LOCATION" "CT55"
					( Origin gFrontEnd )
				)
				( attribute "MATERIAL" "X7R"
					( Origin gFrontEnd )
				)
				( attribute "PACK_TYPE" "0402LF"
					( Origin gFrontEnd )
				)
				( attribute "PART_NUMBER" "A36096-046"
					( Origin gFrontEnd )
				)
				( attribute "PHYS_PAGE" "210"
					( Origin gFrontEnd )
				)
				( attribute "ROOM" "VDDQ_KLM_PWR_VR"
					( Origin gFrontEnd )
				)
				( attribute "ROT" "0"
					( Origin gFrontEnd )
				)
				( attribute "TOLERANCE" "10%"
					( Origin gFrontEnd )
				)
				( attribute "VALUE" "1000PF"
					( Origin gFrontEnd )
				)
				( attribute "VER" "1"
					( Origin gFrontEnd )
				)
				( attribute "VOLTAGE" "50V"
					( Units "uVoltage" "V" 1.000000)
					( Origin gFrontEnd )
				)
				( attribute "XY" "(-2650,3625)"
					( Origin gFrontEnd )
				)
				( attribute "CHIPS_PART_NAME" "CAP"
					( Origin gPackager )
				)
				( attribute "CDS_PART_NAME" "CAP_0402LF-1000PF,50V,10%,X7R,A"
					( Origin gPackager )
				)
				( attribute "CDS_LOCATION" "CT55"
					( Origin gPackager )
				)
				( attribute "SEC" "1"
					( Origin gFrontEnd )
				)
				( attribute "POP" "NOPOP"
					( Origin gFrontEnd )
				)
				( attribute "SEC_TYPE" "0402LF"
					( Origin gFrontEnd )
				)
				( attribute "CDS_SEC" "1"
					( Origin gPackager )
				)
				( objectStatus "CT55" )
			)
			( gate "@baseboard_fab2_lib.baseboard_fab2(sch_1):page212_i118"
				( attribute "CDS_LIB" "mstr_discrete"
					( Origin gPackager )
				)
				( attribute "LOCATION" "CT72"
					( Origin gFrontEnd )
				)
				( attribute "MATERIAL" "X7R"
					( Origin gFrontEnd )
				)
				( attribute "PACK_TYPE" "0402LF"
					( Origin gFrontEnd )
				)
				( attribute "PART_NUMBER" "A36096-046"
					( Origin gFrontEnd )
				)
				( attribute "PHYS_PAGE" "212"
					( Origin gFrontEnd )
				)
				( attribute "POP" "NOPOP"
					( Origin gFrontEnd )
				)
				( attribute "ROOM" "VDDQ_KLM_PWR_VR"
					( Origin gFrontEnd )
				)
				( attribute "ROT" "0"
					( Origin gFrontEnd )
				)
				( attribute "TOLERANCE" "10%"
					( Origin gFrontEnd )
				)
				( attribute "VALUE" "1000PF"
					( Origin gFrontEnd )
				)
				( attribute "VER" "1"
					( Origin gFrontEnd )
				)
				( attribute "VOLTAGE" "50V"
					( Units "uVoltage" "V" 1.000000)
					( Origin gFrontEnd )
				)
				( attribute "XY" "(2625,3450)"
					( Origin gFrontEnd )
				)
				( attribute "CHIPS_PART_NAME" "CAP"
					( Origin gPackager )
				)
				( attribute "CDS_PART_NAME" "CAP_0402LF-1000PF,50V,10%,X7R,A"
					( Origin gPackager )
				)
				( attribute "CDS_LOCATION" "CT72"
					( Origin gPackager )
				)
				( attribute "SEC" "1"
					( Origin gFrontEnd )
				)
				( attribute "SEC_TYPE" "0402LF"
					( Origin gFrontEnd )
				)
				( attribute "CDS_SEC" "1"
					( Origin gPackager )
				)
				( objectStatus "CT72" )
			)
			( gate "@baseboard_fab2_lib.baseboard_fab2(sch_1):page205_i65"
				( attribute "CDS_LIB" "mstr_discrete"
					( Origin gPackager )
				)
				( attribute "LOCATION" "CT58"
					( Origin gFrontEnd )
				)
				( attribute "MATERIAL" "X7R"
					( Origin gFrontEnd )
				)
				( attribute "PACK_TYPE" "0402LF"
					( Origin gFrontEnd )
				)
				( attribute "PART_NUMBER" "A36096-046"
					( Origin gFrontEnd )
				)
				( attribute "PHYS_PAGE" "205"
					( Origin gFrontEnd )
				)
				( attribute "ROOM" "VDDQ_KLM_PWR_VR"
					( Origin gFrontEnd )
				)
				( attribute "ROT" "0"
					( Origin gFrontEnd )
				)
				( attribute "TOLERANCE" "10%"
					( Origin gFrontEnd )
				)
				( attribute "VALUE" "1000PF"
					( Origin gFrontEnd )
				)
				( attribute "VER" "1"
					( Origin gFrontEnd )
				)
				( attribute "VOLTAGE" "50V"
					( Units "uVoltage" "V" 1.000000)
					( Origin gFrontEnd )
				)
				( attribute "XY" "(-2025,3950)"
					( Origin gFrontEnd )
				)
				( attribute "CHIPS_PART_NAME" "CAP"
					( Origin gPackager )
				)
				( attribute "CDS_PART_NAME" "CAP_0402LF-1000PF,50V,10%,X7R,A"
					( Origin gPackager )
				)
				( attribute "CDS_LOCATION" "CT58"
					( Origin gPackager )
				)
				( attribute "SEC" "1"
					( Origin gFrontEnd )
				)
				( attribute "SEC_TYPE" "0402LF"
					( Origin gFrontEnd )
				)
				( attribute "CDS_SEC" "1"
					( Origin gPackager )
				)
				( attribute "POP" "NOPOP"
					( Origin gFrontEnd )
				)
				( objectStatus "CT58" )
			)
			( gate "@baseboard_fab2_lib.baseboard_fab2(sch_1):page214_i176"
				( attribute "ATTRIBUTE" "1 OHM"
					( Origin gFrontEnd )
				)
				( attribute "CDS_LIB" "w_hdl"
					( Origin gPackager )
				)
				( attribute "CDS_LMAN_SYM_OUTLINE" "-50,75,50,-75"
					( Origin gPackager )
				)
				( attribute "LOCATION" "RT42"
					( Origin gFrontEnd )
				)
				( attribute "PACK_TYPE" "RCL_GP"
					( Origin gFrontEnd )
				)
				( attribute "PART_NUMBER" "64.1R005.55L"
					( Origin gFrontEnd )
				)
				( attribute "PHYS_PAGE" "214"
					( Origin gFrontEnd )
				)
				( attribute "POP" "NOPOP"
					( Origin gFrontEnd )
				)
				( attribute "RATED" "1/10W"
					( Origin gFrontEnd )
				)
				( attribute "ROT" "0"
					( Origin gFrontEnd )
				)
				( attribute "SEC" "1"
					( Origin gFrontEnd )
				)
				( attribute "SEC_TYPE" "RCL_GP"
					( Origin gFrontEnd )
				)
				( attribute "TOLERANCE" "1%"
					( Origin gFrontEnd )
				)
				( attribute "VALUE" "1R3F-GP"
					( Origin gFrontEnd )
				)
				( attribute "VER" "1"
					( Origin gFrontEnd )
				)
				( attribute "XY" "(2200,3100)"
					( Origin gFrontEnd )
				)
				( attribute "CHIPS_PART_NAME" "1R3F-GP"
					( Origin gPackager )
				)
				( attribute "CDS_PART_NAME" "1R3F-GP_RCL_GP-1R3F-GP,64.1R00A"
					( Origin gPackager )
				)
				( attribute "PACK_SIZE" "0603"
					( Origin gFrontEnd )
				)
				( attribute "CDS_LOCATION" "RT42"
					( Origin gPackager )
				)
				( attribute "CDS_SEC" "1"
					( Origin gPackager )
				)
				( objectStatus "RT42" )
			)
			( gate "@baseboard_fab2_lib.baseboard_fab2(sch_1):page205_i69"
				( attribute "CDS_LIB" "dev_discrete"
					( Origin gPackager )
				)
				( attribute "LOCATION" "CT60"
					( Origin gFrontEnd )
				)
				( attribute "MATERIAL" "X7R"
					( Origin gFrontEnd )
				)
				( attribute "PACK_TYPE" "0402V"
					( Origin gFrontEnd )
				)
				( attribute "PART_NUMBER" "A36096-030"
					( Origin gFrontEnd )
				)
				( attribute "PHYS_PAGE" "205"
					( Origin gFrontEnd )
				)
				( attribute "ROOM" "PVCCIN_CPU0_PWR_VR"
					( Origin gFrontEnd )
				)
				( attribute "ROT" "0"
					( Origin gFrontEnd )
				)
				( attribute "TOLERANCE" "10%"
					( Origin gFrontEnd )
				)
				( attribute "VALUE" "0.1UF"
					( Origin gFrontEnd )
				)
				( attribute "VER" "1"
					( Origin gFrontEnd )
				)
				( attribute "VOLTAGE" "16V"
					( Units "uVoltage" "V" 1.000000)
					( Origin gFrontEnd )
				)
				( attribute "XY" "(-3850,3425)"
					( Origin gFrontEnd )
				)
				( attribute "CHIPS_PART_NAME" "CAP_A"
					( Origin gPackager )
				)
				( attribute "CDS_PART_NAME" "CAP_A_0402V-0.1UF,16V,10%,X7R,A"
					( Origin gPackager )
				)
				( attribute "CDS_LOCATION" "CT60"
					( Origin gPackager )
				)
				( attribute "SEC" "1"
					( Origin gFrontEnd )
				)
				( attribute "SEC_TYPE" "0402V"
					( Origin gFrontEnd )
				)
				( attribute "CDS_SEC" "1"
					( Origin gPackager )
				)
				( attribute "POP" "NOPOP"
					( Origin gFrontEnd )
				)
				( objectStatus "CT60" )
			)
			( gate "@baseboard_fab2_lib.baseboard_fab2(sch_1):page219_i142"
				( attribute "BOM_COST" "NT_GBE_BASE"
					( Origin gFrontEnd )
				)
				( attribute "CDS_LIB" "mstr_discrete"
					( Origin gPackager )
				)
				( attribute "LOCATION" "RT31"
					( Origin gFrontEnd )
				)
				( attribute "MATERIAL" "CHIP"
					( Origin gFrontEnd )
				)
				( attribute "PACK_TYPE" "0603"
					( Origin gFrontEnd )
				)
				( attribute "PART_NUMBER" "G22178-002"
					( Origin gFrontEnd )
				)
				( attribute "PHYS_PAGE" "219"
					( Origin gFrontEnd )
				)
				( attribute "ROOM" "NIC_SPRV"
					( Origin gFrontEnd )
				)
				( attribute "ROT" "0"
					( Origin gFrontEnd )
				)
				( attribute "TOLERANCE" "5.0%"
					( Origin gFrontEnd )
				)
				( attribute "VALUE" "0"
					( Origin gFrontEnd )
				)
				( attribute "VER" "1"
					( Origin gFrontEnd )
				)
				( attribute "WATTAGE" "1/10W"
					( Origin gFrontEnd )
				)
				( attribute "XY" "(175,-350)"
					( Origin gFrontEnd )
				)
				( attribute "CHIPS_PART_NAME" "RES"
					( Origin gPackager )
				)
				( attribute "CDS_PART_NAME" "RES_0603-0,5.0%,1/10W,CHIP,G22A"
					( Origin gPackager )
				)
				( attribute "CDS_LOCATION" "RT31"
					( Origin gPackager )
				)
				( attribute "SEC" "1"
					( Origin gFrontEnd )
				)
				( attribute "SEC_TYPE" "0603"
					( Origin gFrontEnd )
				)
				( attribute "CDS_SEC" "1"
					( Origin gPackager )
				)
				( attribute "BOM_SS" "NOPOP"
					( Origin gFrontEnd )
				)
				( objectStatus "RT31" )
			)
			( gate "@baseboard_fab2_lib.baseboard_fab2(sch_1):page219_i141"
				( attribute "BOM_COST" "NT_GBE_BASE"
					( Origin gFrontEnd )
				)
				( attribute "CDS_LIB" "mstr_discrete"
					( Origin gPackager )
				)
				( attribute "LOCATION" "RT30"
					( Origin gFrontEnd )
				)
				( attribute "MATERIAL" "CHIP"
					( Origin gFrontEnd )
				)
				( attribute "PACK_TYPE" "0603"
					( Origin gFrontEnd )
				)
				( attribute "PART_NUMBER" "G22178-002"
					( Origin gFrontEnd )
				)
				( attribute "PHYS_PAGE" "219"
					( Origin gFrontEnd )
				)
				( attribute "ROOM" "NIC_SPRV"
					( Origin gFrontEnd )
				)
				( attribute "ROT" "0"
					( Origin gFrontEnd )
				)
				( attribute "TOLERANCE" "5.0%"
					( Origin gFrontEnd )
				)
				( attribute "VALUE" "0"
					( Origin gFrontEnd )
				)
				( attribute "VER" "1"
					( Origin gFrontEnd )
				)
				( attribute "WATTAGE" "1/10W"
					( Origin gFrontEnd )
				)
				( attribute "XY" "(-125,1900)"
					( Origin gFrontEnd )
				)
				( attribute "CHIPS_PART_NAME" "RES"
					( Origin gPackager )
				)
				( attribute "CDS_PART_NAME" "RES_0603-0,5.0%,1/10W,CHIP,G22A"
					( Origin gPackager )
				)
				( attribute "CDS_LOCATION" "RT30"
					( Origin gPackager )
				)
				( attribute "SEC" "1"
					( Origin gFrontEnd )
				)
				( attribute "SEC_TYPE" "0603"
					( Origin gFrontEnd )
				)
				( attribute "CDS_SEC" "1"
					( Origin gPackager )
				)
				( objectStatus "RT30" )
			)
			( gate "@baseboard_fab2_lib.baseboard_fab2(sch_1):page214_i134"
				( attribute "CDS_LIB" "mstr_discrete"
					( Origin gPackager )
				)
				( attribute "LOCATION" "CT61"
					( Origin gFrontEnd )
				)
				( attribute "MATERIAL" "X7R"
					( Origin gFrontEnd )
				)
				( attribute "PACK_TYPE" "0402LF"
					( Origin gFrontEnd )
				)
				( attribute "PART_NUMBER" "A36096-046"
					( Origin gFrontEnd )
				)
				( attribute "PHYS_PAGE" "214"
					( Origin gFrontEnd )
				)
				( attribute "ROOM" "VDDQ_KLM_PWR_VR"
					( Origin gFrontEnd )
				)
				( attribute "ROT" "0"
					( Origin gFrontEnd )
				)
				( attribute "TOLERANCE" "10%"
					( Origin gFrontEnd )
				)
				( attribute "VALUE" "1000PF"
					( Origin gFrontEnd )
				)
				( attribute "VER" "1"
					( Origin gFrontEnd )
				)
				( attribute "VOLTAGE" "50V"
					( Units "uVoltage" "V" 1.000000)
					( Origin gFrontEnd )
				)
				( attribute "XY" "(2275,3950)"
					( Origin gFrontEnd )
				)
				( attribute "CHIPS_PART_NAME" "CAP"
					( Origin gPackager )
				)
				( attribute "CDS_PART_NAME" "CAP_0402LF-1000PF,50V,10%,X7R,A"
					( Origin gPackager )
				)
				( attribute "CDS_LOCATION" "CT61"
					( Origin gPackager )
				)
				( attribute "SEC" "1"
					( Origin gFrontEnd )
				)
				( attribute "POP" "NOPOP"
					( Origin gFrontEnd )
				)
				( attribute "SEC_TYPE" "0402LF"
					( Origin gFrontEnd )
				)
				( attribute "CDS_SEC" "1"
					( Origin gPackager )
				)
				( objectStatus "CT61" )
			)
			( gate "@baseboard_fab2_lib.baseboard_fab2(sch_1):page214_i137"
				( attribute "CDS_LIB" "dev_discrete"
					( Origin gPackager )
				)
				( attribute "LOCATION" "CT63"
					( Origin gFrontEnd )
				)
				( attribute "MATERIAL" "X7R"
					( Origin gFrontEnd )
				)
				( attribute "PACK_TYPE" "0402V"
					( Origin gFrontEnd )
				)
				( attribute "PART_NUMBER" "A36096-030"
					( Origin gFrontEnd )
				)
				( attribute "PHYS_PAGE" "214"
					( Origin gFrontEnd )
				)
				( attribute "ROOM" "PVCCIN_CPU0_PWR_VR"
					( Origin gFrontEnd )
				)
				( attribute "ROT" "0"
					( Origin gFrontEnd )
				)
				( attribute "TOLERANCE" "10%"
					( Origin gFrontEnd )
				)
				( attribute "VALUE" "0.1UF"
					( Origin gFrontEnd )
				)
				( attribute "VER" "1"
					( Origin gFrontEnd )
				)
				( attribute "VOLTAGE" "16V"
					( Units "uVoltage" "V" 1.000000)
					( Origin gFrontEnd )
				)
				( attribute "XY" "(275,3425)"
					( Origin gFrontEnd )
				)
				( attribute "CHIPS_PART_NAME" "CAP_A"
					( Origin gPackager )
				)
				( attribute "CDS_PART_NAME" "CAP_A_0402V-0.1UF,16V,10%,X7R,A"
					( Origin gPackager )
				)
				( attribute "CDS_LOCATION" "CT63"
					( Origin gPackager )
				)
				( attribute "SEC" "1"
					( Origin gFrontEnd )
				)
				( attribute "POP" "NOPOP"
					( Origin gFrontEnd )
				)
				( attribute "SEC_TYPE" "0402V"
					( Origin gFrontEnd )
				)
				( attribute "CDS_SEC" "1"
					( Origin gPackager )
				)
				( objectStatus "CT63" )
			)
			( gate "@baseboard_fab2_lib.baseboard_fab2(sch_1):page242_i91"
				( attribute "BOM_COST" "PROC_SOCKET"
					( Origin gFrontEnd )
				)
				( attribute "CDS_LIB" "mstr_discrete"
					( Origin gPackager )
				)
				( attribute "LOCATION" "C5G78"
					( Origin gFrontEnd )
				)
				( attribute "MATERIAL" "X6S"
					( Origin gFrontEnd )
				)
				( attribute "PACK_TYPE" "0805"
					( Origin gFrontEnd )
				)
				( attribute "PART_NUMBER" "C95333-006"
					( Origin gFrontEnd )
				)
				( attribute "PHYS_PAGE" "242"
					( Origin gFrontEnd )
				)
				( attribute "ROOM" "PVCCIN_CPU0_DECAP_VR"
					( Origin gFrontEnd )
				)
				( attribute "ROT" "0"
					( Origin gFrontEnd )
				)
				( attribute "TOLERANCE" "20%"
					( Origin gFrontEnd )
				)
				( attribute "VALUE" "47UF"
					( Origin gFrontEnd )
				)
				( attribute "VER" "1"
					( Origin gFrontEnd )
				)
				( attribute "VOLTAGE" "4V"
					( Units "uVoltage" "V" 1.000000)
					( Origin gFrontEnd )
				)
				( attribute "XY" "(-3400,3775)"
					( Origin gFrontEnd )
				)
				( attribute "CHIPS_PART_NAME" "CAP"
					( Origin gPackager )
				)
				( attribute "CDS_PART_NAME" "CAP_0805-47UF,4V,20%,X6S,C9533A"
					( Origin gPackager )
				)
				( attribute "CDS_LOCATION" "C5G78"
					( Origin gPackager )
				)
				( attribute "SEC" "1"
					( Origin gFrontEnd )
				)
				( attribute "SEC_TYPE" "0805"
					( Origin gFrontEnd )
				)
				( attribute "CDS_SEC" "1"
					( Origin gPackager )
				)
				( attribute "GROUP" "PWR_MLCC_CAP"
					( Origin gFrontEnd )
				)
				( attribute "POP" "NOPOP"
					( Origin gFrontEnd )
				)
				( objectStatus "C5G78" )
			)
			( gate "@baseboard_fab2_lib.baseboard_fab2(sch_1):page236_i124"
				( attribute "CDS_LIB" "dev_discrete"
					( Origin gPackager )
				)
				( attribute "LOCATION" "CT67"
					( Origin gFrontEnd )
				)
				( attribute "MATERIAL" "X7R"
					( Origin gFrontEnd )
				)
				( attribute "PACK_TYPE" "0402V"
					( Origin gFrontEnd )
				)
				( attribute "PART_NUMBER" "A36096-030"
					( Origin gFrontEnd )
				)
				( attribute "PHYS_PAGE" "236"
					( Origin gFrontEnd )
				)
				( attribute "ROOM" "PVCCIN_CPU0_PWR_VR"
					( Origin gFrontEnd )
				)
				( attribute "ROT" "0"
					( Origin gFrontEnd )
				)
				( attribute "TOLERANCE" "10%"
					( Origin gFrontEnd )
				)
				( attribute "VALUE" "0.1UF"
					( Origin gFrontEnd )
				)
				( attribute "VER" "1"
					( Origin gFrontEnd )
				)
				( attribute "VOLTAGE" "16V"
					( Units "uVoltage" "V" 1.000000)
					( Origin gFrontEnd )
				)
				( attribute "XY" "(9125,2025)"
					( Origin gFrontEnd )
				)
				( attribute "CHIPS_PART_NAME" "CAP_A"
					( Origin gPackager )
				)
				( attribute "CDS_PART_NAME" "CAP_A_0402V-0.1UF,16V,10%,X7R,A"
					( Origin gPackager )
				)
				( attribute "CDS_LOCATION" "CT67"
					( Origin gPackager )
				)
				( attribute "CDS_SEC" "1"
					( Origin gPackager )
				)
				( attribute "SEC" "1"
					( Origin gPackager )
				)
				( attribute "POP" "NOPOP"
					( Origin gFrontEnd )
				)
				( objectStatus "CT67" )
			)
			( gate "@baseboard_fab2_lib.baseboard_fab2(sch_1):page236_i127"
				( attribute "CDS_LIB" "dev_discrete"
					( Origin gPackager )
				)
				( attribute "LOCATION" "CT66"
					( Origin gFrontEnd )
				)
				( attribute "MATERIAL" "X7R"
					( Origin gFrontEnd )
				)
				( attribute "PACK_TYPE" "0402V"
					( Origin gFrontEnd )
				)
				( attribute "PART_NUMBER" "A36096-030"
					( Origin gFrontEnd )
				)
				( attribute "PHYS_PAGE" "236"
					( Origin gFrontEnd )
				)
				( attribute "ROOM" "PVCCIN_CPU0_PWR_VR"
					( Origin gFrontEnd )
				)
				( attribute "ROT" "0"
					( Origin gFrontEnd )
				)
				( attribute "TOLERANCE" "10%"
					( Origin gFrontEnd )
				)
				( attribute "VALUE" "0.1UF"
					( Origin gFrontEnd )
				)
				( attribute "VER" "1"
					( Origin gFrontEnd )
				)
				( attribute "VOLTAGE" "16V"
					( Units "uVoltage" "V" 1.000000)
					( Origin gFrontEnd )
				)
				( attribute "XY" "(9125,3775)"
					( Origin gFrontEnd )
				)
				( attribute "CHIPS_PART_NAME" "CAP_A"
					( Origin gPackager )
				)
				( attribute "CDS_PART_NAME" "CAP_A_0402V-0.1UF,16V,10%,X7R,A"
					( Origin gPackager )
				)
				( attribute "CDS_LOCATION" "CT66"
					( Origin gPackager )
				)
				( attribute "SEC" "1"
					( Origin gFrontEnd )
				)
				( attribute "POP" "NOPOP"
					( Origin gFrontEnd )
				)
				( attribute "SEC_TYPE" "0402V"
					( Origin gFrontEnd )
				)
				( attribute "CDS_SEC" "1"
					( Origin gPackager )
				)
				( objectStatus "CT66" )
			)
			( gate "@baseboard_fab2_lib.baseboard_fab2(sch_1):page216_i139"
				( attribute "BOM_COST" "NT_GBE_BASE"
					( Origin gFrontEnd )
				)
				( attribute "CDS_LIB" "mstr_discrete"
					( Origin gPackager )
				)
				( attribute "LOCATION" "RT33"
					( Origin gFrontEnd )
				)
				( attribute "MATERIAL" "CHIP"
					( Origin gFrontEnd )
				)
				( attribute "PACK_TYPE" "0603"
					( Origin gFrontEnd )
				)
				( attribute "PART_NUMBER" "G22178-002"
					( Origin gFrontEnd )
				)
				( attribute "PHYS_PAGE" "216"
					( Origin gFrontEnd )
				)
				( attribute "ROOM" "NIC_SPRV"
					( Origin gFrontEnd )
				)
				( attribute "ROT" "0"
					( Origin gFrontEnd )
				)
				( attribute "TOLERANCE" "5.0%"
					( Origin gFrontEnd )
				)
				( attribute "VALUE" "0"
					( Origin gFrontEnd )
				)
				( attribute "VER" "1"
					( Origin gFrontEnd )
				)
				( attribute "WATTAGE" "1/10W"
					( Origin gFrontEnd )
				)
				( attribute "XY" "(125,2075)"
					( Origin gFrontEnd )
				)
				( attribute "CHIPS_PART_NAME" "RES"
					( Origin gPackager )
				)
				( attribute "CDS_PART_NAME" "RES_0603-0,5.0%,1/10W,CHIP,G22A"
					( Origin gPackager )
				)
				( attribute "CDS_LOCATION" "RT33"
					( Origin gPackager )
				)
				( attribute "SEC" "1"
					( Origin gFrontEnd )
				)
				( attribute "SEC_TYPE" "0603"
					( Origin gFrontEnd )
				)
				( attribute "CDS_SEC" "1"
					( Origin gPackager )
				)
				( objectStatus "RT33" )
			)
			( gate "@baseboard_fab2_lib.baseboard_fab2(sch_1):page227_i150"
				( attribute "ATTRIBUTE" "1 OHM"
					( Origin gFrontEnd )
				)
				( attribute "CDS_LIB" "w_hdl"
					( Origin gPackager )
				)
				( attribute "CDS_LMAN_SYM_OUTLINE" "-50,75,50,-75"
					( Origin gPackager )
				)
				( attribute "LOCATION" "RT7"
					( Origin gFrontEnd )
				)
				( attribute "PACK_TYPE" "RCL_GP"
					( Origin gFrontEnd )
				)
				( attribute "PART_NUMBER" "64.1R005.55L"
					( Origin gFrontEnd )
				)
				( attribute "PHYS_PAGE" "227"
					( Origin gFrontEnd )
				)
				( attribute "POP" "NOPOP"
					( Origin gFrontEnd )
				)
				( attribute "RATED" "1/10W"
					( Origin gFrontEnd )
				)
				( attribute "ROT" "0"
					( Origin gFrontEnd )
				)
				( attribute "SEC" "1"
					( Origin gFrontEnd )
				)
				( attribute "SEC_TYPE" "RCL_GP"
					( Origin gFrontEnd )
				)
				( attribute "TOLERANCE" "1%"
					( Origin gFrontEnd )
				)
				( attribute "VALUE" "1R3F-GP"
					( Origin gFrontEnd )
				)
				( attribute "VER" "1"
					( Origin gFrontEnd )
				)
				( attribute "XY" "(2925,-800)"
					( Origin gFrontEnd )
				)
				( attribute "CHIPS_PART_NAME" "1R3F-GP"
					( Origin gPackager )
				)
				( attribute "CDS_PART_NAME" "1R3F-GP_RCL_GP-1R3F-GP,64.1R00A"
					( Origin gPackager )
				)
				( attribute "PACK_SIZE" "0603"
					( Origin gFrontEnd )
				)
				( attribute "CDS_LOCATION" "RT7"
					( Origin gPackager )
				)
				( attribute "CDS_SEC" "1"
					( Origin gPackager )
				)
				( attribute "BOM_SS" "NOPOP"
					( Origin gFrontEnd )
				)
				( objectStatus "RT7" )
			)
			( gate "@baseboard_fab2_lib.baseboard_fab2(sch_1):page236_i134"
				( attribute "CDS_LIB" "mstr_discrete"
					( Origin gPackager )
				)
				( attribute "LOCATION" "CT69"
					( Origin gFrontEnd )
				)
				( attribute "MATERIAL" "X7R"
					( Origin gFrontEnd )
				)
				( attribute "PACK_TYPE" "0402LF"
					( Origin gFrontEnd )
				)
				( attribute "PART_NUMBER" "A36096-046"
					( Origin gFrontEnd )
				)
				( attribute "PHYS_PAGE" "236"
					( Origin gFrontEnd )
				)
				( attribute "ROOM" "VDDQ_KLM_PWR_VR"
					( Origin gFrontEnd )
				)
				( attribute "ROT" "0"
					( Origin gFrontEnd )
				)
				( attribute "TOLERANCE" "10%"
					( Origin gFrontEnd )
				)
				( attribute "VALUE" "1000PF"
					( Origin gFrontEnd )
				)
				( attribute "VER" "1"
					( Origin gFrontEnd )
				)
				( attribute "VOLTAGE" "50V"
					( Units "uVoltage" "V" 1.000000)
					( Origin gFrontEnd )
				)
				( attribute "XY" "(10900,2600)"
					( Origin gFrontEnd )
				)
				( attribute "CHIPS_PART_NAME" "CAP"
					( Origin gPackager )
				)
				( attribute "CDS_PART_NAME" "CAP_0402LF-1000PF,50V,10%,X7R,A"
					( Origin gPackager )
				)
				( attribute "CDS_LOCATION" "CT69"
					( Origin gPackager )
				)
				( attribute "SEC" "1"
					( Origin gFrontEnd )
				)
				( attribute "POP" "NOPOP"
					( Origin gFrontEnd )
				)
				( attribute "SEC_TYPE" "0402LF"
					( Origin gFrontEnd )
				)
				( attribute "CDS_SEC" "1"
					( Origin gPackager )
				)
				( objectStatus "CT69" )
			)
			( gate "@baseboard_fab2_lib.baseboard_fab2(sch_1):page236_i136"
				( attribute "CDS_LIB" "mstr_discrete"
					( Origin gPackager )
				)
				( attribute "LOCATION" "CT64"
					( Origin gFrontEnd )
				)
				( attribute "MATERIAL" "X7R"
					( Origin gFrontEnd )
				)
				( attribute "PACK_TYPE" "0402LF"
					( Origin gFrontEnd )
				)
				( attribute "PART_NUMBER" "A36096-046"
					( Origin gFrontEnd )
				)
				( attribute "PHYS_PAGE" "236"
					( Origin gFrontEnd )
				)
				( attribute "ROOM" "VDDQ_KLM_PWR_VR"
					( Origin gFrontEnd )
				)
				( attribute "ROT" "0"
					( Origin gFrontEnd )
				)
				( attribute "TOLERANCE" "10%"
					( Origin gFrontEnd )
				)
				( attribute "VALUE" "1000PF"
					( Origin gFrontEnd )
				)
				( attribute "VER" "1"
					( Origin gFrontEnd )
				)
				( attribute "VOLTAGE" "50V"
					( Units "uVoltage" "V" 1.000000)
					( Origin gFrontEnd )
				)
				( attribute "XY" "(10925,4300)"
					( Origin gFrontEnd )
				)
				( attribute "CHIPS_PART_NAME" "CAP"
					( Origin gPackager )
				)
				( attribute "CDS_PART_NAME" "CAP_0402LF-1000PF,50V,10%,X7R,A"
					( Origin gPackager )
				)
				( attribute "CDS_LOCATION" "CT64"
					( Origin gPackager )
				)
				( attribute "SEC" "1"
					( Origin gFrontEnd )
				)
				( attribute "POP" "NOPOP"
					( Origin gFrontEnd )
				)
				( attribute "SEC_TYPE" "0402LF"
					( Origin gFrontEnd )
				)
				( attribute "CDS_SEC" "1"
					( Origin gPackager )
				)
				( objectStatus "CT64" )
			)
			( gate "@baseboard_fab2_lib.baseboard_fab2(sch_1):page242_i92"
				( attribute "BOM_COST" "PROC_SOCKET"
					( Origin gFrontEnd )
				)
				( attribute "CDS_LIB" "mstr_discrete"
					( Origin gPackager )
				)
				( attribute "LOCATION" "C5G21"
					( Origin gFrontEnd )
				)
				( attribute "MATERIAL" "X6S"
					( Origin gFrontEnd )
				)
				( attribute "PACK_TYPE" "0805"
					( Origin gFrontEnd )
				)
				( attribute "PART_NUMBER" "C95333-006"
					( Origin gFrontEnd )
				)
				( attribute "PHYS_PAGE" "242"
					( Origin gFrontEnd )
				)
				( attribute "ROOM" "PVCCIN_CPU0_DECAP_VR"
					( Origin gFrontEnd )
				)
				( attribute "ROT" "0"
					( Origin gFrontEnd )
				)
				( attribute "TOLERANCE" "20%"
					( Origin gFrontEnd )
				)
				( attribute "VALUE" "47UF"
					( Origin gFrontEnd )
				)
				( attribute "VER" "1"
					( Origin gFrontEnd )
				)
				( attribute "VOLTAGE" "4V"
					( Units "uVoltage" "V" 1.000000)
					( Origin gFrontEnd )
				)
				( attribute "XY" "(-7750,3775)"
					( Origin gFrontEnd )
				)
				( attribute "CHIPS_PART_NAME" "CAP"
					( Origin gPackager )
				)
				( attribute "CDS_PART_NAME" "CAP_0805-47UF,4V,20%,X6S,C9533A"
					( Origin gPackager )
				)
				( attribute "SEC" "1"
					( Origin gFrontEnd )
				)
				( attribute "SEC_TYPE" "0805"
					( Origin gFrontEnd )
				)
				( attribute "CDS_LOCATION" "C5G21"
					( Origin gPackager )
				)
				( attribute "CDS_SEC" "1"
					( Origin gPackager )
				)
				( attribute "GROUP" "PWR_MLCC_CAP"
					( Origin gFrontEnd )
				)
				( attribute "POP" "NOPOP"
					( Origin gFrontEnd )
				)
				( objectStatus "C5G21" )
			)
			( gate "@baseboard_fab2_lib.baseboard_fab2(sch_1):page212_i106"
				( attribute "CDS_LIB" "dev_discrete"
					( Origin gPackager )
				)
				( attribute "LOCATION" "CT70"
					( Origin gFrontEnd )
				)
				( attribute "MATERIAL" "X7R"
					( Origin gFrontEnd )
				)
				( attribute "PACK_TYPE" "0402V"
					( Origin gFrontEnd )
				)
				( attribute "PART_NUMBER" "A36096-030"
					( Origin gFrontEnd )
				)
				( attribute "PHYS_PAGE" "212"
					( Origin gFrontEnd )
				)
				( attribute "ROOM" "PVCCIN_CPU0_PWR_VR"
					( Origin gFrontEnd )
				)
				( attribute "ROT" "0"
					( Origin gFrontEnd )
				)
				( attribute "TOLERANCE" "10%"
					( Origin gFrontEnd )
				)
				( attribute "VALUE" "0.1UF"
					( Origin gFrontEnd )
				)
				( attribute "VER" "1"
					( Origin gFrontEnd )
				)
				( attribute "VOLTAGE" "16V"
					( Units "uVoltage" "V" 1.000000)
					( Origin gFrontEnd )
				)
				( attribute "XY" "(450,3450)"
					( Origin gFrontEnd )
				)
				( attribute "CHIPS_PART_NAME" "CAP_A"
					( Origin gPackager )
				)
				( attribute "CDS_PART_NAME" "CAP_A_0402V-0.1UF,16V,10%,X7R,A"
					( Origin gPackager )
				)
				( attribute "CDS_LOCATION" "CT70"
					( Origin gPackager )
				)
				( attribute "CDS_SEC" "1"
					( Origin gPackager )
				)
				( attribute "SEC" "1"
					( Origin gPackager )
				)
				( attribute "POP" "NOPOP"
					( Origin gFrontEnd )
				)
				( objectStatus "CT70" )
			)
			( gate "@baseboard_fab2_lib.baseboard_fab2(sch_1):page158_i148"
				( attribute "BOM_COST" "DEBUG"
					( Origin gFrontEnd )
				)
				( attribute "CDS_LIB" "mstr_discrete"
					( Origin gPackager )
				)
				( attribute "LOCATION" "R9F65"
					( Origin gFrontEnd )
				)
				( attribute "MATERIAL" "CHIP"
					( Origin gFrontEnd )
				)
				( attribute "PACK_TYPE" "0402"
					( Origin gFrontEnd )
				)
				( attribute "PART_NUMBER" "G21497-005"
					( Origin gFrontEnd )
				)
				( attribute "PHYS_PAGE" "158"
					( Origin gFrontEnd )
				)
				( attribute "ROOM" "UART_MUX"
					( Origin gFrontEnd )
				)
				( attribute "ROT" "0"
					( Origin gFrontEnd )
				)
				( attribute "TOLERANCE" "5%"
					( Origin gFrontEnd )
				)
				( attribute "VALUE" "0.0"
					( Origin gFrontEnd )
				)
				( attribute "VER" "1"
					( Origin gFrontEnd )
				)
				( attribute "WATTAGE" "1/16W"
					( Origin gFrontEnd )
				)
				( attribute "XY" "(-3125,3750)"
					( Origin gFrontEnd )
				)
				( attribute "CHIPS_PART_NAME" "RES"
					( Origin gPackager )
				)
				( attribute "CDS_PART_NAME" "RES_0402-0.0,5%,1/16W,CHIP,G21A"
					( Origin gPackager )
				)
				( attribute "CDS_LOCATION" "R9F65"
					( Origin gPackager )
				)
				( attribute "SEC" "1"
					( Origin gFrontEnd )
				)
				( attribute "SEC_TYPE" "0402"
					( Origin gFrontEnd )
				)
				( attribute "CDS_SEC" "1"
					( Origin gPackager )
				)
				( objectStatus "R9F65" )
			)
			( gate "@baseboard_fab2_lib.baseboard_fab2(sch_1):page212_i109"
				( attribute "CDS_LIB" "mstr_discrete"
					( Origin gPackager )
				)
				( attribute "LOCATION" "CT71"
					( Origin gFrontEnd )
				)
				( attribute "MATERIAL" "X7R"
					( Origin gFrontEnd )
				)
				( attribute "PACK_TYPE" "0402LF"
					( Origin gFrontEnd )
				)
				( attribute "PART_NUMBER" "A36096-046"
					( Origin gFrontEnd )
				)
				( attribute "PHYS_PAGE" "212"
					( Origin gFrontEnd )
				)
				( attribute "ROOM" "VDDQ_KLM_PWR_VR"
					( Origin gFrontEnd )
				)
				( attribute "ROT" "0"
					( Origin gFrontEnd )
				)
				( attribute "TOLERANCE" "10%"
					( Origin gFrontEnd )
				)
				( attribute "VALUE" "1000PF"
					( Origin gFrontEnd )
				)
				( attribute "VER" "1"
					( Origin gFrontEnd )
				)
				( attribute "VOLTAGE" "50V"
					( Units "uVoltage" "V" 1.000000)
					( Origin gFrontEnd )
				)
				( attribute "XY" "(2375,3975)"
					( Origin gFrontEnd )
				)
				( attribute "CHIPS_PART_NAME" "CAP"
					( Origin gPackager )
				)
				( attribute "CDS_PART_NAME" "CAP_0402LF-1000PF,50V,10%,X7R,A"
					( Origin gPackager )
				)
				( attribute "CDS_LOCATION" "CT71"
					( Origin gPackager )
				)
				( attribute "CDS_SEC" "1"
					( Origin gPackager )
				)
				( attribute "SEC" "1"
					( Origin gPackager )
				)
				( attribute "POP" "NOPOP"
					( Origin gFrontEnd )
				)
				( objectStatus "CT71" )
			)
			( gate "@baseboard_fab2_lib.baseboard_fab2(sch_1):page216_i135"
				( attribute "CDS_LIB" "mstr_discrete"
					( Origin gPackager )
				)
				( attribute "LOCATION" "CT50"
					( Origin gFrontEnd )
				)
				( attribute "MATERIAL" "X7R"
					( Origin gFrontEnd )
				)
				( attribute "PACK_TYPE" "0402LF"
					( Origin gFrontEnd )
				)
				( attribute "PART_NUMBER" "A36096-046"
					( Origin gFrontEnd )
				)
				( attribute "PHYS_PAGE" "216"
					( Origin gFrontEnd )
				)
				( attribute "POP" "NOPOP"
					( Origin gFrontEnd )
				)
				( attribute "ROOM" "VDDQ_KLM_PWR_VR"
					( Origin gFrontEnd )
				)
				( attribute "ROT" "0"
					( Origin gFrontEnd )
				)
				( attribute "TOLERANCE" "10%"
					( Origin gFrontEnd )
				)
				( attribute "VALUE" "1000PF"
					( Origin gFrontEnd )
				)
				( attribute "VER" "1"
					( Origin gFrontEnd )
				)
				( attribute "VOLTAGE" "50V"
					( Units "uVoltage" "V" 1.000000)
					( Origin gFrontEnd )
				)
				( attribute "XY" "(2900,1850)"
					( Origin gFrontEnd )
				)
				( attribute "CHIPS_PART_NAME" "CAP"
					( Origin gPackager )
				)
				( attribute "CDS_PART_NAME" "CAP_0402LF-1000PF,50V,10%,X7R,A"
					( Origin gPackager )
				)
				( attribute "CDS_LOCATION" "CT50"
					( Origin gPackager )
				)
				( attribute "SEC" "1"
					( Origin gFrontEnd )
				)
				( attribute "SEC_TYPE" "0402LF"
					( Origin gFrontEnd )
				)
				( attribute "CDS_SEC" "1"
					( Origin gPackager )
				)
				( objectStatus "CT50" )
			)
			( gate "@baseboard_fab2_lib.baseboard_fab2(sch_1):page225_i246"
				( attribute "CDS_LIB" "w_hdl"
					( Origin gPackager )
				)
				( attribute "CDS_LMAN_SYM_OUTLINE" "-50,25,50,-25"
					( Origin gPackager )
				)
				( attribute "LOCATION" "C22W1"
					( Origin gFrontEnd )
				)
				( attribute "PACK_TYPE" "SMD-BCG5"
					( Origin gFrontEnd )
				)
				( attribute "PART_NUMBER" "078.22611.0811"
					( Origin gFrontEnd )
				)
				( attribute "PHYS_PAGE" "225"
					( Origin gFrontEnd )
				)
				( attribute "ROT" "0"
					( Origin gFrontEnd )
				)
				( attribute "SEC" "1"
					( Origin gFrontEnd )
				)
				( attribute "SEC_TYPE" "SMD-BCG5"
					( Origin gFrontEnd )
				)
				( attribute "VALUE" "SC22U16V5MX-4-GP"
					( Origin gFrontEnd )
				)
				( attribute "VER" "1"
					( Origin gFrontEnd )
				)
				( attribute "XY" "(-250,1150)"
					( Origin gFrontEnd )
				)
				( attribute "CHIPS_PART_NAME" "SC22U16V5MX-4-GP"
					( Origin gPackager )
				)
				( attribute "CDS_PART_NAME" "SC22U16V5MX-4-GP_SMD-BCG5-SC22A"
					( Origin gPackager )
				)
				( attribute "CDS_LOCATION" "C22W1"
					( Origin gPackager )
				)
				( attribute "CDS_SEC" "1"
					( Origin gPackager )
				)
				( attribute "ATTRIBUTE" "22UF"
					( Origin gFrontEnd )
				)
				( attribute "PACK_SIZE" "0805"
					( Origin gFrontEnd )
				)
				( attribute "RATED" "16V"
					( Origin gFrontEnd )
				)
				( attribute "TOLERANCE" "20%"
					( Origin gFrontEnd )
				)
				( attribute "TYPE" "X6S"
					( Origin gFrontEnd )
				)
				( objectStatus "C22W1" )
			)
			( gate "@baseboard_fab2_lib.baseboard_fab2(sch_1):page207_i81"
				( attribute "CDS_LIB" "dev_discrete"
					( Origin gPackager )
				)
				( attribute "LOCATION" "CT25"
					( Origin gFrontEnd )
				)
				( attribute "MATERIAL" "X7R"
					( Origin gFrontEnd )
				)
				( attribute "PACK_TYPE" "0402V"
					( Origin gFrontEnd )
				)
				( attribute "PART_NUMBER" "A36096-030"
					( Origin gFrontEnd )
				)
				( attribute "PHYS_PAGE" "207"
					( Origin gFrontEnd )
				)
				( attribute "ROOM" "PVCCIN_CPU0_PWR_VR"
					( Origin gFrontEnd )
				)
				( attribute "ROT" "0"
					( Origin gFrontEnd )
				)
				( attribute "TOLERANCE" "10%"
					( Origin gFrontEnd )
				)
				( attribute "VALUE" "0.1UF"
					( Origin gFrontEnd )
				)
				( attribute "VER" "1"
					( Origin gFrontEnd )
				)
				( attribute "VOLTAGE" "16V"
					( Units "uVoltage" "V" 1.000000)
					( Origin gFrontEnd )
				)
				( attribute "XY" "(-3825,750)"
					( Origin gFrontEnd )
				)
				( attribute "CHIPS_PART_NAME" "CAP_A"
					( Origin gPackager )
				)
				( attribute "CDS_PART_NAME" "CAP_A_0402V-0.1UF,16V,10%,X7R,A"
					( Origin gPackager )
				)
				( attribute "CDS_LOCATION" "CT25"
					( Origin gPackager )
				)
				( attribute "SEC" "1"
					( Origin gFrontEnd )
				)
				( attribute "SEC_TYPE" "0402V"
					( Origin gFrontEnd )
				)
				( attribute "CDS_SEC" "1"
					( Origin gPackager )
				)
				( attribute "POP" "NOPOP"
					( Origin gFrontEnd )
				)
				( objectStatus "CT25" )
			)
			( gate "@baseboard_fab2_lib.baseboard_fab2(sch_1):page207_i82"
				( attribute "CDS_LIB" "mstr_discrete"
					( Origin gPackager )
				)
				( attribute "LOCATION" "CT26"
					( Origin gFrontEnd )
				)
				( attribute "MATERIAL" "X7R"
					( Origin gFrontEnd )
				)
				( attribute "PACK_TYPE" "0402LF"
					( Origin gFrontEnd )
				)
				( attribute "PART_NUMBER" "A36096-046"
					( Origin gFrontEnd )
				)
				( attribute "PHYS_PAGE" "207"
					( Origin gFrontEnd )
				)
				( attribute "ROOM" "VDDQ_KLM_PWR_VR"
					( Origin gFrontEnd )
				)
				( attribute "ROT" "0"
					( Origin gFrontEnd )
				)
				( attribute "TOLERANCE" "10%"
					( Origin gFrontEnd )
				)
				( attribute "VALUE" "1000PF"
					( Origin gFrontEnd )
				)
				( attribute "VER" "1"
					( Origin gFrontEnd )
				)
				( attribute "VOLTAGE" "50V"
					( Units "uVoltage" "V" 1.000000)
					( Origin gFrontEnd )
				)
				( attribute "XY" "(-2075,1250)"
					( Origin gFrontEnd )
				)
				( attribute "CHIPS_PART_NAME" "CAP"
					( Origin gPackager )
				)
				( attribute "CDS_PART_NAME" "CAP_0402LF-1000PF,50V,10%,X7R,A"
					( Origin gPackager )
				)
				( attribute "CDS_LOCATION" "CT26"
					( Origin gPackager )
				)
				( attribute "SEC" "1"
					( Origin gFrontEnd )
				)
				( attribute "POP" "NOPOP"
					( Origin gFrontEnd )
				)
				( attribute "SEC_TYPE" "0402LF"
					( Origin gFrontEnd )
				)
				( attribute "CDS_SEC" "1"
					( Origin gPackager )
				)
				( objectStatus "CT26" )
			)
			( gate "@baseboard_fab2_lib.baseboard_fab2(sch_1):page219_i137"
				( attribute "CDS_LIB" "mstr_discrete"
					( Origin gPackager )
				)
				( attribute "LOCATION" "CT44"
					( Origin gFrontEnd )
				)
				( attribute "MATERIAL" "X7R"
					( Origin gFrontEnd )
				)
				( attribute "PACK_TYPE" "0402LF"
					( Origin gFrontEnd )
				)
				( attribute "PART_NUMBER" "A36096-046"
					( Origin gFrontEnd )
				)
				( attribute "PHYS_PAGE" "219"
					( Origin gFrontEnd )
				)
				( attribute "POP" "NOPOP"
					( Origin gFrontEnd )
				)
				( attribute "ROOM" "VDDQ_KLM_PWR_VR"
					( Origin gFrontEnd )
				)
				( attribute "ROT" "0"
					( Origin gFrontEnd )
				)
				( attribute "TOLERANCE" "10%"
					( Origin gFrontEnd )
				)
				( attribute "VALUE" "1000PF"
					( Origin gFrontEnd )
				)
				( attribute "VER" "1"
					( Origin gFrontEnd )
				)
				( attribute "VOLTAGE" "50V"
					( Units "uVoltage" "V" 1.000000)
					( Origin gFrontEnd )
				)
				( attribute "XY" "(2850,1625)"
					( Origin gFrontEnd )
				)
				( attribute "CHIPS_PART_NAME" "CAP"
					( Origin gPackager )
				)
				( attribute "CDS_PART_NAME" "CAP_0402LF-1000PF,50V,10%,X7R,A"
					( Origin gPackager )
				)
				( attribute "CDS_LOCATION" "CT44"
					( Origin gPackager )
				)
				( attribute "SEC" "1"
					( Origin gFrontEnd )
				)
				( attribute "SEC_TYPE" "0402LF"
					( Origin gFrontEnd )
				)
				( attribute "CDS_SEC" "1"
					( Origin gPackager )
				)
				( objectStatus "CT44" )
			)
			( gate "@baseboard_fab2_lib.baseboard_fab2(sch_1):page236_i182"
				( attribute "ATTRIBUTE" "1 OHM"
					( Origin gFrontEnd )
				)
				( attribute "CDS_LIB" "w_hdl"
					( Origin gPackager )
				)
				( attribute "CDS_LMAN_SYM_OUTLINE" "-50,75,50,-75"
					( Origin gPackager )
				)
				( attribute "LOCATION" "RT43"
					( Origin gFrontEnd )
				)
				( attribute "PACK_TYPE" "RCL_GP"
					( Origin gFrontEnd )
				)
				( attribute "PART_NUMBER" "64.1R005.55L"
					( Origin gFrontEnd )
				)
				( attribute "PHYS_PAGE" "236"
					( Origin gFrontEnd )
				)
				( attribute "POP" "NOPOP"
					( Origin gFrontEnd )
				)
				( attribute "RATED" "1/10W"
					( Origin gFrontEnd )
				)
				( attribute "ROT" "0"
					( Origin gFrontEnd )
				)
				( attribute "SEC" "1"
					( Origin gFrontEnd )
				)
				( attribute "SEC_TYPE" "RCL_GP"
					( Origin gFrontEnd )
				)
				( attribute "TOLERANCE" "1%"
					( Origin gFrontEnd )
				)
				( attribute "VALUE" "1R3F-GP"
					( Origin gFrontEnd )
				)
				( attribute "VER" "1"
					( Origin gFrontEnd )
				)
				( attribute "XY" "(10550,3550)"
					( Origin gFrontEnd )
				)
				( attribute "CHIPS_PART_NAME" "1R3F-GP"
					( Origin gPackager )
				)
				( attribute "CDS_PART_NAME" "1R3F-GP_RCL_GP-1R3F-GP,64.1R00A"
					( Origin gPackager )
				)
				( attribute "PACK_SIZE" "0603"
					( Origin gFrontEnd )
				)
				( attribute "CDS_LOCATION" "RT43"
					( Origin gPackager )
				)
				( attribute "CDS_SEC" "1"
					( Origin gPackager )
				)
				( objectStatus "RT43" )
			)
			( gate "@baseboard_fab2_lib.baseboard_fab2(sch_1):page202_i87"
				( attribute "CDS_LIB" "mstr_discrete"
					( Origin gPackager )
				)
				( attribute "CDS_LOCATION" "CT4"
					( Origin gPackager )
				)
				( attribute "LOCATION" "CT4"
					( Origin gFrontEnd )
				)
				( attribute "MATERIAL" "X7R"
					( Origin gFrontEnd )
				)
				( attribute "PACK_TYPE" "0402LF"
					( Origin gFrontEnd )
				)
				( attribute "PART_NUMBER" "A36096-046"
					( Origin gFrontEnd )
				)
				( attribute "PHYS_PAGE" "202"
					( Origin gFrontEnd )
				)
				( attribute "ROOM" "VDDQ_KLM_PWR_VR"
					( Origin gFrontEnd )
				)
				( attribute "ROT" "0"
					( Origin gFrontEnd )
				)
				( attribute "SEC" "1"
					( Origin gFrontEnd )
				)
				( attribute "TOLERANCE" "10%"
					( Origin gFrontEnd )
				)
				( attribute "VALUE" "1000PF"
					( Origin gFrontEnd )
				)
				( attribute "VER" "1"
					( Origin gFrontEnd )
				)
				( attribute "VOLTAGE" "50V"
					( Units "uVoltage" "V" 1.000000)
					( Origin gFrontEnd )
				)
				( attribute "XY" "(-2450,1250)"
					( Origin gFrontEnd )
				)
				( attribute "CHIPS_PART_NAME" "CAP"
					( Origin gPackager )
				)
				( attribute "CDS_PART_NAME" "CAP_0402LF-1000PF,50V,10%,X7R,A"
					( Origin gPackager )
				)
				( attribute "POP" "NOPOP"
					( Origin gFrontEnd )
				)
				( attribute "SEC_TYPE" "0402LF"
					( Origin gFrontEnd )
				)
				( attribute "CDS_SEC" "1"
					( Origin gPackager )
				)
				( objectStatus "CT4" )
			)
			( gate "@baseboard_fab2_lib.baseboard_fab2(sch_1):page244_i2"
				( attribute "CDS_LIB" "mstr_discrete"
					( Origin gPackager )
				)
				( attribute "CDS_LOCATION" "C831"
					( Origin gPackager )
				)
				( attribute "LOCATION" "C831"
					( Origin gPackager )
				)
				( attribute "MATERIAL" "X7R"
					( Origin gFrontEnd )
				)
				( attribute "PACK_TYPE" "0402"
					( Origin gFrontEnd )
				)
				( attribute "PART_NUMBER" "A36096-155"
					( Origin gFrontEnd )
				)
				( attribute "PHYS_PAGE" "244"
					( Origin gFrontEnd )
				)
				( attribute "ROOM" "OCP_STEERING"
					( Origin gFrontEnd )
				)
				( attribute "ROT" "2"
					( Origin gFrontEnd )
				)
				( attribute "SEC" "1"
					( Origin gFrontEnd )
				)
				( attribute "TOLERANCE" "10%"
					( Origin gFrontEnd )
				)
				( attribute "VALUE" "0.22UF"
					( Origin gFrontEnd )
				)
				( attribute "VER" "1"
					( Origin gFrontEnd )
				)
				( attribute "VOLTAGE" "16V"
					( Units "uVoltage" "V" 1.000000)
					( Origin gFrontEnd )
				)
				( attribute "XY" "(-5925,1725)"
					( Origin gFrontEnd )
				)
				( attribute "CHIPS_PART_NAME" "CAP"
					( Origin gPackager )
				)
				( attribute "CDS_PART_NAME" "CAP_0402-0.22UF,16V,10%,X7R,A3A"
					( Origin gPackager )
				)
				( attribute "SEC_TYPE" "0402"
					( Origin gFrontEnd )
				)
				( attribute "CDS_SEC" "1"
					( Origin gPackager )
				)
				( attribute "GROUP" "PCIE_RISER"
					( Origin gFrontEnd )
				)
				( objectStatus "C831" )
			)
			( gate "@baseboard_fab2_lib.baseboard_fab2(sch_1):page244_i5"
				( attribute "CDS_LIB" "mstr_discrete"
					( Origin gPackager )
				)
				( attribute "CDS_LOCATION" "C829"
					( Origin gPackager )
				)
				( attribute "LOCATION" "C829"
					( Origin gPackager )
				)
				( attribute "MATERIAL" "X7R"
					( Origin gFrontEnd )
				)
				( attribute "PACK_TYPE" "0402"
					( Origin gFrontEnd )
				)
				( attribute "PART_NUMBER" "A36096-155"
					( Origin gFrontEnd )
				)
				( attribute "PHYS_PAGE" "244"
					( Origin gFrontEnd )
				)
				( attribute "ROOM" "OCP_STEERING"
					( Origin gFrontEnd )
				)
				( attribute "ROT" "2"
					( Origin gFrontEnd )
				)
				( attribute "SEC" "1"
					( Origin gFrontEnd )
				)
				( attribute "TOLERANCE" "10%"
					( Origin gFrontEnd )
				)
				( attribute "VALUE" "0.22UF"
					( Origin gFrontEnd )
				)
				( attribute "VER" "1"
					( Origin gFrontEnd )
				)
				( attribute "VOLTAGE" "16V"
					( Units "uVoltage" "V" 1.000000)
					( Origin gFrontEnd )
				)
				( attribute "XY" "(-5525,1725)"
					( Origin gFrontEnd )
				)
				( attribute "CHIPS_PART_NAME" "CAP"
					( Origin gPackager )
				)
				( attribute "CDS_PART_NAME" "CAP_0402-0.22UF,16V,10%,X7R,A3A"
					( Origin gPackager )
				)
				( attribute "SEC_TYPE" "0402"
					( Origin gFrontEnd )
				)
				( attribute "CDS_SEC" "1"
					( Origin gPackager )
				)
				( attribute "GROUP" "PCIE_RISER"
					( Origin gFrontEnd )
				)
				( objectStatus "C829" )
			)
			( gate "@baseboard_fab2_lib.baseboard_fab2(sch_1):page244_i8"
				( attribute "CDS_LIB" "mstr_discrete"
					( Origin gPackager )
				)
				( attribute "CDS_LOCATION" "C833"
					( Origin gPackager )
				)
				( attribute "LOCATION" "C833"
					( Origin gPackager )
				)
				( attribute "MATERIAL" "X7R"
					( Origin gFrontEnd )
				)
				( attribute "PACK_TYPE" "0402"
					( Origin gFrontEnd )
				)
				( attribute "PART_NUMBER" "A36096-155"
					( Origin gFrontEnd )
				)
				( attribute "PHYS_PAGE" "244"
					( Origin gFrontEnd )
				)
				( attribute "ROOM" "OCP_STEERING"
					( Origin gFrontEnd )
				)
				( attribute "ROT" "2"
					( Origin gFrontEnd )
				)
				( attribute "SEC" "1"
					( Origin gFrontEnd )
				)
				( attribute "TOLERANCE" "10%"
					( Origin gFrontEnd )
				)
				( attribute "VALUE" "0.22UF"
					( Origin gFrontEnd )
				)
				( attribute "VER" "1"
					( Origin gFrontEnd )
				)
				( attribute "VOLTAGE" "16V"
					( Units "uVoltage" "V" 1.000000)
					( Origin gFrontEnd )
				)
				( attribute "XY" "(-5125,1725)"
					( Origin gFrontEnd )
				)
				( attribute "CHIPS_PART_NAME" "CAP"
					( Origin gPackager )
				)
				( attribute "CDS_PART_NAME" "CAP_0402-0.22UF,16V,10%,X7R,A3A"
					( Origin gPackager )
				)
				( attribute "SEC_TYPE" "0402"
					( Origin gFrontEnd )
				)
				( attribute "CDS_SEC" "1"
					( Origin gPackager )
				)
				( attribute "GROUP" "PCIE_RISER"
					( Origin gFrontEnd )
				)
				( objectStatus "C833" )
			)
			( gate "@baseboard_fab2_lib.baseboard_fab2(sch_1):page244_i12"
				( attribute "CDS_LIB" "mstr_discrete"
					( Origin gPackager )
				)
				( attribute "CDS_LOCATION" "C827"
					( Origin gPackager )
				)
				( attribute "LOCATION" "C827"
					( Origin gPackager )
				)
				( attribute "MATERIAL" "X7R"
					( Origin gFrontEnd )
				)
				( attribute "PACK_TYPE" "0402"
					( Origin gFrontEnd )
				)
				( attribute "PART_NUMBER" "A36096-155"
					( Origin gFrontEnd )
				)
				( attribute "PHYS_PAGE" "244"
					( Origin gFrontEnd )
				)
				( attribute "ROOM" "OCP_STEERING"
					( Origin gFrontEnd )
				)
				( attribute "ROT" "2"
					( Origin gFrontEnd )
				)
				( attribute "SEC" "1"
					( Origin gFrontEnd )
				)
				( attribute "TOLERANCE" "10%"
					( Origin gFrontEnd )
				)
				( attribute "VALUE" "0.22UF"
					( Origin gFrontEnd )
				)
				( attribute "VER" "1"
					( Origin gFrontEnd )
				)
				( attribute "VOLTAGE" "16V"
					( Units "uVoltage" "V" 1.000000)
					( Origin gFrontEnd )
				)
				( attribute "XY" "(-5725,2025)"
					( Origin gFrontEnd )
				)
				( attribute "CHIPS_PART_NAME" "CAP"
					( Origin gPackager )
				)
				( attribute "CDS_PART_NAME" "CAP_0402-0.22UF,16V,10%,X7R,A3A"
					( Origin gPackager )
				)
				( attribute "SEC_TYPE" "0402"
					( Origin gFrontEnd )
				)
				( attribute "CDS_SEC" "1"
					( Origin gPackager )
				)
				( attribute "GROUP" "PCIE_RISER"
					( Origin gFrontEnd )
				)
				( objectStatus "C827" )
			)
			( gate "@baseboard_fab2_lib.baseboard_fab2(sch_1):page244_i17"
				( attribute "CDS_LIB" "mstr_discrete"
					( Origin gPackager )
				)
				( attribute "CDS_LOCATION" "C841"
					( Origin gPackager )
				)
				( attribute "LOCATION" "C841"
					( Origin gPackager )
				)
				( attribute "MATERIAL" "X7R"
					( Origin gFrontEnd )
				)
				( attribute "PACK_TYPE" "0402"
					( Origin gFrontEnd )
				)
				( attribute "PART_NUMBER" "A36096-155"
					( Origin gFrontEnd )
				)
				( attribute "PHYS_PAGE" "244"
					( Origin gFrontEnd )
				)
				( attribute "ROOM" "OCP_STEERING"
					( Origin gFrontEnd )
				)
				( attribute "ROT" "2"
					( Origin gFrontEnd )
				)
				( attribute "SEC" "1"
					( Origin gFrontEnd )
				)
				( attribute "TOLERANCE" "10%"
					( Origin gFrontEnd )
				)
				( attribute "VALUE" "0.22UF"
					( Origin gFrontEnd )
				)
				( attribute "VER" "1"
					( Origin gFrontEnd )
				)
				( attribute "VOLTAGE" "16V"
					( Units "uVoltage" "V" 1.000000)
					( Origin gFrontEnd )
				)
				( attribute "XY" "(-5325,2025)"
					( Origin gFrontEnd )
				)
				( attribute "CHIPS_PART_NAME" "CAP"
					( Origin gPackager )
				)
				( attribute "CDS_PART_NAME" "CAP_0402-0.22UF,16V,10%,X7R,A3A"
					( Origin gPackager )
				)
				( attribute "SEC_TYPE" "0402"
					( Origin gFrontEnd )
				)
				( attribute "CDS_SEC" "1"
					( Origin gPackager )
				)
				( attribute "GROUP" "PCIE_RISER"
					( Origin gFrontEnd )
				)
				( objectStatus "C841" )
			)
			( gate "@baseboard_fab2_lib.baseboard_fab2(sch_1):page244_i23"
				( attribute "CDS_LIB" "mstr_discrete"
					( Origin gPackager )
				)
				( attribute "CDS_LOCATION" "C830"
					( Origin gPackager )
				)
				( attribute "LOCATION" "C830"
					( Origin gPackager )
				)
				( attribute "MATERIAL" "X7R"
					( Origin gFrontEnd )
				)
				( attribute "PACK_TYPE" "0402"
					( Origin gFrontEnd )
				)
				( attribute "PART_NUMBER" "A36096-155"
					( Origin gFrontEnd )
				)
				( attribute "PHYS_PAGE" "244"
					( Origin gFrontEnd )
				)
				( attribute "ROOM" "OCP_STEERING"
					( Origin gFrontEnd )
				)
				( attribute "ROT" "2"
					( Origin gFrontEnd )
				)
				( attribute "SEC" "1"
					( Origin gFrontEnd )
				)
				( attribute "TOLERANCE" "10%"
					( Origin gFrontEnd )
				)
				( attribute "VALUE" "0.22UF"
					( Origin gFrontEnd )
				)
				( attribute "VER" "1"
					( Origin gFrontEnd )
				)
				( attribute "VOLTAGE" "16V"
					( Units "uVoltage" "V" 1.000000)
					( Origin gFrontEnd )
				)
				( attribute "XY" "(-6025,3025)"
					( Origin gFrontEnd )
				)
				( attribute "CHIPS_PART_NAME" "CAP"
					( Origin gPackager )
				)
				( attribute "CDS_PART_NAME" "CAP_0402-0.22UF,16V,10%,X7R,A3A"
					( Origin gPackager )
				)
				( attribute "SEC_TYPE" "0402"
					( Origin gFrontEnd )
				)
				( attribute "CDS_SEC" "1"
					( Origin gPackager )
				)
				( attribute "GROUP" "PCIE_RISER"
					( Origin gFrontEnd )
				)
				( objectStatus "C830" )
			)
			( gate "@baseboard_fab2_lib.baseboard_fab2(sch_1):page244_i24"
				( attribute "CDS_LIB" "mstr_discrete"
					( Origin gPackager )
				)
				( attribute "CDS_LOCATION" "C826"
					( Origin gPackager )
				)
				( attribute "LOCATION" "C826"
					( Origin gPackager )
				)
				( attribute "MATERIAL" "X7R"
					( Origin gFrontEnd )
				)
				( attribute "PACK_TYPE" "0402"
					( Origin gFrontEnd )
				)
				( attribute "PART_NUMBER" "A36096-155"
					( Origin gFrontEnd )
				)
				( attribute "PHYS_PAGE" "244"
					( Origin gFrontEnd )
				)
				( attribute "ROOM" "OCP_STEERING"
					( Origin gFrontEnd )
				)
				( attribute "ROT" "2"
					( Origin gFrontEnd )
				)
				( attribute "SEC" "1"
					( Origin gFrontEnd )
				)
				( attribute "TOLERANCE" "10%"
					( Origin gFrontEnd )
				)
				( attribute "VALUE" "0.22UF"
					( Origin gFrontEnd )
				)
				( attribute "VER" "1"
					( Origin gFrontEnd )
				)
				( attribute "VOLTAGE" "16V"
					( Units "uVoltage" "V" 1.000000)
					( Origin gFrontEnd )
				)
				( attribute "XY" "(-5825,3325)"
					( Origin gFrontEnd )
				)
				( attribute "CHIPS_PART_NAME" "CAP"
					( Origin gPackager )
				)
				( attribute "CDS_PART_NAME" "CAP_0402-0.22UF,16V,10%,X7R,A3A"
					( Origin gPackager )
				)
				( attribute "SEC_TYPE" "0402"
					( Origin gFrontEnd )
				)
				( attribute "CDS_SEC" "1"
					( Origin gPackager )
				)
				( attribute "GROUP" "PCIE_RISER"
					( Origin gFrontEnd )
				)
				( objectStatus "C826" )
			)
			( gate "@baseboard_fab2_lib.baseboard_fab2(sch_1):page244_i28"
				( attribute "CDS_LIB" "mstr_discrete"
					( Origin gPackager )
				)
				( attribute "CDS_LOCATION" "C828"
					( Origin gPackager )
				)
				( attribute "LOCATION" "C828"
					( Origin gPackager )
				)
				( attribute "MATERIAL" "X7R"
					( Origin gFrontEnd )
				)
				( attribute "PACK_TYPE" "0402"
					( Origin gFrontEnd )
				)
				( attribute "PART_NUMBER" "A36096-155"
					( Origin gFrontEnd )
				)
				( attribute "PHYS_PAGE" "244"
					( Origin gFrontEnd )
				)
				( attribute "ROOM" "OCP_STEERING"
					( Origin gFrontEnd )
				)
				( attribute "ROT" "2"
					( Origin gFrontEnd )
				)
				( attribute "SEC" "1"
					( Origin gFrontEnd )
				)
				( attribute "TOLERANCE" "10%"
					( Origin gFrontEnd )
				)
				( attribute "VALUE" "0.22UF"
					( Origin gFrontEnd )
				)
				( attribute "VER" "1"
					( Origin gFrontEnd )
				)
				( attribute "VOLTAGE" "16V"
					( Units "uVoltage" "V" 1.000000)
					( Origin gFrontEnd )
				)
				( attribute "XY" "(-5625,3025)"
					( Origin gFrontEnd )
				)
				( attribute "CHIPS_PART_NAME" "CAP"
					( Origin gPackager )
				)
				( attribute "CDS_PART_NAME" "CAP_0402-0.22UF,16V,10%,X7R,A3A"
					( Origin gPackager )
				)
				( attribute "SEC_TYPE" "0402"
					( Origin gFrontEnd )
				)
				( attribute "CDS_SEC" "1"
					( Origin gPackager )
				)
				( attribute "GROUP" "PCIE_RISER"
					( Origin gFrontEnd )
				)
				( objectStatus "C828" )
			)
			( gate "@baseboard_fab2_lib.baseboard_fab2(sch_1):page244_i29"
				( attribute "CDS_LIB" "mstr_discrete"
					( Origin gPackager )
				)
				( attribute "CDS_LOCATION" "C840"
					( Origin gPackager )
				)
				( attribute "LOCATION" "C840"
					( Origin gPackager )
				)
				( attribute "MATERIAL" "X7R"
					( Origin gFrontEnd )
				)
				( attribute "PACK_TYPE" "0402"
					( Origin gFrontEnd )
				)
				( attribute "PART_NUMBER" "A36096-155"
					( Origin gFrontEnd )
				)
				( attribute "PHYS_PAGE" "244"
					( Origin gFrontEnd )
				)
				( attribute "ROOM" "OCP_STEERING"
					( Origin gFrontEnd )
				)
				( attribute "ROT" "2"
					( Origin gFrontEnd )
				)
				( attribute "SEC" "1"
					( Origin gFrontEnd )
				)
				( attribute "TOLERANCE" "10%"
					( Origin gFrontEnd )
				)
				( attribute "VALUE" "0.22UF"
					( Origin gFrontEnd )
				)
				( attribute "VER" "1"
					( Origin gFrontEnd )
				)
				( attribute "VOLTAGE" "16V"
					( Units "uVoltage" "V" 1.000000)
					( Origin gFrontEnd )
				)
				( attribute "XY" "(-5425,3325)"
					( Origin gFrontEnd )
				)
				( attribute "CHIPS_PART_NAME" "CAP"
					( Origin gPackager )
				)
				( attribute "CDS_PART_NAME" "CAP_0402-0.22UF,16V,10%,X7R,A3A"
					( Origin gPackager )
				)
				( attribute "SEC_TYPE" "0402"
					( Origin gFrontEnd )
				)
				( attribute "CDS_SEC" "1"
					( Origin gPackager )
				)
				( attribute "GROUP" "PCIE_RISER"
					( Origin gFrontEnd )
				)
				( objectStatus "C840" )
			)
			( gate "@baseboard_fab2_lib.baseboard_fab2(sch_1):page244_i30"
				( attribute "CDS_LIB" "mstr_discrete"
					( Origin gPackager )
				)
				( attribute "CDS_LOCATION" "C832"
					( Origin gPackager )
				)
				( attribute "LOCATION" "C832"
					( Origin gPackager )
				)
				( attribute "MATERIAL" "X7R"
					( Origin gFrontEnd )
				)
				( attribute "PACK_TYPE" "0402"
					( Origin gFrontEnd )
				)
				( attribute "PART_NUMBER" "A36096-155"
					( Origin gFrontEnd )
				)
				( attribute "PHYS_PAGE" "244"
					( Origin gFrontEnd )
				)
				( attribute "ROOM" "OCP_STEERING"
					( Origin gFrontEnd )
				)
				( attribute "ROT" "2"
					( Origin gFrontEnd )
				)
				( attribute "SEC" "1"
					( Origin gFrontEnd )
				)
				( attribute "TOLERANCE" "10%"
					( Origin gFrontEnd )
				)
				( attribute "VALUE" "0.22UF"
					( Origin gFrontEnd )
				)
				( attribute "VER" "1"
					( Origin gFrontEnd )
				)
				( attribute "VOLTAGE" "16V"
					( Units "uVoltage" "V" 1.000000)
					( Origin gFrontEnd )
				)
				( attribute "XY" "(-5225,3025)"
					( Origin gFrontEnd )
				)
				( attribute "CHIPS_PART_NAME" "CAP"
					( Origin gPackager )
				)
				( attribute "CDS_PART_NAME" "CAP_0402-0.22UF,16V,10%,X7R,A3A"
					( Origin gPackager )
				)
				( attribute "SEC_TYPE" "0402"
					( Origin gFrontEnd )
				)
				( attribute "CDS_SEC" "1"
					( Origin gPackager )
				)
				( attribute "GROUP" "PCIE_RISER"
					( Origin gFrontEnd )
				)
				( objectStatus "C832" )
			)
			( gate "@baseboard_fab2_lib.baseboard_fab2(sch_1):page244_i35"
				( attribute "CDS_LIB" "mstr_discrete"
					( Origin gPackager )
				)
				( attribute "CDS_LOCATION" "C845"
					( Origin gPackager )
				)
				( attribute "LOCATION" "C845"
					( Origin gPackager )
				)
				( attribute "MATERIAL" "X7R"
					( Origin gFrontEnd )
				)
				( attribute "PACK_TYPE" "0402"
					( Origin gFrontEnd )
				)
				( attribute "PART_NUMBER" "A36096-155"
					( Origin gFrontEnd )
				)
				( attribute "PHYS_PAGE" "244"
					( Origin gFrontEnd )
				)
				( attribute "ROOM" "OCP_STEERING"
					( Origin gFrontEnd )
				)
				( attribute "ROT" "2"
					( Origin gFrontEnd )
				)
				( attribute "SEC" "1"
					( Origin gFrontEnd )
				)
				( attribute "TOLERANCE" "10%"
					( Origin gFrontEnd )
				)
				( attribute "VALUE" "0.22UF"
					( Origin gFrontEnd )
				)
				( attribute "VER" "1"
					( Origin gFrontEnd )
				)
				( attribute "VOLTAGE" "16V"
					( Units "uVoltage" "V" 1.000000)
					( Origin gFrontEnd )
				)
				( attribute "XY" "(-4725,1725)"
					( Origin gFrontEnd )
				)
				( attribute "CHIPS_PART_NAME" "CAP"
					( Origin gPackager )
				)
				( attribute "CDS_PART_NAME" "CAP_0402-0.22UF,16V,10%,X7R,A3A"
					( Origin gPackager )
				)
				( attribute "SEC_TYPE" "0402"
					( Origin gFrontEnd )
				)
				( attribute "CDS_SEC" "1"
					( Origin gPackager )
				)
				( attribute "GROUP" "PCIE_RISER"
					( Origin gFrontEnd )
				)
				( objectStatus "C845" )
			)
			( gate "@baseboard_fab2_lib.baseboard_fab2(sch_1):page244_i39"
				( attribute "CDS_LIB" "mstr_discrete"
					( Origin gPackager )
				)
				( attribute "CDS_LOCATION" "R767"
					( Origin gPackager )
				)
				( attribute "LOCATION" "R767"
					( Origin gPackager )
				)
				( attribute "MATERIAL" "CHIP"
					( Origin gFrontEnd )
				)
				( attribute "PACK_TYPE" "0402"
					( Origin gFrontEnd )
				)
				( attribute "PART_NUMBER" "G21497-005"
					( Origin gFrontEnd )
				)
				( attribute "PHYS_PAGE" "244"
					( Origin gFrontEnd )
				)
				( attribute "ROOM" "PCIE_STEERING"
					( Origin gFrontEnd )
				)
				( attribute "ROT" "0"
					( Origin gFrontEnd )
				)
				( attribute "SEC" "1"
					( Origin gFrontEnd )
				)
				( attribute "TOLERANCE" "5%"
					( Origin gFrontEnd )
				)
				( attribute "VALUE" "0.0"
					( Origin gFrontEnd )
				)
				( attribute "VER" "2"
					( Origin gFrontEnd )
				)
				( attribute "WATTAGE" "1/16W"
					( Origin gFrontEnd )
				)
				( attribute "XY" "(-3425,1725)"
					( Origin gFrontEnd )
				)
				( attribute "CHIPS_PART_NAME" "RES"
					( Origin gPackager )
				)
				( attribute "CDS_PART_NAME" "RES_0402-0.0,5%,1/16W,CHIP,G21A"
					( Origin gPackager )
				)
				( attribute "SEC_TYPE" "0402"
					( Origin gFrontEnd )
				)
				( attribute "CDS_SEC" "1"
					( Origin gPackager )
				)
				( attribute "GROUP" "PCIE_RISER"
					( Origin gFrontEnd )
				)
				( objectStatus "R767" )
			)
			( gate "@baseboard_fab2_lib.baseboard_fab2(sch_1):page244_i41"
				( attribute "CDS_LIB" "mstr_discrete"
					( Origin gPackager )
				)
				( attribute "CDS_LOCATION" "C835"
					( Origin gPackager )
				)
				( attribute "LOCATION" "C835"
					( Origin gPackager )
				)
				( attribute "MATERIAL" "X7R"
					( Origin gFrontEnd )
				)
				( attribute "PACK_TYPE" "0402"
					( Origin gFrontEnd )
				)
				( attribute "PART_NUMBER" "A36096-155"
					( Origin gFrontEnd )
				)
				( attribute "PHYS_PAGE" "244"
					( Origin gFrontEnd )
				)
				( attribute "ROOM" "OCP_STEERING"
					( Origin gFrontEnd )
				)
				( attribute "ROT" "2"
					( Origin gFrontEnd )
				)
				( attribute "SEC" "1"
					( Origin gFrontEnd )
				)
				( attribute "TOLERANCE" "10%"
					( Origin gFrontEnd )
				)
				( attribute "VALUE" "0.22UF"
					( Origin gFrontEnd )
				)
				( attribute "VER" "1"
					( Origin gFrontEnd )
				)
				( attribute "VOLTAGE" "16V"
					( Units "uVoltage" "V" 1.000000)
					( Origin gFrontEnd )
				)
				( attribute "XY" "(-4925,2025)"
					( Origin gFrontEnd )
				)
				( attribute "CHIPS_PART_NAME" "CAP"
					( Origin gPackager )
				)
				( attribute "CDS_PART_NAME" "CAP_0402-0.22UF,16V,10%,X7R,A3A"
					( Origin gPackager )
				)
				( attribute "SEC_TYPE" "0402"
					( Origin gFrontEnd )
				)
				( attribute "CDS_SEC" "1"
					( Origin gPackager )
				)
				( attribute "GROUP" "PCIE_RISER"
					( Origin gFrontEnd )
				)
				( objectStatus "C835" )
			)
			( gate "@baseboard_fab2_lib.baseboard_fab2(sch_1):page244_i47"
				( attribute "CDS_LIB" "mstr_discrete"
					( Origin gPackager )
				)
				( attribute "CDS_LOCATION" "C843"
					( Origin gPackager )
				)
				( attribute "LOCATION" "C843"
					( Origin gPackager )
				)
				( attribute "MATERIAL" "X7R"
					( Origin gFrontEnd )
				)
				( attribute "PACK_TYPE" "0402"
					( Origin gFrontEnd )
				)
				( attribute "PART_NUMBER" "A36096-155"
					( Origin gFrontEnd )
				)
				( attribute "PHYS_PAGE" "244"
					( Origin gFrontEnd )
				)
				( attribute "ROOM" "OCP_STEERING"
					( Origin gFrontEnd )
				)
				( attribute "ROT" "2"
					( Origin gFrontEnd )
				)
				( attribute "SEC" "1"
					( Origin gFrontEnd )
				)
				( attribute "TOLERANCE" "10%"
					( Origin gFrontEnd )
				)
				( attribute "VALUE" "0.22UF"
					( Origin gFrontEnd )
				)
				( attribute "VER" "1"
					( Origin gFrontEnd )
				)
				( attribute "VOLTAGE" "16V"
					( Units "uVoltage" "V" 1.000000)
					( Origin gFrontEnd )
				)
				( attribute "XY" "(-4525,2025)"
					( Origin gFrontEnd )
				)
				( attribute "CHIPS_PART_NAME" "CAP"
					( Origin gPackager )
				)
				( attribute "CDS_PART_NAME" "CAP_0402-0.22UF,16V,10%,X7R,A3A"
					( Origin gPackager )
				)
				( attribute "SEC_TYPE" "0402"
					( Origin gFrontEnd )
				)
				( attribute "CDS_SEC" "1"
					( Origin gPackager )
				)
				( attribute "GROUP" "PCIE_RISER"
					( Origin gFrontEnd )
				)
				( objectStatus "C843" )
			)
			( gate "@baseboard_fab2_lib.baseboard_fab2(sch_1):page244_i50"
				( attribute "CDS_LIB" "mstr_discrete"
					( Origin gPackager )
				)
				( attribute "CDS_LOCATION" "C834"
					( Origin gPackager )
				)
				( attribute "LOCATION" "C834"
					( Origin gPackager )
				)
				( attribute "MATERIAL" "X7R"
					( Origin gFrontEnd )
				)
				( attribute "PACK_TYPE" "0402"
					( Origin gFrontEnd )
				)
				( attribute "PART_NUMBER" "A36096-155"
					( Origin gFrontEnd )
				)
				( attribute "PHYS_PAGE" "244"
					( Origin gFrontEnd )
				)
				( attribute "ROOM" "OCP_STEERING"
					( Origin gFrontEnd )
				)
				( attribute "ROT" "2"
					( Origin gFrontEnd )
				)
				( attribute "SEC" "1"
					( Origin gFrontEnd )
				)
				( attribute "TOLERANCE" "10%"
					( Origin gFrontEnd )
				)
				( attribute "VALUE" "0.22UF"
					( Origin gFrontEnd )
				)
				( attribute "VER" "1"
					( Origin gFrontEnd )
				)
				( attribute "VOLTAGE" "16V"
					( Units "uVoltage" "V" 1.000000)
					( Origin gFrontEnd )
				)
				( attribute "XY" "(-5025,3325)"
					( Origin gFrontEnd )
				)
				( attribute "CHIPS_PART_NAME" "CAP"
					( Origin gPackager )
				)
				( attribute "CDS_PART_NAME" "CAP_0402-0.22UF,16V,10%,X7R,A3A"
					( Origin gPackager )
				)
				( attribute "SEC_TYPE" "0402"
					( Origin gFrontEnd )
				)
				( attribute "CDS_SEC" "1"
					( Origin gPackager )
				)
				( attribute "GROUP" "PCIE_RISER"
					( Origin gFrontEnd )
				)
				( objectStatus "C834" )
			)
			( gate "@baseboard_fab2_lib.baseboard_fab2(sch_1):page244_i51"
				( attribute "CDS_LIB" "mstr_discrete"
					( Origin gPackager )
				)
				( attribute "CDS_LOCATION" "C844"
					( Origin gPackager )
				)
				( attribute "LOCATION" "C844"
					( Origin gPackager )
				)
				( attribute "MATERIAL" "X7R"
					( Origin gFrontEnd )
				)
				( attribute "PACK_TYPE" "0402"
					( Origin gFrontEnd )
				)
				( attribute "PART_NUMBER" "A36096-155"
					( Origin gFrontEnd )
				)
				( attribute "PHYS_PAGE" "244"
					( Origin gFrontEnd )
				)
				( attribute "ROOM" "OCP_STEERING"
					( Origin gFrontEnd )
				)
				( attribute "ROT" "2"
					( Origin gFrontEnd )
				)
				( attribute "SEC" "1"
					( Origin gFrontEnd )
				)
				( attribute "TOLERANCE" "10%"
					( Origin gFrontEnd )
				)
				( attribute "VALUE" "0.22UF"
					( Origin gFrontEnd )
				)
				( attribute "VER" "1"
					( Origin gFrontEnd )
				)
				( attribute "VOLTAGE" "16V"
					( Units "uVoltage" "V" 1.000000)
					( Origin gFrontEnd )
				)
				( attribute "XY" "(-4825,3025)"
					( Origin gFrontEnd )
				)
				( attribute "CHIPS_PART_NAME" "CAP"
					( Origin gPackager )
				)
				( attribute "CDS_PART_NAME" "CAP_0402-0.22UF,16V,10%,X7R,A3A"
					( Origin gPackager )
				)
				( attribute "SEC_TYPE" "0402"
					( Origin gFrontEnd )
				)
				( attribute "CDS_SEC" "1"
					( Origin gPackager )
				)
				( attribute "GROUP" "PCIE_RISER"
					( Origin gFrontEnd )
				)
				( objectStatus "C844" )
			)
			( gate "@baseboard_fab2_lib.baseboard_fab2(sch_1):page244_i52"
				( attribute "CDS_LIB" "mstr_discrete"
					( Origin gPackager )
				)
				( attribute "CDS_LOCATION" "C842"
					( Origin gPackager )
				)
				( attribute "LOCATION" "C842"
					( Origin gPackager )
				)
				( attribute "MATERIAL" "X7R"
					( Origin gFrontEnd )
				)
				( attribute "PACK_TYPE" "0402"
					( Origin gFrontEnd )
				)
				( attribute "PART_NUMBER" "A36096-155"
					( Origin gFrontEnd )
				)
				( attribute "PHYS_PAGE" "244"
					( Origin gFrontEnd )
				)
				( attribute "ROOM" "OCP_STEERING"
					( Origin gFrontEnd )
				)
				( attribute "ROT" "2"
					( Origin gFrontEnd )
				)
				( attribute "SEC" "1"
					( Origin gFrontEnd )
				)
				( attribute "TOLERANCE" "10%"
					( Origin gFrontEnd )
				)
				( attribute "VALUE" "0.22UF"
					( Origin gFrontEnd )
				)
				( attribute "VER" "1"
					( Origin gFrontEnd )
				)
				( attribute "VOLTAGE" "16V"
					( Units "uVoltage" "V" 1.000000)
					( Origin gFrontEnd )
				)
				( attribute "XY" "(-4625,3300)"
					( Origin gFrontEnd )
				)
				( attribute "CHIPS_PART_NAME" "CAP"
					( Origin gPackager )
				)
				( attribute "CDS_PART_NAME" "CAP_0402-0.22UF,16V,10%,X7R,A3A"
					( Origin gPackager )
				)
				( attribute "SEC_TYPE" "0402"
					( Origin gFrontEnd )
				)
				( attribute "CDS_SEC" "1"
					( Origin gPackager )
				)
				( attribute "GROUP" "PCIE_RISER"
					( Origin gFrontEnd )
				)
				( objectStatus "C842" )
			)
			( gate "@baseboard_fab2_lib.baseboard_fab2(sch_1):page244_i58"
				( attribute "CDS_LIB" "mstr_discrete"
					( Origin gPackager )
				)
				( attribute "CDS_LOCATION" "R769"
					( Origin gPackager )
				)
				( attribute "LOCATION" "R769"
					( Origin gPackager )
				)
				( attribute "MATERIAL" "CHIP"
					( Origin gFrontEnd )
				)
				( attribute "PACK_TYPE" "0402"
					( Origin gFrontEnd )
				)
				( attribute "PART_NUMBER" "G21497-005"
					( Origin gFrontEnd )
				)
				( attribute "PHYS_PAGE" "244"
					( Origin gFrontEnd )
				)
				( attribute "ROOM" "PCIE_STEERING"
					( Origin gFrontEnd )
				)
				( attribute "ROT" "0"
					( Origin gFrontEnd )
				)
				( attribute "SEC" "1"
					( Origin gFrontEnd )
				)
				( attribute "TOLERANCE" "5%"
					( Origin gFrontEnd )
				)
				( attribute "VALUE" "0.0"
					( Origin gFrontEnd )
				)
				( attribute "VER" "2"
					( Origin gFrontEnd )
				)
				( attribute "WATTAGE" "1/16W"
					( Origin gFrontEnd )
				)
				( attribute "XY" "(-3225,2075)"
					( Origin gFrontEnd )
				)
				( attribute "CHIPS_PART_NAME" "RES"
					( Origin gPackager )
				)
				( attribute "CDS_PART_NAME" "RES_0402-0.0,5%,1/16W,CHIP,G21A"
					( Origin gPackager )
				)
				( attribute "SEC_TYPE" "0402"
					( Origin gFrontEnd )
				)
				( attribute "CDS_SEC" "1"
					( Origin gPackager )
				)
				( attribute "GROUP" "PCIE_RISER"
					( Origin gFrontEnd )
				)
				( objectStatus "R769" )
			)
			( gate "@baseboard_fab2_lib.baseboard_fab2(sch_1):page244_i64"
				( attribute "CDS_LIB" "mstr_discrete"
					( Origin gPackager )
				)
				( attribute "CDS_LOCATION" "R760"
					( Origin gPackager )
				)
				( attribute "LOCATION" "R760"
					( Origin gPackager )
				)
				( attribute "MATERIAL" "CHIP"
					( Origin gFrontEnd )
				)
				( attribute "PACK_TYPE" "0402"
					( Origin gFrontEnd )
				)
				( attribute "PART_NUMBER" "G21497-005"
					( Origin gFrontEnd )
				)
				( attribute "PHYS_PAGE" "244"
					( Origin gFrontEnd )
				)
				( attribute "ROOM" "PCIE_STEERING"
					( Origin gFrontEnd )
				)
				( attribute "ROT" "0"
					( Origin gFrontEnd )
				)
				( attribute "SEC" "1"
					( Origin gFrontEnd )
				)
				( attribute "TOLERANCE" "5%"
					( Origin gFrontEnd )
				)
				( attribute "VALUE" "0.0"
					( Origin gFrontEnd )
				)
				( attribute "VER" "2"
					( Origin gFrontEnd )
				)
				( attribute "WATTAGE" "1/16W"
					( Origin gFrontEnd )
				)
				( attribute "XY" "(-3500,3025)"
					( Origin gFrontEnd )
				)
				( attribute "CHIPS_PART_NAME" "RES"
					( Origin gPackager )
				)
				( attribute "CDS_PART_NAME" "RES_0402-0.0,5%,1/16W,CHIP,G21A"
					( Origin gPackager )
				)
				( attribute "SEC_TYPE" "0402"
					( Origin gFrontEnd )
				)
				( attribute "CDS_SEC" "1"
					( Origin gPackager )
				)
				( attribute "GROUP" "PCIE_RISER"
					( Origin gFrontEnd )
				)
				( objectStatus "R760" )
			)
			( gate "@baseboard_fab2_lib.baseboard_fab2(sch_1):page244_i65"
				( attribute "CDS_LIB" "mstr_discrete"
					( Origin gPackager )
				)
				( attribute "CDS_LOCATION" "R771"
					( Origin gPackager )
				)
				( attribute "LOCATION" "R771"
					( Origin gPackager )
				)
				( attribute "MATERIAL" "CHIP"
					( Origin gFrontEnd )
				)
				( attribute "PACK_TYPE" "0402"
					( Origin gFrontEnd )
				)
				( attribute "PART_NUMBER" "G21497-005"
					( Origin gFrontEnd )
				)
				( attribute "PHYS_PAGE" "244"
					( Origin gFrontEnd )
				)
				( attribute "ROOM" "PCIE_STEERING"
					( Origin gFrontEnd )
				)
				( attribute "ROT" "0"
					( Origin gFrontEnd )
				)
				( attribute "SEC" "1"
					( Origin gFrontEnd )
				)
				( attribute "TOLERANCE" "5%"
					( Origin gFrontEnd )
				)
				( attribute "VALUE" "0.0"
					( Origin gFrontEnd )
				)
				( attribute "VER" "2"
					( Origin gFrontEnd )
				)
				( attribute "WATTAGE" "1/16W"
					( Origin gFrontEnd )
				)
				( attribute "XY" "(-3100,3025)"
					( Origin gFrontEnd )
				)
				( attribute "CHIPS_PART_NAME" "RES"
					( Origin gPackager )
				)
				( attribute "CDS_PART_NAME" "RES_0402-0.0,5%,1/16W,CHIP,G21A"
					( Origin gPackager )
				)
				( attribute "SEC_TYPE" "0402"
					( Origin gFrontEnd )
				)
				( attribute "CDS_SEC" "1"
					( Origin gPackager )
				)
				( attribute "GROUP" "PCIE_RISER"
					( Origin gFrontEnd )
				)
				( objectStatus "R771" )
			)
			( gate "@baseboard_fab2_lib.baseboard_fab2(sch_1):page244_i66"
				( attribute "CDS_LIB" "mstr_discrete"
					( Origin gPackager )
				)
				( attribute "CDS_LOCATION" "R768"
					( Origin gPackager )
				)
				( attribute "LOCATION" "R768"
					( Origin gPackager )
				)
				( attribute "MATERIAL" "CHIP"
					( Origin gFrontEnd )
				)
				( attribute "PACK_TYPE" "0402"
					( Origin gFrontEnd )
				)
				( attribute "PART_NUMBER" "G21497-005"
					( Origin gFrontEnd )
				)
				( attribute "PHYS_PAGE" "244"
					( Origin gFrontEnd )
				)
				( attribute "ROOM" "PCIE_STEERING"
					( Origin gFrontEnd )
				)
				( attribute "ROT" "0"
					( Origin gFrontEnd )
				)
				( attribute "SEC" "1"
					( Origin gFrontEnd )
				)
				( attribute "TOLERANCE" "5%"
					( Origin gFrontEnd )
				)
				( attribute "VALUE" "0.0"
					( Origin gFrontEnd )
				)
				( attribute "VER" "2"
					( Origin gFrontEnd )
				)
				( attribute "WATTAGE" "1/16W"
					( Origin gFrontEnd )
				)
				( attribute "XY" "(-3300,3375)"
					( Origin gFrontEnd )
				)
				( attribute "CHIPS_PART_NAME" "RES"
					( Origin gPackager )
				)
				( attribute "CDS_PART_NAME" "RES_0402-0.0,5%,1/16W,CHIP,G21A"
					( Origin gPackager )
				)
				( attribute "SEC_TYPE" "0402"
					( Origin gFrontEnd )
				)
				( attribute "CDS_SEC" "1"
					( Origin gPackager )
				)
				( attribute "GROUP" "PCIE_RISER"
					( Origin gFrontEnd )
				)
				( objectStatus "R768" )
			)
			( gate "@baseboard_fab2_lib.baseboard_fab2(sch_1):page244_i72"
				( attribute "CDS_LIB" "mstr_discrete"
					( Origin gPackager )
				)
				( attribute "CDS_LOCATION" "R774"
					( Origin gPackager )
				)
				( attribute "LOCATION" "R774"
					( Origin gPackager )
				)
				( attribute "MATERIAL" "CHIP"
					( Origin gFrontEnd )
				)
				( attribute "PACK_TYPE" "0402"
					( Origin gFrontEnd )
				)
				( attribute "PART_NUMBER" "G21497-005"
					( Origin gFrontEnd )
				)
				( attribute "PHYS_PAGE" "244"
					( Origin gFrontEnd )
				)
				( attribute "ROOM" "PCIE_STEERING"
					( Origin gFrontEnd )
				)
				( attribute "ROT" "0"
					( Origin gFrontEnd )
				)
				( attribute "SEC" "1"
					( Origin gFrontEnd )
				)
				( attribute "TOLERANCE" "5%"
					( Origin gFrontEnd )
				)
				( attribute "VALUE" "0.0"
					( Origin gFrontEnd )
				)
				( attribute "VER" "2"
					( Origin gFrontEnd )
				)
				( attribute "WATTAGE" "1/16W"
					( Origin gFrontEnd )
				)
				( attribute "XY" "(-3025,1725)"
					( Origin gFrontEnd )
				)
				( attribute "CHIPS_PART_NAME" "RES"
					( Origin gPackager )
				)
				( attribute "CDS_PART_NAME" "RES_0402-0.0,5%,1/16W,CHIP,G21A"
					( Origin gPackager )
				)
				( attribute "SEC_TYPE" "0402"
					( Origin gFrontEnd )
				)
				( attribute "CDS_SEC" "1"
					( Origin gPackager )
				)
				( attribute "GROUP" "PCIE_RISER"
					( Origin gFrontEnd )
				)
				( objectStatus "R774" )
			)
			( gate "@baseboard_fab2_lib.baseboard_fab2(sch_1):page244_i74"
				( attribute "CDS_LIB" "mstr_discrete"
					( Origin gPackager )
				)
				( attribute "CDS_LOCATION" "R779"
					( Origin gPackager )
				)
				( attribute "LOCATION" "R779"
					( Origin gPackager )
				)
				( attribute "MATERIAL" "CHIP"
					( Origin gFrontEnd )
				)
				( attribute "PACK_TYPE" "0402"
					( Origin gFrontEnd )
				)
				( attribute "PART_NUMBER" "G21497-005"
					( Origin gFrontEnd )
				)
				( attribute "PHYS_PAGE" "244"
					( Origin gFrontEnd )
				)
				( attribute "ROOM" "PCIE_STEERING"
					( Origin gFrontEnd )
				)
				( attribute "ROT" "0"
					( Origin gFrontEnd )
				)
				( attribute "SEC" "1"
					( Origin gFrontEnd )
				)
				( attribute "TOLERANCE" "5%"
					( Origin gFrontEnd )
				)
				( attribute "VALUE" "0.0"
					( Origin gFrontEnd )
				)
				( attribute "VER" "2"
					( Origin gFrontEnd )
				)
				( attribute "WATTAGE" "1/16W"
					( Origin gFrontEnd )
				)
				( attribute "XY" "(-2625,1725)"
					( Origin gFrontEnd )
				)
				( attribute "CHIPS_PART_NAME" "RES"
					( Origin gPackager )
				)
				( attribute "CDS_PART_NAME" "RES_0402-0.0,5%,1/16W,CHIP,G21A"
					( Origin gPackager )
				)
				( attribute "SEC_TYPE" "0402"
					( Origin gFrontEnd )
				)
				( attribute "CDS_SEC" "1"
					( Origin gPackager )
				)
				( attribute "GROUP" "PCIE_RISER"
					( Origin gFrontEnd )
				)
				( objectStatus "R779" )
			)
			( gate "@baseboard_fab2_lib.baseboard_fab2(sch_1):page244_i77"
				( attribute "CDS_LIB" "mstr_discrete"
					( Origin gPackager )
				)
				( attribute "CDS_LOCATION" "R783"
					( Origin gPackager )
				)
				( attribute "LOCATION" "R783"
					( Origin gPackager )
				)
				( attribute "MATERIAL" "CHIP"
					( Origin gFrontEnd )
				)
				( attribute "PACK_TYPE" "0402"
					( Origin gFrontEnd )
				)
				( attribute "PART_NUMBER" "G21497-005"
					( Origin gFrontEnd )
				)
				( attribute "PHYS_PAGE" "244"
					( Origin gFrontEnd )
				)
				( attribute "ROOM" "PCIE_STEERING"
					( Origin gFrontEnd )
				)
				( attribute "ROT" "0"
					( Origin gFrontEnd )
				)
				( attribute "SEC" "1"
					( Origin gFrontEnd )
				)
				( attribute "TOLERANCE" "5%"
					( Origin gFrontEnd )
				)
				( attribute "VALUE" "0.0"
					( Origin gFrontEnd )
				)
				( attribute "VER" "2"
					( Origin gFrontEnd )
				)
				( attribute "WATTAGE" "1/16W"
					( Origin gFrontEnd )
				)
				( attribute "XY" "(-2225,1725)"
					( Origin gFrontEnd )
				)
				( attribute "CHIPS_PART_NAME" "RES"
					( Origin gPackager )
				)
				( attribute "CDS_PART_NAME" "RES_0402-0.0,5%,1/16W,CHIP,G21A"
					( Origin gPackager )
				)
				( attribute "SEC_TYPE" "0402"
					( Origin gFrontEnd )
				)
				( attribute "CDS_SEC" "1"
					( Origin gPackager )
				)
				( attribute "GROUP" "PCIE_RISER"
					( Origin gFrontEnd )
				)
				( objectStatus "R783" )
			)
			( gate "@baseboard_fab2_lib.baseboard_fab2(sch_1):page244_i80"
				( attribute "CDS_LIB" "mstr_discrete"
					( Origin gPackager )
				)
				( attribute "CDS_LOCATION" "R777"
					( Origin gPackager )
				)
				( attribute "LOCATION" "R777"
					( Origin gPackager )
				)
				( attribute "MATERIAL" "CHIP"
					( Origin gFrontEnd )
				)
				( attribute "PACK_TYPE" "0402"
					( Origin gFrontEnd )
				)
				( attribute "PART_NUMBER" "G21497-005"
					( Origin gFrontEnd )
				)
				( attribute "PHYS_PAGE" "244"
					( Origin gFrontEnd )
				)
				( attribute "ROOM" "PCIE_STEERING"
					( Origin gFrontEnd )
				)
				( attribute "ROT" "0"
					( Origin gFrontEnd )
				)
				( attribute "SEC" "1"
					( Origin gFrontEnd )
				)
				( attribute "TOLERANCE" "5%"
					( Origin gFrontEnd )
				)
				( attribute "VALUE" "0.0"
					( Origin gFrontEnd )
				)
				( attribute "VER" "2"
					( Origin gFrontEnd )
				)
				( attribute "WATTAGE" "1/16W"
					( Origin gFrontEnd )
				)
				( attribute "XY" "(-2825,2075)"
					( Origin gFrontEnd )
				)
				( attribute "CHIPS_PART_NAME" "RES"
					( Origin gPackager )
				)
				( attribute "CDS_PART_NAME" "RES_0402-0.0,5%,1/16W,CHIP,G21A"
					( Origin gPackager )
				)
				( attribute "SEC_TYPE" "0402"
					( Origin gFrontEnd )
				)
				( attribute "CDS_SEC" "1"
					( Origin gPackager )
				)
				( attribute "GROUP" "PCIE_RISER"
					( Origin gFrontEnd )
				)
				( objectStatus "R777" )
			)
			( gate "@baseboard_fab2_lib.baseboard_fab2(sch_1):page244_i86"
				( attribute "CDS_LIB" "mstr_discrete"
					( Origin gPackager )
				)
				( attribute "CDS_LOCATION" "R781"
					( Origin gPackager )
				)
				( attribute "LOCATION" "R781"
					( Origin gPackager )
				)
				( attribute "MATERIAL" "CHIP"
					( Origin gFrontEnd )
				)
				( attribute "PACK_TYPE" "0402"
					( Origin gFrontEnd )
				)
				( attribute "PART_NUMBER" "G21497-005"
					( Origin gFrontEnd )
				)
				( attribute "PHYS_PAGE" "244"
					( Origin gFrontEnd )
				)
				( attribute "ROOM" "PCIE_STEERING"
					( Origin gFrontEnd )
				)
				( attribute "ROT" "0"
					( Origin gFrontEnd )
				)
				( attribute "SEC" "1"
					( Origin gFrontEnd )
				)
				( attribute "TOLERANCE" "5%"
					( Origin gFrontEnd )
				)
				( attribute "VALUE" "0.0"
					( Origin gFrontEnd )
				)
				( attribute "VER" "2"
					( Origin gFrontEnd )
				)
				( attribute "WATTAGE" "1/16W"
					( Origin gFrontEnd )
				)
				( attribute "XY" "(-2425,2075)"
					( Origin gFrontEnd )
				)
				( attribute "CHIPS_PART_NAME" "RES"
					( Origin gPackager )
				)
				( attribute "CDS_PART_NAME" "RES_0402-0.0,5%,1/16W,CHIP,G21A"
					( Origin gPackager )
				)
				( attribute "SEC_TYPE" "0402"
					( Origin gFrontEnd )
				)
				( attribute "CDS_SEC" "1"
					( Origin gPackager )
				)
				( attribute "GROUP" "PCIE_RISER"
					( Origin gFrontEnd )
				)
				( objectStatus "R781" )
			)
			( gate "@baseboard_fab2_lib.baseboard_fab2(sch_1):page244_i93"
				( attribute "CDS_LIB" "mstr_discrete"
					( Origin gPackager )
				)
				( attribute "CDS_LOCATION" "R775"
					( Origin gPackager )
				)
				( attribute "LOCATION" "R775"
					( Origin gPackager )
				)
				( attribute "MATERIAL" "CHIP"
					( Origin gFrontEnd )
				)
				( attribute "PACK_TYPE" "0402"
					( Origin gFrontEnd )
				)
				( attribute "PART_NUMBER" "G21497-005"
					( Origin gFrontEnd )
				)
				( attribute "PHYS_PAGE" "244"
					( Origin gFrontEnd )
				)
				( attribute "ROOM" "PCIE_STEERING"
					( Origin gFrontEnd )
				)
				( attribute "ROT" "0"
					( Origin gFrontEnd )
				)
				( attribute "SEC" "1"
					( Origin gFrontEnd )
				)
				( attribute "TOLERANCE" "5%"
					( Origin gFrontEnd )
				)
				( attribute "VALUE" "0.0"
					( Origin gFrontEnd )
				)
				( attribute "VER" "2"
					( Origin gFrontEnd )
				)
				( attribute "WATTAGE" "1/16W"
					( Origin gFrontEnd )
				)
				( attribute "XY" "(-2900,3375)"
					( Origin gFrontEnd )
				)
				( attribute "CHIPS_PART_NAME" "RES"
					( Origin gPackager )
				)
				( attribute "CDS_PART_NAME" "RES_0402-0.0,5%,1/16W,CHIP,G21A"
					( Origin gPackager )
				)
				( attribute "SEC_TYPE" "0402"
					( Origin gFrontEnd )
				)
				( attribute "CDS_SEC" "1"
					( Origin gPackager )
				)
				( attribute "GROUP" "PCIE_RISER"
					( Origin gFrontEnd )
				)
				( objectStatus "R775" )
			)
			( gate "@baseboard_fab2_lib.baseboard_fab2(sch_1):page244_i94"
				( attribute "CDS_LIB" "mstr_discrete"
					( Origin gPackager )
				)
				( attribute "CDS_LOCATION" "R778"
					( Origin gPackager )
				)
				( attribute "LOCATION" "R778"
					( Origin gPackager )
				)
				( attribute "MATERIAL" "CHIP"
					( Origin gFrontEnd )
				)
				( attribute "PACK_TYPE" "0402"
					( Origin gFrontEnd )
				)
				( attribute "PART_NUMBER" "G21497-005"
					( Origin gFrontEnd )
				)
				( attribute "PHYS_PAGE" "244"
					( Origin gFrontEnd )
				)
				( attribute "ROOM" "PCIE_STEERING"
					( Origin gFrontEnd )
				)
				( attribute "ROT" "0"
					( Origin gFrontEnd )
				)
				( attribute "SEC" "1"
					( Origin gFrontEnd )
				)
				( attribute "TOLERANCE" "5%"
					( Origin gFrontEnd )
				)
				( attribute "VALUE" "0.0"
					( Origin gFrontEnd )
				)
				( attribute "VER" "2"
					( Origin gFrontEnd )
				)
				( attribute "WATTAGE" "1/16W"
					( Origin gFrontEnd )
				)
				( attribute "XY" "(-2700,3025)"
					( Origin gFrontEnd )
				)
				( attribute "CHIPS_PART_NAME" "RES"
					( Origin gPackager )
				)
				( attribute "CDS_PART_NAME" "RES_0402-0.0,5%,1/16W,CHIP,G21A"
					( Origin gPackager )
				)
				( attribute "SEC_TYPE" "0402"
					( Origin gFrontEnd )
				)
				( attribute "CDS_SEC" "1"
					( Origin gPackager )
				)
				( attribute "GROUP" "PCIE_RISER"
					( Origin gFrontEnd )
				)
				( objectStatus "R778" )
			)
			( gate "@baseboard_fab2_lib.baseboard_fab2(sch_1):page244_i97"
				( attribute "CDS_LIB" "mstr_discrete"
					( Origin gPackager )
				)
				( attribute "CDS_LOCATION" "R780"
					( Origin gPackager )
				)
				( attribute "LOCATION" "R780"
					( Origin gPackager )
				)
				( attribute "MATERIAL" "CHIP"
					( Origin gFrontEnd )
				)
				( attribute "PACK_TYPE" "0402"
					( Origin gFrontEnd )
				)
				( attribute "PART_NUMBER" "G21497-005"
					( Origin gFrontEnd )
				)
				( attribute "PHYS_PAGE" "244"
					( Origin gFrontEnd )
				)
				( attribute "ROOM" "PCIE_STEERING"
					( Origin gFrontEnd )
				)
				( attribute "ROT" "0"
					( Origin gFrontEnd )
				)
				( attribute "SEC" "1"
					( Origin gFrontEnd )
				)
				( attribute "TOLERANCE" "5%"
					( Origin gFrontEnd )
				)
				( attribute "VALUE" "0.0"
					( Origin gFrontEnd )
				)
				( attribute "VER" "2"
					( Origin gFrontEnd )
				)
				( attribute "WATTAGE" "1/16W"
					( Origin gFrontEnd )
				)
				( attribute "XY" "(-2500,3375)"
					( Origin gFrontEnd )
				)
				( attribute "CHIPS_PART_NAME" "RES"
					( Origin gPackager )
				)
				( attribute "CDS_PART_NAME" "RES_0402-0.0,5%,1/16W,CHIP,G21A"
					( Origin gPackager )
				)
				( attribute "SEC_TYPE" "0402"
					( Origin gFrontEnd )
				)
				( attribute "CDS_SEC" "1"
					( Origin gPackager )
				)
				( attribute "GROUP" "PCIE_RISER"
					( Origin gFrontEnd )
				)
				( objectStatus "R780" )
			)
			( gate "@baseboard_fab2_lib.baseboard_fab2(sch_1):page244_i98"
				( attribute "CDS_LIB" "mstr_discrete"
					( Origin gPackager )
				)
				( attribute "CDS_LOCATION" "R782"
					( Origin gPackager )
				)
				( attribute "LOCATION" "R782"
					( Origin gPackager )
				)
				( attribute "MATERIAL" "CHIP"
					( Origin gFrontEnd )
				)
				( attribute "PACK_TYPE" "0402"
					( Origin gFrontEnd )
				)
				( attribute "PART_NUMBER" "G21497-005"
					( Origin gFrontEnd )
				)
				( attribute "PHYS_PAGE" "244"
					( Origin gFrontEnd )
				)
				( attribute "ROOM" "PCIE_STEERING"
					( Origin gFrontEnd )
				)
				( attribute "ROT" "0"
					( Origin gFrontEnd )
				)
				( attribute "SEC" "1"
					( Origin gFrontEnd )
				)
				( attribute "TOLERANCE" "5%"
					( Origin gFrontEnd )
				)
				( attribute "VALUE" "0.0"
					( Origin gFrontEnd )
				)
				( attribute "VER" "2"
					( Origin gFrontEnd )
				)
				( attribute "WATTAGE" "1/16W"
					( Origin gFrontEnd )
				)
				( attribute "XY" "(-2300,3025)"
					( Origin gFrontEnd )
				)
				( attribute "CHIPS_PART_NAME" "RES"
					( Origin gPackager )
				)
				( attribute "CDS_PART_NAME" "RES_0402-0.0,5%,1/16W,CHIP,G21A"
					( Origin gPackager )
				)
				( attribute "SEC_TYPE" "0402"
					( Origin gFrontEnd )
				)
				( attribute "CDS_SEC" "1"
					( Origin gPackager )
				)
				( attribute "GROUP" "PCIE_RISER"
					( Origin gFrontEnd )
				)
				( objectStatus "R782" )
			)
			( gate "@baseboard_fab2_lib.baseboard_fab2(sch_1):page244_i99"
				( attribute "CDS_LIB" "mstr_discrete"
					( Origin gPackager )
				)
				( attribute "CDS_LOCATION" "R784"
					( Origin gPackager )
				)
				( attribute "LOCATION" "R784"
					( Origin gPackager )
				)
				( attribute "MATERIAL" "CHIP"
					( Origin gFrontEnd )
				)
				( attribute "PACK_TYPE" "0402"
					( Origin gFrontEnd )
				)
				( attribute "PART_NUMBER" "G21497-005"
					( Origin gFrontEnd )
				)
				( attribute "PHYS_PAGE" "244"
					( Origin gFrontEnd )
				)
				( attribute "ROOM" "PCIE_STEERING"
					( Origin gFrontEnd )
				)
				( attribute "ROT" "0"
					( Origin gFrontEnd )
				)
				( attribute "SEC" "1"
					( Origin gFrontEnd )
				)
				( attribute "TOLERANCE" "5%"
					( Origin gFrontEnd )
				)
				( attribute "VALUE" "0.0"
					( Origin gFrontEnd )
				)
				( attribute "VER" "2"
					( Origin gFrontEnd )
				)
				( attribute "WATTAGE" "1/16W"
					( Origin gFrontEnd )
				)
				( attribute "XY" "(-2100,3375)"
					( Origin gFrontEnd )
				)
				( attribute "CHIPS_PART_NAME" "RES"
					( Origin gPackager )
				)
				( attribute "CDS_PART_NAME" "RES_0402-0.0,5%,1/16W,CHIP,G21A"
					( Origin gPackager )
				)
				( attribute "SEC_TYPE" "0402"
					( Origin gFrontEnd )
				)
				( attribute "CDS_SEC" "1"
					( Origin gPackager )
				)
				( attribute "GROUP" "PCIE_RISER"
					( Origin gFrontEnd )
				)
				( objectStatus "R784" )
			)
			( gate "@baseboard_fab2_lib.baseboard_fab2(sch_1):page244_i103"
				( attribute "CDS_LIB" "mstr_discrete"
					( Origin gPackager )
				)
				( attribute "CDS_LOCATION" "R785"
					( Origin gPackager )
				)
				( attribute "LOCATION" "R785"
					( Origin gPackager )
				)
				( attribute "MATERIAL" "CHIP"
					( Origin gFrontEnd )
				)
				( attribute "PACK_TYPE" "0402"
					( Origin gFrontEnd )
				)
				( attribute "PART_NUMBER" "G21497-005"
					( Origin gFrontEnd )
				)
				( attribute "PHYS_PAGE" "244"
					( Origin gFrontEnd )
				)
				( attribute "ROOM" "PCIE_STEERING"
					( Origin gFrontEnd )
				)
				( attribute "ROT" "0"
					( Origin gFrontEnd )
				)
				( attribute "SEC" "1"
					( Origin gFrontEnd )
				)
				( attribute "TOLERANCE" "5%"
					( Origin gFrontEnd )
				)
				( attribute "VALUE" "0.0"
					( Origin gFrontEnd )
				)
				( attribute "VER" "2"
					( Origin gFrontEnd )
				)
				( attribute "WATTAGE" "1/16W"
					( Origin gFrontEnd )
				)
				( attribute "XY" "(-2025,2075)"
					( Origin gFrontEnd )
				)
				( attribute "CHIPS_PART_NAME" "RES"
					( Origin gPackager )
				)
				( attribute "CDS_PART_NAME" "RES_0402-0.0,5%,1/16W,CHIP,G21A"
					( Origin gPackager )
				)
				( attribute "SEC_TYPE" "0402"
					( Origin gFrontEnd )
				)
				( attribute "CDS_SEC" "1"
					( Origin gPackager )
				)
				( attribute "GROUP" "PCIE_RISER"
					( Origin gFrontEnd )
				)
				( objectStatus "R785" )
			)
			( gate "@baseboard_fab2_lib.baseboard_fab2(sch_1):page245_i48"
				( attribute "CDS_LIB" "w_hdl"
					( Origin gPackager )
				)
				( attribute "CDS_LMAN_SYM_OUTLINE" "-100,900,100,-900"
					( Origin gPackager )
				)
				( attribute "CDS_LOCATION" "CONX8"
					( Origin gPackager )
				)
				( attribute "CDS_SEC" "1"
					( Origin gPackager )
				)
				( attribute "LOCATION" "CONX8"
					( Origin gFrontEnd )
				)
				( attribute "PACK_TYPE" "CONN-G7"
					( Origin gFrontEnd )
				)
				( attribute "PART_NUMBER" "020.C0082.0060"
					( Origin gFrontEnd )
				)
				( attribute "PHYS_PAGE" "245"
					( Origin gFrontEnd )
				)
				( attribute "ROT" "0"
					( Origin gFrontEnd )
				)
				( attribute "SEC" "1"
					( Origin gPackager )
				)
				( attribute "VALUE" "SMC-CONN60A-22-GP"
					( Origin gFrontEnd )
				)
				( attribute "VER" "1"
					( Origin gFrontEnd )
				)
				( attribute "XY" "(-4000,3775)"
					( Origin gFrontEnd )
				)
				( attribute "CHIPS_PART_NAME" "SMC-CONN60A-22-GP"
					( Origin gPackager )
				)
				( attribute "CDS_PART_NAME" "SMC-CONN60A-22-GP_CONN-G7-SMC-A"
					( Origin gPackager )
				)
				( objectStatus "CONX8" )
			)
			( gate "@baseboard_fab2_lib.baseboard_fab2(sch_1):page109_i78"
				( attribute "CDS_LIB" "mstr_sconn"
					( Origin gPackager )
				)
				( attribute "CDS_LMAN_SYM_OUTLINE" "-300,1350,300,-1350"
					( Origin gPackager )
				)
				( attribute "LOCATION" "J8G1"
					( Origin gFrontEnd )
				)
				( attribute "MATERIAL" "CONN"
					( Origin gFrontEnd )
				)
				( attribute "PACK_TYPE" "SM"
					( Origin gFrontEnd )
				)
				( attribute "PART_NUMBER" "H68296-001"
					( Origin gFrontEnd )
				)
				( attribute "PHYS_PAGE" "109"
					( Origin gFrontEnd )
				)
				( attribute "ROOM" "IO_SLOT"
					( Origin gFrontEnd )
				)
				( attribute "ROT" "0"
					( Origin gFrontEnd )
				)
				( attribute "SEC" "2"
					( Origin gFrontEnd )
				)
				( attribute "SEC_TYPE" "SM"
					( Origin gFrontEnd )
				)
				( attribute "VER" "2"
					( Origin gFrontEnd )
				)
				( attribute "XY" "(-1000,3200)"
					( Origin gFrontEnd )
				)
				( attribute "CHIPS_PART_NAME" "SCONN200_H68296001"
					( Origin gPackager )
				)
				( attribute "CDS_PART_NAME" "SCONN200_H68296001_SM-CONN,H68A"
					( Origin gPackager )
				)
				( attribute "CDS_LOCATION" "J8G1"
					( Origin gPackager )
				)
				( attribute "CDS_SEC" "2"
					( Origin gPackager )
				)
				( objectStatus "J8G1" )
			)
			( gate "@baseboard_fab2_lib.baseboard_fab2(sch_1):page246_i9"
				( attribute "BOM_COST" "SM_MEM"
					( Origin gFrontEnd )
				)
				( attribute "CDS_LIB" "mstr_discrete"
					( Origin gPackager )
				)
				( attribute "CDS_LOCATION" "RN8F5"
					( Origin gPackager )
				)
				( attribute "CDS_SEC" "1"
					( Origin gPackager )
				)
				( attribute "LOCATION" "RN8F5"
					( Origin gFrontEnd )
				)
				( attribute "MATERIAL" "CHIP"
					( Origin gFrontEnd )
				)
				( attribute "PACK_TYPE" "0402"
					( Origin gFrontEnd )
				)
				( attribute "PART_NUMBER" "G21796-074"
					( Origin gFrontEnd )
				)
				( attribute "PHYS_PAGE" "246"
					( Origin gFrontEnd )
				)
				( attribute "ROOM" "BMC_BOOT_SPI"
					( Origin gFrontEnd )
				)
				( attribute "ROT" "0"
					( Origin gFrontEnd )
				)
				( attribute "SEC" "1"
					( Origin gFrontEnd )
				)
				( attribute "SEC_TYPE" "0402"
					( Origin gFrontEnd )
				)
				( attribute "TOLERANCE" "1%"
					( Origin gFrontEnd )
				)
				( attribute "VALUE" "33.2"
					( Origin gFrontEnd )
				)
				( attribute "VER" "1"
					( Origin gFrontEnd )
				)
				( attribute "WATTAGE" "1/16W"
					( Origin gFrontEnd )
				)
				( attribute "XY" "(-5725,2750)"
					( Origin gFrontEnd )
				)
				( attribute "CHIPS_PART_NAME" "RES"
					( Origin gPackager )
				)
				( attribute "CDS_PART_NAME" "RES_0402-33.2,1%,1/16W,CHIP,G2A"
					( Origin gPackager )
				)
				( objectStatus "RN8F5" )
			)
			( gate "@baseboard_fab2_lib.baseboard_fab2(sch_1):page246_i11"
				( attribute "BOM_COST" "SM_MEM"
					( Origin gFrontEnd )
				)
				( attribute "CDS_LIB" "mstr_discrete"
					( Origin gPackager )
				)
				( attribute "CDS_LOCATION" "RN8F3"
					( Origin gPackager )
				)
				( attribute "CDS_SEC" "1"
					( Origin gPackager )
				)
				( attribute "LOCATION" "RN8F3"
					( Origin gFrontEnd )
				)
				( attribute "MATERIAL" "CHIP"
					( Origin gFrontEnd )
				)
				( attribute "PACK_TYPE" "0402"
					( Origin gFrontEnd )
				)
				( attribute "PART_NUMBER" "G21796-072"
					( Origin gFrontEnd )
				)
				( attribute "PHYS_PAGE" "246"
					( Origin gFrontEnd )
				)
				( attribute "ROOM" "BMC_BOOT_SPI"
					( Origin gFrontEnd )
				)
				( attribute "ROT" "2"
					( Origin gFrontEnd )
				)
				( attribute "SEC" "1"
					( Origin gFrontEnd )
				)
				( attribute "SEC_TYPE" "0402"
					( Origin gFrontEnd )
				)
				( attribute "TOLERANCE" "1%"
					( Origin gFrontEnd )
				)
				( attribute "VALUE" "4.75K"
					( Origin gFrontEnd )
				)
				( attribute "VER" "2"
					( Origin gFrontEnd )
				)
				( attribute "WATTAGE" "1/16W"
					( Origin gFrontEnd )
				)
				( attribute "XY" "(-5775,3200)"
					( Origin gFrontEnd )
				)
				( attribute "CHIPS_PART_NAME" "RES"
					( Origin gPackager )
				)
				( attribute "CDS_PART_NAME" "RES_0402-4.75K,1%,1/16W,CHIP,GA"
					( Origin gPackager )
				)
				( objectStatus "RN8F3" )
			)
			( gate "@baseboard_fab2_lib.baseboard_fab2(sch_1):page246_i12"
				( attribute "BOM_COST" "SM_MEM"
					( Origin gFrontEnd )
				)
				( attribute "CDS_LIB" "mstr_discrete"
					( Origin gPackager )
				)
				( attribute "CDS_LOCATION" "RN8F4"
					( Origin gPackager )
				)
				( attribute "CDS_SEC" "1"
					( Origin gPackager )
				)
				( attribute "LOCATION" "RN8F4"
					( Origin gFrontEnd )
				)
				( attribute "MATERIAL" "EMPTY"
					( Origin gFrontEnd )
				)
				( attribute "PACK_TYPE" "0402"
					( Origin gFrontEnd )
				)
				( attribute "PART_NUMBER" "G21796-072"
					( Origin gFrontEnd )
				)
				( attribute "PHYS_PAGE" "246"
					( Origin gFrontEnd )
				)
				( attribute "ROOM" "BMC_BOOT_SPI"
					( Origin gFrontEnd )
				)
				( attribute "ROT" "2"
					( Origin gFrontEnd )
				)
				( attribute "SEC" "1"
					( Origin gFrontEnd )
				)
				( attribute "SEC_TYPE" "0402"
					( Origin gFrontEnd )
				)
				( attribute "TOLERANCE" "1%"
					( Origin gFrontEnd )
				)
				( attribute "VALUE" "4.75K"
					( Origin gFrontEnd )
				)
				( attribute "VER" "2"
					( Origin gFrontEnd )
				)
				( attribute "WATTAGE" "1/16W"
					( Origin gFrontEnd )
				)
				( attribute "XY" "(-5225,3225)"
					( Origin gFrontEnd )
				)
				( attribute "CHIPS_PART_NAME" "RES"
					( Origin gPackager )
				)
				( attribute "CDS_PART_NAME" "RES_0402-4.75K,1%,1/16W,EMPTY,A"
					( Origin gPackager )
				)
				( objectStatus "RN8F4" )
			)
			( gate "@baseboard_fab2_lib.baseboard_fab2(sch_1):page151_i212"
				( attribute "CDS_LIB" "dev_discrete"
					( Origin gPackager )
				)
				( attribute "CDS_LOCATION" "C25W12"
					( Origin gPackager )
				)
				( attribute "CDS_SEC" "1"
					( Origin gPackager )
				)
				( attribute "LOCATION" "C25W12"
					( Origin gFrontEnd )
				)
				( attribute "MATERIAL" "X6S"
					( Origin gFrontEnd )
				)
				( attribute "PACK_TYPE" "0402V"
					( Origin gFrontEnd )
				)
				( attribute "PART_NUMBER" "D97712-004"
					( Origin gFrontEnd )
				)
				( attribute "PHYS_PAGE" "151"
					( Origin gFrontEnd )
				)
				( attribute "ROOM" "VDDQ_KLM_PWR_VR"
					( Origin gFrontEnd )
				)
				( attribute "ROT" "0"
					( Origin gFrontEnd )
				)
				( attribute "SEC" "1"
					( Origin gFrontEnd )
				)
				( attribute "SEC_TYPE" "0402V"
					( Origin gFrontEnd )
				)
				( attribute "TOLERANCE" "10%"
					( Origin gFrontEnd )
				)
				( attribute "VALUE" "1.0UF"
					( Origin gFrontEnd )
				)
				( attribute "VER" "1"
					( Origin gFrontEnd )
				)
				( attribute "VOLTAGE" "6.3V"
					( Units "uVoltage" "V" 1.000000)
					( Origin gFrontEnd )
				)
				( attribute "XY" "(-1950,-2000)"
					( Origin gFrontEnd )
				)
				( attribute "CHIPS_PART_NAME" "CAP_A"
					( Origin gPackager )
				)
				( attribute "CDS_PART_NAME" "CAP_A_0402V-1.0UF,6.3V,10%,X6SA"
					( Origin gPackager )
				)
				( objectStatus "C25W12" )
			)
			( gate "@baseboard_fab2_lib.baseboard_fab2(sch_1):page151_i213"
				( attribute "BOM_COST" "MEM"
					( Origin gFrontEnd )
				)
				( attribute "CDS_LIB" "dev_discrete"
					( Origin gPackager )
				)
				( attribute "CDS_LOCATION" "C25W10"
					( Origin gPackager )
				)
				( attribute "CDS_SEC" "1"
					( Origin gPackager )
				)
				( attribute "LOCATION" "C25W10"
					( Origin gFrontEnd )
				)
				( attribute "MATERIAL" "X7R"
					( Origin gFrontEnd )
				)
				( attribute "PACK_TYPE" "0402V"
					( Origin gFrontEnd )
				)
				( attribute "PART_NUMBER" "A36096-045"
					( Origin gFrontEnd )
				)
				( attribute "PHYS_PAGE" "151"
					( Origin gFrontEnd )
				)
				( attribute "ROOM" "DDR4_CH_M"
					( Origin gFrontEnd )
				)
				( attribute "ROT" "2"
					( Origin gFrontEnd )
				)
				( attribute "SEC" "1"
					( Origin gFrontEnd )
				)
				( attribute "SEC_TYPE" "0402V"
					( Origin gFrontEnd )
				)
				( attribute "TOLERANCE" "10%"
					( Origin gFrontEnd )
				)
				( attribute "VALUE" "0.01UF"
					( Origin gFrontEnd )
				)
				( attribute "VER" "1"
					( Origin gFrontEnd )
				)
				( attribute "VOLTAGE" "25V"
					( Units "uVoltage" "V" 1.000000)
					( Origin gFrontEnd )
				)
				( attribute "XY" "(-2275,-1600)"
					( Origin gFrontEnd )
				)
				( attribute "CHIPS_PART_NAME" "CAP_A"
					( Origin gPackager )
				)
				( attribute "CDS_PART_NAME" "CAP_A_0402V-0.01UF,25V,10%,X7RA"
					( Origin gPackager )
				)
				( attribute "POP" "NOPOP"
					( Origin gFrontEnd )
				)
				( objectStatus "C25W10" )
			)
			( gate "@baseboard_fab2_lib.baseboard_fab2(sch_1):page246_i17"
				( attribute "BOM_COST" "SM_MEM"
					( Origin gFrontEnd )
				)
				( attribute "CDS_LIB" "mstr_memory"
					( Origin gPackager )
				)
				( attribute "CDS_LOCATION" "UN8F2"
					( Origin gPackager )
				)
				( attribute "CDS_SEC" "1"
					( Origin gPackager )
				)
				( attribute "LOCATION" "UN8F2"
					( Origin gFrontEnd )
				)
				( attribute "MATERIAL" "IC"
					( Origin gFrontEnd )
				)
				( attribute "PACK_TYPE" "XSOI"
					( Origin gFrontEnd )
				)
				( attribute "PART_NUMBER" "H25002-001"
					( Origin gFrontEnd )
				)
				( attribute "PHYS_PAGE" "246"
					( Origin gFrontEnd )
				)
				( attribute "ROOM" "BMC_BOOT_SPI"
					( Origin gFrontEnd )
				)
				( attribute "ROT" "0"
					( Origin gFrontEnd )
				)
				( attribute "SEC" "1"
					( Origin gFrontEnd )
				)
				( attribute "SEC_TYPE" "XSOI"
					( Origin gFrontEnd )
				)
				( attribute "VER" "1"
					( Origin gFrontEnd )
				)
				( attribute "XY" "(-3675,2750)"
					( Origin gFrontEnd )
				)
				( attribute "CHIPS_PART_NAME" "W25Q256"
					( Origin gPackager )
				)
				( attribute "CDS_PART_NAME" "W25Q256_XSOI-IC,H25002-001"
					( Origin gPackager )
				)
				( objectStatus "UN8F2" )
			)
			( gate "@baseboard_fab2_lib.baseboard_fab2(sch_1):page200_i225"
				( attribute "CDS_LIB" "mstr_discrete"
					( Origin gPackager )
				)
				( attribute "LOCATION" "Q6W1"
					( Origin gFrontEnd )
				)
				( attribute "MATERIAL" "FET"
					( Origin gFrontEnd )
				)
				( attribute "PACK_TYPE" "SOT23LF"
					( Origin gFrontEnd )
				)
				( attribute "PART_NUMBER" "C79254-001"
					( Origin gFrontEnd )
				)
				( attribute "PHYS_PAGE" "200"
					( Origin gFrontEnd )
				)
				( attribute "ROOM" "HOT_SWAP"
					( Origin gFrontEnd )
				)
				( attribute "ROT" "0"
					( Origin gFrontEnd )
				)
				( attribute "VALUE" "2N7002"
					( Origin gFrontEnd )
				)
				( attribute "VER" "8"
					( Origin gFrontEnd )
				)
				( attribute "XY" "(-1500,1675)"
					( Origin gFrontEnd )
				)
				( attribute "CHIPS_PART_NAME" "FET_N"
					( Origin gPackager )
				)
				( attribute "CDS_PART_NAME" "FET_N_SOT23LF-2N7002,FET,C7925A"
					( Origin gPackager )
				)
				( attribute "CDS_LOCATION" "Q6W1"
					( Origin gPackager )
				)
				( attribute "CDS_SEC" "1"
					( Origin gPackager )
				)
				( attribute "SEC" "1"
					( Origin gPackager )
				)
				( objectStatus "Q6W1" )
			)
			( gate "@baseboard_fab2_lib.baseboard_fab2(sch_1):page247_i1"
				( attribute "BOM_COST" "SM_THERM"
					( Origin gFrontEnd )
				)
				( attribute "CDS_LIB" "mstr_discrete"
					( Origin gPackager )
				)
				( attribute "LOCATION" "R6W10"
					( Origin gFrontEnd )
				)
				( attribute "MATERIAL" "CHIP"
					( Origin gFrontEnd )
				)
				( attribute "PACK_TYPE" "0402"
					( Origin gFrontEnd )
				)
				( attribute "PART_NUMBER" "G21796-072"
					( Origin gFrontEnd )
				)
				( attribute "PHYS_PAGE" "247"
					( Origin gFrontEnd )
				)
				( attribute "ROOM" "CPU_FANS"
					( Origin gFrontEnd )
				)
				( attribute "ROT" "2"
					( Origin gFrontEnd )
				)
				( attribute "TOLERANCE" "1%"
					( Origin gFrontEnd )
				)
				( attribute "VALUE" "4.75K"
					( Origin gFrontEnd )
				)
				( attribute "VER" "2"
					( Origin gFrontEnd )
				)
				( attribute "WATTAGE" "1/16W"
					( Origin gFrontEnd )
				)
				( attribute "XY" "(-7450,3350)"
					( Origin gFrontEnd )
				)
				( attribute "CHIPS_PART_NAME" "RES"
					( Origin gPackager )
				)
				( attribute "CDS_PART_NAME" "RES_0402-4.75K,1%,1/16W,CHIP,GA"
					( Origin gPackager )
				)
				( attribute "CDS_LOCATION" "R6W10"
					( Origin gPackager )
				)
				( attribute "SEC" "1"
					( Origin gFrontEnd )
				)
				( attribute "SEC_TYPE" "0402"
					( Origin gFrontEnd )
				)
				( attribute "CDS_SEC" "1"
					( Origin gPackager )
				)
				( objectStatus "R6W10" )
			)
			( gate "@baseboard_fab2_lib.baseboard_fab2(sch_1):page215_i13"
				( attribute "CDS_LIB" "mstr_discrete"
					( Origin gPackager )
				)
				( attribute "CDS_LOCATION" "R7F21"
					( Origin gPackager )
				)
				( attribute "CDS_SEC" "1"
					( Origin gPackager )
				)
				( attribute "LOCATION" "R7F21"
					( Origin gFrontEnd )
				)
				( attribute "MATERIAL" "CHIP"
					( Origin gFrontEnd )
				)
				( attribute "PACK_TYPE" "0402"
					( Origin gFrontEnd )
				)
				( attribute "PART_NUMBER" "G21497-005"
					( Origin gFrontEnd )
				)
				( attribute "PHYS_PAGE" "215"
					( Origin gFrontEnd )
				)
				( attribute "ROOM" "PVCCIN_CPU0_VR"
					( Origin gFrontEnd )
				)
				( attribute "ROT" "0"
					( Origin gFrontEnd )
				)
				( attribute "SEC" "1"
					( Origin gFrontEnd )
				)
				( attribute "SEC_TYPE" "0402"
					( Origin gFrontEnd )
				)
				( attribute "TOLERANCE" "5%"
					( Origin gFrontEnd )
				)
				( attribute "VALUE" "0.0"
					( Origin gFrontEnd )
				)
				( attribute "VER" "1"
					( Origin gFrontEnd )
				)
				( attribute "WATTAGE" "1/16W"
					( Origin gFrontEnd )
				)
				( attribute "XY" "(-425,1300)"
					( Origin gFrontEnd )
				)
				( attribute "CHIPS_PART_NAME" "RES"
					( Origin gPackager )
				)
				( attribute "CDS_PART_NAME" "RES_0402-0.0,5%,1/16W,CHIP,G21A"
					( Origin gPackager )
				)
				( objectStatus "R7F21" )
			)
			( gate "@baseboard_fab2_lib.baseboard_fab2(sch_1):page215_i12"
				( attribute "CDS_LIB" "mstr_discrete"
					( Origin gPackager )
				)
				( attribute "CDS_LOCATION" "R7G9"
					( Origin gPackager )
				)
				( attribute "CDS_SEC" "1"
					( Origin gPackager )
				)
				( attribute "LOCATION" "R7G9"
					( Origin gFrontEnd )
				)
				( attribute "MATERIAL" "CHIP"
					( Origin gFrontEnd )
				)
				( attribute "NO_XNET_CONNECTION" "1"
					( Origin gFrontEnd )
				)
				( attribute "PACK_TYPE" "0402"
					( Origin gFrontEnd )
				)
				( attribute "PART_NUMBER" "G21796-066"
					( Origin gFrontEnd )
				)
				( attribute "PHYS_PAGE" "215"
					( Origin gFrontEnd )
				)
				( attribute "ROOM" "VDDQ_ABC_PWR_VR"
					( Origin gFrontEnd )
				)
				( attribute "ROT" "0"
					( Origin gFrontEnd )
				)
				( attribute "SEC" "1"
					( Origin gFrontEnd )
				)
				( attribute "SEC_TYPE" "0402"
					( Origin gFrontEnd )
				)
				( attribute "TOLERANCE" "1%"
					( Origin gFrontEnd )
				)
				( attribute "VALUE" "10.0"
					( Origin gFrontEnd )
				)
				( attribute "VER" "1"
					( Origin gFrontEnd )
				)
				( attribute "WATTAGE" "1/16W"
					( Origin gFrontEnd )
				)
				( attribute "XY" "(-575,1025)"
					( Origin gFrontEnd )
				)
				( attribute "CHIPS_PART_NAME" "RES"
					( Origin gPackager )
				)
				( attribute "CDS_PART_NAME" "RES_0402-10.0,1%,1/16W,CHIP,G2A"
					( Origin gPackager )
				)
				( objectStatus "R7G9" )
			)
			( gate "@baseboard_fab2_lib.baseboard_fab2(sch_1):page249_i37"
				( attribute "CDS_LIB" "dev_discrete"
					( Origin gPackager )
				)
				( attribute "CDS_LOCATION" "C8W2"
					( Origin gPackager )
				)
				( attribute "CDS_SEC" "1"
					( Origin gPackager )
				)
				( attribute "LOCATION" "C8W2"
					( Origin gFrontEnd )
				)
				( attribute "MATERIAL" "X7R"
					( Origin gFrontEnd )
				)
				( attribute "PACK_TYPE" "0402V"
					( Origin gFrontEnd )
				)
				( attribute "PART_NUMBER" "A36096-030"
					( Origin gFrontEnd )
				)
				( attribute "PHYS_PAGE" "249"
					( Origin gFrontEnd )
				)
				( attribute "ROOM" "VDDQ_KLM_PWR_VR"
					( Origin gFrontEnd )
				)
				( attribute "ROT" "0"
					( Origin gFrontEnd )
				)
				( attribute "SEC" "1"
					( Origin gFrontEnd )
				)
				( attribute "SEC_TYPE" "0402V"
					( Origin gFrontEnd )
				)
				( attribute "TOLERANCE" "10%"
					( Origin gFrontEnd )
				)
				( attribute "VALUE" "0.1UF"
					( Origin gFrontEnd )
				)
				( attribute "VER" "1"
					( Origin gFrontEnd )
				)
				( attribute "VOLTAGE" "16V"
					( Units "uVoltage" "V" 1.000000)
					( Origin gFrontEnd )
				)
				( attribute "XY" "(-2050,3000)"
					( Origin gFrontEnd )
				)
				( attribute "CHIPS_PART_NAME" "CAP_A"
					( Origin gPackager )
				)
				( attribute "CDS_PART_NAME" "CAP_A_0402V-0.1UF,16V,10%,X7R,A"
					( Origin gPackager )
				)
				( objectStatus "C8W2" )
			)
			( gate "@baseboard_fab2_lib.baseboard_fab2(sch_1):page251_i31"
				( attribute "BOM_COST" "SM_THERM"
					( Origin gFrontEnd )
				)
				( attribute "CDS_LIB" "mstr_discrete"
					( Origin gPackager )
				)
				( attribute "CDS_LOCATION" "R10W7"
					( Origin gPackager )
				)
				( attribute "CDS_SEC" "1"
					( Origin gPackager )
				)
				( attribute "LOCATION" "R10W7"
					( Origin gFrontEnd )
				)
				( attribute "MATERIAL" "CHIP"
					( Origin gFrontEnd )
				)
				( attribute "PACK_TYPE" "0402"
					( Origin gFrontEnd )
				)
				( attribute "PART_NUMBER" "G21796-072"
					( Origin gFrontEnd )
				)
				( attribute "PHYS_PAGE" "251"
					( Origin gFrontEnd )
				)
				( attribute "ROOM" "CPU_FANS"
					( Origin gFrontEnd )
				)
				( attribute "ROT" "0"
					( Origin gFrontEnd )
				)
				( attribute "SEC" "1"
					( Origin gFrontEnd )
				)
				( attribute "SEC_TYPE" "0402"
					( Origin gFrontEnd )
				)
				( attribute "TOLERANCE" "1%"
					( Origin gFrontEnd )
				)
				( attribute "VALUE" "4.75K"
					( Origin gFrontEnd )
				)
				( attribute "VER" "2"
					( Origin gFrontEnd )
				)
				( attribute "WATTAGE" "1/16W"
					( Origin gFrontEnd )
				)
				( attribute "XY" "(-5300,3900)"
					( Origin gFrontEnd )
				)
				( attribute "CHIPS_PART_NAME" "RES"
					( Origin gPackager )
				)
				( attribute "CDS_PART_NAME" "RES_0402-4.75K,1%,1/16W,CHIP,GA"
					( Origin gPackager )
				)
				( objectStatus "R10W7" )
			)
			( gate "@baseboard_fab2_lib.baseboard_fab2(sch_1):page251_i29"
				( attribute "BOM_COST" "SM_THERM"
					( Origin gFrontEnd )
				)
				( attribute "CDS_LIB" "dev_discrete"
					( Origin gPackager )
				)
				( attribute "CDS_LOCATION" "C10W5"
					( Origin gPackager )
				)
				( attribute "CDS_SEC" "1"
					( Origin gPackager )
				)
				( attribute "LOCATION" "C10W5"
					( Origin gFrontEnd )
				)
				( attribute "MATERIAL" "X7R"
					( Origin gFrontEnd )
				)
				( attribute "PACK_TYPE" "0402V"
					( Origin gFrontEnd )
				)
				( attribute "PART_NUMBER" "A36096-045"
					( Origin gFrontEnd )
				)
				( attribute "PHYS_PAGE" "251"
					( Origin gFrontEnd )
				)
				( attribute "ROOM" "CPU_FANS"
					( Origin gFrontEnd )
				)
				( attribute "ROT" "2"
					( Origin gFrontEnd )
				)
				( attribute "SEC" "1"
					( Origin gFrontEnd )
				)
				( attribute "SEC_TYPE" "0402V"
					( Origin gFrontEnd )
				)
				( attribute "TOLERANCE" "10%"
					( Origin gFrontEnd )
				)
				( attribute "VALUE" "0.01UF"
					( Origin gFrontEnd )
				)
				( attribute "VER" "1"
					( Origin gFrontEnd )
				)
				( attribute "VOLTAGE" "25V"
					( Units "uVoltage" "V" 1.000000)
					( Origin gFrontEnd )
				)
				( attribute "XY" "(-5175,3500)"
					( Origin gFrontEnd )
				)
				( attribute "CHIPS_PART_NAME" "CAP_A"
					( Origin gPackager )
				)
				( attribute "CDS_PART_NAME" "CAP_A_0402V-0.01UF,25V,10%,X7RA"
					( Origin gPackager )
				)
				( objectStatus "C10W5" )
			)
			( gate "@baseboard_fab2_lib.baseboard_fab2(sch_1):page251_i27"
				( attribute "BOM_COST" "SM_THERM"
					( Origin gFrontEnd )
				)
				( attribute "CDS_LIB" "mstr_discrete"
					( Origin gPackager )
				)
				( attribute "CDS_LOCATION" "R10W6"
					( Origin gPackager )
				)
				( attribute "CDS_SEC" "1"
					( Origin gPackager )
				)
				( attribute "LOCATION" "R10W6"
					( Origin gFrontEnd )
				)
				( attribute "MATERIAL" "CHIP"
					( Origin gFrontEnd )
				)
				( attribute "NO_XNET_CONNECTION" "1"
					( Origin gFrontEnd )
				)
				( attribute "PACK_TYPE" "0402"
					( Origin gFrontEnd )
				)
				( attribute "PART_NUMBER" "G21796-017"
					( Origin gFrontEnd )
				)
				( attribute "PHYS_PAGE" "251"
					( Origin gFrontEnd )
				)
				( attribute "ROOM" "CPU_FANS"
					( Origin gFrontEnd )
				)
				( attribute "ROT" "0"
					( Origin gFrontEnd )
				)
				( attribute "SEC" "1"
					( Origin gFrontEnd )
				)
				( attribute "SEC_TYPE" "0402"
					( Origin gFrontEnd )
				)
				( attribute "TOLERANCE" "1%"
					( Origin gFrontEnd )
				)
				( attribute "VALUE" "100.0"
					( Origin gFrontEnd )
				)
				( attribute "VER" "1"
					( Origin gFrontEnd )
				)
				( attribute "WATTAGE" "1/16W"
					( Origin gFrontEnd )
				)
				( attribute "XY" "(-4650,3700)"
					( Origin gFrontEnd )
				)
				( attribute "CHIPS_PART_NAME" "RES"
					( Origin gPackager )
				)
				( attribute "CDS_PART_NAME" "RES_0402-100.0,1%,1/16W,CHIP,GA"
					( Origin gPackager )
				)
				( objectStatus "R10W6" )
			)
			( gate "@baseboard_fab2_lib.baseboard_fab2(sch_1):page251_i25"
				( attribute "BOM_COST" "SM_THERM"
					( Origin gFrontEnd )
				)
				( attribute "CDS_LIB" "mstr_conn"
					( Origin gPackager )
				)
				( attribute "CDS_LOCATION" "J1B2"
					( Origin gPackager )
				)
				( attribute "CDS_SEC" "1"
					( Origin gPackager )
				)
				( attribute "LOCATION" "J1B2"
					( Origin gFrontEnd )
				)
				( attribute "MATERIAL" "HDR"
					( Origin gFrontEnd )
				)
				( attribute "PACK_TYPE" "PIP"
					( Origin gFrontEnd )
				)
				( attribute "PART_NUMBER" "C74770-005"
					( Origin gFrontEnd )
				)
				( attribute "PHYS_PAGE" "251"
					( Origin gFrontEnd )
				)
				( attribute "ROOM" "CPU_FANS"
					( Origin gFrontEnd )
				)
				( attribute "ROT" "0"
					( Origin gFrontEnd )
				)
				( attribute "SEC" "1"
					( Origin gFrontEnd )
				)
				( attribute "SEC_TYPE" "PIP"
					( Origin gFrontEnd )
				)
				( attribute "TOLERANCE" "10%"
					( Origin gFrontEnd )
				)
				( attribute "VALUE" "0.22UF"
					( Origin gFrontEnd )
				)
				( attribute "VER" "1"
					( Origin gFrontEnd )
				)
				( attribute "VOLTAGE" "16V"
					( Units "uVoltage" "V" 1.000000)
					( Origin gFrontEnd )
				)
				( attribute "XY" "(-1550,5200)"
					( Origin gFrontEnd )
				)
				( attribute "CHIPS_PART_NAME" "CONN6_C74770005"
					( Origin gPackager )
				)
				( attribute "CDS_PART_NAME" "CONN6_C74770005_PIP-HDR,C74770A"
					( Origin gPackager )
				)
				( objectStatus "J1B2" )
			)
			( gate "@baseboard_fab2_lib.baseboard_fab2(sch_1):page146_i65"
				( attribute "BOM_COST" "SM_CONTROLLER"
					( Origin gFrontEnd )
				)
				( attribute "CDS_LIB" "mstr_discrete"
					( Origin gPackager )
				)
				( attribute "CDS_LOCATION" "R25W63"
					( Origin gPackager )
				)
				( attribute "CDS_SEC" "1"
					( Origin gPackager )
				)
				( attribute "LOCATION" "R25W63"
					( Origin gFrontEnd )
				)
				( attribute "MATERIAL" "CHIP"
					( Origin gFrontEnd )
				)
				( attribute "PACK_TYPE" "0402"
					( Origin gFrontEnd )
				)
				( attribute "PART_NUMBER" "G21796-010"
					( Origin gFrontEnd )
				)
				( attribute "PHYS_PAGE" "146"
					( Origin gFrontEnd )
				)
				( attribute "ROOM" "BMC"
					( Origin gFrontEnd )
				)
				( attribute "ROT" "0"
					( Origin gFrontEnd )
				)
				( attribute "SEC" "1"
					( Origin gFrontEnd )
				)
				( attribute "SEC_TYPE" "0402"
					( Origin gFrontEnd )
				)
				( attribute "TOLERANCE" "1%"
					( Origin gFrontEnd )
				)
				( attribute "VALUE" "100.0K"
					( Origin gFrontEnd )
				)
				( attribute "VER" "2"
					( Origin gFrontEnd )
				)
				( attribute "WATTAGE" "1/16W"
					( Origin gFrontEnd )
				)
				( attribute "XY" "(-1550,1400)"
					( Origin gFrontEnd )
				)
				( attribute "CHIPS_PART_NAME" "RES"
					( Origin gPackager )
				)
				( attribute "CDS_PART_NAME" "RES_0402-100.0K,1%,1/16W,CHIP,A"
					( Origin gPackager )
				)
				( objectStatus "R25W63" )
			)
			( gate "@baseboard_fab2_lib.baseboard_fab2(sch_1):page168_i47"
				( attribute "BOM_COST" "DEBUG"
					( Origin gFrontEnd )
				)
				( attribute "CDS_LIB" "mstr_discrete"
					( Origin gPackager )
				)
				( attribute "CDS_LOCATION" "Q6W2"
					( Origin gPackager )
				)
				( attribute "CDS_SEC" "1"
					( Origin gPackager )
				)
				( attribute "LOCATION" "Q6W2"
					( Origin gFrontEnd )
				)
				( attribute "MATERIAL" "IC"
					( Origin gFrontEnd )
				)
				( attribute "PACK_TYPE" "SM"
					( Origin gFrontEnd )
				)
				( attribute "PART_NUMBER" "C52245-001"
					( Origin gFrontEnd )
				)
				( attribute "PHYS_PAGE" "168"
					( Origin gFrontEnd )
				)
				( attribute "ROOM" "UART_MUX"
					( Origin gFrontEnd )
				)
				( attribute "ROT" "0"
					( Origin gFrontEnd )
				)
				( attribute "SEC" "1"
					( Origin gFrontEnd )
				)
				( attribute "SEC_TYPE" "SM"
					( Origin gFrontEnd )
				)
				( attribute "VALUE" "MMBT3904"
					( Origin gFrontEnd )
				)
				( attribute "VER" "1"
					( Origin gFrontEnd )
				)
				( attribute "XY" "(-4000,1450)"
					( Origin gFrontEnd )
				)
				( attribute "CHIPS_PART_NAME" "NPN"
					( Origin gPackager )
				)
				( attribute "CDS_PART_NAME" "NPN_SM-MMBT3904,IC,C52245-001"
					( Origin gPackager )
				)
				( objectStatus "Q6W2" )
			)
			( gate "@baseboard_fab2_lib.baseboard_fab2(sch_1):page164_i97"
				( attribute "CDS_LIB" "w_hdl"
					( Origin gPackager )
				)
				( attribute "CDS_LMAN_SYM_OUTLINE" "-200,300,200,-300"
					( Origin gPackager )
				)
				( attribute "LOCATION" "U6W11"
					( Origin gFrontEnd )
				)
				( attribute "PACK_TYPE" "DISCRET-G1"
					( Origin gFrontEnd )
				)
				( attribute "PART_NUMBER" "71.09554.C0W"
					( Origin gFrontEnd )
				)
				( attribute "PHYS_PAGE" "164"
					( Origin gFrontEnd )
				)
				( attribute "ROT" "0"
					( Origin gFrontEnd )
				)
				( attribute "SEC" "1"
					( Origin gFrontEnd )
				)
				( attribute "SEC_TYPE" "DISCRET-G1"
					( Origin gFrontEnd )
				)
				( attribute "VALUE" "PCA9554PWR-GP"
					( Origin gFrontEnd )
				)
				( attribute "VER" "1"
					( Origin gFrontEnd )
				)
				( attribute "XY" "(-2150,3500)"
					( Origin gFrontEnd )
				)
				( attribute "CHIPS_PART_NAME" "PCA9554PWR-GP"
					( Origin gPackager )
				)
				( attribute "CDS_PART_NAME" "PCA9554PWR-GP_DISCRET-G1-PCA95A"
					( Origin gPackager )
				)
				( attribute "CDS_LOCATION" "U6W11"
					( Origin gPackager )
				)
				( attribute "CDS_SEC" "1"
					( Origin gPackager )
				)
				( objectStatus "U6W11" )
			)
			( gate "@baseboard_fab2_lib.baseboard_fab2(sch_1):page144_i150"
				( attribute "ATTRIBUTE" "18KOHM"
					( Origin gFrontEnd )
				)
				( attribute "CDS_LIB" "w_hdl"
					( Origin gPackager )
				)
				( attribute "CDS_LMAN_SYM_OUTLINE" "-50,75,50,-75"
					( Origin gPackager )
				)
				( attribute "LOCATION" "R25W58"
					( Origin gFrontEnd )
				)
				( attribute "PACK_TYPE" "RCL_GP"
					( Origin gFrontEnd )
				)
				( attribute "PART_NUMBER" "64.18025.6DL"
					( Origin gFrontEnd )
				)
				( attribute "PHYS_PAGE" "144"
					( Origin gFrontEnd )
				)
				( attribute "RATED" "1/16W"
					( Origin gFrontEnd )
				)
				( attribute "ROT" "0"
					( Origin gFrontEnd )
				)
				( attribute "SEC" "1"
					( Origin gFrontEnd )
				)
				( attribute "SEC_TYPE" "RCL_GP"
					( Origin gFrontEnd )
				)
				( attribute "TOLERANCE" "1%"
					( Origin gFrontEnd )
				)
				( attribute "VALUE" "18KR2F-GP"
					( Origin gFrontEnd )
				)
				( attribute "VER" "1"
					( Origin gFrontEnd )
				)
				( attribute "XY" "(-2400,-3525)"
					( Origin gFrontEnd )
				)
				( attribute "CHIPS_PART_NAME" "18KR2F-GP"
					( Origin gPackager )
				)
				( attribute "CDS_PART_NAME" "18KR2F-GP_RCL_GP-18KR2F-GP,64.A"
					( Origin gPackager )
				)
				( attribute "PACK_SIZE" "0402"
					( Origin gFrontEnd )
				)
				( attribute "CDS_LOCATION" "R25W58"
					( Origin gPackager )
				)
				( attribute "CDS_SEC" "1"
					( Origin gPackager )
				)
				( objectStatus "R25W58" )
			)
			( gate "@baseboard_fab2_lib.baseboard_fab2(sch_1):page247_i53"
				( attribute "CHIPS_PART_NAME" "TTL1G07_A"
					( Origin gPackager )
				)
			)
			( gate "@baseboard_fab2_lib.baseboard_fab2(sch_1):page249_i2"
				( attribute "CDS_LIB" "mstr_discrete"
					( Origin gPackager )
				)
				( attribute "LOCATION" "R3W1"
					( Origin gFrontEnd )
				)
				( attribute "MATERIAL" "CHIP"
					( Origin gFrontEnd )
				)
				( attribute "PACK_TYPE" "0402"
					( Origin gFrontEnd )
				)
				( attribute "PART_NUMBER" "G21796-026"
					( Origin gFrontEnd )
				)
				( attribute "PHYS_PAGE" "249"
					( Origin gFrontEnd )
				)
				( attribute "ROOM" "BMC_DEBUG_HEADER"
					( Origin gFrontEnd )
				)
				( attribute "ROT" "0"
					( Origin gFrontEnd )
				)
				( attribute "TOLERANCE" "1%"
					( Origin gFrontEnd )
				)
				( attribute "VALUE" "1.00K"
					( Origin gFrontEnd )
				)
				( attribute "VER" "2"
					( Origin gFrontEnd )
				)
				( attribute "WATTAGE" "1/16W"
					( Origin gFrontEnd )
				)
				( attribute "XY" "(-6850,1950)"
					( Origin gFrontEnd )
				)
				( attribute "CHIPS_PART_NAME" "RES"
					( Origin gPackager )
				)
				( attribute "CDS_PART_NAME" "RES_0402-1.00K,1%,1/16W,CHIP,GA"
					( Origin gPackager )
				)
				( attribute "CDS_LOCATION" "R3W1"
					( Origin gPackager )
				)
				( attribute "SEC" "1"
					( Origin gFrontEnd )
				)
				( attribute "SEC_TYPE" "0402"
					( Origin gFrontEnd )
				)
				( attribute "CDS_SEC" "1"
					( Origin gPackager )
				)
				( attribute "CONFIG" "64.47035.L0L"
					( Origin gFrontEnd )
				)
				( attribute "NEW_VALUE" "470K"
					( Origin gFrontEnd )
				)
				( objectStatus "R3W1" )
			)
			( gate "@baseboard_fab2_lib.baseboard_fab2(sch_1):page249_i7"
				( attribute "BOM_COST" "ST_FLASH"
					( Origin gFrontEnd )
				)
				( attribute "CDS_LIB" "mstr_discrete"
					( Origin gPackager )
				)
				( attribute "LOCATION" "R3W9"
					( Origin gFrontEnd )
				)
				( attribute "MATERIAL" "CHIP"
					( Origin gFrontEnd )
				)
				( attribute "PACK_TYPE" "0402"
					( Origin gFrontEnd )
				)
				( attribute "PART_NUMBER" "G21796-016"
					( Origin gFrontEnd )
				)
				( attribute "PHYS_PAGE" "249"
					( Origin gFrontEnd )
				)
				( attribute "ROOM" "M_2"
					( Origin gFrontEnd )
				)
				( attribute "ROT" "0"
					( Origin gFrontEnd )
				)
				( attribute "TOLERANCE" "1%"
					( Origin gFrontEnd )
				)
				( attribute "VALUE" "10.0K"
					( Origin gFrontEnd )
				)
				( attribute "VER" "2"
					( Origin gFrontEnd )
				)
				( attribute "WATTAGE" "1/16W"
					( Origin gFrontEnd )
				)
				( attribute "XY" "(-3325,2300)"
					( Origin gFrontEnd )
				)
				( attribute "CHIPS_PART_NAME" "RES"
					( Origin gPackager )
				)
				( attribute "CDS_PART_NAME" "RES_0402-10.0K,1%,1/16W,CHIP,GA"
					( Origin gPackager )
				)
				( attribute "CDS_LOCATION" "R3W9"
					( Origin gPackager )
				)
				( attribute "SEC" "1"
					( Origin gFrontEnd )
				)
				( attribute "SEC_TYPE" "0402"
					( Origin gFrontEnd )
				)
				( attribute "CDS_SEC" "1"
					( Origin gPackager )
				)
				( objectStatus "R3W9" )
			)
			( gate "@baseboard_fab2_lib.baseboard_fab2(sch_1):page249_i8"
				( attribute "BOM_COST" "MIO_BIOS_MEM"
					( Origin gFrontEnd )
				)
				( attribute "CDS_LIB" "mstr_discrete"
					( Origin gPackager )
				)
				( attribute "LOCATION" "R3W7"
					( Origin gFrontEnd )
				)
				( attribute "MATERIAL" "CHIP"
					( Origin gFrontEnd )
				)
				( attribute "NO_XNET_CONNECTION" "1"
					( Origin gFrontEnd )
				)
				( attribute "PACK_TYPE" "0402"
					( Origin gFrontEnd )
				)
				( attribute "PART_NUMBER" "G21796-072"
					( Origin gFrontEnd )
				)
				( attribute "PHYS_PAGE" "249"
					( Origin gFrontEnd )
				)
				( attribute "ROOM" "SB_SPI"
					( Origin gFrontEnd )
				)
				( attribute "ROT" "2"
					( Origin gFrontEnd )
				)
				( attribute "TOLERANCE" "1%"
					( Origin gFrontEnd )
				)
				( attribute "VALUE" "4.75K"
					( Origin gFrontEnd )
				)
				( attribute "VER" "2"
					( Origin gFrontEnd )
				)
				( attribute "WATTAGE" "1/16W"
					( Origin gFrontEnd )
				)
				( attribute "XY" "(-3325,2775)"
					( Origin gFrontEnd )
				)
				( attribute "CHIPS_PART_NAME" "RES"
					( Origin gPackager )
				)
				( attribute "CDS_PART_NAME" "RES_0402-4.75K,1%,1/16W,CHIP,GA"
					( Origin gPackager )
				)
				( attribute "CDS_LOCATION" "R3W7"
					( Origin gPackager )
				)
				( attribute "SEC" "1"
					( Origin gFrontEnd )
				)
				( attribute "SEC_TYPE" "0402"
					( Origin gFrontEnd )
				)
				( attribute "CDS_SEC" "1"
					( Origin gPackager )
				)
				( objectStatus "R3W7" )
			)
			( gate "@baseboard_fab2_lib.baseboard_fab2(sch_1):page249_i31"
				( attribute "CDS_LIB" "w_hdl"
					( Origin gPackager )
				)
				( attribute "CDS_LMAN_SYM_OUTLINE" "-50,75,50,-75"
					( Origin gPackager )
				)
				( attribute "LOCATION" "R3W4"
					( Origin gFrontEnd )
				)
				( attribute "PACK_TYPE" "RCL_GP"
					( Origin gFrontEnd )
				)
				( attribute "PART_NUMBER" "64.47025.6DL"
					( Origin gFrontEnd )
				)
				( attribute "PHYS_PAGE" "249"
					( Origin gFrontEnd )
				)
				( attribute "ROT" "1"
					( Origin gFrontEnd )
				)
				( attribute "VALUE" "47KR2F-GP"
					( Origin gFrontEnd )
				)
				( attribute "VER" "1"
					( Origin gFrontEnd )
				)
				( attribute "XY" "(-4325,3850)"
					( Origin gFrontEnd )
				)
				( attribute "CHIPS_PART_NAME" "47KR2F-GP"
					( Origin gPackager )
				)
				( attribute "CDS_PART_NAME" "47KR2F-GP_RCL_GP-47KR2F-GP,64.A"
					( Origin gPackager )
				)
				( attribute "CDS_LOCATION" "R3W4"
					( Origin gPackager )
				)
				( attribute "CDS_SEC" "1"
					( Origin gPackager )
				)
				( attribute "SEC" "1"
					( Origin gPackager )
				)
				( attribute "ATTRIBUTE" "47KOHM"
					( Origin gFrontEnd )
				)
				( attribute "RATED" "1/16W"
					( Origin gFrontEnd )
				)
				( attribute "TOLERANCE" "1%"
					( Origin gFrontEnd )
				)
				( attribute "PACK_SIZE" "0402"
					( Origin gFrontEnd )
				)
				( objectStatus "R3W4" )
			)
			( gate "@baseboard_fab2_lib.baseboard_fab2(sch_1):page249_i15"
				( attribute "CDS_LIB" "w_hdl"
					( Origin gPackager )
				)
				( attribute "CDS_LMAN_SYM_OUTLINE" "-100,100,100,-100"
					( Origin gPackager )
				)
				( attribute "PACK_TYPE" "DISCRET-G"
					( Origin gFrontEnd )
				)
				( attribute "PART_NUMBER" "74.00331.A2F"
					( Origin gFrontEnd )
				)
				( attribute "PHYS_PAGE" "249"
					( Origin gFrontEnd )
				)
				( attribute "ROT" "0"
					( Origin gFrontEnd )
				)
				( attribute "VALUE" "LMV331IDCKRG4-GP"
					( Origin gFrontEnd )
				)
				( attribute "VER" "1"
					( Origin gFrontEnd )
				)
				( attribute "XY" "(-2300,2550)"
					( Origin gFrontEnd )
				)
				( attribute "CHIPS_PART_NAME" "LMV331IDCKRG4-GP"
					( Origin gPackager )
				)
				( attribute "CDS_PART_NAME" "LMV331IDCKRG4-GP_DISCRET-G-LMVA"
					( Origin gPackager )
				)
				( attribute "LOCATION" "Q9W4"
					( Origin gFrontEnd )
				)
				( attribute "CDS_LOCATION" "Q9W4"
					( Origin gPackager )
				)
				( attribute "CDS_SEC" "1"
					( Origin gPackager )
				)
				( attribute "SEC" "1"
					( Origin gPackager )
				)
				( objectStatus "Q9W4" )
			)
			( gate "@baseboard_fab2_lib.baseboard_fab2(sch_1):page133_i365"
				( attribute "CDS_LIB" "mstr_discrete"
					( Origin gPackager )
				)
				( attribute "LOCATION" "R3P53"
					( Origin gFrontEnd )
				)
				( attribute "MATERIAL" "CHIP"
					( Origin gFrontEnd )
				)
				( attribute "PACK_TYPE" "0402"
					( Origin gFrontEnd )
				)
				( attribute "PART_NUMBER" "G21796-072"
					( Origin gFrontEnd )
				)
				( attribute "PHYS_PAGE" "133"
					( Origin gFrontEnd )
				)
				( attribute "ROOM" "SB_PU_PD"
					( Origin gFrontEnd )
				)
				( attribute "ROT" "0"
					( Origin gFrontEnd )
				)
				( attribute "TOLERANCE" "1%"
					( Origin gFrontEnd )
				)
				( attribute "VALUE" "4.75K"
					( Origin gFrontEnd )
				)
				( attribute "VER" "1"
					( Origin gFrontEnd )
				)
				( attribute "WATTAGE" "1/16W"
					( Origin gFrontEnd )
				)
				( attribute "XY" "(-375,3525)"
					( Origin gFrontEnd )
				)
				( attribute "CHIPS_PART_NAME" "RES"
					( Origin gPackager )
				)
				( attribute "CDS_PART_NAME" "RES_0402-4.75K,1%,1/16W,CHIP,GA"
					( Origin gPackager )
				)
				( attribute "CDS_LOCATION" "R3P53"
					( Origin gPackager )
				)
				( attribute "CDS_SEC" "1"
					( Origin gPackager )
				)
				( attribute "SEC" "1"
					( Origin gPackager )
				)
				( objectStatus "R3P53" )
			)
			( gate "@baseboard_fab2_lib.baseboard_fab2(sch_1):page151_i217"
				( attribute "CDS_LIB" "dev_discrete"
					( Origin gPackager )
				)
				( attribute "CDS_LOCATION" "C25W13"
					( Origin gPackager )
				)
				( attribute "CDS_SEC" "1"
					( Origin gPackager )
				)
				( attribute "LOCATION" "C25W13"
					( Origin gFrontEnd )
				)
				( attribute "MATERIAL" "X7R"
					( Origin gFrontEnd )
				)
				( attribute "PACK_TYPE" "0402V"
					( Origin gFrontEnd )
				)
				( attribute "PART_NUMBER" "A36096-030"
					( Origin gFrontEnd )
				)
				( attribute "PHYS_PAGE" "151"
					( Origin gFrontEnd )
				)
				( attribute "ROOM" "VDDQ_KLM_PWR_VR"
					( Origin gFrontEnd )
				)
				( attribute "ROT" "0"
					( Origin gFrontEnd )
				)
				( attribute "SEC" "1"
					( Origin gFrontEnd )
				)
				( attribute "SEC_TYPE" "0402V"
					( Origin gFrontEnd )
				)
				( attribute "TOLERANCE" "10%"
					( Origin gFrontEnd )
				)
				( attribute "VALUE" "0.1UF"
					( Origin gFrontEnd )
				)
				( attribute "VER" "1"
					( Origin gFrontEnd )
				)
				( attribute "VOLTAGE" "16V"
					( Units "uVoltage" "V" 1.000000)
					( Origin gFrontEnd )
				)
				( attribute "XY" "(600,-100)"
					( Origin gFrontEnd )
				)
				( attribute "CHIPS_PART_NAME" "CAP_A"
					( Origin gPackager )
				)
				( attribute "CDS_PART_NAME" "CAP_A_0402V-0.1UF,16V,10%,X7R,A"
					( Origin gPackager )
				)
				( objectStatus "C25W13" )
			)
			( gate "@baseboard_fab2_lib.baseboard_fab2(sch_1):page249_i48"
				( attribute "BOM_COST" "MIO_BIOS_MEM"
					( Origin gFrontEnd )
				)
				( attribute "CDS_LIB" "mstr_discrete"
					( Origin gPackager )
				)
				( attribute "CDS_LOCATION" "R3W6"
					( Origin gPackager )
				)
				( attribute "CDS_SEC" "1"
					( Origin gPackager )
				)
				( attribute "LOCATION" "R3W6"
					( Origin gFrontEnd )
				)
				( attribute "MATERIAL" "CHIP"
					( Origin gFrontEnd )
				)
				( attribute "NO_XNET_CONNECTION" "1"
					( Origin gFrontEnd )
				)
				( attribute "PACK_TYPE" "0402"
					( Origin gFrontEnd )
				)
				( attribute "PART_NUMBER" "G21796-072"
					( Origin gFrontEnd )
				)
				( attribute "PHYS_PAGE" "249"
					( Origin gFrontEnd )
				)
				( attribute "ROOM" "SB_SPI"
					( Origin gFrontEnd )
				)
				( attribute "ROT" "2"
					( Origin gFrontEnd )
				)
				( attribute "SEC" "1"
					( Origin gFrontEnd )
				)
				( attribute "SEC_TYPE" "0402"
					( Origin gFrontEnd )
				)
				( attribute "TOLERANCE" "1%"
					( Origin gFrontEnd )
				)
				( attribute "VALUE" "4.75K"
					( Origin gFrontEnd )
				)
				( attribute "VER" "2"
					( Origin gFrontEnd )
				)
				( attribute "WATTAGE" "1/16W"
					( Origin gFrontEnd )
				)
				( attribute "XY" "(-2300,4450)"
					( Origin gFrontEnd )
				)
				( attribute "CHIPS_PART_NAME" "RES"
					( Origin gPackager )
				)
				( attribute "CDS_PART_NAME" "RES_0402-4.75K,1%,1/16W,CHIP,GA"
					( Origin gPackager )
				)
				( objectStatus "R3W6" )
			)
			( gate "@baseboard_fab2_lib.baseboard_fab2(sch_1):page249_i57"
				( attribute "BOM_COST" "PROC_SIDEBAND"
					( Origin gFrontEnd )
				)
				( attribute "CDS_LIB" "dev_discrete"
					( Origin gPackager )
				)
				( attribute "CDS_LOCATION" "C3W2"
					( Origin gPackager )
				)
				( attribute "CDS_SEC" "1"
					( Origin gPackager )
				)
				( attribute "LOCATION" "C3W2"
					( Origin gFrontEnd )
				)
				( attribute "MATERIAL" "X7R"
					( Origin gFrontEnd )
				)
				( attribute "PACK_TYPE" "0402V"
					( Origin gFrontEnd )
				)
				( attribute "PART_NUMBER" "A36096-030"
					( Origin gFrontEnd )
				)
				( attribute "PHYS_PAGE" "249"
					( Origin gFrontEnd )
				)
				( attribute "ROOM" "PROC_SIDEBAND"
					( Origin gFrontEnd )
				)
				( attribute "ROT" "0"
					( Origin gFrontEnd )
				)
				( attribute "SEC" "1"
					( Origin gFrontEnd )
				)
				( attribute "SEC_TYPE" "0402V"
					( Origin gFrontEnd )
				)
				( attribute "TOLERANCE" "10%"
					( Origin gFrontEnd )
				)
				( attribute "VALUE" "0.1UF"
					( Origin gFrontEnd )
				)
				( attribute "VER" "1"
					( Origin gFrontEnd )
				)
				( attribute "VOLTAGE" "16V"
					( Units "uVoltage" "V" 1.000000)
					( Origin gFrontEnd )
				)
				( attribute "XY" "(-5950,1950)"
					( Origin gFrontEnd )
				)
				( attribute "CHIPS_PART_NAME" "CAP_A"
					( Origin gPackager )
				)
				( attribute "CDS_PART_NAME" "CAP_A_0402V-0.1UF,16V,10%,X7R,A"
					( Origin gPackager )
				)
				( objectStatus "C3W2" )
			)
			( gate "@baseboard_fab2_lib.baseboard_fab2(sch_1):page249_i29"
				( attribute "CDS_LIB" "mstr_discrete"
					( Origin gPackager )
				)
				( attribute "LOCATION" "Q9W2"
					( Origin gFrontEnd )
				)
				( attribute "MATERIAL" "IC"
					( Origin gFrontEnd )
				)
				( attribute "PACK_TYPE" "SM"
					( Origin gFrontEnd )
				)
				( attribute "PART_NUMBER" "C52245-001"
					( Origin gFrontEnd )
				)
				( attribute "PHYS_PAGE" "249"
					( Origin gFrontEnd )
				)
				( attribute "ROOM" "SB"
					( Origin gFrontEnd )
				)
				( attribute "ROT" "0"
					( Origin gFrontEnd )
				)
				( attribute "VALUE" "MMBT3904"
					( Origin gFrontEnd )
				)
				( attribute "VER" "1"
					( Origin gFrontEnd )
				)
				( attribute "XY" "(-3250,3850)"
					( Origin gFrontEnd )
				)
				( attribute "CHIPS_PART_NAME" "NPN"
					( Origin gPackager )
				)
				( attribute "CDS_PART_NAME" "NPN_SM-MMBT3904,IC,C52245-001"
					( Origin gPackager )
				)
				( attribute "CDS_LOCATION" "Q9W2"
					( Origin gPackager )
				)
				( attribute "SEC" "1"
					( Origin gFrontEnd )
				)
				( attribute "SEC_TYPE" "SM"
					( Origin gFrontEnd )
				)
				( attribute "CDS_SEC" "1"
					( Origin gPackager )
				)
				( objectStatus "Q9W2" )
			)
			( gate "@baseboard_fab2_lib.baseboard_fab2(sch_1):page248_i11"
				( attribute "CHIPS_PART_NAME" "TTL1G08"
					( Origin gPackager )
				)
				( attribute "BOM_COST" "MIO_CHASSIS"
					( Origin gFrontEnd )
				)
				( attribute "CDS_LIB" "mstr_ttl"
					( Origin gPackager )
				)
				( attribute "LOCATION" "U14E2"
					( Origin gFrontEnd )
				)
				( attribute "MATERIAL" "IC"
					( Origin gFrontEnd )
				)
				( attribute "PACK_TYPE" "SOTLF"
					( Origin gFrontEnd )
				)
				( attribute "PART_NUMBER" "D10321-001"
					( Origin gFrontEnd )
				)
				( attribute "PHYS_PAGE" "248"
					( Origin gFrontEnd )
				)
				( attribute "ROOM" "MIO_CHASSIS"
					( Origin gFrontEnd )
				)
				( attribute "ROT" "0"
					( Origin gFrontEnd )
				)
				( attribute "VALUE" "NC7SZ08"
					( Origin gFrontEnd )
				)
				( attribute "VER" "1"
					( Origin gFrontEnd )
				)
				( attribute "XY" "(-3175,1625)"
					( Origin gFrontEnd )
				)
				( attribute "CDS_PART_NAME" "TTL1G08_SOTLF-NC7SZ08,IC,D1032C"
					( Origin gPackager )
				)
				( attribute "SEC" "1"
					( Origin gFrontEnd )
				)
				( attribute "SEC_TYPE" "SOTLF"
					( Origin gFrontEnd )
				)
				( attribute "CDS_LOCATION" "U14E2"
					( Origin gPackager )
				)
				( attribute "CDS_SEC" "1"
					( Origin gPackager )
				)
				( objectStatus "U14E2" )
			)
			( gate "@baseboard_fab2_lib.baseboard_fab2(sch_1):page145_i120"
				( attribute "BOM_COST" "MIO_USB"
					( Origin gFrontEnd )
				)
				( attribute "CDS_LIB" "mstr_discrete"
					( Origin gPackager )
				)
				( attribute "LOCATION" "R6W17"
					( Origin gFrontEnd )
				)
				( attribute "MATERIAL" "CHIP"
					( Origin gFrontEnd )
				)
				( attribute "PACK_TYPE" "0402"
					( Origin gFrontEnd )
				)
				( attribute "PART_NUMBER" "G21497-005"
					( Origin gFrontEnd )
				)
				( attribute "PHYS_PAGE" "145"
					( Origin gFrontEnd )
				)
				( attribute "ROOM" "USB"
					( Origin gFrontEnd )
				)
				( attribute "ROT" "0"
					( Origin gFrontEnd )
				)
				( attribute "TOLERANCE" "5%"
					( Origin gFrontEnd )
				)
				( attribute "VALUE" "0.0"
					( Origin gFrontEnd )
				)
				( attribute "VER" "1"
					( Origin gFrontEnd )
				)
				( attribute "WATTAGE" "1/16W"
					( Origin gFrontEnd )
				)
				( attribute "XY" "(-6450,-2350)"
					( Origin gFrontEnd )
				)
				( attribute "CHIPS_PART_NAME" "RES"
					( Origin gPackager )
				)
				( attribute "CDS_PART_NAME" "RES_0402-0.0,5%,1/16W,CHIP,G21A"
					( Origin gPackager )
				)
				( attribute "CDS_LOCATION" "R6W17"
					( Origin gPackager )
				)
				( attribute "SEC" "1"
					( Origin gFrontEnd )
				)
				( attribute "SEC_TYPE" "0402"
					( Origin gFrontEnd )
				)
				( attribute "CDS_SEC" "1"
					( Origin gPackager )
				)
				( objectStatus "R6W17" )
			)
			( gate "@baseboard_fab2_lib.baseboard_fab2(sch_1):page145_i38"
				( attribute "BOM_COST" "SM_CONTROLLER"
					( Origin gFrontEnd )
				)
				( attribute "CDS_LIB" "mstr_discrete"
					( Origin gPackager )
				)
				( attribute "CDS_LOCATION" "R25W65"
					( Origin gPackager )
				)
				( attribute "CDS_SEC" "1"
					( Origin gPackager )
				)
				( attribute "LOCATION" "R25W65"
					( Origin gFrontEnd )
				)
				( attribute "MATERIAL" "CHIP"
					( Origin gFrontEnd )
				)
				( attribute "PACK_TYPE" "0402"
					( Origin gFrontEnd )
				)
				( attribute "PART_NUMBER" "G21796-010"
					( Origin gFrontEnd )
				)
				( attribute "PHYS_PAGE" "145"
					( Origin gFrontEnd )
				)
				( attribute "ROOM" "BMC"
					( Origin gFrontEnd )
				)
				( attribute "ROT" "0"
					( Origin gFrontEnd )
				)
				( attribute "SEC" "1"
					( Origin gFrontEnd )
				)
				( attribute "SEC_TYPE" "0402"
					( Origin gFrontEnd )
				)
				( attribute "TOLERANCE" "1%"
					( Origin gFrontEnd )
				)
				( attribute "VALUE" "100.0K"
					( Origin gFrontEnd )
				)
				( attribute "VER" "2"
					( Origin gFrontEnd )
				)
				( attribute "WATTAGE" "1/16W"
					( Origin gFrontEnd )
				)
				( attribute "XY" "(-6200,-4150)"
					( Origin gFrontEnd )
				)
				( attribute "CHIPS_PART_NAME" "RES"
					( Origin gPackager )
				)
				( attribute "CDS_PART_NAME" "RES_0402-100.0K,1%,1/16W,CHIP,A"
					( Origin gPackager )
				)
				( attribute "GROUP" "AST2520"
					( Origin gFrontEnd )
				)
				( objectStatus "R25W65" )
			)
			( gate "@baseboard_fab2_lib.baseboard_fab2(sch_1):page145_i36"
				( attribute "BOM_COST" "SM_CONTROLLER"
					( Origin gFrontEnd )
				)
				( attribute "CDS_LIB" "mstr_discrete"
					( Origin gPackager )
				)
				( attribute "CDS_LOCATION" "R25W64"
					( Origin gPackager )
				)
				( attribute "CDS_SEC" "1"
					( Origin gPackager )
				)
				( attribute "LOCATION" "R25W64"
					( Origin gFrontEnd )
				)
				( attribute "MATERIAL" "CHIP"
					( Origin gFrontEnd )
				)
				( attribute "PACK_TYPE" "0402"
					( Origin gFrontEnd )
				)
				( attribute "PART_NUMBER" "G21796-010"
					( Origin gFrontEnd )
				)
				( attribute "PHYS_PAGE" "145"
					( Origin gFrontEnd )
				)
				( attribute "ROOM" "BMC"
					( Origin gFrontEnd )
				)
				( attribute "ROT" "0"
					( Origin gFrontEnd )
				)
				( attribute "SEC" "1"
					( Origin gFrontEnd )
				)
				( attribute "SEC_TYPE" "0402"
					( Origin gFrontEnd )
				)
				( attribute "TOLERANCE" "1%"
					( Origin gFrontEnd )
				)
				( attribute "VALUE" "100.0K"
					( Origin gFrontEnd )
				)
				( attribute "VER" "2"
					( Origin gFrontEnd )
				)
				( attribute "WATTAGE" "1/16W"
					( Origin gFrontEnd )
				)
				( attribute "XY" "(-5950,-4150)"
					( Origin gFrontEnd )
				)
				( attribute "CHIPS_PART_NAME" "RES"
					( Origin gPackager )
				)
				( attribute "CDS_PART_NAME" "RES_0402-100.0K,1%,1/16W,CHIP,A"
					( Origin gPackager )
				)
				( attribute "GROUP" "AST2520"
					( Origin gFrontEnd )
				)
				( objectStatus "R25W64" )
			)
			( gate "@baseboard_fab2_lib.baseboard_fab2(sch_1):page151_i269"
				( attribute "ATTRIBUTE" "120OHM"
					( Origin gFrontEnd )
				)
				( attribute "CDS_LIB" "w_hdl"
					( Origin gPackager )
				)
				( attribute "CDS_LMAN_SYM_OUTLINE" "-50,75,50,-75"
					( Origin gPackager )
				)
				( attribute "LOCATION" "R25W23"
					( Origin gFrontEnd )
				)
				( attribute "PACK_TYPE" "RCL_GP"
					( Origin gFrontEnd )
				)
				( attribute "PART_NUMBER" "64.12005.6DL"
					( Origin gFrontEnd )
				)
				( attribute "PHYS_PAGE" "151"
					( Origin gFrontEnd )
				)
				( attribute "RATED" "1/16W"
					( Origin gFrontEnd )
				)
				( attribute "ROT" "1"
					( Origin gFrontEnd )
				)
				( attribute "SEC" "1"
					( Origin gFrontEnd )
				)
				( attribute "SEC_TYPE" "RCL_GP"
					( Origin gFrontEnd )
				)
				( attribute "TOLERANCE" "1%"
					( Origin gFrontEnd )
				)
				( attribute "VALUE" "120R2F-GP"
					( Origin gFrontEnd )
				)
				( attribute "VER" "1"
					( Origin gFrontEnd )
				)
				( attribute "XY" "(-3025,575)"
					( Origin gFrontEnd )
				)
				( attribute "CHIPS_PART_NAME" "120R2F-GP"
					( Origin gPackager )
				)
				( attribute "CDS_PART_NAME" "120R2F-GP_RCL_GP-120R2F-GP,64.A"
					( Origin gPackager )
				)
				( attribute "PACK_SIZE" "0402"
					( Origin gFrontEnd )
				)
				( attribute "CDS_LOCATION" "R25W23"
					( Origin gPackager )
				)
				( attribute "CDS_SEC" "1"
					( Origin gPackager )
				)
				( objectStatus "R25W23" )
			)
			( gate "@baseboard_fab2_lib.baseboard_fab2(sch_1):page151_i138"
				( attribute "BOM_COST" "SM_CONTROLLER"
					( Origin gFrontEnd )
				)
				( attribute "CDS_LIB" "mstr_discrete"
					( Origin gPackager )
				)
				( attribute "CDS_LOCATION" "R9E24"
					( Origin gPackager )
				)
				( attribute "CDS_SEC" "1"
					( Origin gPackager )
				)
				( attribute "LOCATION" "R9E24"
					( Origin gFrontEnd )
				)
				( attribute "MATERIAL" "CHIP"
					( Origin gFrontEnd )
				)
				( attribute "PACK_TYPE" "0402"
					( Origin gFrontEnd )
				)
				( attribute "PART_NUMBER" "G21796-271"
					( Origin gFrontEnd )
				)
				( attribute "PHYS_PAGE" "151"
					( Origin gFrontEnd )
				)
				( attribute "ROOM" "BMC"
					( Origin gFrontEnd )
				)
				( attribute "ROT" "0"
					( Origin gFrontEnd )
				)
				( attribute "SEC" "1"
					( Origin gFrontEnd )
				)
				( attribute "SEC_TYPE" "0402"
					( Origin gFrontEnd )
				)
				( attribute "TOLERANCE" "1.0%"
					( Origin gFrontEnd )
				)
				( attribute "VALUE" "221"
					( Origin gFrontEnd )
				)
				( attribute "VER" "1"
					( Origin gFrontEnd )
				)
				( attribute "WATTAGE" "1/16W"
					( Origin gFrontEnd )
				)
				( attribute "XY" "(-300,0)"
					( Origin gFrontEnd )
				)
				( attribute "CHIPS_PART_NAME" "RES"
					( Origin gPackager )
				)
				( attribute "CDS_PART_NAME" "RES_0402-221,1.0%,1/16W,CHIP,GA"
					( Origin gPackager )
				)
				( objectStatus "R9E24" )
			)
			( gate "@baseboard_fab2_lib.baseboard_fab2(sch_1):page145_i15"
				( attribute "BOM_COST" "SM_CONTROLLER"
					( Origin gFrontEnd )
				)
				( attribute "CDS_LIB" "dev_discrete"
					( Origin gPackager )
				)
				( attribute "CDS_LOCATION" "C9F23"
					( Origin gPackager )
				)
				( attribute "CDS_SEC" "1"
					( Origin gPackager )
				)
				( attribute "LOCATION" "C9F23"
					( Origin gFrontEnd )
				)
				( attribute "MATERIAL" "X7R"
					( Origin gFrontEnd )
				)
				( attribute "PACK_TYPE" "0402V"
					( Origin gFrontEnd )
				)
				( attribute "PART_NUMBER" "A36096-030"
					( Origin gFrontEnd )
				)
				( attribute "PHYS_PAGE" "145"
					( Origin gFrontEnd )
				)
				( attribute "ROOM" "BMC"
					( Origin gFrontEnd )
				)
				( attribute "ROT" "0"
					( Origin gFrontEnd )
				)
				( attribute "SEC" "1"
					( Origin gFrontEnd )
				)
				( attribute "SEC_TYPE" "0402V"
					( Origin gFrontEnd )
				)
				( attribute "TOLERANCE" "10%"
					( Origin gFrontEnd )
				)
				( attribute "VALUE" "0.1UF"
					( Origin gFrontEnd )
				)
				( attribute "VER" "1"
					( Origin gFrontEnd )
				)
				( attribute "VOLTAGE" "16V"
					( Units "uVoltage" "V" 1.000000)
					( Origin gFrontEnd )
				)
				( attribute "XY" "(-7500,-450)"
					( Origin gFrontEnd )
				)
				( attribute "CHIPS_PART_NAME" "CAP_A"
					( Origin gPackager )
				)
				( attribute "CDS_PART_NAME" "CAP_A_0402V-0.1UF,16V,10%,X7R,A"
					( Origin gPackager )
				)
				( objectStatus "C9F23" )
			)
			( gate "@baseboard_fab2_lib.baseboard_fab2(sch_1):page145_i20"
				( attribute "BOM_COST" "SM_CONTROLLER"
					( Origin gFrontEnd )
				)
				( attribute "CDS_LIB" "mstr_discrete"
					( Origin gPackager )
				)
				( attribute "CDS_LOCATION" "R9F33"
					( Origin gPackager )
				)
				( attribute "CDS_SEC" "1"
					( Origin gPackager )
				)
				( attribute "LOCATION" "R9F33"
					( Origin gFrontEnd )
				)
				( attribute "MATERIAL" "CHIP"
					( Origin gFrontEnd )
				)
				( attribute "PACK_TYPE" "0402"
					( Origin gFrontEnd )
				)
				( attribute "PART_NUMBER" "G21497-005"
					( Origin gFrontEnd )
				)
				( attribute "PHYS_PAGE" "145"
					( Origin gFrontEnd )
				)
				( attribute "ROOM" "BMC"
					( Origin gFrontEnd )
				)
				( attribute "ROT" "0"
					( Origin gFrontEnd )
				)
				( attribute "SEC" "1"
					( Origin gFrontEnd )
				)
				( attribute "SEC_TYPE" "0402"
					( Origin gFrontEnd )
				)
				( attribute "TOLERANCE" "5%"
					( Origin gFrontEnd )
				)
				( attribute "VALUE" "0.0"
					( Origin gFrontEnd )
				)
				( attribute "VER" "1"
					( Origin gFrontEnd )
				)
				( attribute "WATTAGE" "1/16W"
					( Origin gFrontEnd )
				)
				( attribute "XY" "(-6450,-3250)"
					( Origin gFrontEnd )
				)
				( attribute "CHIPS_PART_NAME" "RES"
					( Origin gPackager )
				)
				( attribute "CDS_PART_NAME" "RES_0402-0.0,5%,1/16W,CHIP,G21A"
					( Origin gPackager )
				)
				( objectStatus "R9F33" )
			)
			( gate "@baseboard_fab2_lib.baseboard_fab2(sch_1):page197_i111"
				( attribute "ATTRIBUTE" "665KOHM"
					( Origin gFrontEnd )
				)
				( attribute "CDS_LIB" "w_hdl"
					( Origin gPackager )
				)
				( attribute "CDS_LMAN_SYM_OUTLINE" "-50,75,50,-75"
					( Origin gPackager )
				)
				( attribute "LOCATION" "R12W5"
					( Origin gFrontEnd )
				)
				( attribute "PACK_TYPE" "SMD-RG2"
					( Origin gFrontEnd )
				)
				( attribute "PART_NUMBER" "064.6653D.06DD"
					( Origin gFrontEnd )
				)
				( attribute "PHYS_PAGE" "197"
					( Origin gFrontEnd )
				)
				( attribute "POP" "NOPOP"
					( Origin gFrontEnd )
				)
				( attribute "RATED" "1/16W"
					( Origin gFrontEnd )
				)
				( attribute "ROT" "1"
					( Origin gFrontEnd )
				)
				( attribute "SEC" "1"
					( Origin gFrontEnd )
				)
				( attribute "SEC_TYPE" "SMD-RG2"
					( Origin gFrontEnd )
				)
				( attribute "TOLERANCE" "0.1%"
					( Origin gFrontEnd )
				)
				( attribute "VALUE" "665KR2B-GP"
					( Origin gFrontEnd )
				)
				( attribute "VER" "1"
					( Origin gFrontEnd )
				)
				( attribute "XY" "(-4250,3800)"
					( Origin gFrontEnd )
				)
				( attribute "CHIPS_PART_NAME" "665KR2B-GP"
					( Origin gPackager )
				)
				( attribute "CDS_PART_NAME" "665KR2B-GP_SMD-RG2-665KR2B-GP,A"
					( Origin gPackager )
				)
				( attribute "PACK_SIZE" "0402"
					( Origin gFrontEnd )
				)
				( attribute "CDS_LOCATION" "R12W5"
					( Origin gPackager )
				)
				( attribute "CDS_SEC" "1"
					( Origin gPackager )
				)
				( objectStatus "R12W5" )
			)
			( gate "@baseboard_fab2_lib.baseboard_fab2(sch_1):page147_i162"
				( attribute "BOM_COST" "PROC_SIDEBAND"
					( Origin gFrontEnd )
				)
				( attribute "CDS_LIB" "dev_discrete"
					( Origin gPackager )
				)
				( attribute "CDS_LOCATION" "C25W8"
					( Origin gPackager )
				)
				( attribute "CDS_SEC" "1"
					( Origin gPackager )
				)
				( attribute "LOCATION" "C25W8"
					( Origin gFrontEnd )
				)
				( attribute "MATERIAL" "X7R"
					( Origin gFrontEnd )
				)
				( attribute "PACK_TYPE" "0402V"
					( Origin gFrontEnd )
				)
				( attribute "PART_NUMBER" "A36096-030"
					( Origin gFrontEnd )
				)
				( attribute "PHYS_PAGE" "147"
					( Origin gFrontEnd )
				)
				( attribute "ROOM" "PROC_SIDEBAND"
					( Origin gFrontEnd )
				)
				( attribute "ROT" "1"
					( Origin gFrontEnd )
				)
				( attribute "SEC" "1"
					( Origin gFrontEnd )
				)
				( attribute "SEC_TYPE" "0402V"
					( Origin gFrontEnd )
				)
				( attribute "TOLERANCE" "10%"
					( Origin gFrontEnd )
				)
				( attribute "VALUE" "0.1UF"
					( Origin gFrontEnd )
				)
				( attribute "VER" "1"
					( Origin gFrontEnd )
				)
				( attribute "VOLTAGE" "16V"
					( Units "uVoltage" "V" 1.000000)
					( Origin gFrontEnd )
				)
				( attribute "XY" "(2000,1950)"
					( Origin gFrontEnd )
				)
				( attribute "CHIPS_PART_NAME" "CAP_A"
					( Origin gPackager )
				)
				( attribute "CDS_PART_NAME" "CAP_A_0402V-0.1UF,16V,10%,X7R,A"
					( Origin gPackager )
				)
				( objectStatus "C25W8" )
			)
			( gate "@baseboard_fab2_lib.baseboard_fab2(sch_1):page145_i30"
				( attribute "BOM_COST" "SM_CONTROLLER"
					( Origin gFrontEnd )
				)
				( attribute "CDS_LIB" "mstr_discrete"
					( Origin gPackager )
				)
				( attribute "CDS_LOCATION" "R25W61"
					( Origin gPackager )
				)
				( attribute "CDS_SEC" "1"
					( Origin gPackager )
				)
				( attribute "LOCATION" "R25W61"
					( Origin gFrontEnd )
				)
				( attribute "MATERIAL" "CHIP"
					( Origin gFrontEnd )
				)
				( attribute "PACK_TYPE" "0402"
					( Origin gFrontEnd )
				)
				( attribute "PART_NUMBER" "G21796-010"
					( Origin gFrontEnd )
				)
				( attribute "PHYS_PAGE" "145"
					( Origin gFrontEnd )
				)
				( attribute "ROOM" "BMC"
					( Origin gFrontEnd )
				)
				( attribute "ROT" "0"
					( Origin gFrontEnd )
				)
				( attribute "SEC" "1"
					( Origin gFrontEnd )
				)
				( attribute "SEC_TYPE" "0402"
					( Origin gFrontEnd )
				)
				( attribute "TOLERANCE" "1%"
					( Origin gFrontEnd )
				)
				( attribute "VALUE" "100.0K"
					( Origin gFrontEnd )
				)
				( attribute "VER" "2"
					( Origin gFrontEnd )
				)
				( attribute "WATTAGE" "1/16W"
					( Origin gFrontEnd )
				)
				( attribute "XY" "(-5450,-4150)"
					( Origin gFrontEnd )
				)
				( attribute "CHIPS_PART_NAME" "RES"
					( Origin gPackager )
				)
				( attribute "CDS_PART_NAME" "RES_0402-100.0K,1%,1/16W,CHIP,A"
					( Origin gPackager )
				)
				( attribute "GROUP" "AST2520"
					( Origin gFrontEnd )
				)
				( objectStatus "R25W61" )
			)
			( gate "@baseboard_fab2_lib.baseboard_fab2(sch_1):page145_i31"
				( attribute "BOM_COST" "SM_CONTROLLER"
					( Origin gFrontEnd )
				)
				( attribute "CDS_LIB" "mstr_discrete"
					( Origin gPackager )
				)
				( attribute "CDS_LOCATION" "R25W62"
					( Origin gPackager )
				)
				( attribute "CDS_SEC" "1"
					( Origin gPackager )
				)
				( attribute "LOCATION" "R25W62"
					( Origin gFrontEnd )
				)
				( attribute "MATERIAL" "CHIP"
					( Origin gFrontEnd )
				)
				( attribute "PACK_TYPE" "0402"
					( Origin gFrontEnd )
				)
				( attribute "PART_NUMBER" "G21796-010"
					( Origin gFrontEnd )
				)
				( attribute "PHYS_PAGE" "145"
					( Origin gFrontEnd )
				)
				( attribute "ROOM" "BMC"
					( Origin gFrontEnd )
				)
				( attribute "ROT" "0"
					( Origin gFrontEnd )
				)
				( attribute "SEC" "1"
					( Origin gFrontEnd )
				)
				( attribute "SEC_TYPE" "0402"
					( Origin gFrontEnd )
				)
				( attribute "TOLERANCE" "1%"
					( Origin gFrontEnd )
				)
				( attribute "VALUE" "100.0K"
					( Origin gFrontEnd )
				)
				( attribute "VER" "2"
					( Origin gFrontEnd )
				)
				( attribute "WATTAGE" "1/16W"
					( Origin gFrontEnd )
				)
				( attribute "XY" "(-5200,-4150)"
					( Origin gFrontEnd )
				)
				( attribute "CHIPS_PART_NAME" "RES"
					( Origin gPackager )
				)
				( attribute "CDS_PART_NAME" "RES_0402-100.0K,1%,1/16W,CHIP,A"
					( Origin gPackager )
				)
				( attribute "GROUP" "AST2520"
					( Origin gFrontEnd )
				)
				( objectStatus "R25W62" )
			)
			( gate "@baseboard_fab2_lib.baseboard_fab2(sch_1):page151_i69"
				( attribute "CHIPS_PART_NAME" "TTL1G07_A"
					( Origin gPackager )
				)
			)
			( gate "@baseboard_fab2_lib.baseboard_fab2(sch_1):page146_i197"
				( attribute "CHIPS_PART_NAME" "TTL1G07_A"
					( Origin gPackager )
				)
			)
			( gate "@baseboard_fab2_lib.baseboard_fab2(sch_1):page247_i100"
				( attribute "BOM_COST" "SM_THERM"
					( Origin gFrontEnd )
				)
				( attribute "CDS_LIB" "mstr_discrete"
					( Origin gPackager )
				)
				( attribute "LOCATION" "R6W24"
					( Origin gFrontEnd )
				)
				( attribute "MATERIAL" "CHIP"
					( Origin gFrontEnd )
				)
				( attribute "PACK_TYPE" "0402"
					( Origin gFrontEnd )
				)
				( attribute "PART_NUMBER" "G21796-072"
					( Origin gFrontEnd )
				)
				( attribute "PHYS_PAGE" "247"
					( Origin gFrontEnd )
				)
				( attribute "ROOM" "CPU_FANS"
					( Origin gFrontEnd )
				)
				( attribute "ROT" "2"
					( Origin gFrontEnd )
				)
				( attribute "TOLERANCE" "1%"
					( Origin gFrontEnd )
				)
				( attribute "VALUE" "4.75K"
					( Origin gFrontEnd )
				)
				( attribute "VER" "2"
					( Origin gFrontEnd )
				)
				( attribute "WATTAGE" "1/16W"
					( Origin gFrontEnd )
				)
				( attribute "XY" "(-7550,1950)"
					( Origin gFrontEnd )
				)
				( attribute "CHIPS_PART_NAME" "RES"
					( Origin gPackager )
				)
				( attribute "CDS_PART_NAME" "RES_0402-4.75K,1%,1/16W,CHIP,GA"
					( Origin gPackager )
				)
				( attribute "CDS_LOCATION" "R6W24"
					( Origin gPackager )
				)
				( attribute "SEC" "1"
					( Origin gFrontEnd )
				)
				( attribute "SEC_TYPE" "0402"
					( Origin gFrontEnd )
				)
				( attribute "CDS_SEC" "1"
					( Origin gPackager )
				)
				( objectStatus "R6W24" )
			)
			( gate "@baseboard_fab2_lib.baseboard_fab2(sch_1):page150_i190"
				( attribute "BOM_COST" "SM_CONTROLLER"
					( Origin gFrontEnd )
				)
				( attribute "CDS_LIB" "mstr_discrete"
					( Origin gPackager )
				)
				( attribute "CDS_LOCATION" "R25W107"
					( Origin gPackager )
				)
				( attribute "CDS_SEC" "1"
					( Origin gPackager )
				)
				( attribute "LOCATION" "R25W107"
					( Origin gFrontEnd )
				)
				( attribute "MATERIAL" "CHIP"
					( Origin gFrontEnd )
				)
				( attribute "PACK_TYPE" "0402"
					( Origin gFrontEnd )
				)
				( attribute "PART_NUMBER" "G21796-072"
					( Origin gFrontEnd )
				)
				( attribute "PHYS_PAGE" "150"
					( Origin gFrontEnd )
				)
				( attribute "ROOM" "BMC"
					( Origin gFrontEnd )
				)
				( attribute "ROT" "0"
					( Origin gFrontEnd )
				)
				( attribute "SEC" "1"
					( Origin gFrontEnd )
				)
				( attribute "SEC_TYPE" "0402"
					( Origin gFrontEnd )
				)
				( attribute "TOLERANCE" "1%"
					( Origin gFrontEnd )
				)
				( attribute "VALUE" "4.75K"
					( Origin gFrontEnd )
				)
				( attribute "VER" "1"
					( Origin gFrontEnd )
				)
				( attribute "WATTAGE" "1/16W"
					( Origin gFrontEnd )
				)
				( attribute "XY" "(-600,-1900)"
					( Origin gFrontEnd )
				)
				( attribute "CHIPS_PART_NAME" "RES"
					( Origin gPackager )
				)
				( attribute "CDS_PART_NAME" "RES_0402-4.75K,1%,1/16W,CHIP,GA"
					( Origin gPackager )
				)
				( objectStatus "R25W107" )
			)
			( gate "@baseboard_fab2_lib.baseboard_fab2(sch_1):page157_i393"
				( attribute "BOM_COST" "MEM_NV"
					( Origin gFrontEnd )
				)
				( attribute "CDS_LIB" "mstr_discrete"
					( Origin gPackager )
				)
				( attribute "CDS_LOCATION" "R9E14"
					( Origin gPackager )
				)
				( attribute "CDS_SEC" "1"
					( Origin gPackager )
				)
				( attribute "LOCATION" "R9E14"
					( Origin gFrontEnd )
				)
				( attribute "MATERIAL" "EMPTY"
					( Origin gFrontEnd )
				)
				( attribute "PACK_TYPE" "0402"
					( Origin gFrontEnd )
				)
				( attribute "PART_NUMBER" "G21497-005"
					( Origin gFrontEnd )
				)
				( attribute "PHYS_PAGE" "157"
					( Origin gFrontEnd )
				)
				( attribute "ROOM" "NV_DIMM"
					( Origin gFrontEnd )
				)
				( attribute "ROT" "0"
					( Origin gFrontEnd )
				)
				( attribute "SEC" "1"
					( Origin gFrontEnd )
				)
				( attribute "SEC_TYPE" "0402"
					( Origin gFrontEnd )
				)
				( attribute "TOLERANCE" "5%"
					( Origin gFrontEnd )
				)
				( attribute "VALUE" "0.0"
					( Origin gFrontEnd )
				)
				( attribute "VER" "1"
					( Origin gFrontEnd )
				)
				( attribute "WATTAGE" "1/16W"
					( Origin gFrontEnd )
				)
				( attribute "XY" "(-1450,875)"
					( Origin gFrontEnd )
				)
				( attribute "CHIPS_PART_NAME" "RES"
					( Origin gPackager )
				)
				( attribute "CDS_PART_NAME" "RES_0402-0.0,5%,1/16W,EMPTY,G2A"
					( Origin gPackager )
				)
				( objectStatus "R9E14" )
			)
			( gate "@baseboard_fab2_lib.baseboard_fab2(sch_1):page219_i153"
				( attribute "ATTRIBUTE" "1 OHM"
					( Origin gFrontEnd )
				)
				( attribute "CDS_LIB" "w_hdl"
					( Origin gPackager )
				)
				( attribute "CDS_LMAN_SYM_OUTLINE" "-50,75,50,-75"
					( Origin gPackager )
				)
				( attribute "LOCATION" "RT29"
					( Origin gFrontEnd )
				)
				( attribute "PACK_TYPE" "RCL_GP"
					( Origin gFrontEnd )
				)
				( attribute "PART_NUMBER" "64.1R005.55L"
					( Origin gFrontEnd )
				)
				( attribute "PHYS_PAGE" "219"
					( Origin gFrontEnd )
				)
				( attribute "POP" "NOPOP"
					( Origin gFrontEnd )
				)
				( attribute "RATED" "1/10W"
					( Origin gFrontEnd )
				)
				( attribute "ROT" "0"
					( Origin gFrontEnd )
				)
				( attribute "SEC" "1"
					( Origin gFrontEnd )
				)
				( attribute "SEC_TYPE" "RCL_GP"
					( Origin gFrontEnd )
				)
				( attribute "TOLERANCE" "1%"
					( Origin gFrontEnd )
				)
				( attribute "VALUE" "1R3F-GP"
					( Origin gFrontEnd )
				)
				( attribute "VER" "1"
					( Origin gFrontEnd )
				)
				( attribute "XY" "(2850,1325)"
					( Origin gFrontEnd )
				)
				( attribute "CHIPS_PART_NAME" "1R3F-GP"
					( Origin gPackager )
				)
				( attribute "CDS_PART_NAME" "1R3F-GP_RCL_GP-1R3F-GP,64.1R00A"
					( Origin gPackager )
				)
				( attribute "PACK_SIZE" "0603"
					( Origin gFrontEnd )
				)
				( attribute "CDS_LOCATION" "RT29"
					( Origin gPackager )
				)
				( attribute "CDS_SEC" "1"
					( Origin gPackager )
				)
				( objectStatus "RT29" )
			)
			( gate "@baseboard_fab2_lib.baseboard_fab2(sch_1):page151_i55"
				( attribute "BOM_COST" "SM_MEM"
					( Origin gFrontEnd )
				)
				( attribute "CDS_LIB" "mstr_discrete"
					( Origin gPackager )
				)
				( attribute "CDS_LOCATION" "R9F29"
					( Origin gPackager )
				)
				( attribute "CDS_SEC" "1"
					( Origin gPackager )
				)
				( attribute "LOCATION" "R9F29"
					( Origin gFrontEnd )
				)
				( attribute "MATERIAL" "CHIP"
					( Origin gFrontEnd )
				)
				( attribute "PACK_TYPE" "0402"
					( Origin gFrontEnd )
				)
				( attribute "PART_NUMBER" "G21796-072"
					( Origin gFrontEnd )
				)
				( attribute "PHYS_PAGE" "151"
					( Origin gFrontEnd )
				)
				( attribute "ROOM" "BMC_MEMORY"
					( Origin gFrontEnd )
				)
				( attribute "ROT" "0"
					( Origin gFrontEnd )
				)
				( attribute "SEC" "1"
					( Origin gFrontEnd )
				)
				( attribute "SEC_TYPE" "0402"
					( Origin gFrontEnd )
				)
				( attribute "TOLERANCE" "1%"
					( Origin gFrontEnd )
				)
				( attribute "VALUE" "4.75K"
					( Origin gFrontEnd )
				)
				( attribute "VER" "2"
					( Origin gFrontEnd )
				)
				( attribute "WATTAGE" "1/16W"
					( Origin gFrontEnd )
				)
				( attribute "XY" "(2775,2150)"
					( Origin gFrontEnd )
				)
				( attribute "CHIPS_PART_NAME" "RES"
					( Origin gPackager )
				)
				( attribute "CDS_PART_NAME" "RES_0402-4.75K,1%,1/16W,CHIP,GA"
					( Origin gPackager )
				)
				( attribute "POP" "NOPOP"
					( Origin gFrontEnd )
				)
				( objectStatus "R9F29" )
			)
			( gate "@baseboard_fab2_lib.baseboard_fab2(sch_1):page150_i144"
				( attribute "BOM_COST" "SM_CONTROLLER"
					( Origin gFrontEnd )
				)
				( attribute "CDS_LIB" "mstr_discrete"
					( Origin gPackager )
				)
				( attribute "CDS_LOCATION" "R25W95"
					( Origin gPackager )
				)
				( attribute "LOCATION" "R25W95"
					( Origin gFrontEnd )
				)
				( attribute "MATERIAL" "CHIP"
					( Origin gFrontEnd )
				)
				( attribute "PACK_TYPE" "0402"
					( Origin gFrontEnd )
				)
				( attribute "PART_NUMBER" "G21796-072"
					( Origin gFrontEnd )
				)
				( attribute "PHYS_PAGE" "150"
					( Origin gFrontEnd )
				)
				( attribute "ROOM" "BMC"
					( Origin gFrontEnd )
				)
				( attribute "ROT" "0"
					( Origin gFrontEnd )
				)
				( attribute "SEC" "1"
					( Origin gFrontEnd )
				)
				( attribute "TOLERANCE" "1%"
					( Origin gFrontEnd )
				)
				( attribute "VALUE" "4.75K"
					( Origin gFrontEnd )
				)
				( attribute "VER" "1"
					( Origin gFrontEnd )
				)
				( attribute "WATTAGE" "1/16W"
					( Origin gFrontEnd )
				)
				( attribute "XY" "(-600,200)"
					( Origin gFrontEnd )
				)
				( attribute "CHIPS_PART_NAME" "RES"
					( Origin gPackager )
				)
				( attribute "CDS_PART_NAME" "RES_0402-4.75K,1%,1/16W,CHIP,GA"
					( Origin gPackager )
				)
				( attribute "SEC_TYPE" "0402"
					( Origin gFrontEnd )
				)
				( attribute "CDS_SEC" "1"
					( Origin gPackager )
				)
				( objectStatus "R25W95" )
			)
			( gate "@baseboard_fab2_lib.baseboard_fab2(sch_1):page150_i145"
				( attribute "BOM_COST" "SM_CONTROLLER"
					( Origin gFrontEnd )
				)
				( attribute "CDS_LIB" "mstr_discrete"
					( Origin gPackager )
				)
				( attribute "CDS_LOCATION" "R25W96"
					( Origin gPackager )
				)
				( attribute "LOCATION" "R25W96"
					( Origin gFrontEnd )
				)
				( attribute "MATERIAL" "CHIP"
					( Origin gFrontEnd )
				)
				( attribute "PACK_TYPE" "0402"
					( Origin gFrontEnd )
				)
				( attribute "PART_NUMBER" "G21796-072"
					( Origin gFrontEnd )
				)
				( attribute "PHYS_PAGE" "150"
					( Origin gFrontEnd )
				)
				( attribute "ROOM" "BMC"
					( Origin gFrontEnd )
				)
				( attribute "ROT" "0"
					( Origin gFrontEnd )
				)
				( attribute "SEC" "1"
					( Origin gFrontEnd )
				)
				( attribute "TOLERANCE" "1%"
					( Origin gFrontEnd )
				)
				( attribute "VALUE" "4.75K"
					( Origin gFrontEnd )
				)
				( attribute "VER" "1"
					( Origin gFrontEnd )
				)
				( attribute "WATTAGE" "1/16W"
					( Origin gFrontEnd )
				)
				( attribute "XY" "(-600,0)"
					( Origin gFrontEnd )
				)
				( attribute "CHIPS_PART_NAME" "RES"
					( Origin gPackager )
				)
				( attribute "CDS_PART_NAME" "RES_0402-4.75K,1%,1/16W,CHIP,GA"
					( Origin gPackager )
				)
				( attribute "SEC_TYPE" "0402"
					( Origin gFrontEnd )
				)
				( attribute "CDS_SEC" "1"
					( Origin gPackager )
				)
				( objectStatus "R25W96" )
			)
			( gate "@baseboard_fab2_lib.baseboard_fab2(sch_1):page150_i146"
				( attribute "BOM_COST" "SM_CONTROLLER"
					( Origin gFrontEnd )
				)
				( attribute "CDS_LIB" "mstr_discrete"
					( Origin gPackager )
				)
				( attribute "CDS_LOCATION" "R25W97"
					( Origin gPackager )
				)
				( attribute "LOCATION" "R25W97"
					( Origin gFrontEnd )
				)
				( attribute "MATERIAL" "EMPTY"
					( Origin gFrontEnd )
				)
				( attribute "PACK_TYPE" "0402"
					( Origin gFrontEnd )
				)
				( attribute "PART_NUMBER" "G21796-072"
					( Origin gFrontEnd )
				)
				( attribute "PHYS_PAGE" "150"
					( Origin gFrontEnd )
				)
				( attribute "ROOM" "BMC"
					( Origin gFrontEnd )
				)
				( attribute "ROT" "0"
					( Origin gFrontEnd )
				)
				( attribute "SEC" "1"
					( Origin gFrontEnd )
				)
				( attribute "TOLERANCE" "1%"
					( Origin gFrontEnd )
				)
				( attribute "VALUE" "4.75K"
					( Origin gFrontEnd )
				)
				( attribute "VER" "1"
					( Origin gFrontEnd )
				)
				( attribute "WATTAGE" "1/16W"
					( Origin gFrontEnd )
				)
				( attribute "XY" "(-600,-200)"
					( Origin gFrontEnd )
				)
				( attribute "CHIPS_PART_NAME" "RES"
					( Origin gPackager )
				)
				( attribute "CDS_PART_NAME" "RES_0402-4.75K,1%,1/16W,EMPTY,A"
					( Origin gPackager )
				)
				( attribute "SEC_TYPE" "0402"
					( Origin gFrontEnd )
				)
				( attribute "CDS_SEC" "1"
					( Origin gPackager )
				)
				( objectStatus "R25W97" )
			)
			( gate "@baseboard_fab2_lib.baseboard_fab2(sch_1):page150_i232"
				( attribute "BOM_COST" "SM_CONTROLLER"
					( Origin gFrontEnd )
				)
				( attribute "CDS_LIB" "mstr_discrete"
					( Origin gPackager )
				)
				( attribute "LOCATION" "R25W151"
					( Origin gFrontEnd )
				)
				( attribute "MATERIAL" "CHIP"
					( Origin gFrontEnd )
				)
				( attribute "PACK_TYPE" "0402"
					( Origin gFrontEnd )
				)
				( attribute "PART_NUMBER" "G21796-072"
					( Origin gFrontEnd )
				)
				( attribute "PHYS_PAGE" "150"
					( Origin gFrontEnd )
				)
				( attribute "ROOM" "BMC"
					( Origin gFrontEnd )
				)
				( attribute "ROT" "0"
					( Origin gFrontEnd )
				)
				( attribute "SEC" "1"
					( Origin gFrontEnd )
				)
				( attribute "SEC_TYPE" "0402"
					( Origin gFrontEnd )
				)
				( attribute "TOLERANCE" "1%"
					( Origin gFrontEnd )
				)
				( attribute "VALUE" "4.75K"
					( Origin gFrontEnd )
				)
				( attribute "VER" "1"
					( Origin gFrontEnd )
				)
				( attribute "WATTAGE" "1/16W"
					( Origin gFrontEnd )
				)
				( attribute "XY" "(-600,-3650)"
					( Origin gFrontEnd )
				)
				( attribute "CHIPS_PART_NAME" "RES"
					( Origin gPackager )
				)
				( attribute "CDS_PART_NAME" "RES_0402-4.75K,1%,1/16W,CHIP,GA"
					( Origin gPackager )
				)
				( attribute "CDS_LOCATION" "R25W151"
					( Origin gPackager )
				)
				( attribute "CDS_SEC" "1"
					( Origin gPackager )
				)
				( objectStatus "R25W151" )
			)
			( gate "@baseboard_fab2_lib.baseboard_fab2(sch_1):page150_i230"
				( attribute "BOM_COST" "SM_CONTROLLER"
					( Origin gFrontEnd )
				)
				( attribute "CDS_LIB" "mstr_discrete"
					( Origin gPackager )
				)
				( attribute "LOCATION" "R25W113"
					( Origin gFrontEnd )
				)
				( attribute "MATERIAL" "EMPTY"
					( Origin gFrontEnd )
				)
				( attribute "PACK_TYPE" "0402"
					( Origin gFrontEnd )
				)
				( attribute "PART_NUMBER" "G21796-072"
					( Origin gFrontEnd )
				)
				( attribute "PHYS_PAGE" "150"
					( Origin gFrontEnd )
				)
				( attribute "ROOM" "BMC"
					( Origin gFrontEnd )
				)
				( attribute "ROT" "0"
					( Origin gFrontEnd )
				)
				( attribute "SEC" "1"
					( Origin gFrontEnd )
				)
				( attribute "SEC_TYPE" "0402"
					( Origin gFrontEnd )
				)
				( attribute "TOLERANCE" "1%"
					( Origin gFrontEnd )
				)
				( attribute "VALUE" "4.75K"
					( Origin gFrontEnd )
				)
				( attribute "VER" "1"
					( Origin gFrontEnd )
				)
				( attribute "WATTAGE" "1/16W"
					( Origin gFrontEnd )
				)
				( attribute "XY" "(-600,-3500)"
					( Origin gFrontEnd )
				)
				( attribute "CHIPS_PART_NAME" "RES"
					( Origin gPackager )
				)
				( attribute "CDS_PART_NAME" "RES_0402-4.75K,1%,1/16W,EMPTY,A"
					( Origin gPackager )
				)
				( attribute "CDS_LOCATION" "R25W113"
					( Origin gPackager )
				)
				( attribute "CDS_SEC" "1"
					( Origin gPackager )
				)
				( objectStatus "R25W113" )
			)
			( gate "@baseboard_fab2_lib.baseboard_fab2(sch_1):page150_i228"
				( attribute "BOM_COST" "SM_CONTROLLER"
					( Origin gFrontEnd )
				)
				( attribute "CDS_LIB" "mstr_discrete"
					( Origin gPackager )
				)
				( attribute "LOCATION" "R25W112"
					( Origin gFrontEnd )
				)
				( attribute "MATERIAL" "EMPTY"
					( Origin gFrontEnd )
				)
				( attribute "PACK_TYPE" "0402"
					( Origin gFrontEnd )
				)
				( attribute "PART_NUMBER" "G21796-072"
					( Origin gFrontEnd )
				)
				( attribute "PHYS_PAGE" "150"
					( Origin gFrontEnd )
				)
				( attribute "ROOM" "BMC"
					( Origin gFrontEnd )
				)
				( attribute "ROT" "0"
					( Origin gFrontEnd )
				)
				( attribute "SEC" "1"
					( Origin gFrontEnd )
				)
				( attribute "SEC_TYPE" "0402"
					( Origin gFrontEnd )
				)
				( attribute "TOLERANCE" "1%"
					( Origin gFrontEnd )
				)
				( attribute "VALUE" "4.75K"
					( Origin gFrontEnd )
				)
				( attribute "VER" "1"
					( Origin gFrontEnd )
				)
				( attribute "WATTAGE" "1/16W"
					( Origin gFrontEnd )
				)
				( attribute "XY" "(-600,-3100)"
					( Origin gFrontEnd )
				)
				( attribute "CHIPS_PART_NAME" "RES"
					( Origin gPackager )
				)
				( attribute "CDS_PART_NAME" "RES_0402-4.75K,1%,1/16W,EMPTY,A"
					( Origin gPackager )
				)
				( attribute "CDS_LOCATION" "R25W112"
					( Origin gPackager )
				)
				( attribute "CDS_SEC" "1"
					( Origin gPackager )
				)
				( objectStatus "R25W112" )
			)
			( gate "@baseboard_fab2_lib.baseboard_fab2(sch_1):page150_i239"
				( attribute "BOM_COST" "SM_CONTROLLER"
					( Origin gFrontEnd )
				)
				( attribute "CDS_LIB" "mstr_discrete"
					( Origin gPackager )
				)
				( attribute "CDS_LOCATION" "R25W102"
					( Origin gPackager )
				)
				( attribute "CDS_SEC" "1"
					( Origin gPackager )
				)
				( attribute "LOCATION" "R25W102"
					( Origin gFrontEnd )
				)
				( attribute "MATERIAL" "EMPTY"
					( Origin gFrontEnd )
				)
				( attribute "PACK_TYPE" "0402"
					( Origin gFrontEnd )
				)
				( attribute "PART_NUMBER" "G21796-072"
					( Origin gFrontEnd )
				)
				( attribute "PHYS_PAGE" "150"
					( Origin gFrontEnd )
				)
				( attribute "ROOM" "BMC"
					( Origin gFrontEnd )
				)
				( attribute "ROT" "0"
					( Origin gFrontEnd )
				)
				( attribute "SEC" "1"
					( Origin gFrontEnd )
				)
				( attribute "SEC_TYPE" "0402"
					( Origin gFrontEnd )
				)
				( attribute "TOLERANCE" "1%"
					( Origin gFrontEnd )
				)
				( attribute "VALUE" "4.75K"
					( Origin gFrontEnd )
				)
				( attribute "VER" "1"
					( Origin gFrontEnd )
				)
				( attribute "WATTAGE" "1/16W"
					( Origin gFrontEnd )
				)
				( attribute "XY" "(1850,-1000)"
					( Origin gFrontEnd )
				)
				( attribute "CHIPS_PART_NAME" "RES"
					( Origin gPackager )
				)
				( attribute "CDS_PART_NAME" "RES_0402-4.75K,1%,1/16W,EMPTY,A"
					( Origin gPackager )
				)
				( objectStatus "R25W102" )
			)
			( gate "@baseboard_fab2_lib.baseboard_fab2(sch_1):page147_i156"
				( attribute "CDS_LIB" "mstr_discrete"
					( Origin gPackager )
				)
				( attribute "CDS_LOCATION" "R25W142"
					( Origin gPackager )
				)
				( attribute "CDS_SEC" "1"
					( Origin gPackager )
				)
				( attribute "LOCATION" "R25W142"
					( Origin gFrontEnd )
				)
				( attribute "MATERIAL" "CHIP"
					( Origin gFrontEnd )
				)
				( attribute "PACK_TYPE" "0402"
					( Origin gFrontEnd )
				)
				( attribute "PART_NUMBER" "G21796-010"
					( Origin gFrontEnd )
				)
				( attribute "PHYS_PAGE" "147"
					( Origin gFrontEnd )
				)
				( attribute "ROT" "0"
					( Origin gFrontEnd )
				)
				( attribute "SEC" "1"
					( Origin gFrontEnd )
				)
				( attribute "SEC_TYPE" "0402"
					( Origin gFrontEnd )
				)
				( attribute "TOLERANCE" "1%"
					( Origin gFrontEnd )
				)
				( attribute "VALUE" "100.0K"
					( Origin gFrontEnd )
				)
				( attribute "VER" "2"
					( Origin gFrontEnd )
				)
				( attribute "WATTAGE" "1/16W"
					( Origin gFrontEnd )
				)
				( attribute "XY" "(-4700,1950)"
					( Origin gFrontEnd )
				)
				( attribute "CHIPS_PART_NAME" "RES"
					( Origin gPackager )
				)
				( attribute "CDS_PART_NAME" "RES_0402-100.0K,1%,1/16W,CHIP,A"
					( Origin gPackager )
				)
				( objectStatus "R25W142" )
			)
			( gate "@baseboard_fab2_lib.baseboard_fab2(sch_1):page150_i175"
				( attribute "BOM_COST" "SM_CONTROLLER"
					( Origin gFrontEnd )
				)
				( attribute "CDS_LIB" "mstr_discrete"
					( Origin gPackager )
				)
				( attribute "CDS_LOCATION" "R25W106"
					( Origin gPackager )
				)
				( attribute "LOCATION" "R25W106"
					( Origin gFrontEnd )
				)
				( attribute "MATERIAL" "EMPTY"
					( Origin gFrontEnd )
				)
				( attribute "PACK_TYPE" "0402"
					( Origin gFrontEnd )
				)
				( attribute "PART_NUMBER" "G21796-072"
					( Origin gFrontEnd )
				)
				( attribute "PHYS_PAGE" "150"
					( Origin gFrontEnd )
				)
				( attribute "ROOM" "BMC"
					( Origin gFrontEnd )
				)
				( attribute "ROT" "0"
					( Origin gFrontEnd )
				)
				( attribute "SEC" "1"
					( Origin gFrontEnd )
				)
				( attribute "TOLERANCE" "1%"
					( Origin gFrontEnd )
				)
				( attribute "VALUE" "4.75K"
					( Origin gFrontEnd )
				)
				( attribute "VER" "1"
					( Origin gFrontEnd )
				)
				( attribute "WATTAGE" "1/16W"
					( Origin gFrontEnd )
				)
				( attribute "XY" "(-600,-1100)"
					( Origin gFrontEnd )
				)
				( attribute "CHIPS_PART_NAME" "RES"
					( Origin gPackager )
				)
				( attribute "CDS_PART_NAME" "RES_0402-4.75K,1%,1/16W,EMPTY,A"
					( Origin gPackager )
				)
				( attribute "SEC_TYPE" "0402"
					( Origin gFrontEnd )
				)
				( attribute "CDS_SEC" "1"
					( Origin gPackager )
				)
				( objectStatus "R25W106" )
			)
			( gate "@baseboard_fab2_lib.baseboard_fab2(sch_1):page207_i112"
				( attribute "ATTRIBUTE" "1 OHM"
					( Origin gFrontEnd )
				)
				( attribute "CDS_LIB" "w_hdl"
					( Origin gPackager )
				)
				( attribute "CDS_LMAN_SYM_OUTLINE" "-50,75,50,-75"
					( Origin gPackager )
				)
				( attribute "LOCATION" "RT18"
					( Origin gFrontEnd )
				)
				( attribute "PACK_TYPE" "RCL_GP"
					( Origin gFrontEnd )
				)
				( attribute "PART_NUMBER" "64.1R005.55L"
					( Origin gFrontEnd )
				)
				( attribute "PHYS_PAGE" "207"
					( Origin gFrontEnd )
				)
				( attribute "POP" "NOPOP"
					( Origin gFrontEnd )
				)
				( attribute "RATED" "1/10W"
					( Origin gFrontEnd )
				)
				( attribute "ROT" "0"
					( Origin gFrontEnd )
				)
				( attribute "SEC" "1"
					( Origin gFrontEnd )
				)
				( attribute "SEC_TYPE" "RCL_GP"
					( Origin gFrontEnd )
				)
				( attribute "TOLERANCE" "1%"
					( Origin gFrontEnd )
				)
				( attribute "VALUE" "1R3F-GP"
					( Origin gFrontEnd )
				)
				( attribute "VER" "1"
					( Origin gFrontEnd )
				)
				( attribute "XY" "(-1925,550)"
					( Origin gFrontEnd )
				)
				( attribute "CHIPS_PART_NAME" "1R3F-GP"
					( Origin gPackager )
				)
				( attribute "CDS_PART_NAME" "1R3F-GP_RCL_GP-1R3F-GP,64.1R00A"
					( Origin gPackager )
				)
				( attribute "PACK_SIZE" "0603"
					( Origin gFrontEnd )
				)
				( attribute "CDS_LOCATION" "RT18"
					( Origin gPackager )
				)
				( attribute "CDS_SEC" "1"
					( Origin gPackager )
				)
				( objectStatus "RT18" )
			)
			( gate "@baseboard_fab2_lib.baseboard_fab2(sch_1):page205_i84"
				( attribute "ATTRIBUTE" "1 OHM"
					( Origin gFrontEnd )
				)
				( attribute "CDS_LIB" "w_hdl"
					( Origin gPackager )
				)
				( attribute "CDS_LMAN_SYM_OUTLINE" "-50,75,50,-75"
					( Origin gPackager )
				)
				( attribute "LOCATION" "RT39"
					( Origin gFrontEnd )
				)
				( attribute "PACK_TYPE" "RCL_GP"
					( Origin gFrontEnd )
				)
				( attribute "PART_NUMBER" "64.1R005.55L"
					( Origin gFrontEnd )
				)
				( attribute "PHYS_PAGE" "205"
					( Origin gFrontEnd )
				)
				( attribute "POP" "NOPOP"
					( Origin gFrontEnd )
				)
				( attribute "RATED" "1/10W"
					( Origin gFrontEnd )
				)
				( attribute "ROT" "0"
					( Origin gFrontEnd )
				)
				( attribute "SEC" "1"
					( Origin gFrontEnd )
				)
				( attribute "SEC_TYPE" "RCL_GP"
					( Origin gFrontEnd )
				)
				( attribute "TOLERANCE" "1%"
					( Origin gFrontEnd )
				)
				( attribute "VALUE" "1R3F-GP"
					( Origin gFrontEnd )
				)
				( attribute "VER" "1"
					( Origin gFrontEnd )
				)
				( attribute "XY" "(-2050,3150)"
					( Origin gFrontEnd )
				)
				( attribute "CHIPS_PART_NAME" "1R3F-GP"
					( Origin gPackager )
				)
				( attribute "CDS_PART_NAME" "1R3F-GP_RCL_GP-1R3F-GP,64.1R00A"
					( Origin gPackager )
				)
				( attribute "PACK_SIZE" "0603"
					( Origin gFrontEnd )
				)
				( attribute "CDS_LOCATION" "RT39"
					( Origin gPackager )
				)
				( attribute "CDS_SEC" "1"
					( Origin gPackager )
				)
				( objectStatus "RT39" )
			)
			( gate "@baseboard_fab2_lib.baseboard_fab2(sch_1):page151_i49"
				( attribute "CDS_LIB" "w_hdl"
					( Origin gPackager )
				)
				( attribute "CDS_LMAN_SYM_OUTLINE" "-325,1525,325,-1525"
					( Origin gPackager )
				)
				( attribute "CDS_LOCATION" "U25W5"
					( Origin gPackager )
				)
				( attribute "CDS_SEC" "1"
					( Origin gPackager )
				)
				( attribute "LOCATION" "U25W5"
					( Origin gFrontEnd )
				)
				( attribute "PACK_TYPE" "MEMORY-G2"
					( Origin gFrontEnd )
				)
				( attribute "PART_NUMBER" "072.00546.0A0U"
					( Origin gFrontEnd )
				)
				( attribute "PHYS_PAGE" "151"
					( Origin gFrontEnd )
				)
				( attribute "ROT" "0"
					( Origin gFrontEnd )
				)
				( attribute "SEC" "1"
					( Origin gPackager )
				)
				( attribute "VALUE" "H5AN4G6NAFR-TFC-GP"
					( Origin gFrontEnd )
				)
				( attribute "VER" "1"
					( Origin gFrontEnd )
				)
				( attribute "XY" "(2650,25)"
					( Origin gFrontEnd )
				)
				( attribute "CHIPS_PART_NAME" "H5AN4G6NAFR-TFC-GP"
					( Origin gPackager )
				)
				( attribute "CDS_PART_NAME" "H5AN4G6NAFR-TFC-GP_MEMORY-G2-HA"
					( Origin gPackager )
				)
				( objectStatus "U25W5" )
			)
			( gate "@baseboard_fab2_lib.baseboard_fab2(sch_1):page155_i196"
				( attribute "BOM_COST" "DEBUG"
					( Origin gFrontEnd )
				)
				( attribute "CDS_LIB" "mstr_discrete"
					( Origin gPackager )
				)
				( attribute "LOCATION" "R6W19"
					( Origin gFrontEnd )
				)
				( attribute "MATERIAL" "CHIP"
					( Origin gFrontEnd )
				)
				( attribute "PACK_TYPE" "0402"
					( Origin gFrontEnd )
				)
				( attribute "PART_NUMBER" "G21497-005"
					( Origin gFrontEnd )
				)
				( attribute "PHYS_PAGE" "155"
					( Origin gFrontEnd )
				)
				( attribute "ROOM" "BMC_DEBUG_HEADER"
					( Origin gFrontEnd )
				)
				( attribute "ROT" "0"
					( Origin gFrontEnd )
				)
				( attribute "TOLERANCE" "5%"
					( Origin gFrontEnd )
				)
				( attribute "VALUE" "0.0"
					( Origin gFrontEnd )
				)
				( attribute "VER" "1"
					( Origin gFrontEnd )
				)
				( attribute "WATTAGE" "1/16W"
					( Origin gFrontEnd )
				)
				( attribute "XY" "(-1950,1775)"
					( Origin gFrontEnd )
				)
				( attribute "CHIPS_PART_NAME" "RES"
					( Origin gPackager )
				)
				( attribute "CDS_PART_NAME" "RES_0402-0.0,5%,1/16W,CHIP,G21A"
					( Origin gPackager )
				)
				( attribute "CDS_LOCATION" "R6W19"
					( Origin gPackager )
				)
				( attribute "SEC" "1"
					( Origin gFrontEnd )
				)
				( attribute "POP" "NOPOP"
					( Origin gFrontEnd )
				)
				( attribute "SEC_TYPE" "0402"
					( Origin gFrontEnd )
				)
				( attribute "CDS_SEC" "1"
					( Origin gPackager )
				)
				( objectStatus "R6W19" )
			)
			( gate "@baseboard_fab2_lib.baseboard_fab2(sch_1):page146_i68"
				( attribute "BOM_COST" "SM_CONTROLLER"
					( Origin gFrontEnd )
				)
				( attribute "CDS_LIB" "mstr_discrete"
					( Origin gPackager )
				)
				( attribute "CDS_LOCATION" "R25W82"
					( Origin gPackager )
				)
				( attribute "LOCATION" "R25W82"
					( Origin gFrontEnd )
				)
				( attribute "MATERIAL" "CHIP"
					( Origin gFrontEnd )
				)
				( attribute "PACK_TYPE" "0402"
					( Origin gFrontEnd )
				)
				( attribute "PART_NUMBER" "G21796-074"
					( Origin gFrontEnd )
				)
				( attribute "PHYS_PAGE" "146"
					( Origin gFrontEnd )
				)
				( attribute "ROOM" "BMC"
					( Origin gFrontEnd )
				)
				( attribute "ROT" "0"
					( Origin gFrontEnd )
				)
				( attribute "SEC" "1"
					( Origin gFrontEnd )
				)
				( attribute "SEC_TYPE" "0402"
					( Origin gFrontEnd )
				)
				( attribute "TOLERANCE" "1%"
					( Origin gFrontEnd )
				)
				( attribute "VALUE" "33.2"
					( Origin gFrontEnd )
				)
				( attribute "VER" "1"
					( Origin gFrontEnd )
				)
				( attribute "WATTAGE" "1/16W"
					( Origin gFrontEnd )
				)
				( attribute "XY" "(-6350,2500)"
					( Origin gFrontEnd )
				)
				( attribute "CHIPS_PART_NAME" "RES"
					( Origin gPackager )
				)
				( attribute "CDS_PART_NAME" "RES_0402-33.2,1%,1/16W,CHIP,G2A"
					( Origin gPackager )
				)
				( attribute "CDS_SEC" "1"
					( Origin gPackager )
				)
				( objectStatus "R25W82" )
			)
			( gate "@baseboard_fab2_lib.baseboard_fab2(sch_1):page149_i1"
				( attribute "CDS_LIB" "mstr_discrete"
					( Origin gPackager )
				)
				( attribute "CDS_LOCATION" "C25W30"
					( Origin gPackager )
				)
				( attribute "CDS_SEC" "1"
					( Origin gPackager )
				)
				( attribute "LOCATION" "C25W30"
					( Origin gFrontEnd )
				)
				( attribute "MATERIAL" "X6S"
					( Origin gFrontEnd )
				)
				( attribute "PACK_TYPE" "0603"
					( Origin gFrontEnd )
				)
				( attribute "PART_NUMBER" "E15431-003"
					( Origin gFrontEnd )
				)
				( attribute "PHYS_PAGE" "149"
					( Origin gFrontEnd )
				)
				( attribute "ROT" "0"
					( Origin gFrontEnd )
				)
				( attribute "SEC" "1"
					( Origin gPackager )
				)
				( attribute "TOLERANCE" "10%"
					( Origin gFrontEnd )
				)
				( attribute "VALUE" "4.7UF"
					( Origin gFrontEnd )
				)
				( attribute "VER" "1"
					( Origin gFrontEnd )
				)
				( attribute "VOLTAGE" "6.3V"
					( Units "uVoltage" "V" 1.000000)
					( Origin gFrontEnd )
				)
				( attribute "XY" "(550,5400)"
					( Origin gFrontEnd )
				)
				( attribute "CHIPS_PART_NAME" "CAP"
					( Origin gPackager )
				)
				( attribute "CDS_PART_NAME" "CAP_0603-4.7UF,6.3V,10%,X6S,E1A"
					( Origin gPackager )
				)
				( objectStatus "C25W30" )
			)
			( gate "@baseboard_fab2_lib.baseboard_fab2(sch_1):page239_i73"
				( attribute "CDS_LIB" "mstr_vreg"
					( Origin gPackager )
				)
				( attribute "LOCATION" "EU25F2"
					( Origin gFrontEnd )
				)
				( attribute "MATERIAL" "IC"
					( Origin gFrontEnd )
				)
				( attribute "PACK_TYPE" "DFN"
					( Origin gFrontEnd )
				)
				( attribute "PART_NUMBER" "H65765-001"
					( Origin gFrontEnd )
				)
				( attribute "PHYS_PAGE" "239"
					( Origin gFrontEnd )
				)
				( attribute "ROT" "0"
					( Origin gFrontEnd )
				)
				( attribute "VER" "1"
					( Origin gFrontEnd )
				)
				( attribute "XY" "(8425,1700)"
					( Origin gFrontEnd )
				)
				( attribute "CHIPS_PART_NAME" "RT9059"
					( Origin gPackager )
				)
				( attribute "CDS_PART_NAME" "RT9059_DFN-IC,H65765-001"
					( Origin gPackager )
				)
				( attribute "CDS_LOCATION" "EU25F2"
					( Origin gPackager )
				)
				( attribute "CDS_SEC" "1"
					( Origin gPackager )
				)
				( attribute "SEC" "1"
					( Origin gPackager )
				)
				( objectStatus "EU25F2" )
			)
			( gate "@baseboard_fab2_lib.baseboard_fab2(sch_1):page239_i77"
				( attribute "CDS_LIB" "mstr_discrete"
					( Origin gPackager )
				)
				( attribute "LOCATION" "R1W9"
					( Origin gFrontEnd )
				)
				( attribute "MATERIAL" "CHIP"
					( Origin gFrontEnd )
				)
				( attribute "PACK_TYPE" "0402"
					( Origin gFrontEnd )
				)
				( attribute "PART_NUMBER" "G21796-250"
					( Origin gFrontEnd )
				)
				( attribute "PHYS_PAGE" "239"
					( Origin gFrontEnd )
				)
				( attribute "ROOM" "P1V538_BMC_STBY_VR"
					( Origin gFrontEnd )
				)
				( attribute "ROT" "0"
					( Origin gFrontEnd )
				)
				( attribute "TOLERANCE" "1.0%"
					( Origin gFrontEnd )
				)
				( attribute "VALUE" "22.1"
					( Origin gFrontEnd )
				)
				( attribute "VER" "1"
					( Origin gFrontEnd )
				)
				( attribute "WATTAGE" "1/16W"
					( Origin gFrontEnd )
				)
				( attribute "XY" "(10275,2200)"
					( Origin gFrontEnd )
				)
				( attribute "CHIPS_PART_NAME" "RES"
					( Origin gPackager )
				)
				( attribute "CDS_PART_NAME" "RES_0402-22.1,1.0%,1/16W,CHIP,A"
					( Origin gPackager )
				)
				( attribute "CDS_LOCATION" "R1W9"
					( Origin gPackager )
				)
				( attribute "SEC" "1"
					( Origin gFrontEnd )
				)
				( attribute "SEC_TYPE" "0402"
					( Origin gFrontEnd )
				)
				( attribute "CDS_SEC" "1"
					( Origin gPackager )
				)
				( objectStatus "R1W9" )
			)
			( gate "@baseboard_fab2_lib.baseboard_fab2(sch_1):page239_i79"
				( attribute "BOM_COST" "P1V538_BMC_STBY_VR"
					( Origin gFrontEnd )
				)
				( attribute "CDS_LIB" "mstr_discrete"
					( Origin gPackager )
				)
				( attribute "LOCATION" "R9W12"
					( Origin gFrontEnd )
				)
				( attribute "MATERIAL" "CHIP"
					( Origin gFrontEnd )
				)
				( attribute "P1V5_STBY_IBMC" "<< NULL >>"
					( Origin gFrontEnd )
				)
				( attribute "P1V5_STBY_IBMC_VR" "<< NULL >>"
					( Origin gFrontEnd )
				)
				( attribute "PACK_TYPE" "0402"
					( Origin gFrontEnd )
				)
				( attribute "PART_NUMBER" "G21796-016"
					( Origin gFrontEnd )
				)
				( attribute "PHYS_PAGE" "239"
					( Origin gFrontEnd )
				)
				( attribute "ROOM" "P1V538_BMC_STBY_VR"
					( Origin gFrontEnd )
				)
				( attribute "ROT" "0"
					( Origin gFrontEnd )
				)
				( attribute "TOLERANCE" "1%"
					( Origin gFrontEnd )
				)
				( attribute "VALUE" "10.0K"
					( Origin gFrontEnd )
				)
				( attribute "VER" "2"
					( Origin gFrontEnd )
				)
				( attribute "WATTAGE" "1/16W"
					( Origin gFrontEnd )
				)
				( attribute "XY" "(9200,2450)"
					( Origin gFrontEnd )
				)
				( attribute "CHIPS_PART_NAME" "RES"
					( Origin gPackager )
				)
				( attribute "CDS_PART_NAME" "RES_0402-10.0K,1%,1/16W,CHIP,GA"
					( Origin gPackager )
				)
				( attribute "CDS_LOCATION" "R9W12"
					( Origin gPackager )
				)
				( attribute "SEC" "1"
					( Origin gFrontEnd )
				)
				( attribute "SEC_TYPE" "0402"
					( Origin gFrontEnd )
				)
				( attribute "CDS_SEC" "1"
					( Origin gPackager )
				)
				( objectStatus "R9W12" )
			)
			( gate "@baseboard_fab2_lib.baseboard_fab2(sch_1):page239_i81"
				( attribute "BOM_COST" "P1V538_BMC_STBY_VR"
					( Origin gFrontEnd )
				)
				( attribute "CDS_LIB" "mstr_discrete"
					( Origin gPackager )
				)
				( attribute "LOCATION" "C9W13"
					( Origin gFrontEnd )
				)
				( attribute "MATERIAL" "X6S"
					( Origin gFrontEnd )
				)
				( attribute "PACK_TYPE" "0805LF"
					( Origin gFrontEnd )
				)
				( attribute "PART_NUMBER" "C95333-002"
					( Origin gFrontEnd )
				)
				( attribute "PHYS_PAGE" "239"
					( Origin gFrontEnd )
				)
				( attribute "ROOM" "P1V538_BMC_STBY_VR"
					( Origin gFrontEnd )
				)
				( attribute "ROT" "0"
					( Origin gFrontEnd )
				)
				( attribute "TOLERANCE" "20%"
					( Origin gFrontEnd )
				)
				( attribute "VALUE" "22UF"
					( Origin gFrontEnd )
				)
				( attribute "VER" "1"
					( Origin gFrontEnd )
				)
				( attribute "VOLTAGE" "4V"
					( Units "uVoltage" "V" 1.000000)
					( Origin gFrontEnd )
				)
				( attribute "XY" "(11300,1500)"
					( Origin gFrontEnd )
				)
				( attribute "CHIPS_PART_NAME" "CAP"
					( Origin gPackager )
				)
				( attribute "CDS_PART_NAME" "CAP_0805LF-22UF,4V,20%,X6S,C95A"
					( Origin gPackager )
				)
				( attribute "CDS_LOCATION" "C9W13"
					( Origin gPackager )
				)
				( attribute "SEC" "1"
					( Origin gFrontEnd )
				)
				( attribute "SEC_TYPE" "0805LF"
					( Origin gFrontEnd )
				)
				( attribute "CDS_SEC" "1"
					( Origin gPackager )
				)
				( objectStatus "C9W13" )
			)
			( gate "@baseboard_fab2_lib.baseboard_fab2(sch_1):page239_i83"
				( attribute "BOM_COST" "P1V538_BMC_STBY_VR"
					( Origin gFrontEnd )
				)
				( attribute "CDS_LIB" "mstr_discrete"
					( Origin gPackager )
				)
				( attribute "LOCATION" "C1W15"
					( Origin gFrontEnd )
				)
				( attribute "MATERIAL" "X6S"
					( Origin gFrontEnd )
				)
				( attribute "PACK_TYPE" "0603"
					( Origin gFrontEnd )
				)
				( attribute "PART_NUMBER" "E15431-002"
					( Origin gFrontEnd )
				)
				( attribute "PHYS_PAGE" "239"
					( Origin gFrontEnd )
				)
				( attribute "ROOM" "P1V538_BMC_STBY_VR"
					( Origin gFrontEnd )
				)
				( attribute "ROT" "0"
					( Origin gFrontEnd )
				)
				( attribute "TOLERANCE" "20%"
					( Origin gFrontEnd )
				)
				( attribute "VALUE" "10UF"
					( Origin gFrontEnd )
				)
				( attribute "VER" "1"
					( Origin gFrontEnd )
				)
				( attribute "VOLTAGE" "6.3V"
					( Units "uVoltage" "V" 1.000000)
					( Origin gFrontEnd )
				)
				( attribute "XY" "(10450,1500)"
					( Origin gFrontEnd )
				)
				( attribute "CHIPS_PART_NAME" "CAP"
					( Origin gPackager )
				)
				( attribute "CDS_PART_NAME" "CAP_0603-10UF,6.3V,20%,X6S,E15A"
					( Origin gPackager )
				)
				( attribute "CDS_LOCATION" "C1W15"
					( Origin gPackager )
				)
				( attribute "SEC" "1"
					( Origin gFrontEnd )
				)
				( attribute "SEC_TYPE" "0603"
					( Origin gFrontEnd )
				)
				( attribute "CDS_SEC" "1"
					( Origin gPackager )
				)
				( objectStatus "C1W15" )
			)
			( gate "@baseboard_fab2_lib.baseboard_fab2(sch_1):page239_i84"
				( attribute "BOM_COST" "P1V538_BMC_STBY_VR"
					( Origin gFrontEnd )
				)
				( attribute "CDS_LIB" "mstr_discrete"
					( Origin gPackager )
				)
				( attribute "LOCATION" "C9W10"
					( Origin gFrontEnd )
				)
				( attribute "MATERIAL" "X7R"
					( Origin gFrontEnd )
				)
				( attribute "PACK_TYPE" "0402LF"
					( Origin gFrontEnd )
				)
				( attribute "PART_NUMBER" "A36096-046"
					( Origin gFrontEnd )
				)
				( attribute "PHYS_PAGE" "239"
					( Origin gFrontEnd )
				)
				( attribute "ROOM" "P1V538_BMC_STBY_VR"
					( Origin gFrontEnd )
				)
				( attribute "ROT" "0"
					( Origin gFrontEnd )
				)
				( attribute "TOLERANCE" "10%"
					( Origin gFrontEnd )
				)
				( attribute "VALUE" "1000PF"
					( Origin gFrontEnd )
				)
				( attribute "VER" "1"
					( Origin gFrontEnd )
				)
				( attribute "VOLTAGE" "50V"
					( Units "uVoltage" "V" 1.000000)
					( Origin gFrontEnd )
				)
				( attribute "XY" "(9950,2075)"
					( Origin gFrontEnd )
				)
				( attribute "CHIPS_PART_NAME" "CAP"
					( Origin gPackager )
				)
				( attribute "CDS_PART_NAME" "CAP_0402LF-1000PF,50V,10%,X7R,A"
					( Origin gPackager )
				)
				( attribute "CDS_LOCATION" "C9W10"
					( Origin gPackager )
				)
				( attribute "SEC" "1"
					( Origin gFrontEnd )
				)
				( attribute "SEC_TYPE" "0402LF"
					( Origin gFrontEnd )
				)
				( attribute "CDS_SEC" "1"
					( Origin gPackager )
				)
				( objectStatus "C9W10" )
			)
			( gate "@baseboard_fab2_lib.baseboard_fab2(sch_1):page239_i90"
				( attribute "CDS_LIB" "dev_discrete"
					( Origin gPackager )
				)
				( attribute "LOCATION" "C9W5"
					( Origin gFrontEnd )
				)
				( attribute "MATERIAL" "X7R"
					( Origin gFrontEnd )
				)
				( attribute "PACK_TYPE" "0402V"
					( Origin gFrontEnd )
				)
				( attribute "PART_NUMBER" "A36096-030"
					( Origin gFrontEnd )
				)
				( attribute "PHYS_PAGE" "239"
					( Origin gFrontEnd )
				)
				( attribute "ROT" "0"
					( Origin gFrontEnd )
				)
				( attribute "TOLERANCE" "10%"
					( Origin gFrontEnd )
				)
				( attribute "VALUE" "0.1UF"
					( Origin gFrontEnd )
				)
				( attribute "VER" "1"
					( Origin gFrontEnd )
				)
				( attribute "VOLTAGE" "16V"
					( Units "uVoltage" "V" 1.000000)
					( Origin gFrontEnd )
				)
				( attribute "XY" "(7250,2075)"
					( Origin gFrontEnd )
				)
				( attribute "CHIPS_PART_NAME" "CAP_A"
					( Origin gPackager )
				)
				( attribute "CDS_PART_NAME" "CAP_A_0402V-0.1UF,16V,10%,X7R,A"
					( Origin gPackager )
				)
				( attribute "CDS_LOCATION" "C9W5"
					( Origin gPackager )
				)
				( attribute "SEC" "1"
					( Origin gFrontEnd )
				)
				( attribute "SEC_TYPE" "0402V"
					( Origin gFrontEnd )
				)
				( attribute "CDS_SEC" "1"
					( Origin gPackager )
				)
				( objectStatus "C9W5" )
			)
			( gate "@baseboard_fab2_lib.baseboard_fab2(sch_1):page239_i91"
				( attribute "BOM_COST" "P1V538_BMC_STBY_VR"
					( Origin gFrontEnd )
				)
				( attribute "CDS_LIB" "mstr_discrete"
					( Origin gPackager )
				)
				( attribute "LOCATION" "C9W6"
					( Origin gFrontEnd )
				)
				( attribute "MATERIAL" "EMPTY"
					( Origin gFrontEnd )
				)
				( attribute "PACK_TYPE" "0402LF"
					( Origin gFrontEnd )
				)
				( attribute "PART_NUMBER" "A36096-046"
					( Origin gFrontEnd )
				)
				( attribute "PHYS_PAGE" "239"
					( Origin gFrontEnd )
				)
				( attribute "ROOM" "P1V538_BMC_STBY_VR"
					( Origin gFrontEnd )
				)
				( attribute "ROT" "2"
					( Origin gFrontEnd )
				)
				( attribute "TOLERANCE" "10%"
					( Origin gFrontEnd )
				)
				( attribute "VALUE" "1000PF"
					( Origin gFrontEnd )
				)
				( attribute "VER" "1"
					( Origin gFrontEnd )
				)
				( attribute "VOLTAGE" "50V"
					( Units "uVoltage" "V" 1.000000)
					( Origin gFrontEnd )
				)
				( attribute "XY" "(6625,1225)"
					( Origin gFrontEnd )
				)
				( attribute "CHIPS_PART_NAME" "CAP"
					( Origin gPackager )
				)
				( attribute "CDS_PART_NAME" "CAP_0402LF-1000PF,50V,10%,EMPTA"
					( Origin gPackager )
				)
				( attribute "CDS_LOCATION" "C9W6"
					( Origin gPackager )
				)
				( attribute "SEC" "1"
					( Origin gFrontEnd )
				)
				( attribute "SEC_TYPE" "0402LF"
					( Origin gFrontEnd )
				)
				( attribute "CDS_SEC" "1"
					( Origin gPackager )
				)
				( objectStatus "C9W6" )
			)
			( gate "@baseboard_fab2_lib.baseboard_fab2(sch_1):page239_i92"
				( attribute "BOM_COST" "P1V538_BMC_STBY_VR"
					( Origin gFrontEnd )
				)
				( attribute "CDS_LIB" "mstr_discrete"
					( Origin gPackager )
				)
				( attribute "LOCATION" "C1W7"
					( Origin gFrontEnd )
				)
				( attribute "MATERIAL" "X6S"
					( Origin gFrontEnd )
				)
				( attribute "PACK_TYPE" "0603"
					( Origin gFrontEnd )
				)
				( attribute "PART_NUMBER" "E15431-002"
					( Origin gFrontEnd )
				)
				( attribute "PHYS_PAGE" "239"
					( Origin gFrontEnd )
				)
				( attribute "ROOM" "P1V538_BMC_STBY_VR"
					( Origin gFrontEnd )
				)
				( attribute "ROT" "0"
					( Origin gFrontEnd )
				)
				( attribute "TOLERANCE" "20%"
					( Origin gFrontEnd )
				)
				( attribute "VALUE" "10UF"
					( Origin gFrontEnd )
				)
				( attribute "VER" "1"
					( Origin gFrontEnd )
				)
				( attribute "VOLTAGE" "6.3V"
					( Units "uVoltage" "V" 1.000000)
					( Origin gFrontEnd )
				)
				( attribute "XY" "(5575,2075)"
					( Origin gFrontEnd )
				)
				( attribute "CHIPS_PART_NAME" "CAP"
					( Origin gPackager )
				)
				( attribute "CDS_PART_NAME" "CAP_0603-10UF,6.3V,20%,X6S,E15A"
					( Origin gPackager )
				)
				( attribute "CDS_LOCATION" "C1W7"
					( Origin gPackager )
				)
				( attribute "SEC" "1"
					( Origin gFrontEnd )
				)
				( attribute "SEC_TYPE" "0603"
					( Origin gFrontEnd )
				)
				( attribute "CDS_SEC" "1"
					( Origin gPackager )
				)
				( objectStatus "C1W7" )
			)
			( gate "@baseboard_fab2_lib.baseboard_fab2(sch_1):page144_i95"
				( attribute "CDS_LIB" "w_hdl"
					( Origin gPackager )
				)
				( attribute "CDS_LMAN_SYM_OUTLINE" "-1150,1150,1150,-1150"
					( Origin gPackager )
				)
				( attribute "LOCATION" "U25W4"
					( Origin gFrontEnd )
				)
				( attribute "PACK_TYPE" "ASIC2-GB1"
					( Origin gFrontEnd )
				)
				( attribute "PART_NUMBER" "071.2520A.M001"
					( Origin gFrontEnd )
				)
				( attribute "PHYS_PAGE" "144"
					( Origin gFrontEnd )
				)
				( attribute "ROT" "0"
					( Origin gFrontEnd )
				)
				( attribute "VALUE" "AST2520A1-GP-GP"
					( Origin gFrontEnd )
				)
				( attribute "VER" "2"
					( Origin gFrontEnd )
				)
				( attribute "XY" "(-4800,-2600)"
					( Origin gFrontEnd )
				)
				( attribute "CHIPS_PART_NAME" "AST2520A1-GP-GP"
					( Origin gPackager )
				)
				( attribute "CDS_PART_NAME" "AST2520A1-GP-GP_ASIC2-GB1-AST2A"
					( Origin gPackager )
				)
				( attribute "CDS_LOCATION" "U25W4"
					( Origin gPackager )
				)
				( attribute "CDS_SEC" "2"
					( Origin gPackager )
				)
				( attribute "SEC" "2"
					( Origin gPackager )
				)
				( objectStatus "U25W4" )
			)
			( gate "@baseboard_fab2_lib.baseboard_fab2(sch_1):page249_i30"
				( attribute "CDS_LIB" "mstr_discrete"
					( Origin gPackager )
				)
				( attribute "LOCATION" "Q9W1"
					( Origin gFrontEnd )
				)
				( attribute "MATERIAL" "FET"
					( Origin gFrontEnd )
				)
				( attribute "PACK_TYPE" "SOT23LF"
					( Origin gFrontEnd )
				)
				( attribute "PART_NUMBER" "C79254-001"
					( Origin gFrontEnd )
				)
				( attribute "PHYS_PAGE" "249"
					( Origin gFrontEnd )
				)
				( attribute "ROOM" "HOT_SWAP"
					( Origin gFrontEnd )
				)
				( attribute "ROT" "0"
					( Origin gFrontEnd )
				)
				( attribute "VALUE" "2N7002"
					( Origin gFrontEnd )
				)
				( attribute "VER" "8"
					( Origin gFrontEnd )
				)
				( attribute "XY" "(-4850,2250)"
					( Origin gFrontEnd )
				)
				( attribute "CHIPS_PART_NAME" "FET_N"
					( Origin gPackager )
				)
				( attribute "CDS_PART_NAME" "FET_N_SOT23LF-2N7002,FET,C7925A"
					( Origin gPackager )
				)
				( attribute "CDS_LOCATION" "Q9W1"
					( Origin gPackager )
				)
				( attribute "SEC" "1"
					( Origin gFrontEnd )
				)
				( attribute "SEC_TYPE" "SOT23LF"
					( Origin gFrontEnd )
				)
				( attribute "CDS_SEC" "1"
					( Origin gPackager )
				)
				( objectStatus "Q9W1" )
			)
			( gate "@baseboard_fab2_lib.baseboard_fab2(sch_1):page247_i101"
				( attribute "BOM_COST" "SM_THERM"
					( Origin gFrontEnd )
				)
				( attribute "CDS_LIB" "mstr_discrete"
					( Origin gPackager )
				)
				( attribute "LOCATION" "R6W25"
					( Origin gFrontEnd )
				)
				( attribute "MATERIAL" "CHIP"
					( Origin gFrontEnd )
				)
				( attribute "PACK_TYPE" "0402"
					( Origin gFrontEnd )
				)
				( attribute "PART_NUMBER" "G21796-072"
					( Origin gFrontEnd )
				)
				( attribute "PHYS_PAGE" "247"
					( Origin gFrontEnd )
				)
				( attribute "ROOM" "CPU_FANS"
					( Origin gFrontEnd )
				)
				( attribute "ROT" "2"
					( Origin gFrontEnd )
				)
				( attribute "TOLERANCE" "1%"
					( Origin gFrontEnd )
				)
				( attribute "VALUE" "4.75K"
					( Origin gFrontEnd )
				)
				( attribute "VER" "2"
					( Origin gFrontEnd )
				)
				( attribute "WATTAGE" "1/16W"
					( Origin gFrontEnd )
				)
				( attribute "XY" "(-7200,1950)"
					( Origin gFrontEnd )
				)
				( attribute "CHIPS_PART_NAME" "RES"
					( Origin gPackager )
				)
				( attribute "CDS_PART_NAME" "RES_0402-4.75K,1%,1/16W,CHIP,GA"
					( Origin gPackager )
				)
				( attribute "CDS_LOCATION" "R6W25"
					( Origin gPackager )
				)
				( attribute "SEC" "1"
					( Origin gFrontEnd )
				)
				( attribute "SEC_TYPE" "0402"
					( Origin gFrontEnd )
				)
				( attribute "CDS_SEC" "1"
					( Origin gPackager )
				)
				( objectStatus "R6W25" )
			)
			( gate "@baseboard_fab2_lib.baseboard_fab2(sch_1):page146_i104"
				( attribute "CDS_LIB" "w_hdl"
					( Origin gPackager )
				)
				( attribute "CDS_LMAN_SYM_OUTLINE" "-1350,800,1350,-800"
					( Origin gPackager )
				)
				( attribute "LOCATION" "U25W4"
					( Origin gFrontEnd )
				)
				( attribute "PACK_TYPE" "ASIC2-GB1"
					( Origin gFrontEnd )
				)
				( attribute "PART_NUMBER" "071.2520A.M001"
					( Origin gFrontEnd )
				)
				( attribute "PHYS_PAGE" "146"
					( Origin gFrontEnd )
				)
				( attribute "ROT" "0"
					( Origin gFrontEnd )
				)
				( attribute "VALUE" "AST2520A1-GP-GP"
					( Origin gFrontEnd )
				)
				( attribute "VER" "4"
					( Origin gFrontEnd )
				)
				( attribute "XY" "(-3875,4000)"
					( Origin gFrontEnd )
				)
				( attribute "CHIPS_PART_NAME" "AST2520A1-GP-GP"
					( Origin gPackager )
				)
				( attribute "CDS_PART_NAME" "AST2520A1-GP-GP_ASIC2-GB1-AST2A"
					( Origin gPackager )
				)
				( attribute "CDS_LOCATION" "U25W4"
					( Origin gPackager )
				)
				( attribute "CDS_SEC" "4"
					( Origin gPackager )
				)
				( attribute "SEC" "4"
					( Origin gPackager )
				)
				( objectStatus "U25W4" )
			)
			( gate "@baseboard_fab2_lib.baseboard_fab2(sch_1):page200_i235"
				( attribute "CDS_LIB" "w_hdl"
					( Origin gPackager )
				)
				( attribute "CDS_LMAN_SYM_OUTLINE" "-50,25,50,-25"
					( Origin gPackager )
				)
				( attribute "PACK_TYPE" "SMD-BCG"
					( Origin gFrontEnd )
				)
				( attribute "PART_NUMBER" "78.22034.1FL"
					( Origin gFrontEnd )
				)
				( attribute "PHYS_PAGE" "200"
					( Origin gFrontEnd )
				)
				( attribute "ROT" "0"
					( Origin gFrontEnd )
				)
				( attribute "VALUE" "SC22P50V2JN-4GP"
					( Origin gFrontEnd )
				)
				( attribute "VER" "1"
					( Origin gFrontEnd )
				)
				( attribute "XY" "(-700,-100)"
					( Origin gFrontEnd )
				)
				( attribute "CHIPS_PART_NAME" "SC22P50V2JN-4GP"
					( Origin gPackager )
				)
				( attribute "CDS_PART_NAME" "SC22P50V2JN-4GP_SMD-BCG-SC22P5A"
					( Origin gPackager )
				)
				( attribute "LOCATION" "C9W1"
					( Origin gFrontEnd )
				)
				( attribute "SEC" "1"
					( Origin gFrontEnd )
				)
				( attribute "POP" "NOPOP"
					( Origin gFrontEnd )
				)
				( attribute "SEC_TYPE" "SMD-BCG"
					( Origin gFrontEnd )
				)
				( attribute "CDS_LOCATION" "C9W1"
					( Origin gPackager )
				)
				( attribute "CDS_SEC" "1"
					( Origin gPackager )
				)
				( attribute "ATTRIBUTE" "22PF"
					( Origin gFrontEnd )
				)
				( attribute "PACK_SIZE" "0402"
					( Origin gFrontEnd )
				)
				( attribute "RATED" "50V"
					( Origin gFrontEnd )
				)
				( attribute "TOLERANCE" "5%"
					( Origin gFrontEnd )
				)
				( attribute "TYPE" "NPO"
					( Origin gFrontEnd )
				)
				( objectStatus "C9W1" )
			)
			( gate "@baseboard_fab2_lib.baseboard_fab2(sch_1):page200_i236"
				( attribute "CDS_LIB" "w_hdl"
					( Origin gPackager )
				)
				( attribute "CDS_LMAN_SYM_OUTLINE" "-50,25,50,-25"
					( Origin gPackager )
				)
				( attribute "PACK_TYPE" "SMD-BCG"
					( Origin gFrontEnd )
				)
				( attribute "PART_NUMBER" "78.22034.1FL"
					( Origin gFrontEnd )
				)
				( attribute "PHYS_PAGE" "200"
					( Origin gFrontEnd )
				)
				( attribute "ROT" "0"
					( Origin gFrontEnd )
				)
				( attribute "VALUE" "SC22P50V2JN-4GP"
					( Origin gFrontEnd )
				)
				( attribute "VER" "1"
					( Origin gFrontEnd )
				)
				( attribute "XY" "(-1050,175)"
					( Origin gFrontEnd )
				)
				( attribute "CHIPS_PART_NAME" "SC22P50V2JN-4GP"
					( Origin gPackager )
				)
				( attribute "CDS_PART_NAME" "SC22P50V2JN-4GP_SMD-BCG-SC22P5A"
					( Origin gPackager )
				)
				( attribute "LOCATION" "C9W2"
					( Origin gFrontEnd )
				)
				( attribute "SEC" "1"
					( Origin gFrontEnd )
				)
				( attribute "POP" "NOPOP"
					( Origin gFrontEnd )
				)
				( attribute "SEC_TYPE" "SMD-BCG"
					( Origin gFrontEnd )
				)
				( attribute "CDS_LOCATION" "C9W2"
					( Origin gPackager )
				)
				( attribute "CDS_SEC" "1"
					( Origin gPackager )
				)
				( attribute "ATTRIBUTE" "22PF"
					( Origin gFrontEnd )
				)
				( attribute "PACK_SIZE" "0402"
					( Origin gFrontEnd )
				)
				( attribute "RATED" "50V"
					( Origin gFrontEnd )
				)
				( attribute "TOLERANCE" "5%"
					( Origin gFrontEnd )
				)
				( attribute "TYPE" "NPO"
					( Origin gFrontEnd )
				)
				( objectStatus "C9W2" )
			)
			( gate "@baseboard_fab2_lib.baseboard_fab2(sch_1):page146_i67"
				( attribute "BOM_COST" "SM_CONTROLLER"
					( Origin gFrontEnd )
				)
				( attribute "CDS_LIB" "mstr_discrete"
					( Origin gPackager )
				)
				( attribute "CDS_LOCATION" "R25W81"
					( Origin gPackager )
				)
				( attribute "LOCATION" "R25W81"
					( Origin gFrontEnd )
				)
				( attribute "MATERIAL" "CHIP"
					( Origin gFrontEnd )
				)
				( attribute "PACK_TYPE" "0402"
					( Origin gFrontEnd )
				)
				( attribute "PART_NUMBER" "G21796-074"
					( Origin gFrontEnd )
				)
				( attribute "PHYS_PAGE" "146"
					( Origin gFrontEnd )
				)
				( attribute "ROOM" "BMC"
					( Origin gFrontEnd )
				)
				( attribute "ROT" "0"
					( Origin gFrontEnd )
				)
				( attribute "SEC" "1"
					( Origin gFrontEnd )
				)
				( attribute "SEC_TYPE" "0402"
					( Origin gFrontEnd )
				)
				( attribute "TOLERANCE" "1%"
					( Origin gFrontEnd )
				)
				( attribute "VALUE" "33.2"
					( Origin gFrontEnd )
				)
				( attribute "VER" "1"
					( Origin gFrontEnd )
				)
				( attribute "WATTAGE" "1/16W"
					( Origin gFrontEnd )
				)
				( attribute "XY" "(-6350,2350)"
					( Origin gFrontEnd )
				)
				( attribute "CHIPS_PART_NAME" "RES"
					( Origin gPackager )
				)
				( attribute "CDS_PART_NAME" "RES_0402-33.2,1%,1/16W,CHIP,G2A"
					( Origin gPackager )
				)
				( attribute "CDS_SEC" "1"
					( Origin gPackager )
				)
				( objectStatus "R25W81" )
			)
			( gate "@baseboard_fab2_lib.baseboard_fab2(sch_1):page150_i180"
				( attribute "BOM_COST" "SM_CONTROLLER"
					( Origin gFrontEnd )
				)
				( attribute "CDS_LIB" "mstr_discrete"
					( Origin gPackager )
				)
				( attribute "CDS_LOCATION" "R25W111"
					( Origin gPackager )
				)
				( attribute "LOCATION" "R25W111"
					( Origin gFrontEnd )
				)
				( attribute "MATERIAL" "EMPTY"
					( Origin gFrontEnd )
				)
				( attribute "PACK_TYPE" "0402"
					( Origin gFrontEnd )
				)
				( attribute "PART_NUMBER" "G21796-072"
					( Origin gFrontEnd )
				)
				( attribute "PHYS_PAGE" "150"
					( Origin gFrontEnd )
				)
				( attribute "ROOM" "BMC"
					( Origin gFrontEnd )
				)
				( attribute "ROT" "0"
					( Origin gFrontEnd )
				)
				( attribute "SEC" "1"
					( Origin gFrontEnd )
				)
				( attribute "TOLERANCE" "1%"
					( Origin gFrontEnd )
				)
				( attribute "VALUE" "4.75K"
					( Origin gFrontEnd )
				)
				( attribute "VER" "1"
					( Origin gFrontEnd )
				)
				( attribute "WATTAGE" "1/16W"
					( Origin gFrontEnd )
				)
				( attribute "XY" "(-600,-1500)"
					( Origin gFrontEnd )
				)
				( attribute "CHIPS_PART_NAME" "RES"
					( Origin gPackager )
				)
				( attribute "CDS_PART_NAME" "RES_0402-4.75K,1%,1/16W,EMPTY,A"
					( Origin gPackager )
				)
				( attribute "SEC_TYPE" "0402"
					( Origin gFrontEnd )
				)
				( attribute "CDS_SEC" "1"
					( Origin gPackager )
				)
				( objectStatus "R25W111" )
			)
			( gate "@baseboard_fab2_lib.baseboard_fab2(sch_1):page204_i99"
				( attribute "BOM_COST" "NT_GBE_BASE"
					( Origin gFrontEnd )
				)
				( attribute "CDS_LIB" "mstr_discrete"
					( Origin gPackager )
				)
				( attribute "LOCATION" "RT23"
					( Origin gFrontEnd )
				)
				( attribute "MATERIAL" "CHIP"
					( Origin gFrontEnd )
				)
				( attribute "PACK_TYPE" "0603"
					( Origin gFrontEnd )
				)
				( attribute "PART_NUMBER" "G22178-002"
					( Origin gFrontEnd )
				)
				( attribute "PHYS_PAGE" "204"
					( Origin gFrontEnd )
				)
				( attribute "ROOM" "NIC_SPRV"
					( Origin gFrontEnd )
				)
				( attribute "ROT" "0"
					( Origin gFrontEnd )
				)
				( attribute "TOLERANCE" "5.0%"
					( Origin gFrontEnd )
				)
				( attribute "VALUE" "0"
					( Origin gFrontEnd )
				)
				( attribute "VER" "1"
					( Origin gFrontEnd )
				)
				( attribute "WATTAGE" "1/10W"
					( Origin gFrontEnd )
				)
				( attribute "XY" "(-4875,3725)"
					( Origin gFrontEnd )
				)
				( attribute "CHIPS_PART_NAME" "RES"
					( Origin gPackager )
				)
				( attribute "CDS_PART_NAME" "RES_0603-0,5.0%,1/10W,CHIP,G22A"
					( Origin gPackager )
				)
				( attribute "CDS_LOCATION" "RT23"
					( Origin gPackager )
				)
				( attribute "SEC" "1"
					( Origin gFrontEnd )
				)
				( attribute "SEC_TYPE" "0603"
					( Origin gFrontEnd )
				)
				( attribute "CDS_SEC" "1"
					( Origin gPackager )
				)
				( objectStatus "RT23" )
			)
			( gate "@baseboard_fab2_lib.baseboard_fab2(sch_1):page147_i151"
				( attribute "CDS_LIB" "mstr_discrete"
					( Origin gPackager )
				)
				( attribute "LOCATION" "R25W57"
					( Origin gFrontEnd )
				)
				( attribute "MATERIAL" "CHIP"
					( Origin gFrontEnd )
				)
				( attribute "PACK_TYPE" "0402"
					( Origin gFrontEnd )
				)
				( attribute "PART_NUMBER" "G21796-048"
					( Origin gFrontEnd )
				)
				( attribute "PHYS_PAGE" "147"
					( Origin gFrontEnd )
				)
				( attribute "ROOM" "V_SUPER"
					( Origin gFrontEnd )
				)
				( attribute "ROT" "0"
					( Origin gFrontEnd )
				)
				( attribute "TOLERANCE" "1%"
					( Origin gFrontEnd )
				)
				( attribute "VALUE" "49.9K"
					( Origin gFrontEnd )
				)
				( attribute "VER" "2"
					( Origin gFrontEnd )
				)
				( attribute "WATTAGE" "1/16W"
					( Origin gFrontEnd )
				)
				( attribute "XY" "(900,1950)"
					( Origin gFrontEnd )
				)
				( attribute "CHIPS_PART_NAME" "RES"
					( Origin gPackager )
				)
				( attribute "CDS_PART_NAME" "RES_0402-49.9K,1%,1/16W,CHIP,GA"
					( Origin gPackager )
				)
				( attribute "CDS_LOCATION" "R25W57"
					( Origin gPackager )
				)
				( attribute "SEC" "1"
					( Origin gFrontEnd )
				)
				( attribute "SEC_TYPE" "0402"
					( Origin gFrontEnd )
				)
				( attribute "CDS_SEC" "1"
					( Origin gPackager )
				)
				( objectStatus "R25W57" )
			)
			( gate "@baseboard_fab2_lib.baseboard_fab2(sch_1):page207_i99"
				( attribute "BOM_COST" "NT_GBE_BASE"
					( Origin gFrontEnd )
				)
				( attribute "CDS_LIB" "mstr_discrete"
					( Origin gPackager )
				)
				( attribute "LOCATION" "RT15"
					( Origin gFrontEnd )
				)
				( attribute "MATERIAL" "CHIP"
					( Origin gFrontEnd )
				)
				( attribute "PACK_TYPE" "0603"
					( Origin gFrontEnd )
				)
				( attribute "PART_NUMBER" "G22178-002"
					( Origin gFrontEnd )
				)
				( attribute "PHYS_PAGE" "207"
					( Origin gFrontEnd )
				)
				( attribute "ROOM" "NIC_SPRV"
					( Origin gFrontEnd )
				)
				( attribute "ROT" "0"
					( Origin gFrontEnd )
				)
				( attribute "TOLERANCE" "5.0%"
					( Origin gFrontEnd )
				)
				( attribute "VALUE" "0"
					( Origin gFrontEnd )
				)
				( attribute "VER" "1"
					( Origin gFrontEnd )
				)
				( attribute "WATTAGE" "1/10W"
					( Origin gFrontEnd )
				)
				( attribute "XY" "(-4825,3675)"
					( Origin gFrontEnd )
				)
				( attribute "CHIPS_PART_NAME" "RES"
					( Origin gPackager )
				)
				( attribute "CDS_PART_NAME" "RES_0603-0,5.0%,1/10W,CHIP,G22A"
					( Origin gPackager )
				)
				( attribute "CDS_LOCATION" "RT15"
					( Origin gPackager )
				)
				( attribute "SEC" "1"
					( Origin gFrontEnd )
				)
				( attribute "SEC_TYPE" "0603"
					( Origin gFrontEnd )
				)
				( attribute "CDS_SEC" "1"
					( Origin gPackager )
				)
				( objectStatus "RT15" )
			)
			( gate "@baseboard_fab2_lib.baseboard_fab2(sch_1):page210_i68"
				( attribute "BOM_COST" "NT_GBE_BASE"
					( Origin gFrontEnd )
				)
				( attribute "CDS_LIB" "mstr_discrete"
					( Origin gPackager )
				)
				( attribute "LOCATION" "RT37"
					( Origin gFrontEnd )
				)
				( attribute "MATERIAL" "CHIP"
					( Origin gFrontEnd )
				)
				( attribute "PACK_TYPE" "0603"
					( Origin gFrontEnd )
				)
				( attribute "PART_NUMBER" "G22178-002"
					( Origin gFrontEnd )
				)
				( attribute "PHYS_PAGE" "210"
					( Origin gFrontEnd )
				)
				( attribute "ROOM" "NIC_SPRV"
					( Origin gFrontEnd )
				)
				( attribute "ROT" "0"
					( Origin gFrontEnd )
				)
				( attribute "TOLERANCE" "5.0%"
					( Origin gFrontEnd )
				)
				( attribute "VALUE" "0"
					( Origin gFrontEnd )
				)
				( attribute "VER" "1"
					( Origin gFrontEnd )
				)
				( attribute "WATTAGE" "1/10W"
					( Origin gFrontEnd )
				)
				( attribute "XY" "(-5400,3375)"
					( Origin gFrontEnd )
				)
				( attribute "CHIPS_PART_NAME" "RES"
					( Origin gPackager )
				)
				( attribute "CDS_PART_NAME" "RES_0603-0,5.0%,1/10W,CHIP,G22A"
					( Origin gPackager )
				)
				( attribute "CDS_LOCATION" "RT37"
					( Origin gPackager )
				)
				( attribute "SEC" "1"
					( Origin gFrontEnd )
				)
				( attribute "SEC_TYPE" "0603"
					( Origin gFrontEnd )
				)
				( attribute "CDS_SEC" "1"
					( Origin gPackager )
				)
				( objectStatus "RT37" )
			)
			( gate "@baseboard_fab2_lib.baseboard_fab2(sch_1):page209_i75"
				( attribute "BOM_COST" "NT_GBE_BASE"
					( Origin gFrontEnd )
				)
				( attribute "CDS_LIB" "mstr_discrete"
					( Origin gPackager )
				)
				( attribute "LOCATION" "RT9"
					( Origin gFrontEnd )
				)
				( attribute "MATERIAL" "CHIP"
					( Origin gFrontEnd )
				)
				( attribute "PACK_TYPE" "0603"
					( Origin gFrontEnd )
				)
				( attribute "PART_NUMBER" "G22178-002"
					( Origin gFrontEnd )
				)
				( attribute "PHYS_PAGE" "209"
					( Origin gFrontEnd )
				)
				( attribute "ROOM" "NIC_SPRV"
					( Origin gFrontEnd )
				)
				( attribute "ROT" "0"
					( Origin gFrontEnd )
				)
				( attribute "TOLERANCE" "5.0%"
					( Origin gFrontEnd )
				)
				( attribute "VALUE" "0"
					( Origin gFrontEnd )
				)
				( attribute "VER" "1"
					( Origin gFrontEnd )
				)
				( attribute "WATTAGE" "1/10W"
					( Origin gFrontEnd )
				)
				( attribute "XY" "(-4800,3575)"
					( Origin gFrontEnd )
				)
				( attribute "CHIPS_PART_NAME" "RES"
					( Origin gPackager )
				)
				( attribute "CDS_PART_NAME" "RES_0603-0,5.0%,1/10W,CHIP,G22A"
					( Origin gPackager )
				)
				( attribute "CDS_LOCATION" "RT9"
					( Origin gPackager )
				)
				( attribute "SEC" "1"
					( Origin gFrontEnd )
				)
				( attribute "SEC_TYPE" "0603"
					( Origin gFrontEnd )
				)
				( attribute "CDS_SEC" "1"
					( Origin gPackager )
				)
				( objectStatus "RT9" )
			)
			( gate "@baseboard_fab2_lib.baseboard_fab2(sch_1):page216_i140"
				( attribute "BOM_COST" "NT_GBE_BASE"
					( Origin gFrontEnd )
				)
				( attribute "CDS_LIB" "mstr_discrete"
					( Origin gPackager )
				)
				( attribute "LOCATION" "RT36"
					( Origin gFrontEnd )
				)
				( attribute "MATERIAL" "CHIP"
					( Origin gFrontEnd )
				)
				( attribute "PACK_TYPE" "0603"
					( Origin gFrontEnd )
				)
				( attribute "PART_NUMBER" "G22178-002"
					( Origin gFrontEnd )
				)
				( attribute "PHYS_PAGE" "216"
					( Origin gFrontEnd )
				)
				( attribute "ROOM" "NIC_SPRV"
					( Origin gFrontEnd )
				)
				( attribute "ROT" "0"
					( Origin gFrontEnd )
				)
				( attribute "TOLERANCE" "5.0%"
					( Origin gFrontEnd )
				)
				( attribute "VALUE" "0"
					( Origin gFrontEnd )
				)
				( attribute "VER" "1"
					( Origin gFrontEnd )
				)
				( attribute "WATTAGE" "1/10W"
					( Origin gFrontEnd )
				)
				( attribute "XY" "(100,-275)"
					( Origin gFrontEnd )
				)
				( attribute "CHIPS_PART_NAME" "RES"
					( Origin gPackager )
				)
				( attribute "CDS_PART_NAME" "RES_0603-0,5.0%,1/10W,CHIP,G22A"
					( Origin gPackager )
				)
				( attribute "CDS_LOCATION" "RT36"
					( Origin gPackager )
				)
				( attribute "SEC" "1"
					( Origin gFrontEnd )
				)
				( attribute "SEC_TYPE" "0603"
					( Origin gFrontEnd )
				)
				( attribute "CDS_SEC" "1"
					( Origin gPackager )
				)
				( attribute "BOM_SS" "NOPOP"
					( Origin gFrontEnd )
				)
				( objectStatus "RT36" )
			)
			( gate "@baseboard_fab2_lib.baseboard_fab2(sch_1):page236_i153"
				( attribute "BOM_COST" "NT_GBE_BASE"
					( Origin gFrontEnd )
				)
				( attribute "CDS_LIB" "mstr_discrete"
					( Origin gPackager )
				)
				( attribute "LOCATION" "RT44"
					( Origin gFrontEnd )
				)
				( attribute "MATERIAL" "CHIP"
					( Origin gFrontEnd )
				)
				( attribute "PACK_TYPE" "0603"
					( Origin gFrontEnd )
				)
				( attribute "PART_NUMBER" "G22178-002"
					( Origin gFrontEnd )
				)
				( attribute "PHYS_PAGE" "236"
					( Origin gFrontEnd )
				)
				( attribute "ROOM" "NIC_SPRV"
					( Origin gFrontEnd )
				)
				( attribute "ROT" "0"
					( Origin gFrontEnd )
				)
				( attribute "TOLERANCE" "5.0%"
					( Origin gFrontEnd )
				)
				( attribute "VALUE" "0"
					( Origin gFrontEnd )
				)
				( attribute "VER" "1"
					( Origin gFrontEnd )
				)
				( attribute "WATTAGE" "1/10W"
					( Origin gFrontEnd )
				)
				( attribute "XY" "(8025,4050)"
					( Origin gFrontEnd )
				)
				( attribute "CHIPS_PART_NAME" "RES"
					( Origin gPackager )
				)
				( attribute "CDS_PART_NAME" "RES_0603-0,5.0%,1/10W,CHIP,G22A"
					( Origin gPackager )
				)
				( attribute "CDS_LOCATION" "RT44"
					( Origin gPackager )
				)
				( attribute "SEC" "1"
					( Origin gFrontEnd )
				)
				( attribute "SEC_TYPE" "0603"
					( Origin gFrontEnd )
				)
				( attribute "CDS_SEC" "1"
					( Origin gPackager )
				)
				( objectStatus "RT44" )
			)
			( gate "@baseboard_fab2_lib.baseboard_fab2(sch_1):page236_i154"
				( attribute "BOM_COST" "NT_GBE_BASE"
					( Origin gFrontEnd )
				)
				( attribute "CDS_LIB" "mstr_discrete"
					( Origin gPackager )
				)
				( attribute "LOCATION" "RT46"
					( Origin gFrontEnd )
				)
				( attribute "MATERIAL" "CHIP"
					( Origin gFrontEnd )
				)
				( attribute "PACK_TYPE" "0603"
					( Origin gFrontEnd )
				)
				( attribute "PART_NUMBER" "G22178-002"
					( Origin gFrontEnd )
				)
				( attribute "PHYS_PAGE" "236"
					( Origin gFrontEnd )
				)
				( attribute "ROOM" "NIC_SPRV"
					( Origin gFrontEnd )
				)
				( attribute "ROT" "0"
					( Origin gFrontEnd )
				)
				( attribute "TOLERANCE" "5.0%"
					( Origin gFrontEnd )
				)
				( attribute "VALUE" "0"
					( Origin gFrontEnd )
				)
				( attribute "VER" "1"
					( Origin gFrontEnd )
				)
				( attribute "WATTAGE" "1/10W"
					( Origin gFrontEnd )
				)
				( attribute "XY" "(8050,2325)"
					( Origin gFrontEnd )
				)
				( attribute "CHIPS_PART_NAME" "RES"
					( Origin gPackager )
				)
				( attribute "CDS_PART_NAME" "RES_0603-0,5.0%,1/10W,CHIP,G22A"
					( Origin gPackager )
				)
				( attribute "CDS_LOCATION" "RT46"
					( Origin gPackager )
				)
				( attribute "SEC" "1"
					( Origin gFrontEnd )
				)
				( attribute "SEC_TYPE" "0603"
					( Origin gFrontEnd )
				)
				( attribute "CDS_SEC" "1"
					( Origin gPackager )
				)
				( objectStatus "RT46" )
			)
			( gate "@baseboard_fab2_lib.baseboard_fab2(sch_1):page208_i109"
				( attribute "BOM_COST" "NT_GBE_BASE"
					( Origin gFrontEnd )
				)
				( attribute "CDS_LIB" "mstr_discrete"
					( Origin gPackager )
				)
				( attribute "LOCATION" "RT14"
					( Origin gFrontEnd )
				)
				( attribute "MATERIAL" "CHIP"
					( Origin gFrontEnd )
				)
				( attribute "PACK_TYPE" "0603"
					( Origin gFrontEnd )
				)
				( attribute "PART_NUMBER" "G22178-002"
					( Origin gFrontEnd )
				)
				( attribute "PHYS_PAGE" "208"
					( Origin gFrontEnd )
				)
				( attribute "ROOM" "NIC_SPRV"
					( Origin gFrontEnd )
				)
				( attribute "ROT" "0"
					( Origin gFrontEnd )
				)
				( attribute "TOLERANCE" "5.0%"
					( Origin gFrontEnd )
				)
				( attribute "VALUE" "0"
					( Origin gFrontEnd )
				)
				( attribute "VER" "1"
					( Origin gFrontEnd )
				)
				( attribute "WATTAGE" "1/10W"
					( Origin gFrontEnd )
				)
				( attribute "XY" "(-4975,1075)"
					( Origin gFrontEnd )
				)
				( attribute "CHIPS_PART_NAME" "RES"
					( Origin gPackager )
				)
				( attribute "CDS_PART_NAME" "RES_0603-0,5.0%,1/10W,CHIP,G22A"
					( Origin gPackager )
				)
				( attribute "CDS_LOCATION" "RT14"
					( Origin gPackager )
				)
				( attribute "SEC" "1"
					( Origin gFrontEnd )
				)
				( attribute "SEC_TYPE" "0603"
					( Origin gFrontEnd )
				)
				( attribute "CDS_SEC" "1"
					( Origin gPackager )
				)
				( objectStatus "RT14" )
			)
			( gate "@baseboard_fab2_lib.baseboard_fab2(sch_1):page205_i78"
				( attribute "BOM_COST" "NT_GBE_BASE"
					( Origin gFrontEnd )
				)
				( attribute "CDS_LIB" "mstr_discrete"
					( Origin gPackager )
				)
				( attribute "LOCATION" "RT40"
					( Origin gFrontEnd )
				)
				( attribute "MATERIAL" "CHIP"
					( Origin gFrontEnd )
				)
				( attribute "PACK_TYPE" "0603"
					( Origin gFrontEnd )
				)
				( attribute "PART_NUMBER" "G22178-002"
					( Origin gFrontEnd )
				)
				( attribute "PHYS_PAGE" "205"
					( Origin gFrontEnd )
				)
				( attribute "ROOM" "NIC_SPRV"
					( Origin gFrontEnd )
				)
				( attribute "ROT" "0"
					( Origin gFrontEnd )
				)
				( attribute "TOLERANCE" "5.0%"
					( Origin gFrontEnd )
				)
				( attribute "VALUE" "0"
					( Origin gFrontEnd )
				)
				( attribute "VER" "1"
					( Origin gFrontEnd )
				)
				( attribute "WATTAGE" "1/10W"
					( Origin gFrontEnd )
				)
				( attribute "XY" "(-5250,3700)"
					( Origin gFrontEnd )
				)
				( attribute "CHIPS_PART_NAME" "RES"
					( Origin gPackager )
				)
				( attribute "CDS_PART_NAME" "RES_0603-0,5.0%,1/10W,CHIP,G22A"
					( Origin gPackager )
				)
				( attribute "CDS_LOCATION" "RT40"
					( Origin gPackager )
				)
				( attribute "SEC" "1"
					( Origin gFrontEnd )
				)
				( attribute "SEC_TYPE" "0603"
					( Origin gFrontEnd )
				)
				( attribute "CDS_SEC" "1"
					( Origin gPackager )
				)
				( objectStatus "RT40" )
			)
			( gate "@baseboard_fab2_lib.baseboard_fab2(sch_1):page137_i140"
				( attribute "BOM_COST" "SM_CONTROLLER"
					( Origin gFrontEnd )
				)
				( attribute "CDS_LIB" "mstr_discrete"
					( Origin gPackager )
				)
				( attribute "CDS_LOCATION" "R25W94"
					( Origin gPackager )
				)
				( attribute "CDS_SEC" "1"
					( Origin gPackager )
				)
				( attribute "LOCATION" "R25W94"
					( Origin gFrontEnd )
				)
				( attribute "MATERIAL" "CHIP"
					( Origin gFrontEnd )
				)
				( attribute "PACK_TYPE" "0402"
					( Origin gFrontEnd )
				)
				( attribute "PART_NUMBER" "G21796-072"
					( Origin gFrontEnd )
				)
				( attribute "PHYS_PAGE" "137"
					( Origin gFrontEnd )
				)
				( attribute "ROOM" "BMC"
					( Origin gFrontEnd )
				)
				( attribute "ROT" "1"
					( Origin gFrontEnd )
				)
				( attribute "SEC" "1"
					( Origin gFrontEnd )
				)
				( attribute "SEC_TYPE" "0402"
					( Origin gFrontEnd )
				)
				( attribute "TOLERANCE" "1%"
					( Origin gFrontEnd )
				)
				( attribute "VALUE" "4.75K"
					( Origin gFrontEnd )
				)
				( attribute "VER" "1"
					( Origin gFrontEnd )
				)
				( attribute "WATTAGE" "1/16W"
					( Origin gFrontEnd )
				)
				( attribute "XY" "(-1250,3300)"
					( Origin gFrontEnd )
				)
				( attribute "CHIPS_PART_NAME" "RES"
					( Origin gPackager )
				)
				( attribute "CDS_PART_NAME" "RES_0402-4.75K,1%,1/16W,CHIP,GA"
					( Origin gPackager )
				)
				( objectStatus "R25W94" )
			)
			( gate "@baseboard_fab2_lib.baseboard_fab2(sch_1):page137_i133"
				( attribute "BOM_COST" "SM_CONTROLLER"
					( Origin gFrontEnd )
				)
				( attribute "CDS_LIB" "mstr_discrete"
					( Origin gPackager )
				)
				( attribute "CDS_LOCATION" "R25W154"
					( Origin gPackager )
				)
				( attribute "CDS_SEC" "1"
					( Origin gPackager )
				)
				( attribute "LOCATION" "R25W154"
					( Origin gFrontEnd )
				)
				( attribute "MATERIAL" "CHIP"
					( Origin gFrontEnd )
				)
				( attribute "PACK_TYPE" "0402"
					( Origin gFrontEnd )
				)
				( attribute "PART_NUMBER" "G21497-005"
					( Origin gFrontEnd )
				)
				( attribute "PHYS_PAGE" "137"
					( Origin gFrontEnd )
				)
				( attribute "ROOM" "BMC"
					( Origin gFrontEnd )
				)
				( attribute "ROT" "0"
					( Origin gFrontEnd )
				)
				( attribute "SEC" "1"
					( Origin gFrontEnd )
				)
				( attribute "SEC_TYPE" "0402"
					( Origin gFrontEnd )
				)
				( attribute "TOLERANCE" "5%"
					( Origin gFrontEnd )
				)
				( attribute "VALUE" "0.0"
					( Origin gFrontEnd )
				)
				( attribute "VER" "1"
					( Origin gFrontEnd )
				)
				( attribute "WATTAGE" "1/16W"
					( Origin gFrontEnd )
				)
				( attribute "XY" "(-1700,2350)"
					( Origin gFrontEnd )
				)
				( attribute "CHIPS_PART_NAME" "RES"
					( Origin gPackager )
				)
				( attribute "CDS_PART_NAME" "RES_0402-0.0,5%,1/16W,CHIP,G21A"
					( Origin gPackager )
				)
				( objectStatus "R25W154" )
			)
			( gate "@baseboard_fab2_lib.baseboard_fab2(sch_1):page158_i152"
				( attribute "BOM_COST" "DEBUG"
					( Origin gFrontEnd )
				)
				( attribute "CDS_LIB" "mstr_discrete"
					( Origin gPackager )
				)
				( attribute "LOCATION" "R9F66"
					( Origin gFrontEnd )
				)
				( attribute "MATERIAL" "EMPTY"
					( Origin gFrontEnd )
				)
				( attribute "PACK_TYPE" "0402"
					( Origin gFrontEnd )
				)
				( attribute "PART_NUMBER" "G21497-005"
					( Origin gFrontEnd )
				)
				( attribute "PHYS_PAGE" "158"
					( Origin gFrontEnd )
				)
				( attribute "ROOM" "UART_MUX"
					( Origin gFrontEnd )
				)
				( attribute "ROT" "0"
					( Origin gFrontEnd )
				)
				( attribute "TOLERANCE" "5%"
					( Origin gFrontEnd )
				)
				( attribute "VALUE" "0.0"
					( Origin gFrontEnd )
				)
				( attribute "VER" "1"
					( Origin gFrontEnd )
				)
				( attribute "WATTAGE" "1/16W"
					( Origin gFrontEnd )
				)
				( attribute "XY" "(-3150,2575)"
					( Origin gFrontEnd )
				)
				( attribute "CHIPS_PART_NAME" "RES"
					( Origin gPackager )
				)
				( attribute "CDS_PART_NAME" "RES_0402-0.0,5%,1/16W,EMPTY,G2A"
					( Origin gPackager )
				)
				( attribute "CDS_LOCATION" "R9F66"
					( Origin gPackager )
				)
				( attribute "CDS_SEC" "1"
					( Origin gPackager )
				)
				( attribute "SEC" "1"
					( Origin gPackager )
				)
				( objectStatus "R9F66" )
			)
			( gate "@baseboard_fab2_lib.baseboard_fab2(sch_1):page144_i58"
				( attribute "CDS_LIB" "mstr_discrete"
					( Origin gPackager )
				)
				( attribute "CDS_LOCATION" "R1U13"
					( Origin gPackager )
				)
				( attribute "LOCATION" "R1U13"
					( Origin gFrontEnd )
				)
				( attribute "MATERIAL" "CHIP"
					( Origin gFrontEnd )
				)
				( attribute "PACK_TYPE" "0402"
					( Origin gFrontEnd )
				)
				( attribute "PART_NUMBER" "G21497-048"
					( Origin gFrontEnd )
				)
				( attribute "PHYS_PAGE" "144"
					( Origin gFrontEnd )
				)
				( attribute "ROOM" "BMC"
					( Origin gFrontEnd )
				)
				( attribute "ROT" "0"
					( Origin gFrontEnd )
				)
				( attribute "SEC" "1"
					( Origin gFrontEnd )
				)
				( attribute "TOLERANCE" "5.0%"
					( Origin gFrontEnd )
				)
				( attribute "VALUE" "51"
					( Origin gFrontEnd )
				)
				( attribute "VER" "1"
					( Origin gFrontEnd )
				)
				( attribute "WATTAGE" "1/16W"
					( Origin gFrontEnd )
				)
				( attribute "XY" "(-1750,-2050)"
					( Origin gFrontEnd )
				)
				( attribute "CHIPS_PART_NAME" "RES"
					( Origin gPackager )
				)
				( attribute "CDS_PART_NAME" "RES_0402-51,5.0%,1/16W,CHIP,G2A"
					( Origin gPackager )
				)
				( attribute "SEC_TYPE" "0402"
					( Origin gFrontEnd )
				)
				( attribute "CDS_SEC" "1"
					( Origin gPackager )
				)
				( objectStatus "R1U13" )
			)
			( gate "@baseboard_fab2_lib.baseboard_fab2(sch_1):page144_i57"
				( attribute "CDS_LIB" "mstr_discrete"
					( Origin gPackager )
				)
				( attribute "CDS_LOCATION" "R1U14"
					( Origin gPackager )
				)
				( attribute "LOCATION" "R1U14"
					( Origin gFrontEnd )
				)
				( attribute "MATERIAL" "CHIP"
					( Origin gFrontEnd )
				)
				( attribute "PACK_TYPE" "0402"
					( Origin gFrontEnd )
				)
				( attribute "PART_NUMBER" "G21497-048"
					( Origin gFrontEnd )
				)
				( attribute "PHYS_PAGE" "144"
					( Origin gFrontEnd )
				)
				( attribute "ROOM" "BMC"
					( Origin gFrontEnd )
				)
				( attribute "ROT" "0"
					( Origin gFrontEnd )
				)
				( attribute "SEC" "1"
					( Origin gFrontEnd )
				)
				( attribute "TOLERANCE" "5.0%"
					( Origin gFrontEnd )
				)
				( attribute "VALUE" "51"
					( Origin gFrontEnd )
				)
				( attribute "VER" "1"
					( Origin gFrontEnd )
				)
				( attribute "WATTAGE" "1/16W"
					( Origin gFrontEnd )
				)
				( attribute "XY" "(-1750,-2200)"
					( Origin gFrontEnd )
				)
				( attribute "CHIPS_PART_NAME" "RES"
					( Origin gPackager )
				)
				( attribute "CDS_PART_NAME" "RES_0402-51,5.0%,1/16W,CHIP,G2A"
					( Origin gPackager )
				)
				( attribute "SEC_TYPE" "0402"
					( Origin gFrontEnd )
				)
				( attribute "CDS_SEC" "1"
					( Origin gPackager )
				)
				( objectStatus "R1U14" )
			)
			( gate "@baseboard_fab2_lib.baseboard_fab2(sch_1):page148_i28"
				( attribute "CDS_LIB" "w_hdl"
					( Origin gPackager )
				)
				( attribute "CDS_LMAN_SYM_OUTLINE" "-850,2100,850,-2100"
					( Origin gPackager )
				)
				( attribute "LOCATION" "U25W4"
					( Origin gPackager )
				)
				( attribute "PACK_TYPE" "ASIC2-GB1"
					( Origin gFrontEnd )
				)
				( attribute "PART_NUMBER" "071.2520A.M001"
					( Origin gFrontEnd )
				)
				( attribute "PHYS_PAGE" "148"
					( Origin gFrontEnd )
				)
				( attribute "ROT" "0"
					( Origin gFrontEnd )
				)
				( attribute "VALUE" "AST2520A1-GP-GP"
					( Origin gFrontEnd )
				)
				( attribute "VER" "7"
					( Origin gFrontEnd )
				)
				( attribute "XY" "(-3600,2600)"
					( Origin gFrontEnd )
				)
				( attribute "CHIPS_PART_NAME" "AST2520A1-GP-GP"
					( Origin gPackager )
				)
				( attribute "CDS_PART_NAME" "AST2520A1-GP-GP_ASIC2-GB1-AST2A"
					( Origin gPackager )
				)
				( attribute "CDS_LOCATION" "U25W4"
					( Origin gPackager )
				)
				( attribute "CDS_SEC" "7"
					( Origin gPackager )
				)
				( attribute "SEC" "7"
					( Origin gPackager )
				)
				( objectStatus "U25W4" )
			)
			( gate "@baseboard_fab2_lib.baseboard_fab2(sch_1):page149_i123"
				( attribute "CDS_LIB" "dev_discrete"
					( Origin gPackager )
				)
				( attribute "CDS_LOCATION" "C25W49"
					( Origin gPackager )
				)
				( attribute "CDS_SEC" "1"
					( Origin gPackager )
				)
				( attribute "LOCATION" "C25W49"
					( Origin gFrontEnd )
				)
				( attribute "MATERIAL" "X7R"
					( Origin gFrontEnd )
				)
				( attribute "PACK_TYPE" "0402V"
					( Origin gFrontEnd )
				)
				( attribute "PART_NUMBER" "A36096-030"
					( Origin gFrontEnd )
				)
				( attribute "PHYS_PAGE" "149"
					( Origin gFrontEnd )
				)
				( attribute "ROOM" "VDDQ_KLM_PWR_VR"
					( Origin gFrontEnd )
				)
				( attribute "ROT" "0"
					( Origin gFrontEnd )
				)
				( attribute "SEC" "1"
					( Origin gFrontEnd )
				)
				( attribute "SEC_TYPE" "0402V"
					( Origin gFrontEnd )
				)
				( attribute "TOLERANCE" "10%"
					( Origin gFrontEnd )
				)
				( attribute "VALUE" "0.1UF"
					( Origin gFrontEnd )
				)
				( attribute "VER" "1"
					( Origin gFrontEnd )
				)
				( attribute "VOLTAGE" "16V"
					( Units "uVoltage" "V" 1.000000)
					( Origin gFrontEnd )
				)
				( attribute "XY" "(2875,3000)"
					( Origin gFrontEnd )
				)
				( attribute "CHIPS_PART_NAME" "CAP_A"
					( Origin gPackager )
				)
				( attribute "CDS_PART_NAME" "CAP_A_0402V-0.1UF,16V,10%,X7R,A"
					( Origin gPackager )
				)
				( objectStatus "C25W49" )
			)
			( gate "@baseboard_fab2_lib.baseboard_fab2(sch_1):page148_i20"
				( attribute "BOM_COST" "SM_CONTROLLER"
					( Origin gFrontEnd )
				)
				( attribute "CDS_LIB" "dev_discrete"
					( Origin gPackager )
				)
				( attribute "CDS_LOCATION" "C1T21"
					( Origin gPackager )
				)
				( attribute "CDS_SEC" "1"
					( Origin gPackager )
				)
				( attribute "LOCATION" "C1T21"
					( Origin gFrontEnd )
				)
				( attribute "MATERIAL" "X6S"
					( Origin gFrontEnd )
				)
				( attribute "PACK_TYPE" "0402V"
					( Origin gFrontEnd )
				)
				( attribute "PART_NUMBER" "D97712-004"
					( Origin gFrontEnd )
				)
				( attribute "PHYS_PAGE" "148"
					( Origin gFrontEnd )
				)
				( attribute "ROOM" "BMC"
					( Origin gFrontEnd )
				)
				( attribute "ROT" "0"
					( Origin gFrontEnd )
				)
				( attribute "SEC" "1"
					( Origin gFrontEnd )
				)
				( attribute "SEC_TYPE" "0402V"
					( Origin gFrontEnd )
				)
				( attribute "TOLERANCE" "10%"
					( Origin gFrontEnd )
				)
				( attribute "VALUE" "1.0UF"
					( Origin gFrontEnd )
				)
				( attribute "VER" "1"
					( Origin gFrontEnd )
				)
				( attribute "VOLTAGE" "6.3V"
					( Units "uVoltage" "V" 1.000000)
					( Origin gFrontEnd )
				)
				( attribute "XY" "(-7350,2125)"
					( Origin gFrontEnd )
				)
				( attribute "CHIPS_PART_NAME" "CAP_A"
					( Origin gPackager )
				)
				( attribute "CDS_PART_NAME" "CAP_A_0402V-1.0UF,6.3V,10%,X6SA"
					( Origin gPackager )
				)
				( objectStatus "C1T21" )
			)
			( gate "@baseboard_fab2_lib.baseboard_fab2(sch_1):page144_i59"
				( attribute "CDS_LIB" "mstr_discrete"
					( Origin gPackager )
				)
				( attribute "CDS_LOCATION" "R1U12"
					( Origin gPackager )
				)
				( attribute "LOCATION" "R1U12"
					( Origin gFrontEnd )
				)
				( attribute "MATERIAL" "CHIP"
					( Origin gFrontEnd )
				)
				( attribute "PACK_TYPE" "0402"
					( Origin gFrontEnd )
				)
				( attribute "PART_NUMBER" "G21497-048"
					( Origin gFrontEnd )
				)
				( attribute "PHYS_PAGE" "144"
					( Origin gFrontEnd )
				)
				( attribute "ROOM" "BMC"
					( Origin gFrontEnd )
				)
				( attribute "ROT" "0"
					( Origin gFrontEnd )
				)
				( attribute "SEC" "1"
					( Origin gFrontEnd )
				)
				( attribute "TOLERANCE" "5.0%"
					( Origin gFrontEnd )
				)
				( attribute "VALUE" "51"
					( Origin gFrontEnd )
				)
				( attribute "VER" "1"
					( Origin gFrontEnd )
				)
				( attribute "WATTAGE" "1/16W"
					( Origin gFrontEnd )
				)
				( attribute "XY" "(-1750,-2150)"
					( Origin gFrontEnd )
				)
				( attribute "CHIPS_PART_NAME" "RES"
					( Origin gPackager )
				)
				( attribute "CDS_PART_NAME" "RES_0402-51,5.0%,1/16W,CHIP,G2A"
					( Origin gPackager )
				)
				( attribute "SEC_TYPE" "0402"
					( Origin gFrontEnd )
				)
				( attribute "CDS_SEC" "1"
					( Origin gPackager )
				)
				( objectStatus "R1U12" )
			)
			( gate "@baseboard_fab2_lib.baseboard_fab2(sch_1):page148_i16"
				( attribute "BOM_COST" "MIO_USB"
					( Origin gFrontEnd )
				)
				( attribute "CDS_LIB" "mstr_discrete"
					( Origin gPackager )
				)
				( attribute "LOCATION" "R25W59"
					( Origin gFrontEnd )
				)
				( attribute "MATERIAL" "CHIP"
					( Origin gFrontEnd )
				)
				( attribute "PACK_TYPE" "0402"
					( Origin gFrontEnd )
				)
				( attribute "PART_NUMBER" "G21497-005"
					( Origin gFrontEnd )
				)
				( attribute "PHYS_PAGE" "148"
					( Origin gFrontEnd )
				)
				( attribute "ROOM" "USB"
					( Origin gFrontEnd )
				)
				( attribute "ROT" "0"
					( Origin gFrontEnd )
				)
				( attribute "TOLERANCE" "5%"
					( Origin gFrontEnd )
				)
				( attribute "VALUE" "0.0"
					( Origin gFrontEnd )
				)
				( attribute "VER" "1"
					( Origin gFrontEnd )
				)
				( attribute "WATTAGE" "1/16W"
					( Origin gFrontEnd )
				)
				( attribute "XY" "(-6550,3850)"
					( Origin gFrontEnd )
				)
				( attribute "CHIPS_PART_NAME" "RES"
					( Origin gPackager )
				)
				( attribute "CDS_PART_NAME" "RES_0402-0.0,5%,1/16W,CHIP,G21A"
					( Origin gPackager )
				)
				( attribute "CDS_LOCATION" "R25W59"
					( Origin gPackager )
				)
				( attribute "SEC" "1"
					( Origin gFrontEnd )
				)
				( attribute "SEC_TYPE" "0402"
					( Origin gFrontEnd )
				)
				( attribute "CDS_SEC" "1"
					( Origin gPackager )
				)
				( objectStatus "R25W59" )
			)
			( gate "@baseboard_fab2_lib.baseboard_fab2(sch_1):page147_i62"
				( attribute "CDS_LIB" "mstr_discrete"
					( Origin gPackager )
				)
				( attribute "CDS_LOCATION" "R1U2"
					( Origin gPackager )
				)
				( attribute "LOCATION" "R1U2"
					( Origin gFrontEnd )
				)
				( attribute "MATERIAL" "CHIP"
					( Origin gFrontEnd )
				)
				( attribute "PACK_TYPE" "0402"
					( Origin gFrontEnd )
				)
				( attribute "PART_NUMBER" "G21796-010"
					( Origin gFrontEnd )
				)
				( attribute "PHYS_PAGE" "147"
					( Origin gFrontEnd )
				)
				( attribute "ROT" "0"
					( Origin gFrontEnd )
				)
				( attribute "SEC" "1"
					( Origin gFrontEnd )
				)
				( attribute "SEC_TYPE" "0402"
					( Origin gFrontEnd )
				)
				( attribute "TOLERANCE" "1%"
					( Origin gFrontEnd )
				)
				( attribute "VALUE" "100.0K"
					( Origin gFrontEnd )
				)
				( attribute "VER" "2"
					( Origin gFrontEnd )
				)
				( attribute "WATTAGE" "1/16W"
					( Origin gFrontEnd )
				)
				( attribute "XY" "(-3800,1950)"
					( Origin gFrontEnd )
				)
				( attribute "CHIPS_PART_NAME" "RES"
					( Origin gPackager )
				)
				( attribute "CDS_PART_NAME" "RES_0402-100.0K,1%,1/16W,CHIP,A"
					( Origin gPackager )
				)
				( attribute "CDS_SEC" "1"
					( Origin gPackager )
				)
				( objectStatus "R1U2" )
			)
			( gate "@baseboard_fab2_lib.baseboard_fab2(sch_1):page145_i34"
				( attribute "BOM_COST" "SM_CONTROLLER"
					( Origin gFrontEnd )
				)
				( attribute "CDS_LIB" "mstr_discrete"
					( Origin gPackager )
				)
				( attribute "CDS_LOCATION" "R25W60"
					( Origin gPackager )
				)
				( attribute "CDS_SEC" "1"
					( Origin gPackager )
				)
				( attribute "LOCATION" "R25W60"
					( Origin gFrontEnd )
				)
				( attribute "MATERIAL" "CHIP"
					( Origin gFrontEnd )
				)
				( attribute "PACK_TYPE" "0402"
					( Origin gFrontEnd )
				)
				( attribute "PART_NUMBER" "G21796-010"
					( Origin gFrontEnd )
				)
				( attribute "PHYS_PAGE" "145"
					( Origin gFrontEnd )
				)
				( attribute "ROOM" "BMC"
					( Origin gFrontEnd )
				)
				( attribute "ROT" "0"
					( Origin gFrontEnd )
				)
				( attribute "SEC" "1"
					( Origin gFrontEnd )
				)
				( attribute "SEC_TYPE" "0402"
					( Origin gFrontEnd )
				)
				( attribute "TOLERANCE" "1%"
					( Origin gFrontEnd )
				)
				( attribute "VALUE" "100.0K"
					( Origin gFrontEnd )
				)
				( attribute "VER" "2"
					( Origin gFrontEnd )
				)
				( attribute "WATTAGE" "1/16W"
					( Origin gFrontEnd )
				)
				( attribute "XY" "(-5700,-4150)"
					( Origin gFrontEnd )
				)
				( attribute "CHIPS_PART_NAME" "RES"
					( Origin gPackager )
				)
				( attribute "CDS_PART_NAME" "RES_0402-100.0K,1%,1/16W,CHIP,A"
					( Origin gPackager )
				)
				( attribute "GROUP" "AST2520"
					( Origin gFrontEnd )
				)
				( objectStatus "R25W60" )
			)
			( gate "@baseboard_fab2_lib.baseboard_fab2(sch_1):page147_i106"
				( attribute "CDS_LIB" "w_hdl"
					( Origin gPackager )
				)
				( attribute "CDS_LMAN_SYM_OUTLINE" "-1400,1400,1400,-1400"
					( Origin gPackager )
				)
				( attribute "PACK_TYPE" "ASIC2-GB1"
					( Origin gFrontEnd )
				)
				( attribute "PART_NUMBER" "071.2520A.M001"
					( Origin gFrontEnd )
				)
				( attribute "PHYS_PAGE" "147"
					( Origin gFrontEnd )
				)
				( attribute "ROT" "0"
					( Origin gFrontEnd )
				)
				( attribute "VALUE" "AST2520A1-GP-GP"
					( Origin gFrontEnd )
				)
				( attribute "VER" "6"
					( Origin gFrontEnd )
				)
				( attribute "XY" "(-1825,3400)"
					( Origin gFrontEnd )
				)
				( attribute "CHIPS_PART_NAME" "AST2520A1-GP-GP"
					( Origin gPackager )
				)
				( attribute "CDS_PART_NAME" "AST2520A1-GP-GP_ASIC2-GB1-AST2A"
					( Origin gPackager )
				)
				( attribute "LOCATION" "U25W4"
					( Origin gFrontEnd )
				)
				( attribute "SEC" "6"
					( Origin gFrontEnd )
				)
				( attribute "SEC_TYPE" "ASIC2-GB1"
					( Origin gFrontEnd )
				)
				( attribute "CDS_LOCATION" "U25W4"
					( Origin gPackager )
				)
				( attribute "CDS_SEC" "6"
					( Origin gPackager )
				)
				( objectStatus "U25W4" )
			)
			( gate "@baseboard_fab2_lib.baseboard_fab2(sch_1):page147_i61"
				( attribute "CDS_LIB" "mstr_discrete"
					( Origin gPackager )
				)
				( attribute "CDS_LOCATION" "R1U1"
					( Origin gPackager )
				)
				( attribute "LOCATION" "R1U1"
					( Origin gFrontEnd )
				)
				( attribute "MATERIAL" "CHIP"
					( Origin gFrontEnd )
				)
				( attribute "PACK_TYPE" "0402"
					( Origin gFrontEnd )
				)
				( attribute "PART_NUMBER" "G21796-010"
					( Origin gFrontEnd )
				)
				( attribute "PHYS_PAGE" "147"
					( Origin gFrontEnd )
				)
				( attribute "ROT" "0"
					( Origin gFrontEnd )
				)
				( attribute "SEC" "1"
					( Origin gFrontEnd )
				)
				( attribute "SEC_TYPE" "0402"
					( Origin gFrontEnd )
				)
				( attribute "TOLERANCE" "1%"
					( Origin gFrontEnd )
				)
				( attribute "VALUE" "100.0K"
					( Origin gFrontEnd )
				)
				( attribute "VER" "2"
					( Origin gFrontEnd )
				)
				( attribute "WATTAGE" "1/16W"
					( Origin gFrontEnd )
				)
				( attribute "XY" "(-3500,1950)"
					( Origin gFrontEnd )
				)
				( attribute "CHIPS_PART_NAME" "RES"
					( Origin gPackager )
				)
				( attribute "CDS_PART_NAME" "RES_0402-100.0K,1%,1/16W,CHIP,A"
					( Origin gPackager )
				)
				( attribute "CDS_SEC" "1"
					( Origin gPackager )
				)
				( objectStatus "R1U1" )
			)
			( gate "@baseboard_fab2_lib.baseboard_fab2(sch_1):page146_i37"
				( attribute "BOM_COST" "SM_CONTROLLER"
					( Origin gFrontEnd )
				)
				( attribute "CDS_LIB" "mstr_discrete"
					( Origin gPackager )
				)
				( attribute "CDS_LOCATION" "R1T26"
					( Origin gPackager )
				)
				( attribute "LOCATION" "R1T26"
					( Origin gFrontEnd )
				)
				( attribute "MATERIAL" "CHIP"
					( Origin gFrontEnd )
				)
				( attribute "PACK_TYPE" "0402"
					( Origin gFrontEnd )
				)
				( attribute "PART_NUMBER" "G21796-345"
					( Origin gFrontEnd )
				)
				( attribute "PHYS_PAGE" "146"
					( Origin gFrontEnd )
				)
				( attribute "ROOM" "BMC"
					( Origin gFrontEnd )
				)
				( attribute "ROT" "1"
					( Origin gFrontEnd )
				)
				( attribute "SEC" "1"
					( Origin gFrontEnd )
				)
				( attribute "TOLERANCE" "1%"
					( Origin gFrontEnd )
				)
				( attribute "VALUE" "8.2K"
					( Origin gFrontEnd )
				)
				( attribute "VER" "2"
					( Origin gFrontEnd )
				)
				( attribute "WATTAGE" "1/16W"
					( Origin gFrontEnd )
				)
				( attribute "XY" "(-550,4200)"
					( Origin gFrontEnd )
				)
				( attribute "CHIPS_PART_NAME" "RES"
					( Origin gPackager )
				)
				( attribute "CDS_PART_NAME" "RES_0402-8.2K,1%,1/16W,CHIP,G2A"
					( Origin gPackager )
				)
				( attribute "SEC_TYPE" "0402"
					( Origin gFrontEnd )
				)
				( attribute "CDS_SEC" "1"
					( Origin gPackager )
				)
				( objectStatus "R1T26" )
			)
			( gate "@baseboard_fab2_lib.baseboard_fab2(sch_1):page146_i35"
				( attribute "BOM_COST" "SM_CONTROLLER"
					( Origin gFrontEnd )
				)
				( attribute "CDS_LIB" "mstr_discrete"
					( Origin gPackager )
				)
				( attribute "LOCATION" "R1T25"
					( Origin gFrontEnd )
				)
				( attribute "MATERIAL" "CHIP"
					( Origin gFrontEnd )
				)
				( attribute "PACK_TYPE" "0402"
					( Origin gFrontEnd )
				)
				( attribute "PART_NUMBER" "G21796-345"
					( Origin gFrontEnd )
				)
				( attribute "PHYS_PAGE" "146"
					( Origin gFrontEnd )
				)
				( attribute "ROOM" "BMC"
					( Origin gFrontEnd )
				)
				( attribute "ROT" "1"
					( Origin gFrontEnd )
				)
				( attribute "TOLERANCE" "1%"
					( Origin gFrontEnd )
				)
				( attribute "VALUE" "8.2K"
					( Origin gFrontEnd )
				)
				( attribute "VER" "2"
					( Origin gFrontEnd )
				)
				( attribute "WATTAGE" "1/16W"
					( Origin gFrontEnd )
				)
				( attribute "XY" "(-850,4150)"
					( Origin gFrontEnd )
				)
				( attribute "CHIPS_PART_NAME" "RES"
					( Origin gPackager )
				)
				( attribute "CDS_PART_NAME" "RES_0402-8.2K,1%,1/16W,CHIP,G2A"
					( Origin gPackager )
				)
				( attribute "CDS_LOCATION" "R1T25"
					( Origin gPackager )
				)
				( attribute "SEC" "1"
					( Origin gFrontEnd )
				)
				( attribute "SEC_TYPE" "0402"
					( Origin gFrontEnd )
				)
				( attribute "CDS_SEC" "1"
					( Origin gPackager )
				)
				( objectStatus "R1T25" )
			)
			( gate "@baseboard_fab2_lib.baseboard_fab2(sch_1):page146_i26"
				( attribute "BOM_COST" "MIO_USB"
					( Origin gFrontEnd )
				)
				( attribute "CDS_LIB" "mstr_discrete"
					( Origin gPackager )
				)
				( attribute "LOCATION" "R25W83"
					( Origin gFrontEnd )
				)
				( attribute "MATERIAL" "CHIP"
					( Origin gFrontEnd )
				)
				( attribute "PACK_TYPE" "0402"
					( Origin gFrontEnd )
				)
				( attribute "PART_NUMBER" "G21497-005"
					( Origin gFrontEnd )
				)
				( attribute "PHYS_PAGE" "146"
					( Origin gFrontEnd )
				)
				( attribute "ROOM" "USB"
					( Origin gFrontEnd )
				)
				( attribute "ROT" "0"
					( Origin gFrontEnd )
				)
				( attribute "TOLERANCE" "5%"
					( Origin gFrontEnd )
				)
				( attribute "VALUE" "0.0"
					( Origin gFrontEnd )
				)
				( attribute "VER" "1"
					( Origin gFrontEnd )
				)
				( attribute "WATTAGE" "1/16W"
					( Origin gFrontEnd )
				)
				( attribute "XY" "(-6900,3900)"
					( Origin gFrontEnd )
				)
				( attribute "CHIPS_PART_NAME" "RES"
					( Origin gPackager )
				)
				( attribute "CDS_PART_NAME" "RES_0402-0.0,5%,1/16W,CHIP,G21A"
					( Origin gPackager )
				)
				( attribute "CDS_LOCATION" "R25W83"
					( Origin gPackager )
				)
				( attribute "SEC" "1"
					( Origin gFrontEnd )
				)
				( attribute "SEC_TYPE" "0402"
					( Origin gFrontEnd )
				)
				( attribute "CDS_SEC" "1"
					( Origin gPackager )
				)
				( objectStatus "R25W83" )
			)
			( gate "@baseboard_fab2_lib.baseboard_fab2(sch_1):page149_i5"
				( attribute "CDS_LIB" "mstr_discrete"
					( Origin gPackager )
				)
				( attribute "CDS_LOCATION" "C25W70"
					( Origin gPackager )
				)
				( attribute "CDS_SEC" "1"
					( Origin gPackager )
				)
				( attribute "LOCATION" "C25W70"
					( Origin gFrontEnd )
				)
				( attribute "MATERIAL" "X6S"
					( Origin gFrontEnd )
				)
				( attribute "PACK_TYPE" "0603"
					( Origin gFrontEnd )
				)
				( attribute "PART_NUMBER" "E15431-003"
					( Origin gFrontEnd )
				)
				( attribute "PHYS_PAGE" "149"
					( Origin gFrontEnd )
				)
				( attribute "ROT" "0"
					( Origin gFrontEnd )
				)
				( attribute "SEC" "1"
					( Origin gPackager )
				)
				( attribute "TOLERANCE" "10%"
					( Origin gFrontEnd )
				)
				( attribute "VALUE" "4.7UF"
					( Origin gFrontEnd )
				)
				( attribute "VER" "1"
					( Origin gFrontEnd )
				)
				( attribute "VOLTAGE" "6.3V"
					( Units "uVoltage" "V" 1.000000)
					( Origin gFrontEnd )
				)
				( attribute "XY" "(4300,5300)"
					( Origin gFrontEnd )
				)
				( attribute "CHIPS_PART_NAME" "CAP"
					( Origin gPackager )
				)
				( attribute "CDS_PART_NAME" "CAP_0603-4.7UF,6.3V,10%,X6S,E1A"
					( Origin gPackager )
				)
				( objectStatus "C25W70" )
			)
			( gate "@baseboard_fab2_lib.baseboard_fab2(sch_1):page147_i21"
				( attribute "BOM_COST" "SM_CONTROLLER"
					( Origin gFrontEnd )
				)
				( attribute "CDS_LIB" "mstr_discrete"
					( Origin gPackager )
				)
				( attribute "CDS_LOCATION" "R25W90"
					( Origin gPackager )
				)
				( attribute "CDS_SEC" "1"
					( Origin gPackager )
				)
				( attribute "LOCATION" "R25W90"
					( Origin gFrontEnd )
				)
				( attribute "MATERIAL" "CHIP"
					( Origin gFrontEnd )
				)
				( attribute "PACK_TYPE" "0402"
					( Origin gFrontEnd )
				)
				( attribute "PART_NUMBER" "G21796-250"
					( Origin gFrontEnd )
				)
				( attribute "PHYS_PAGE" "147"
					( Origin gFrontEnd )
				)
				( attribute "ROOM" "BMC"
					( Origin gFrontEnd )
				)
				( attribute "ROT" "0"
					( Origin gFrontEnd )
				)
				( attribute "SEC" "1"
					( Origin gFrontEnd )
				)
				( attribute "SEC_TYPE" "0402"
					( Origin gFrontEnd )
				)
				( attribute "TOLERANCE" "1.0%"
					( Origin gFrontEnd )
				)
				( attribute "VALUE" "22.1"
					( Origin gFrontEnd )
				)
				( attribute "VER" "1"
					( Origin gFrontEnd )
				)
				( attribute "WATTAGE" "1/16W"
					( Origin gFrontEnd )
				)
				( attribute "XY" "(1000,4200)"
					( Origin gFrontEnd )
				)
				( attribute "CHIPS_PART_NAME" "RES"
					( Origin gPackager )
				)
				( attribute "CDS_PART_NAME" "RES_0402-22.1,1.0%,1/16W,CHIP,A"
					( Origin gPackager )
				)
				( objectStatus "R25W90" )
			)
			( gate "@baseboard_fab2_lib.baseboard_fab2(sch_1):page149_i124"
				( attribute "CDS_LIB" "dev_discrete"
					( Origin gPackager )
				)
				( attribute "CDS_LOCATION" "C25W55"
					( Origin gPackager )
				)
				( attribute "CDS_SEC" "1"
					( Origin gPackager )
				)
				( attribute "LOCATION" "C25W55"
					( Origin gFrontEnd )
				)
				( attribute "MATERIAL" "X7R"
					( Origin gFrontEnd )
				)
				( attribute "PACK_TYPE" "0402V"
					( Origin gFrontEnd )
				)
				( attribute "PART_NUMBER" "A36096-030"
					( Origin gFrontEnd )
				)
				( attribute "PHYS_PAGE" "149"
					( Origin gFrontEnd )
				)
				( attribute "ROOM" "VDDQ_KLM_PWR_VR"
					( Origin gFrontEnd )
				)
				( attribute "ROT" "0"
					( Origin gFrontEnd )
				)
				( attribute "SEC" "1"
					( Origin gFrontEnd )
				)
				( attribute "SEC_TYPE" "0402V"
					( Origin gFrontEnd )
				)
				( attribute "TOLERANCE" "10%"
					( Origin gFrontEnd )
				)
				( attribute "VALUE" "0.1UF"
					( Origin gFrontEnd )
				)
				( attribute "VER" "1"
					( Origin gFrontEnd )
				)
				( attribute "VOLTAGE" "16V"
					( Units "uVoltage" "V" 1.000000)
					( Origin gFrontEnd )
				)
				( attribute "XY" "(5000,2925)"
					( Origin gFrontEnd )
				)
				( attribute "CHIPS_PART_NAME" "CAP_A"
					( Origin gPackager )
				)
				( attribute "CDS_PART_NAME" "CAP_A_0402V-0.1UF,16V,10%,X7R,A"
					( Origin gPackager )
				)
				( objectStatus "C25W55" )
			)
			( gate "@baseboard_fab2_lib.baseboard_fab2(sch_1):page208_i120"
				( attribute "ATTRIBUTE" "1 OHM"
					( Origin gFrontEnd )
				)
				( attribute "CDS_LIB" "w_hdl"
					( Origin gPackager )
				)
				( attribute "CDS_LMAN_SYM_OUTLINE" "-50,75,50,-75"
					( Origin gPackager )
				)
				( attribute "LOCATION" "RT12"
					( Origin gFrontEnd )
				)
				( attribute "PACK_TYPE" "RCL_GP"
					( Origin gFrontEnd )
				)
				( attribute "PART_NUMBER" "64.1R005.55L"
					( Origin gFrontEnd )
				)
				( attribute "PHYS_PAGE" "208"
					( Origin gFrontEnd )
				)
				( attribute "POP" "NOPOP"
					( Origin gFrontEnd )
				)
				( attribute "RATED" "1/10W"
					( Origin gFrontEnd )
				)
				( attribute "ROT" "0"
					( Origin gFrontEnd )
				)
				( attribute "SEC" "1"
					( Origin gFrontEnd )
				)
				( attribute "SEC_TYPE" "RCL_GP"
					( Origin gFrontEnd )
				)
				( attribute "TOLERANCE" "1%"
					( Origin gFrontEnd )
				)
				( attribute "VALUE" "1R3F-GP"
					( Origin gFrontEnd )
				)
				( attribute "VER" "1"
					( Origin gFrontEnd )
				)
				( attribute "XY" "(-2225,3175)"
					( Origin gFrontEnd )
				)
				( attribute "CHIPS_PART_NAME" "1R3F-GP"
					( Origin gPackager )
				)
				( attribute "CDS_PART_NAME" "1R3F-GP_RCL_GP-1R3F-GP,64.1R00A"
					( Origin gPackager )
				)
				( attribute "PACK_SIZE" "0603"
					( Origin gFrontEnd )
				)
				( attribute "CDS_LOCATION" "RT12"
					( Origin gPackager )
				)
				( attribute "CDS_SEC" "1"
					( Origin gPackager )
				)
				( objectStatus "RT12" )
			)
			( gate "@baseboard_fab2_lib.baseboard_fab2(sch_1):page145_i14"
				( attribute "BOM_COST" "SM_CONTROLLER"
					( Origin gFrontEnd )
				)
				( attribute "CDS_LIB" "mstr_discrete"
					( Origin gPackager )
				)
				( attribute "CDS_LOCATION" "R9F61"
					( Origin gPackager )
				)
				( attribute "CDS_SEC" "1"
					( Origin gPackager )
				)
				( attribute "LOCATION" "R9F61"
					( Origin gFrontEnd )
				)
				( attribute "MATERIAL" "CHIP"
					( Origin gFrontEnd )
				)
				( attribute "PACK_TYPE" "0402"
					( Origin gFrontEnd )
				)
				( attribute "PART_NUMBER" "G21796-016"
					( Origin gFrontEnd )
				)
				( attribute "PHYS_PAGE" "145"
					( Origin gFrontEnd )
				)
				( attribute "ROOM" "BMC"
					( Origin gFrontEnd )
				)
				( attribute "ROT" "0"
					( Origin gFrontEnd )
				)
				( attribute "SEC" "1"
					( Origin gFrontEnd )
				)
				( attribute "SEC_TYPE" "0402"
					( Origin gFrontEnd )
				)
				( attribute "TOLERANCE" "1%"
					( Origin gFrontEnd )
				)
				( attribute "VALUE" "10.0K"
					( Origin gFrontEnd )
				)
				( attribute "VER" "2"
					( Origin gFrontEnd )
				)
				( attribute "WATTAGE" "1/16W"
					( Origin gFrontEnd )
				)
				( attribute "XY" "(-7000,-475)"
					( Origin gFrontEnd )
				)
				( attribute "CHIPS_PART_NAME" "RES"
					( Origin gPackager )
				)
				( attribute "CDS_PART_NAME" "RES_0402-10.0K,1%,1/16W,CHIP,GA"
					( Origin gPackager )
				)
				( objectStatus "R9F61" )
			)
			( gate "@baseboard_fab2_lib.baseboard_fab2(sch_1):page145_i11"
				( attribute "BOM_COST" "SM_CONTROLLER"
					( Origin gFrontEnd )
				)
				( attribute "CDS_LIB" "mstr_discrete"
					( Origin gPackager )
				)
				( attribute "CDS_LOCATION" "R9F62"
					( Origin gPackager )
				)
				( attribute "CDS_SEC" "1"
					( Origin gPackager )
				)
				( attribute "LOCATION" "R9F62"
					( Origin gFrontEnd )
				)
				( attribute "MATERIAL" "CHIP"
					( Origin gFrontEnd )
				)
				( attribute "PACK_TYPE" "0402"
					( Origin gFrontEnd )
				)
				( attribute "PART_NUMBER" "G21497-005"
					( Origin gFrontEnd )
				)
				( attribute "PHYS_PAGE" "145"
					( Origin gFrontEnd )
				)
				( attribute "ROOM" "BMC"
					( Origin gFrontEnd )
				)
				( attribute "ROT" "0"
					( Origin gFrontEnd )
				)
				( attribute "SEC" "1"
					( Origin gFrontEnd )
				)
				( attribute "SEC_TYPE" "0402"
					( Origin gFrontEnd )
				)
				( attribute "TOLERANCE" "5%"
					( Origin gFrontEnd )
				)
				( attribute "VALUE" "0.0"
					( Origin gFrontEnd )
				)
				( attribute "VER" "1"
					( Origin gFrontEnd )
				)
				( attribute "WATTAGE" "1/16W"
					( Origin gFrontEnd )
				)
				( attribute "XY" "(-4450,-550)"
					( Origin gFrontEnd )
				)
				( attribute "CHIPS_PART_NAME" "RES"
					( Origin gPackager )
				)
				( attribute "CDS_PART_NAME" "RES_0402-0.0,5%,1/16W,CHIP,G21A"
					( Origin gPackager )
				)
				( objectStatus "R9F62" )
			)
			( gate "@baseboard_fab2_lib.baseboard_fab2(sch_1):page145_i10"
				( attribute "BOM_COST" "SM_CONTROLLER"
					( Origin gFrontEnd )
				)
				( attribute "CDS_LIB" "mstr_discrete"
					( Origin gPackager )
				)
				( attribute "CDS_LOCATION" "R9F60"
					( Origin gPackager )
				)
				( attribute "CDS_SEC" "1"
					( Origin gPackager )
				)
				( attribute "LOCATION" "R9F60"
					( Origin gFrontEnd )
				)
				( attribute "MATERIAL" "EMPTY"
					( Origin gFrontEnd )
				)
				( attribute "PACK_TYPE" "0402"
					( Origin gFrontEnd )
				)
				( attribute "PART_NUMBER" "G21497-005"
					( Origin gFrontEnd )
				)
				( attribute "PHYS_PAGE" "145"
					( Origin gFrontEnd )
				)
				( attribute "ROOM" "BMC"
					( Origin gFrontEnd )
				)
				( attribute "ROT" "0"
					( Origin gFrontEnd )
				)
				( attribute "SEC" "1"
					( Origin gFrontEnd )
				)
				( attribute "SEC_TYPE" "0402"
					( Origin gFrontEnd )
				)
				( attribute "TOLERANCE" "5%"
					( Origin gFrontEnd )
				)
				( attribute "VALUE" "0.0"
					( Origin gFrontEnd )
				)
				( attribute "VER" "1"
					( Origin gFrontEnd )
				)
				( attribute "WATTAGE" "1/16W"
					( Origin gFrontEnd )
				)
				( attribute "XY" "(-4450,-250)"
					( Origin gFrontEnd )
				)
				( attribute "CHIPS_PART_NAME" "RES"
					( Origin gPackager )
				)
				( attribute "CDS_PART_NAME" "RES_0402-0.0,5%,1/16W,EMPTY,G2A"
					( Origin gPackager )
				)
				( objectStatus "R9F60" )
			)
			( gate "@baseboard_fab2_lib.baseboard_fab2(sch_1):page145_i8"
				( attribute "BOM_COST" "SM_CONTROLLER"
					( Origin gFrontEnd )
				)
				( attribute "CDS_LIB" "mstr_discrete"
					( Origin gPackager )
				)
				( attribute "CDS_LMAN_SYM_OUTLINE" "-350,200,350,-200"
					( Origin gPackager )
				)
				( attribute "CDS_LOCATION" "Y9F2"
					( Origin gPackager )
				)
				( attribute "CDS_SEC" "1"
					( Origin gPackager )
				)
				( attribute "LOCATION" "Y9F2"
					( Origin gFrontEnd )
				)
				( attribute "MATERIAL" "OSC"
					( Origin gFrontEnd )
				)
				( attribute "PACK_TYPE" "SM4"
					( Origin gFrontEnd )
				)
				( attribute "PART_NUMBER" "D34520-021"
					( Origin gFrontEnd )
				)
				( attribute "PHYS_PAGE" "145"
					( Origin gFrontEnd )
				)
				( attribute "ROOM" "BMC"
					( Origin gFrontEnd )
				)
				( attribute "ROT" "0"
					( Origin gFrontEnd )
				)
				( attribute "SEC" "1"
					( Origin gFrontEnd )
				)
				( attribute "SEC_TYPE" "SM4"
					( Origin gFrontEnd )
				)
				( attribute "VALUE" "24MHZ"
					( Origin gFrontEnd )
				)
				( attribute "VER" "11"
					( Origin gFrontEnd )
				)
				( attribute "XY" "(-5750,-650)"
					( Origin gFrontEnd )
				)
				( attribute "CHIPS_PART_NAME" "OSC_C"
					( Origin gPackager )
				)
				( attribute "CDS_PART_NAME" "OSC_C_SM4-24MHZ,OSC,D34520-021"
					( Origin gPackager )
				)
				( objectStatus "Y9F2" )
			)
			( gate "@baseboard_fab2_lib.baseboard_fab2(sch_1):page197_i112"
				( attribute "ATTRIBUTE" "665KOHM"
					( Origin gFrontEnd )
				)
				( attribute "CDS_LIB" "w_hdl"
					( Origin gPackager )
				)
				( attribute "CDS_LMAN_SYM_OUTLINE" "-50,75,50,-75"
					( Origin gPackager )
				)
				( attribute "LOCATION" "R12W15"
					( Origin gFrontEnd )
				)
				( attribute "PACK_TYPE" "SMD-RG2"
					( Origin gFrontEnd )
				)
				( attribute "PART_NUMBER" "064.6653D.06DD"
					( Origin gFrontEnd )
				)
				( attribute "PHYS_PAGE" "197"
					( Origin gFrontEnd )
				)
				( attribute "POP" "NOPOP"
					( Origin gFrontEnd )
				)
				( attribute "RATED" "1/16W"
					( Origin gFrontEnd )
				)
				( attribute "ROT" "1"
					( Origin gFrontEnd )
				)
				( attribute "SEC" "1"
					( Origin gFrontEnd )
				)
				( attribute "SEC_TYPE" "SMD-RG2"
					( Origin gFrontEnd )
				)
				( attribute "TOLERANCE" "0.1%"
					( Origin gFrontEnd )
				)
				( attribute "VALUE" "665KR2B-GP"
					( Origin gFrontEnd )
				)
				( attribute "VER" "1"
					( Origin gFrontEnd )
				)
				( attribute "XY" "(-1700,3800)"
					( Origin gFrontEnd )
				)
				( attribute "CHIPS_PART_NAME" "665KR2B-GP"
					( Origin gPackager )
				)
				( attribute "CDS_PART_NAME" "665KR2B-GP_SMD-RG2-665KR2B-GP,A"
					( Origin gPackager )
				)
				( attribute "PACK_SIZE" "0402"
					( Origin gFrontEnd )
				)
				( attribute "CDS_LOCATION" "R12W15"
					( Origin gPackager )
				)
				( attribute "CDS_SEC" "1"
					( Origin gPackager )
				)
				( objectStatus "R12W15" )
			)
			( gate "@baseboard_fab2_lib.baseboard_fab2(sch_1):page151_i228"
				( attribute "ATTRIBUTE" "120OHM"
					( Origin gFrontEnd )
				)
				( attribute "CDS_LIB" "w_hdl"
					( Origin gPackager )
				)
				( attribute "CDS_LMAN_SYM_OUTLINE" "-50,75,50,-75"
					( Origin gPackager )
				)
				( attribute "LOCATION" "R25W33"
					( Origin gFrontEnd )
				)
				( attribute "PACK_TYPE" "RCL_GP"
					( Origin gFrontEnd )
				)
				( attribute "PART_NUMBER" "64.12005.6DL"
					( Origin gFrontEnd )
				)
				( attribute "PHYS_PAGE" "151"
					( Origin gFrontEnd )
				)
				( attribute "RATED" "1/16W"
					( Origin gFrontEnd )
				)
				( attribute "ROT" "1"
					( Origin gFrontEnd )
				)
				( attribute "SEC" "1"
					( Origin gFrontEnd )
				)
				( attribute "SEC_TYPE" "RCL_GP"
					( Origin gFrontEnd )
				)
				( attribute "TOLERANCE" "1%"
					( Origin gFrontEnd )
				)
				( attribute "VALUE" "120R2F-GP"
					( Origin gFrontEnd )
				)
				( attribute "VER" "1"
					( Origin gFrontEnd )
				)
				( attribute "XY" "(-950,1375)"
					( Origin gFrontEnd )
				)
				( attribute "CHIPS_PART_NAME" "120R2F-GP"
					( Origin gPackager )
				)
				( attribute "CDS_PART_NAME" "120R2F-GP_RCL_GP-120R2F-GP,64.A"
					( Origin gPackager )
				)
				( attribute "PACK_SIZE" "0402"
					( Origin gFrontEnd )
				)
				( attribute "CDS_LOCATION" "R25W33"
					( Origin gPackager )
				)
				( attribute "CDS_SEC" "1"
					( Origin gPackager )
				)
				( objectStatus "R25W33" )
			)
			( gate "@baseboard_fab2_lib.baseboard_fab2(sch_1):page151_i125"
				( attribute "CDS_LIB" "mstr_discrete"
					( Origin gPackager )
				)
				( attribute "CDS_LOCATION" "C25W1"
					( Origin gPackager )
				)
				( attribute "CDS_SEC" "1"
					( Origin gPackager )
				)
				( attribute "LOCATION" "C25W1"
					( Origin gFrontEnd )
				)
				( attribute "MATERIAL" "X6S"
					( Origin gFrontEnd )
				)
				( attribute "PACK_TYPE" "0402"
					( Origin gFrontEnd )
				)
				( attribute "PART_NUMBER" "D97712-011"
					( Origin gFrontEnd )
				)
				( attribute "PHYS_PAGE" "151"
					( Origin gFrontEnd )
				)
				( attribute "ROOM" "VDDQ_KLM_PWR_VR"
					( Origin gFrontEnd )
				)
				( attribute "ROT" "1"
					( Origin gFrontEnd )
				)
				( attribute "SEC" "1"
					( Origin gPackager )
				)
				( attribute "TOLERANCE" "10%"
					( Origin gFrontEnd )
				)
				( attribute "VALUE" "1.0UF"
					( Origin gFrontEnd )
				)
				( attribute "VER" "1"
					( Origin gFrontEnd )
				)
				( attribute "VOLTAGE" "16V"
					( Units "uVoltage" "V" 1.000000)
					( Origin gFrontEnd )
				)
				( attribute "XY" "(325,1675)"
					( Origin gFrontEnd )
				)
				( attribute "CHIPS_PART_NAME" "CAP"
					( Origin gPackager )
				)
				( attribute "CDS_PART_NAME" "CAP_0402-1.0UF,16V,10%,X6S,D97A"
					( Origin gPackager )
				)
				( objectStatus "C25W1" )
			)
			( gate "@baseboard_fab2_lib.baseboard_fab2(sch_1):page151_i123"
				( attribute "CDS_LIB" "mstr_discrete"
					( Origin gPackager )
				)
				( attribute "CDS_LOCATION" "C25W19"
					( Origin gPackager )
				)
				( attribute "LOCATION" "C25W19"
					( Origin gFrontEnd )
				)
				( attribute "MATERIAL" "X6S"
					( Origin gFrontEnd )
				)
				( attribute "PACK_TYPE" "0603"
					( Origin gFrontEnd )
				)
				( attribute "PART_NUMBER" "E15431-003"
					( Origin gFrontEnd )
				)
				( attribute "PHYS_PAGE" "151"
					( Origin gFrontEnd )
				)
				( attribute "ROT" "0"
					( Origin gFrontEnd )
				)
				( attribute "SEC" "1"
					( Origin gFrontEnd )
				)
				( attribute "TOLERANCE" "10%"
					( Origin gFrontEnd )
				)
				( attribute "VALUE" "4.7UF"
					( Origin gFrontEnd )
				)
				( attribute "VER" "1"
					( Origin gFrontEnd )
				)
				( attribute "VOLTAGE" "6.3V"
					( Units "uVoltage" "V" 1.000000)
					( Origin gFrontEnd )
				)
				( attribute "XY" "(-3225,2100)"
					( Origin gFrontEnd )
				)
				( attribute "CHIPS_PART_NAME" "CAP"
					( Origin gPackager )
				)
				( attribute "CDS_PART_NAME" "CAP_0603-4.7UF,6.3V,10%,X6S,E1A"
					( Origin gPackager )
				)
				( attribute "SEC_TYPE" "0603"
					( Origin gFrontEnd )
				)
				( attribute "CDS_SEC" "1"
					( Origin gPackager )
				)
				( objectStatus "C25W19" )
			)
			( gate "@baseboard_fab2_lib.baseboard_fab2(sch_1):page151_i121"
				( attribute "CDS_LIB" "w_hdl"
					( Origin gPackager )
				)
				( attribute "CDS_LMAN_SYM_OUTLINE" "-50,25,50,-25"
					( Origin gPackager )
				)
				( attribute "CDS_LOCATION" "C25W18"
					( Origin gPackager )
				)
				( attribute "CDS_SEC" "1"
					( Origin gPackager )
				)
				( attribute "LOCATION" "C25W18"
					( Origin gFrontEnd )
				)
				( attribute "PACK_TYPE" "SMD-BCG"
					( Origin gFrontEnd )
				)
				( attribute "PART_NUMBER" "78.10521.5BL"
					( Origin gFrontEnd )
				)
				( attribute "PHYS_PAGE" "151"
					( Origin gFrontEnd )
				)
				( attribute "ROT" "0"
					( Origin gFrontEnd )
				)
				( attribute "SEC" "1"
					( Origin gPackager )
				)
				( attribute "VALUE" "SC1U16V3KX-2GP"
					( Origin gFrontEnd )
				)
				( attribute "VER" "1"
					( Origin gFrontEnd )
				)
				( attribute "XY" "(-2925,2100)"
					( Origin gFrontEnd )
				)
				( attribute "CHIPS_PART_NAME" "SC1U16V3KX-2GP"
					( Origin gPackager )
				)
				( attribute "CDS_PART_NAME" "SC1U16V3KX-2GP_SMD-BCG-SC1U16VA"
					( Origin gPackager )
				)
				( attribute "ATTRIBUTE" "1UF"
					( Origin gFrontEnd )
				)
				( attribute "PACK_SIZE" "0603"
					( Origin gFrontEnd )
				)
				( attribute "RATED" "16V"
					( Origin gFrontEnd )
				)
				( attribute "TOLERANCE" "10%"
					( Origin gFrontEnd )
				)
				( attribute "TYPE" "X5R"
					( Origin gFrontEnd )
				)
				( objectStatus "C25W18" )
			)
			( gate "@baseboard_fab2_lib.baseboard_fab2(sch_1):page151_i120"
				( attribute "CDS_LIB" "w_hdl"
					( Origin gPackager )
				)
				( attribute "CDS_LMAN_SYM_OUTLINE" "-50,25,50,-25"
					( Origin gPackager )
				)
				( attribute "CDS_LOCATION" "C25W17"
					( Origin gPackager )
				)
				( attribute "CDS_SEC" "1"
					( Origin gPackager )
				)
				( attribute "LOCATION" "C25W17"
					( Origin gFrontEnd )
				)
				( attribute "PACK_TYPE" "SMD-BCG"
					( Origin gFrontEnd )
				)
				( attribute "PART_NUMBER" "78.10521.5BL"
					( Origin gFrontEnd )
				)
				( attribute "PHYS_PAGE" "151"
					( Origin gFrontEnd )
				)
				( attribute "ROT" "0"
					( Origin gFrontEnd )
				)
				( attribute "SEC" "1"
					( Origin gPackager )
				)
				( attribute "VALUE" "SC1U16V3KX-2GP"
					( Origin gFrontEnd )
				)
				( attribute "VER" "1"
					( Origin gFrontEnd )
				)
				( attribute "XY" "(-2500,2100)"
					( Origin gFrontEnd )
				)
				( attribute "CHIPS_PART_NAME" "SC1U16V3KX-2GP"
					( Origin gPackager )
				)
				( attribute "CDS_PART_NAME" "SC1U16V3KX-2GP_SMD-BCG-SC1U16VA"
					( Origin gPackager )
				)
				( attribute "ATTRIBUTE" "1UF"
					( Origin gFrontEnd )
				)
				( attribute "PACK_SIZE" "0603"
					( Origin gFrontEnd )
				)
				( attribute "RATED" "16V"
					( Origin gFrontEnd )
				)
				( attribute "TOLERANCE" "10%"
					( Origin gFrontEnd )
				)
				( attribute "TYPE" "X5R"
					( Origin gFrontEnd )
				)
				( objectStatus "C25W17" )
			)
			( gate "@baseboard_fab2_lib.baseboard_fab2(sch_1):page146_i160"
				( attribute "CDS_LIB" "mstr_discrete"
					( Origin gPackager )
				)
				( attribute "CDS_LOCATION" "C1W21"
					( Origin gPackager )
				)
				( attribute "CDS_SEC" "1"
					( Origin gPackager )
				)
				( attribute "LOCATION" "C1W21"
					( Origin gFrontEnd )
				)
				( attribute "MATERIAL" "X7R"
					( Origin gFrontEnd )
				)
				( attribute "PACK_TYPE" "0603LF"
					( Origin gFrontEnd )
				)
				( attribute "PART_NUMBER" "603269-064"
					( Origin gFrontEnd )
				)
				( attribute "PHYS_PAGE" "146"
					( Origin gFrontEnd )
				)
				( attribute "ROOM" "HOT_SWAP"
					( Origin gFrontEnd )
				)
				( attribute "ROT" "1"
					( Origin gFrontEnd )
				)
				( attribute "SEC" "1"
					( Origin gFrontEnd )
				)
				( attribute "SEC_TYPE" "0603LF"
					( Origin gFrontEnd )
				)
				( attribute "TOLERANCE" "10%"
					( Origin gFrontEnd )
				)
				( attribute "VALUE" "0.033UF"
					( Origin gFrontEnd )
				)
				( attribute "VER" "1"
					( Origin gFrontEnd )
				)
				( attribute "VOLTAGE" "50V"
					( Units "uVoltage" "V" 1.000000)
					( Origin gFrontEnd )
				)
				( attribute "XY" "(-550,4350)"
					( Origin gFrontEnd )
				)
				( attribute "CHIPS_PART_NAME" "CAP"
					( Origin gPackager )
				)
				( attribute "CDS_PART_NAME" "CAP_0603LF-0.033UF,50V,10%,X7RA"
					( Origin gPackager )
				)
				( objectStatus "C1W21" )
			)
			( gate "@baseboard_fab2_lib.baseboard_fab2(sch_1):page99_i115"
				( attribute "CDS_LIB" "mstr_discrete"
					( Origin gPackager )
				)
				( attribute "CDS_LOCATION" "R6U14"
					( Origin gPackager )
				)
				( attribute "CDS_SEC" "1"
					( Origin gPackager )
				)
				( attribute "LOCATION" "R6U14"
					( Origin gFrontEnd )
				)
				( attribute "MATERIAL" "CHIP"
					( Origin gFrontEnd )
				)
				( attribute "PACK_TYPE" "0402"
					( Origin gFrontEnd )
				)
				( attribute "PART_NUMBER" "G21796-173"
					( Origin gFrontEnd )
				)
				( attribute "PHYS_PAGE" "99"
					( Origin gFrontEnd )
				)
				( attribute "ROOM" "MEM"
					( Origin gFrontEnd )
				)
				( attribute "ROT" "0"
					( Origin gFrontEnd )
				)
				( attribute "SEC" "1"
					( Origin gPackager )
				)
				( attribute "TOLERANCE" "1%"
					( Origin gFrontEnd )
				)
				( attribute "VALUE" "20.0"
					( Origin gFrontEnd )
				)
				( attribute "VER" "1"
					( Origin gFrontEnd )
				)
				( attribute "WATTAGE" "1/16W"
					( Origin gFrontEnd )
				)
				( attribute "XY" "(1600,2100)"
					( Origin gFrontEnd )
				)
				( attribute "CHIPS_PART_NAME" "RES"
					( Origin gPackager )
				)
				( attribute "CDS_PART_NAME" "RES_0402-20.0,1%,1/16W,CHIP,G2A"
					( Origin gPackager )
				)
				( objectStatus "R6U14" )
			)
			( gate "@baseboard_fab2_lib.baseboard_fab2(sch_1):page151_i101"
				( attribute "BOM_COST" "SM_MEM"
					( Origin gFrontEnd )
				)
				( attribute "CDS_LIB" "mstr_discrete"
					( Origin gPackager )
				)
				( attribute "CDS_LOCATION" "R25W117"
					( Origin gPackager )
				)
				( attribute "LOCATION" "R25W117"
					( Origin gFrontEnd )
				)
				( attribute "MATERIAL" "CHIP"
					( Origin gFrontEnd )
				)
				( attribute "PACK_TYPE" "0402"
					( Origin gFrontEnd )
				)
				( attribute "PART_NUMBER" "G21796-294"
					( Origin gFrontEnd )
				)
				( attribute "PHYS_PAGE" "151"
					( Origin gFrontEnd )
				)
				( attribute "ROOM" "BMC_MEMORY"
					( Origin gFrontEnd )
				)
				( attribute "ROT" "0"
					( Origin gFrontEnd )
				)
				( attribute "SEC" "1"
					( Origin gFrontEnd )
				)
				( attribute "TOLERANCE" "1.0%"
					( Origin gFrontEnd )
				)
				( attribute "VALUE" "240"
					( Origin gFrontEnd )
				)
				( attribute "VER" "2"
					( Origin gFrontEnd )
				)
				( attribute "WATTAGE" "1/16W"
					( Origin gFrontEnd )
				)
				( attribute "XY" "(950,-100)"
					( Origin gFrontEnd )
				)
				( attribute "CHIPS_PART_NAME" "RES"
					( Origin gPackager )
				)
				( attribute "CDS_PART_NAME" "RES_0402-240,1.0%,1/16W,CHIP,GA"
					( Origin gPackager )
				)
				( attribute "SEC_TYPE" "0402"
					( Origin gFrontEnd )
				)
				( attribute "CDS_SEC" "1"
					( Origin gPackager )
				)
				( objectStatus "R25W117" )
			)
			( gate "@baseboard_fab2_lib.baseboard_fab2(sch_1):page149_i119"
				( attribute "CDS_LIB" "dev_discrete"
					( Origin gPackager )
				)
				( attribute "CDS_LOCATION" "C25W31"
					( Origin gPackager )
				)
				( attribute "CDS_SEC" "1"
					( Origin gPackager )
				)
				( attribute "LOCATION" "C25W31"
					( Origin gFrontEnd )
				)
				( attribute "MATERIAL" "X7R"
					( Origin gFrontEnd )
				)
				( attribute "PACK_TYPE" "0402V"
					( Origin gFrontEnd )
				)
				( attribute "PART_NUMBER" "A36096-030"
					( Origin gFrontEnd )
				)
				( attribute "PHYS_PAGE" "149"
					( Origin gFrontEnd )
				)
				( attribute "ROOM" "VDDQ_KLM_PWR_VR"
					( Origin gFrontEnd )
				)
				( attribute "ROT" "0"
					( Origin gFrontEnd )
				)
				( attribute "SEC" "1"
					( Origin gFrontEnd )
				)
				( attribute "SEC_TYPE" "0402V"
					( Origin gFrontEnd )
				)
				( attribute "TOLERANCE" "10%"
					( Origin gFrontEnd )
				)
				( attribute "VALUE" "0.1UF"
					( Origin gFrontEnd )
				)
				( attribute "VER" "1"
					( Origin gFrontEnd )
				)
				( attribute "VOLTAGE" "16V"
					( Units "uVoltage" "V" 1.000000)
					( Origin gFrontEnd )
				)
				( attribute "XY" "(-1475,4125)"
					( Origin gFrontEnd )
				)
				( attribute "CHIPS_PART_NAME" "CAP_A"
					( Origin gPackager )
				)
				( attribute "CDS_PART_NAME" "CAP_A_0402V-0.1UF,16V,10%,X7R,A"
					( Origin gPackager )
				)
				( objectStatus "C25W31" )
			)
			( gate "@baseboard_fab2_lib.baseboard_fab2(sch_1):page149_i120"
				( attribute "CDS_LIB" "dev_discrete"
					( Origin gPackager )
				)
				( attribute "CDS_LOCATION" "C25W34"
					( Origin gPackager )
				)
				( attribute "CDS_SEC" "1"
					( Origin gPackager )
				)
				( attribute "LOCATION" "C25W34"
					( Origin gFrontEnd )
				)
				( attribute "MATERIAL" "X7R"
					( Origin gFrontEnd )
				)
				( attribute "PACK_TYPE" "0402V"
					( Origin gFrontEnd )
				)
				( attribute "PART_NUMBER" "A36096-030"
					( Origin gFrontEnd )
				)
				( attribute "PHYS_PAGE" "149"
					( Origin gFrontEnd )
				)
				( attribute "ROOM" "VDDQ_KLM_PWR_VR"
					( Origin gFrontEnd )
				)
				( attribute "ROT" "0"
					( Origin gFrontEnd )
				)
				( attribute "SEC" "1"
					( Origin gFrontEnd )
				)
				( attribute "SEC_TYPE" "0402V"
					( Origin gFrontEnd )
				)
				( attribute "TOLERANCE" "10%"
					( Origin gFrontEnd )
				)
				( attribute "VALUE" "0.1UF"
					( Origin gFrontEnd )
				)
				( attribute "VER" "1"
					( Origin gFrontEnd )
				)
				( attribute "VOLTAGE" "16V"
					( Units "uVoltage" "V" 1.000000)
					( Origin gFrontEnd )
				)
				( attribute "XY" "(425,4000)"
					( Origin gFrontEnd )
				)
				( attribute "CHIPS_PART_NAME" "CAP_A"
					( Origin gPackager )
				)
				( attribute "CDS_PART_NAME" "CAP_A_0402V-0.1UF,16V,10%,X7R,A"
					( Origin gPackager )
				)
				( objectStatus "C25W34" )
			)
			( gate "@baseboard_fab2_lib.baseboard_fab2(sch_1):page151_i248"
				( attribute "ATTRIBUTE" "120OHM"
					( Origin gFrontEnd )
				)
				( attribute "CDS_LIB" "w_hdl"
					( Origin gPackager )
				)
				( attribute "CDS_LMAN_SYM_OUTLINE" "-50,75,50,-75"
					( Origin gPackager )
				)
				( attribute "LOCATION" "R25W1"
					( Origin gFrontEnd )
				)
				( attribute "PACK_TYPE" "RCL_GP"
					( Origin gFrontEnd )
				)
				( attribute "PART_NUMBER" "64.12005.6DL"
					( Origin gFrontEnd )
				)
				( attribute "PHYS_PAGE" "151"
					( Origin gFrontEnd )
				)
				( attribute "RATED" "1/16W"
					( Origin gFrontEnd )
				)
				( attribute "ROT" "1"
					( Origin gFrontEnd )
				)
				( attribute "SEC" "1"
					( Origin gFrontEnd )
				)
				( attribute "SEC_TYPE" "RCL_GP"
					( Origin gFrontEnd )
				)
				( attribute "TOLERANCE" "1%"
					( Origin gFrontEnd )
				)
				( attribute "VALUE" "120R2F-GP"
					( Origin gFrontEnd )
				)
				( attribute "VER" "1"
					( Origin gFrontEnd )
				)
				( attribute "XY" "(-3025,1675)"
					( Origin gFrontEnd )
				)
				( attribute "CHIPS_PART_NAME" "120R2F-GP"
					( Origin gPackager )
				)
				( attribute "CDS_PART_NAME" "120R2F-GP_RCL_GP-120R2F-GP,64.A"
					( Origin gPackager )
				)
				( attribute "PACK_SIZE" "0402"
					( Origin gFrontEnd )
				)
				( attribute "CDS_LOCATION" "R25W1"
					( Origin gPackager )
				)
				( attribute "CDS_SEC" "1"
					( Origin gPackager )
				)
				( objectStatus "R25W1" )
			)
			( gate "@baseboard_fab2_lib.baseboard_fab2(sch_1):page151_i56"
				( attribute "CDS_LIB" "mstr_ttl"
					( Origin gPackager )
				)
				( attribute "CDS_LOCATION" "U9F3"
					( Origin gPackager )
				)
				( attribute "CDS_SEC" "1"
					( Origin gPackager )
				)
				( attribute "LOCATION" "U9F3"
					( Origin gFrontEnd )
				)
				( attribute "MATERIAL" "IC"
					( Origin gFrontEnd )
				)
				( attribute "PACK_TYPE" "SOP"
					( Origin gFrontEnd )
				)
				( attribute "PART_NUMBER" "C88419-001"
					( Origin gFrontEnd )
				)
				( attribute "PHYS_PAGE" "151"
					( Origin gFrontEnd )
				)
				( attribute "ROOM" "BMC_MEMORY"
					( Origin gFrontEnd )
				)
				( attribute "ROT" "0"
					( Origin gFrontEnd )
				)
				( attribute "SEC" "1"
					( Origin gFrontEnd )
				)
				( attribute "SEC_TYPE" "SOP"
					( Origin gFrontEnd )
				)
				( attribute "VALUE" "74LVC1G07"
					( Origin gFrontEnd )
				)
				( attribute "VER" "1"
					( Origin gFrontEnd )
				)
				( attribute "XY" "(2025,1975)"
					( Origin gFrontEnd )
				)
				( attribute "CHIPS_PART_NAME" "TTL1G07_A"
					( Origin gPackager )
				)
				( attribute "CDS_PART_NAME" "TTL1G07_A_SOP-74LVC1G07,IC,C88B"
					( Origin gPackager )
				)
				( attribute "POP" "NOPOP"
					( Origin gFrontEnd )
				)
				( objectStatus "U9F3" )
			)
			( gate "@baseboard_fab2_lib.baseboard_fab2(sch_1):page147_i129"
				( attribute "CDS_LIB" "mstr_discrete"
					( Origin gPackager )
				)
				( attribute "CDS_LOCATION" "R1T24"
					( Origin gPackager )
				)
				( attribute "CDS_SEC" "1"
					( Origin gPackager )
				)
				( attribute "LOCATION" "R1T24"
					( Origin gFrontEnd )
				)
				( attribute "MATERIAL" "EMPTY"
					( Origin gFrontEnd )
				)
				( attribute "PACK_TYPE" "0402"
					( Origin gFrontEnd )
				)
				( attribute "PART_NUMBER" "G21497-005"
					( Origin gFrontEnd )
				)
				( attribute "PHYS_PAGE" "147"
					( Origin gFrontEnd )
				)
				( attribute "ROT" "0"
					( Origin gFrontEnd )
				)
				( attribute "SEC" "1"
					( Origin gFrontEnd )
				)
				( attribute "SEC_TYPE" "0402"
					( Origin gFrontEnd )
				)
				( attribute "TOLERANCE" "5%"
					( Origin gFrontEnd )
				)
				( attribute "VALUE" "0.0"
					( Origin gFrontEnd )
				)
				( attribute "VER" "1"
					( Origin gFrontEnd )
				)
				( attribute "WATTAGE" "1/16W"
					( Origin gFrontEnd )
				)
				( attribute "XY" "(-4100,1500)"
					( Origin gFrontEnd )
				)
				( attribute "CHIPS_PART_NAME" "RES"
					( Origin gPackager )
				)
				( attribute "CDS_PART_NAME" "RES_0402-0.0,5%,1/16W,EMPTY,G2A"
					( Origin gPackager )
				)
				( objectStatus "R1T24" )
			)
			( gate "@baseboard_fab2_lib.baseboard_fab2(sch_1):page147_i66"
				( attribute "CDS_LIB" "mstr_discrete"
					( Origin gPackager )
				)
				( attribute "CDS_LOCATION" "R1U5"
					( Origin gPackager )
				)
				( attribute "LOCATION" "R1U5"
					( Origin gFrontEnd )
				)
				( attribute "MATERIAL" "CHIP"
					( Origin gFrontEnd )
				)
				( attribute "PACK_TYPE" "0402"
					( Origin gFrontEnd )
				)
				( attribute "PART_NUMBER" "G21796-010"
					( Origin gFrontEnd )
				)
				( attribute "PHYS_PAGE" "147"
					( Origin gFrontEnd )
				)
				( attribute "ROT" "0"
					( Origin gFrontEnd )
				)
				( attribute "SEC" "1"
					( Origin gFrontEnd )
				)
				( attribute "SEC_TYPE" "0402"
					( Origin gFrontEnd )
				)
				( attribute "TOLERANCE" "1%"
					( Origin gFrontEnd )
				)
				( attribute "VALUE" "100.0K"
					( Origin gFrontEnd )
				)
				( attribute "VER" "2"
					( Origin gFrontEnd )
				)
				( attribute "WATTAGE" "1/16W"
					( Origin gFrontEnd )
				)
				( attribute "XY" "(-4400,1950)"
					( Origin gFrontEnd )
				)
				( attribute "CHIPS_PART_NAME" "RES"
					( Origin gPackager )
				)
				( attribute "CDS_PART_NAME" "RES_0402-100.0K,1%,1/16W,CHIP,A"
					( Origin gPackager )
				)
				( attribute "CDS_SEC" "1"
					( Origin gPackager )
				)
				( objectStatus "R1U5" )
			)
			( gate "@baseboard_fab2_lib.baseboard_fab2(sch_1):page147_i65"
				( attribute "CDS_LIB" "mstr_discrete"
					( Origin gPackager )
				)
				( attribute "CDS_LOCATION" "R1U4"
					( Origin gPackager )
				)
				( attribute "LOCATION" "R1U4"
					( Origin gFrontEnd )
				)
				( attribute "MATERIAL" "CHIP"
					( Origin gFrontEnd )
				)
				( attribute "PACK_TYPE" "0402"
					( Origin gFrontEnd )
				)
				( attribute "PART_NUMBER" "G21796-010"
					( Origin gFrontEnd )
				)
				( attribute "PHYS_PAGE" "147"
					( Origin gFrontEnd )
				)
				( attribute "ROT" "0"
					( Origin gFrontEnd )
				)
				( attribute "SEC" "1"
					( Origin gFrontEnd )
				)
				( attribute "SEC_TYPE" "0402"
					( Origin gFrontEnd )
				)
				( attribute "TOLERANCE" "1%"
					( Origin gFrontEnd )
				)
				( attribute "VALUE" "100.0K"
					( Origin gFrontEnd )
				)
				( attribute "VER" "2"
					( Origin gFrontEnd )
				)
				( attribute "WATTAGE" "1/16W"
					( Origin gFrontEnd )
				)
				( attribute "XY" "(-4100,1950)"
					( Origin gFrontEnd )
				)
				( attribute "CHIPS_PART_NAME" "RES"
					( Origin gPackager )
				)
				( attribute "CDS_PART_NAME" "RES_0402-100.0K,1%,1/16W,CHIP,A"
					( Origin gPackager )
				)
				( attribute "CDS_SEC" "1"
					( Origin gPackager )
				)
				( objectStatus "R1U4" )
			)
			( gate "@baseboard_fab2_lib.baseboard_fab2(sch_1):page147_i43"
				( attribute "BOM_COST" "SM_CONTROLLER"
					( Origin gFrontEnd )
				)
				( attribute "CDS_LIB" "mstr_discrete"
					( Origin gPackager )
				)
				( attribute "CDS_LOCATION" "R25W80"
					( Origin gPackager )
				)
				( attribute "LOCATION" "R25W80"
					( Origin gFrontEnd )
				)
				( attribute "MATERIAL" "CHIP"
					( Origin gFrontEnd )
				)
				( attribute "PACK_TYPE" "0402"
					( Origin gFrontEnd )
				)
				( attribute "PART_NUMBER" "G21796-016"
					( Origin gFrontEnd )
				)
				( attribute "PHYS_PAGE" "147"
					( Origin gFrontEnd )
				)
				( attribute "ROOM" "BMC"
					( Origin gFrontEnd )
				)
				( attribute "ROT" "0"
					( Origin gFrontEnd )
				)
				( attribute "SEC" "1"
					( Origin gFrontEnd )
				)
				( attribute "SEC_TYPE" "0402"
					( Origin gFrontEnd )
				)
				( attribute "TOLERANCE" "1%"
					( Origin gFrontEnd )
				)
				( attribute "VALUE" "10.0K"
					( Origin gFrontEnd )
				)
				( attribute "VER" "2"
					( Origin gFrontEnd )
				)
				( attribute "WATTAGE" "1/16W"
					( Origin gFrontEnd )
				)
				( attribute "XY" "(-3900,4950)"
					( Origin gFrontEnd )
				)
				( attribute "CHIPS_PART_NAME" "RES"
					( Origin gPackager )
				)
				( attribute "CDS_PART_NAME" "RES_0402-10.0K,1%,1/16W,CHIP,GA"
					( Origin gPackager )
				)
				( attribute "CDS_SEC" "1"
					( Origin gPackager )
				)
				( objectStatus "R25W80" )
			)
			( gate "@baseboard_fab2_lib.baseboard_fab2(sch_1):page147_i42"
				( attribute "BOM_COST" "SM_CONTROLLER"
					( Origin gFrontEnd )
				)
				( attribute "CDS_LIB" "mstr_discrete"
					( Origin gPackager )
				)
				( attribute "CDS_LOCATION" "R25W79"
					( Origin gPackager )
				)
				( attribute "LOCATION" "R25W79"
					( Origin gFrontEnd )
				)
				( attribute "MATERIAL" "CHIP"
					( Origin gFrontEnd )
				)
				( attribute "PACK_TYPE" "0402"
					( Origin gFrontEnd )
				)
				( attribute "PART_NUMBER" "G21796-016"
					( Origin gFrontEnd )
				)
				( attribute "PHYS_PAGE" "147"
					( Origin gFrontEnd )
				)
				( attribute "ROOM" "BMC"
					( Origin gFrontEnd )
				)
				( attribute "ROT" "0"
					( Origin gFrontEnd )
				)
				( attribute "SEC" "1"
					( Origin gFrontEnd )
				)
				( attribute "SEC_TYPE" "0402"
					( Origin gFrontEnd )
				)
				( attribute "TOLERANCE" "1%"
					( Origin gFrontEnd )
				)
				( attribute "VALUE" "10.0K"
					( Origin gFrontEnd )
				)
				( attribute "VER" "2"
					( Origin gFrontEnd )
				)
				( attribute "WATTAGE" "1/16W"
					( Origin gFrontEnd )
				)
				( attribute "XY" "(-3600,4950)"
					( Origin gFrontEnd )
				)
				( attribute "CHIPS_PART_NAME" "RES"
					( Origin gPackager )
				)
				( attribute "CDS_PART_NAME" "RES_0402-10.0K,1%,1/16W,CHIP,GA"
					( Origin gPackager )
				)
				( attribute "CDS_SEC" "1"
					( Origin gPackager )
				)
				( objectStatus "R25W79" )
			)
			( gate "@baseboard_fab2_lib.baseboard_fab2(sch_1):page147_i161"
				( attribute "BOM_COST" "PROC_SIDEBAND"
					( Origin gFrontEnd )
				)
				( attribute "CDS_LIB" "dev_discrete"
					( Origin gPackager )
				)
				( attribute "CDS_LOCATION" "C25W7"
					( Origin gPackager )
				)
				( attribute "CDS_SEC" "1"
					( Origin gPackager )
				)
				( attribute "LOCATION" "C25W7"
					( Origin gFrontEnd )
				)
				( attribute "MATERIAL" "X7R"
					( Origin gFrontEnd )
				)
				( attribute "PACK_TYPE" "0402V"
					( Origin gFrontEnd )
				)
				( attribute "PART_NUMBER" "A36096-030"
					( Origin gFrontEnd )
				)
				( attribute "PHYS_PAGE" "147"
					( Origin gFrontEnd )
				)
				( attribute "ROOM" "PROC_SIDEBAND"
					( Origin gFrontEnd )
				)
				( attribute "ROT" "1"
					( Origin gFrontEnd )
				)
				( attribute "SEC" "1"
					( Origin gFrontEnd )
				)
				( attribute "SEC_TYPE" "0402V"
					( Origin gFrontEnd )
				)
				( attribute "TOLERANCE" "10%"
					( Origin gFrontEnd )
				)
				( attribute "VALUE" "0.1UF"
					( Origin gFrontEnd )
				)
				( attribute "VER" "1"
					( Origin gFrontEnd )
				)
				( attribute "VOLTAGE" "16V"
					( Units "uVoltage" "V" 1.000000)
					( Origin gFrontEnd )
				)
				( attribute "XY" "(2000,2300)"
					( Origin gFrontEnd )
				)
				( attribute "CHIPS_PART_NAME" "CAP_A"
					( Origin gPackager )
				)
				( attribute "CDS_PART_NAME" "CAP_A_0402V-0.1UF,16V,10%,X7R,A"
					( Origin gPackager )
				)
				( objectStatus "C25W7" )
			)
			( gate "@baseboard_fab2_lib.baseboard_fab2(sch_1):page147_i25"
				( attribute "BOM_COST" "SM_CONTROLLER"
					( Origin gFrontEnd )
				)
				( attribute "CDS_LIB" "mstr_discrete"
					( Origin gPackager )
				)
				( attribute "CDS_LOCATION" "R25W87"
					( Origin gPackager )
				)
				( attribute "CDS_SEC" "1"
					( Origin gPackager )
				)
				( attribute "LOCATION" "R25W87"
					( Origin gFrontEnd )
				)
				( attribute "MATERIAL" "CHIP"
					( Origin gFrontEnd )
				)
				( attribute "PACK_TYPE" "0402"
					( Origin gFrontEnd )
				)
				( attribute "PART_NUMBER" "G21796-250"
					( Origin gFrontEnd )
				)
				( attribute "PHYS_PAGE" "147"
					( Origin gFrontEnd )
				)
				( attribute "ROOM" "BMC"
					( Origin gFrontEnd )
				)
				( attribute "ROT" "0"
					( Origin gFrontEnd )
				)
				( attribute "SEC" "1"
					( Origin gFrontEnd )
				)
				( attribute "SEC_TYPE" "0402"
					( Origin gFrontEnd )
				)
				( attribute "TOLERANCE" "1.0%"
					( Origin gFrontEnd )
				)
				( attribute "VALUE" "22.1"
					( Origin gFrontEnd )
				)
				( attribute "VER" "1"
					( Origin gFrontEnd )
				)
				( attribute "WATTAGE" "1/16W"
					( Origin gFrontEnd )
				)
				( attribute "XY" "(800,3800)"
					( Origin gFrontEnd )
				)
				( attribute "CHIPS_PART_NAME" "RES"
					( Origin gPackager )
				)
				( attribute "CDS_PART_NAME" "RES_0402-22.1,1.0%,1/16W,CHIP,A"
					( Origin gPackager )
				)
				( objectStatus "R25W87" )
			)
			( gate "@baseboard_fab2_lib.baseboard_fab2(sch_1):page147_i24"
				( attribute "BOM_COST" "SM_CONTROLLER"
					( Origin gFrontEnd )
				)
				( attribute "CDS_LIB" "mstr_discrete"
					( Origin gPackager )
				)
				( attribute "CDS_LOCATION" "R25W86"
					( Origin gPackager )
				)
				( attribute "CDS_SEC" "1"
					( Origin gPackager )
				)
				( attribute "LOCATION" "R25W86"
					( Origin gFrontEnd )
				)
				( attribute "MATERIAL" "CHIP"
					( Origin gFrontEnd )
				)
				( attribute "PACK_TYPE" "0402"
					( Origin gFrontEnd )
				)
				( attribute "PART_NUMBER" "G21796-250"
					( Origin gFrontEnd )
				)
				( attribute "PHYS_PAGE" "147"
					( Origin gFrontEnd )
				)
				( attribute "ROOM" "BMC"
					( Origin gFrontEnd )
				)
				( attribute "ROT" "0"
					( Origin gFrontEnd )
				)
				( attribute "SEC" "1"
					( Origin gFrontEnd )
				)
				( attribute "SEC_TYPE" "0402"
					( Origin gFrontEnd )
				)
				( attribute "TOLERANCE" "1.0%"
					( Origin gFrontEnd )
				)
				( attribute "VALUE" "22.1"
					( Origin gFrontEnd )
				)
				( attribute "VER" "1"
					( Origin gFrontEnd )
				)
				( attribute "WATTAGE" "1/16W"
					( Origin gFrontEnd )
				)
				( attribute "XY" "(800,3750)"
					( Origin gFrontEnd )
				)
				( attribute "CHIPS_PART_NAME" "RES"
					( Origin gPackager )
				)
				( attribute "CDS_PART_NAME" "RES_0402-22.1,1.0%,1/16W,CHIP,A"
					( Origin gPackager )
				)
				( objectStatus "R25W86" )
			)
			( gate "@baseboard_fab2_lib.baseboard_fab2(sch_1):page147_i23"
				( attribute "BOM_COST" "SM_CONTROLLER"
					( Origin gFrontEnd )
				)
				( attribute "CDS_LIB" "mstr_discrete"
					( Origin gPackager )
				)
				( attribute "CDS_LOCATION" "R25W85"
					( Origin gPackager )
				)
				( attribute "CDS_SEC" "1"
					( Origin gPackager )
				)
				( attribute "LOCATION" "R25W85"
					( Origin gFrontEnd )
				)
				( attribute "MATERIAL" "CHIP"
					( Origin gFrontEnd )
				)
				( attribute "PACK_TYPE" "0402"
					( Origin gFrontEnd )
				)
				( attribute "PART_NUMBER" "G21796-250"
					( Origin gFrontEnd )
				)
				( attribute "PHYS_PAGE" "147"
					( Origin gFrontEnd )
				)
				( attribute "ROOM" "BMC"
					( Origin gFrontEnd )
				)
				( attribute "ROT" "0"
					( Origin gFrontEnd )
				)
				( attribute "SEC" "1"
					( Origin gFrontEnd )
				)
				( attribute "SEC_TYPE" "0402"
					( Origin gFrontEnd )
				)
				( attribute "TOLERANCE" "1.0%"
					( Origin gFrontEnd )
				)
				( attribute "VALUE" "22.1"
					( Origin gFrontEnd )
				)
				( attribute "VER" "1"
					( Origin gFrontEnd )
				)
				( attribute "WATTAGE" "1/16W"
					( Origin gFrontEnd )
				)
				( attribute "XY" "(800,4000)"
					( Origin gFrontEnd )
				)
				( attribute "CHIPS_PART_NAME" "RES"
					( Origin gPackager )
				)
				( attribute "CDS_PART_NAME" "RES_0402-22.1,1.0%,1/16W,CHIP,A"
					( Origin gPackager )
				)
				( objectStatus "R25W85" )
			)
			( gate "@baseboard_fab2_lib.baseboard_fab2(sch_1):page147_i22"
				( attribute "BOM_COST" "SM_CONTROLLER"
					( Origin gFrontEnd )
				)
				( attribute "CDS_LIB" "mstr_discrete"
					( Origin gPackager )
				)
				( attribute "CDS_LOCATION" "R25W89"
					( Origin gPackager )
				)
				( attribute "CDS_SEC" "1"
					( Origin gPackager )
				)
				( attribute "LOCATION" "R25W89"
					( Origin gFrontEnd )
				)
				( attribute "MATERIAL" "CHIP"
					( Origin gFrontEnd )
				)
				( attribute "PACK_TYPE" "0402"
					( Origin gFrontEnd )
				)
				( attribute "PART_NUMBER" "G21796-250"
					( Origin gFrontEnd )
				)
				( attribute "PHYS_PAGE" "147"
					( Origin gFrontEnd )
				)
				( attribute "ROOM" "BMC"
					( Origin gFrontEnd )
				)
				( attribute "ROT" "0"
					( Origin gFrontEnd )
				)
				( attribute "SEC" "1"
					( Origin gFrontEnd )
				)
				( attribute "SEC_TYPE" "0402"
					( Origin gFrontEnd )
				)
				( attribute "TOLERANCE" "1.0%"
					( Origin gFrontEnd )
				)
				( attribute "VALUE" "22.1"
					( Origin gFrontEnd )
				)
				( attribute "VER" "1"
					( Origin gFrontEnd )
				)
				( attribute "WATTAGE" "1/16W"
					( Origin gFrontEnd )
				)
				( attribute "XY" "(1000,4150)"
					( Origin gFrontEnd )
				)
				( attribute "CHIPS_PART_NAME" "RES"
					( Origin gPackager )
				)
				( attribute "CDS_PART_NAME" "RES_0402-22.1,1.0%,1/16W,CHIP,A"
					( Origin gPackager )
				)
				( objectStatus "R25W89" )
			)
			( gate "@baseboard_fab2_lib.baseboard_fab2(sch_1):page147_i8"
				( attribute "BOM_COST" "SM_CONTROLLER"
					( Origin gFrontEnd )
				)
				( attribute "CDS_LIB" "mstr_discrete"
					( Origin gPackager )
				)
				( attribute "CDS_LOCATION" "R25W88"
					( Origin gPackager )
				)
				( attribute "CDS_SEC" "1"
					( Origin gPackager )
				)
				( attribute "LOCATION" "R25W88"
					( Origin gFrontEnd )
				)
				( attribute "MATERIAL" "CHIP"
					( Origin gFrontEnd )
				)
				( attribute "PACK_TYPE" "0402"
					( Origin gFrontEnd )
				)
				( attribute "PART_NUMBER" "G21796-250"
					( Origin gFrontEnd )
				)
				( attribute "PHYS_PAGE" "147"
					( Origin gFrontEnd )
				)
				( attribute "ROOM" "BMC"
					( Origin gFrontEnd )
				)
				( attribute "ROT" "0"
					( Origin gFrontEnd )
				)
				( attribute "SEC" "1"
					( Origin gFrontEnd )
				)
				( attribute "SEC_TYPE" "0402"
					( Origin gFrontEnd )
				)
				( attribute "TOLERANCE" "1.0%"
					( Origin gFrontEnd )
				)
				( attribute "VALUE" "22.1"
					( Origin gFrontEnd )
				)
				( attribute "VER" "1"
					( Origin gFrontEnd )
				)
				( attribute "WATTAGE" "1/16W"
					( Origin gFrontEnd )
				)
				( attribute "XY" "(1000,4400)"
					( Origin gFrontEnd )
				)
				( attribute "CHIPS_PART_NAME" "RES"
					( Origin gPackager )
				)
				( attribute "CDS_PART_NAME" "RES_0402-22.1,1.0%,1/16W,CHIP,A"
					( Origin gPackager )
				)
				( objectStatus "R25W88" )
			)
			( gate "@baseboard_fab2_lib.baseboard_fab2(sch_1):page146_i85"
				( attribute "BOM_COST" "SB"
					( Origin gFrontEnd )
				)
				( attribute "CDS_LIB" "mstr_discrete"
					( Origin gPackager )
				)
				( attribute "LOCATION" "R25W69"
					( Origin gFrontEnd )
				)
				( attribute "MATERIAL" "CHIP"
					( Origin gFrontEnd )
				)
				( attribute "PACK_TYPE" "0402"
					( Origin gFrontEnd )
				)
				( attribute "PART_NUMBER" "G21796-074"
					( Origin gFrontEnd )
				)
				( attribute "PHYS_PAGE" "146"
					( Origin gFrontEnd )
				)
				( attribute "ROOM" "BMC"
					( Origin gFrontEnd )
				)
				( attribute "ROT" "0"
					( Origin gFrontEnd )
				)
				( attribute "TOLERANCE" "1%"
					( Origin gFrontEnd )
				)
				( attribute "VALUE" "33.2"
					( Origin gFrontEnd )
				)
				( attribute "VER" "1"
					( Origin gFrontEnd )
				)
				( attribute "WATTAGE" "1/16W"
					( Origin gFrontEnd )
				)
				( attribute "XY" "(-6850,1300)"
					( Origin gFrontEnd )
				)
				( attribute "CHIPS_PART_NAME" "RES"
					( Origin gPackager )
				)
				( attribute "CDS_PART_NAME" "RES_0402-33.2,1%,1/16W,CHIP,G2A"
					( Origin gPackager )
				)
				( attribute "CDS_LOCATION" "R25W69"
					( Origin gPackager )
				)
				( attribute "SEC" "1"
					( Origin gFrontEnd )
				)
				( attribute "SEC_TYPE" "0402"
					( Origin gFrontEnd )
				)
				( attribute "CDS_SEC" "1"
					( Origin gPackager )
				)
				( objectStatus "R25W69" )
			)
			( gate "@baseboard_fab2_lib.baseboard_fab2(sch_1):page146_i84"
				( attribute "BOM_COST" "SB"
					( Origin gFrontEnd )
				)
				( attribute "CDS_LIB" "mstr_discrete"
					( Origin gPackager )
				)
				( attribute "LOCATION" "R25W68"
					( Origin gFrontEnd )
				)
				( attribute "MATERIAL" "CHIP"
					( Origin gFrontEnd )
				)
				( attribute "PACK_TYPE" "0402"
					( Origin gFrontEnd )
				)
				( attribute "PART_NUMBER" "G21796-074"
					( Origin gFrontEnd )
				)
				( attribute "PHYS_PAGE" "146"
					( Origin gFrontEnd )
				)
				( attribute "ROOM" "BMC"
					( Origin gFrontEnd )
				)
				( attribute "ROT" "0"
					( Origin gFrontEnd )
				)
				( attribute "TOLERANCE" "1%"
					( Origin gFrontEnd )
				)
				( attribute "VALUE" "33.2"
					( Origin gFrontEnd )
				)
				( attribute "VER" "1"
					( Origin gFrontEnd )
				)
				( attribute "WATTAGE" "1/16W"
					( Origin gFrontEnd )
				)
				( attribute "XY" "(-6850,1400)"
					( Origin gFrontEnd )
				)
				( attribute "CHIPS_PART_NAME" "RES"
					( Origin gPackager )
				)
				( attribute "CDS_PART_NAME" "RES_0402-33.2,1%,1/16W,CHIP,G2A"
					( Origin gPackager )
				)
				( attribute "CDS_LOCATION" "R25W68"
					( Origin gPackager )
				)
				( attribute "SEC" "1"
					( Origin gFrontEnd )
				)
				( attribute "SEC_TYPE" "0402"
					( Origin gFrontEnd )
				)
				( attribute "CDS_SEC" "1"
					( Origin gPackager )
				)
				( objectStatus "R25W68" )
			)
			( gate "@baseboard_fab2_lib.baseboard_fab2(sch_1):page146_i78"
				( attribute "BOM_COST" "SM_CONTROLLER"
					( Origin gFrontEnd )
				)
				( attribute "CDS_LIB" "mstr_discrete"
					( Origin gPackager )
				)
				( attribute "CDS_LOCATION" "R1U7"
					( Origin gPackager )
				)
				( attribute "CDS_SEC" "1"
					( Origin gPackager )
				)
				( attribute "LOCATION" "R1U7"
					( Origin gFrontEnd )
				)
				( attribute "MATERIAL" "CHIP"
					( Origin gFrontEnd )
				)
				( attribute "PACK_TYPE" "0402"
					( Origin gFrontEnd )
				)
				( attribute "PART_NUMBER" "G21796-016"
					( Origin gFrontEnd )
				)
				( attribute "PHYS_PAGE" "146"
					( Origin gFrontEnd )
				)
				( attribute "ROOM" "BMC"
					( Origin gFrontEnd )
				)
				( attribute "ROT" "0"
					( Origin gFrontEnd )
				)
				( attribute "SEC" "1"
					( Origin gFrontEnd )
				)
				( attribute "SEC_TYPE" "0402"
					( Origin gFrontEnd )
				)
				( attribute "TOLERANCE" "1%"
					( Origin gFrontEnd )
				)
				( attribute "VALUE" "10.0K"
					( Origin gFrontEnd )
				)
				( attribute "VER" "1"
					( Origin gFrontEnd )
				)
				( attribute "WATTAGE" "1/16W"
					( Origin gFrontEnd )
				)
				( attribute "XY" "(-6350,2650)"
					( Origin gFrontEnd )
				)
				( attribute "CHIPS_PART_NAME" "RES"
					( Origin gPackager )
				)
				( attribute "CDS_PART_NAME" "RES_0402-10.0K,1%,1/16W,CHIP,GA"
					( Origin gPackager )
				)
				( objectStatus "R1U7" )
			)
			( gate "@baseboard_fab2_lib.baseboard_fab2(sch_1):page146_i76"
				( attribute "CDS_LIB" "mstr_discrete"
					( Origin gPackager )
				)
				( attribute "CDS_LOCATION" "R25W66"
					( Origin gPackager )
				)
				( attribute "CDS_SEC" "1"
					( Origin gPackager )
				)
				( attribute "LOCATION" "R25W66"
					( Origin gFrontEnd )
				)
				( attribute "MATERIAL" "CHIP"
					( Origin gFrontEnd )
				)
				( attribute "PACK_TYPE" "0402"
					( Origin gFrontEnd )
				)
				( attribute "PART_NUMBER" "G21796-010"
					( Origin gFrontEnd )
				)
				( attribute "PHYS_PAGE" "146"
					( Origin gFrontEnd )
				)
				( attribute "ROOM" "BMC"
					( Origin gFrontEnd )
				)
				( attribute "ROT" "0"
					( Origin gFrontEnd )
				)
				( attribute "SEC" "1"
					( Origin gPackager )
				)
				( attribute "TOLERANCE" "1%"
					( Origin gFrontEnd )
				)
				( attribute "VALUE" "100.0K"
					( Origin gFrontEnd )
				)
				( attribute "VER" "2"
					( Origin gFrontEnd )
				)
				( attribute "WATTAGE" "1/16W"
					( Origin gFrontEnd )
				)
				( attribute "XY" "(-6250,850)"
					( Origin gFrontEnd )
				)
				( attribute "CHIPS_PART_NAME" "RES"
					( Origin gPackager )
				)
				( attribute "CDS_PART_NAME" "RES_0402-100.0K,1%,1/16W,CHIP,A"
					( Origin gPackager )
				)
				( attribute "POP" "NOPOP"
					( Origin gFrontEnd )
				)
				( objectStatus "R25W66" )
			)
			( gate "@baseboard_fab2_lib.baseboard_fab2(sch_1):page146_i75"
				( attribute "BOM_COST" "SB"
					( Origin gFrontEnd )
				)
				( attribute "CDS_LIB" "mstr_discrete"
					( Origin gPackager )
				)
				( attribute "LOCATION" "R3N26"
					( Origin gFrontEnd )
				)
				( attribute "MATERIAL" "CHIP"
					( Origin gFrontEnd )
				)
				( attribute "PACK_TYPE" "0402"
					( Origin gFrontEnd )
				)
				( attribute "PART_NUMBER" "G21796-074"
					( Origin gFrontEnd )
				)
				( attribute "PHYS_PAGE" "146"
					( Origin gFrontEnd )
				)
				( attribute "ROOM" "BMC"
					( Origin gFrontEnd )
				)
				( attribute "ROT" "0"
					( Origin gFrontEnd )
				)
				( attribute "TOLERANCE" "1%"
					( Origin gFrontEnd )
				)
				( attribute "VALUE" "33.2"
					( Origin gFrontEnd )
				)
				( attribute "VER" "1"
					( Origin gFrontEnd )
				)
				( attribute "WATTAGE" "1/16W"
					( Origin gFrontEnd )
				)
				( attribute "XY" "(-6850,1250)"
					( Origin gFrontEnd )
				)
				( attribute "CHIPS_PART_NAME" "RES"
					( Origin gPackager )
				)
				( attribute "CDS_PART_NAME" "RES_0402-33.2,1%,1/16W,CHIP,G2A"
					( Origin gPackager )
				)
				( attribute "CDS_LOCATION" "R3N26"
					( Origin gPackager )
				)
				( attribute "SEC" "1"
					( Origin gFrontEnd )
				)
				( attribute "SEC_TYPE" "0402"
					( Origin gFrontEnd )
				)
				( attribute "CDS_SEC" "1"
					( Origin gPackager )
				)
				( objectStatus "R3N26" )
			)
			( gate "@baseboard_fab2_lib.baseboard_fab2(sch_1):page146_i74"
				( attribute "BOM_COST" "SB"
					( Origin gFrontEnd )
				)
				( attribute "CDS_LIB" "mstr_discrete"
					( Origin gPackager )
				)
				( attribute "LOCATION" "R3N24"
					( Origin gFrontEnd )
				)
				( attribute "MATERIAL" "CHIP"
					( Origin gFrontEnd )
				)
				( attribute "PACK_TYPE" "0402"
					( Origin gFrontEnd )
				)
				( attribute "PART_NUMBER" "G21796-074"
					( Origin gFrontEnd )
				)
				( attribute "PHYS_PAGE" "146"
					( Origin gFrontEnd )
				)
				( attribute "ROOM" "BMC"
					( Origin gFrontEnd )
				)
				( attribute "ROT" "0"
					( Origin gFrontEnd )
				)
				( attribute "TOLERANCE" "1%"
					( Origin gFrontEnd )
				)
				( attribute "VALUE" "33.2"
					( Origin gFrontEnd )
				)
				( attribute "VER" "1"
					( Origin gFrontEnd )
				)
				( attribute "WATTAGE" "1/16W"
					( Origin gFrontEnd )
				)
				( attribute "XY" "(-6850,1350)"
					( Origin gFrontEnd )
				)
				( attribute "CHIPS_PART_NAME" "RES"
					( Origin gPackager )
				)
				( attribute "CDS_PART_NAME" "RES_0402-33.2,1%,1/16W,CHIP,G2A"
					( Origin gPackager )
				)
				( attribute "CDS_LOCATION" "R3N24"
					( Origin gPackager )
				)
				( attribute "SEC" "1"
					( Origin gFrontEnd )
				)
				( attribute "SEC_TYPE" "0402"
					( Origin gFrontEnd )
				)
				( attribute "CDS_SEC" "1"
					( Origin gPackager )
				)
				( objectStatus "R3N24" )
			)
			( gate "@baseboard_fab2_lib.baseboard_fab2(sch_1):page146_i73"
				( attribute "BOM_COST" "SM_CONTROLLER"
					( Origin gFrontEnd )
				)
				( attribute "CDS_LIB" "mstr_discrete"
					( Origin gPackager )
				)
				( attribute "CDS_LOCATION" "R25W73"
					( Origin gPackager )
				)
				( attribute "CDS_SEC" "1"
					( Origin gPackager )
				)
				( attribute "LOCATION" "R25W73"
					( Origin gFrontEnd )
				)
				( attribute "MATERIAL" "CHIP"
					( Origin gFrontEnd )
				)
				( attribute "PACK_TYPE" "0402"
					( Origin gFrontEnd )
				)
				( attribute "PART_NUMBER" "G21796-074"
					( Origin gFrontEnd )
				)
				( attribute "PHYS_PAGE" "146"
					( Origin gFrontEnd )
				)
				( attribute "ROOM" "BMC"
					( Origin gFrontEnd )
				)
				( attribute "ROT" "0"
					( Origin gFrontEnd )
				)
				( attribute "SEC" "1"
					( Origin gFrontEnd )
				)
				( attribute "SEC_TYPE" "0402"
					( Origin gFrontEnd )
				)
				( attribute "TOLERANCE" "1%"
					( Origin gFrontEnd )
				)
				( attribute "VALUE" "33.2"
					( Origin gFrontEnd )
				)
				( attribute "VER" "1"
					( Origin gFrontEnd )
				)
				( attribute "WATTAGE" "1/16W"
					( Origin gFrontEnd )
				)
				( attribute "XY" "(-6350,1650)"
					( Origin gFrontEnd )
				)
				( attribute "CHIPS_PART_NAME" "RES"
					( Origin gPackager )
				)
				( attribute "CDS_PART_NAME" "RES_0402-33.2,1%,1/16W,CHIP,G2A"
					( Origin gPackager )
				)
				( objectStatus "R25W73" )
			)
			( gate "@baseboard_fab2_lib.baseboard_fab2(sch_1):page201_i185"
				( attribute "CDS_LIB" "mstr_discrete"
					( Origin gPackager )
				)
				( attribute "LOCATION" "RF4"
					( Origin gFrontEnd )
				)
				( attribute "MATERIAL" "CHIP"
					( Origin gFrontEnd )
				)
				( attribute "PACK_TYPE" "0402"
					( Origin gFrontEnd )
				)
				( attribute "PART_NUMBER" "G85996-004"
					( Origin gFrontEnd )
				)
				( attribute "PHYS_PAGE" "201"
					( Origin gFrontEnd )
				)
				( attribute "ROOM" "SB"
					( Origin gFrontEnd )
				)
				( attribute "ROT" "0"
					( Origin gFrontEnd )
				)
				( attribute "TOLERANCE" "0.1%"
					( Origin gFrontEnd )
				)
				( attribute "VALUE" "1.0K"
					( Origin gFrontEnd )
				)
				( attribute "VER" "1"
					( Origin gFrontEnd )
				)
				( attribute "WATTAGE" "1/16W"
					( Origin gFrontEnd )
				)
				( attribute "XY" "(-5425,3500)"
					( Origin gFrontEnd )
				)
				( attribute "CHIPS_PART_NAME" "RES"
					( Origin gPackager )
				)
				( attribute "CDS_PART_NAME" "RES_0402-1.0K,0.1%,1/16W,CHIP,A"
					( Origin gPackager )
				)
				( attribute "CDS_LOCATION" "RF4"
					( Origin gPackager )
				)
				( attribute "SEC" "1"
					( Origin gFrontEnd )
				)
				( attribute "SEC_TYPE" "0402"
					( Origin gFrontEnd )
				)
				( attribute "CDS_SEC" "1"
					( Origin gPackager )
				)
				( attribute "GROUP" "POWER_FAIR"
					( Origin gFrontEnd )
				)
				( attribute "FAIR_SS" "064.9530D.M001"
					( Origin gFrontEnd )
				)
				( objectStatus "RF4" )
			)
			( gate "@baseboard_fab2_lib.baseboard_fab2(sch_1):page146_i71"
				( attribute "BOM_COST" "SM_CONTROLLER"
					( Origin gFrontEnd )
				)
				( attribute "CDS_LIB" "mstr_discrete"
					( Origin gPackager )
				)
				( attribute "CDS_LOCATION" "R25W72"
					( Origin gPackager )
				)
				( attribute "CDS_SEC" "1"
					( Origin gPackager )
				)
				( attribute "LOCATION" "R25W72"
					( Origin gFrontEnd )
				)
				( attribute "MATERIAL" "CHIP"
					( Origin gFrontEnd )
				)
				( attribute "PACK_TYPE" "0402"
					( Origin gFrontEnd )
				)
				( attribute "PART_NUMBER" "G21796-074"
					( Origin gFrontEnd )
				)
				( attribute "PHYS_PAGE" "146"
					( Origin gFrontEnd )
				)
				( attribute "ROOM" "BMC"
					( Origin gFrontEnd )
				)
				( attribute "ROT" "0"
					( Origin gFrontEnd )
				)
				( attribute "SEC" "1"
					( Origin gFrontEnd )
				)
				( attribute "SEC_TYPE" "0402"
					( Origin gFrontEnd )
				)
				( attribute "TOLERANCE" "1%"
					( Origin gFrontEnd )
				)
				( attribute "VALUE" "33.2"
					( Origin gFrontEnd )
				)
				( attribute "VER" "1"
					( Origin gFrontEnd )
				)
				( attribute "WATTAGE" "1/16W"
					( Origin gFrontEnd )
				)
				( attribute "XY" "(-6350,1550)"
					( Origin gFrontEnd )
				)
				( attribute "CHIPS_PART_NAME" "RES"
					( Origin gPackager )
				)
				( attribute "CDS_PART_NAME" "RES_0402-33.2,1%,1/16W,CHIP,G2A"
					( Origin gPackager )
				)
				( objectStatus "R25W72" )
			)
			( gate "@baseboard_fab2_lib.baseboard_fab2(sch_1):page146_i70"
				( attribute "BOM_COST" "SM_CONTROLLER"
					( Origin gFrontEnd )
				)
				( attribute "CDS_LIB" "mstr_discrete"
					( Origin gPackager )
				)
				( attribute "CDS_LOCATION" "R25W74"
					( Origin gPackager )
				)
				( attribute "CDS_SEC" "1"
					( Origin gPackager )
				)
				( attribute "LOCATION" "R25W74"
					( Origin gFrontEnd )
				)
				( attribute "MATERIAL" "CHIP"
					( Origin gFrontEnd )
				)
				( attribute "PACK_TYPE" "0402"
					( Origin gFrontEnd )
				)
				( attribute "PART_NUMBER" "G21497-005"
					( Origin gFrontEnd )
				)
				( attribute "PHYS_PAGE" "146"
					( Origin gFrontEnd )
				)
				( attribute "ROOM" "BMC"
					( Origin gFrontEnd )
				)
				( attribute "ROT" "0"
					( Origin gFrontEnd )
				)
				( attribute "SEC" "1"
					( Origin gFrontEnd )
				)
				( attribute "SEC_TYPE" "0402"
					( Origin gFrontEnd )
				)
				( attribute "TOLERANCE" "5%"
					( Origin gFrontEnd )
				)
				( attribute "VALUE" "0.0"
					( Origin gFrontEnd )
				)
				( attribute "VER" "1"
					( Origin gFrontEnd )
				)
				( attribute "WATTAGE" "1/16W"
					( Origin gFrontEnd )
				)
				( attribute "XY" "(-6350,1750)"
					( Origin gFrontEnd )
				)
				( attribute "CHIPS_PART_NAME" "RES"
					( Origin gPackager )
				)
				( attribute "CDS_PART_NAME" "RES_0402-0.0,5%,1/16W,CHIP,G21A"
					( Origin gPackager )
				)
				( objectStatus "R25W74" )
			)
			( gate "@baseboard_fab2_lib.baseboard_fab2(sch_1):page253_i10"
				( attribute "CHIPS_PART_NAME" "TTL1G07_A"
					( Origin gPackager )
				)
			)
			( gate "@baseboard_fab2_lib.baseboard_fab2(sch_1):page151_i173"
				( attribute "BOM_COST" "SM_CONTROLLER"
					( Origin gFrontEnd )
				)
				( attribute "CDS_LIB" "mstr_discrete"
					( Origin gPackager )
				)
				( attribute "CDS_LOCATION" "R9E21"
					( Origin gPackager )
				)
				( attribute "CDS_SEC" "1"
					( Origin gPackager )
				)
				( attribute "LOCATION" "R9E21"
					( Origin gFrontEnd )
				)
				( attribute "MATERIAL" "CHIP"
					( Origin gFrontEnd )
				)
				( attribute "PACK_TYPE" "0402"
					( Origin gFrontEnd )
				)
				( attribute "PART_NUMBER" "G21796-072"
					( Origin gFrontEnd )
				)
				( attribute "PHYS_PAGE" "151"
					( Origin gFrontEnd )
				)
				( attribute "ROOM" "BMC"
					( Origin gFrontEnd )
				)
				( attribute "ROT" "0"
					( Origin gFrontEnd )
				)
				( attribute "SEC" "1"
					( Origin gFrontEnd )
				)
				( attribute "SEC_TYPE" "0402"
					( Origin gFrontEnd )
				)
				( attribute "TOLERANCE" "1%"
					( Origin gFrontEnd )
				)
				( attribute "VALUE" "4.75K"
					( Origin gFrontEnd )
				)
				( attribute "VER" "2"
					( Origin gFrontEnd )
				)
				( attribute "WATTAGE" "1/16W"
					( Origin gFrontEnd )
				)
				( attribute "XY" "(-1700,-300)"
					( Origin gFrontEnd )
				)
				( attribute "CHIPS_PART_NAME" "RES"
					( Origin gPackager )
				)
				( attribute "CDS_PART_NAME" "RES_0402-4.75K,1%,1/16W,CHIP,GA"
					( Origin gPackager )
				)
				( objectStatus "R9E21" )
			)
			( gate "@baseboard_fab2_lib.baseboard_fab2(sch_1):page151_i249"
				( attribute "ATTRIBUTE" "120OHM"
					( Origin gFrontEnd )
				)
				( attribute "CDS_LIB" "w_hdl"
					( Origin gPackager )
				)
				( attribute "CDS_LMAN_SYM_OUTLINE" "-50,75,50,-75"
					( Origin gPackager )
				)
				( attribute "LOCATION" "R25W2"
					( Origin gFrontEnd )
				)
				( attribute "PACK_TYPE" "RCL_GP"
					( Origin gFrontEnd )
				)
				( attribute "PART_NUMBER" "64.12005.6DL"
					( Origin gFrontEnd )
				)
				( attribute "PHYS_PAGE" "151"
					( Origin gFrontEnd )
				)
				( attribute "RATED" "1/16W"
					( Origin gFrontEnd )
				)
				( attribute "ROT" "1"
					( Origin gFrontEnd )
				)
				( attribute "SEC" "1"
					( Origin gFrontEnd )
				)
				( attribute "SEC_TYPE" "RCL_GP"
					( Origin gFrontEnd )
				)
				( attribute "TOLERANCE" "1%"
					( Origin gFrontEnd )
				)
				( attribute "VALUE" "120R2F-GP"
					( Origin gFrontEnd )
				)
				( attribute "VER" "1"
					( Origin gFrontEnd )
				)
				( attribute "XY" "(-3025,1625)"
					( Origin gFrontEnd )
				)
				( attribute "CHIPS_PART_NAME" "120R2F-GP"
					( Origin gPackager )
				)
				( attribute "CDS_PART_NAME" "120R2F-GP_RCL_GP-120R2F-GP,64.A"
					( Origin gPackager )
				)
				( attribute "PACK_SIZE" "0402"
					( Origin gFrontEnd )
				)
				( attribute "CDS_LOCATION" "R25W2"
					( Origin gPackager )
				)
				( attribute "CDS_SEC" "1"
					( Origin gPackager )
				)
				( objectStatus "R25W2" )
			)
			( gate "@baseboard_fab2_lib.baseboard_fab2(sch_1):page151_i250"
				( attribute "ATTRIBUTE" "120OHM"
					( Origin gFrontEnd )
				)
				( attribute "CDS_LIB" "w_hdl"
					( Origin gPackager )
				)
				( attribute "CDS_LMAN_SYM_OUTLINE" "-50,75,50,-75"
					( Origin gPackager )
				)
				( attribute "LOCATION" "R25W3"
					( Origin gFrontEnd )
				)
				( attribute "PACK_TYPE" "RCL_GP"
					( Origin gFrontEnd )
				)
				( attribute "PART_NUMBER" "64.12005.6DL"
					( Origin gFrontEnd )
				)
				( attribute "PHYS_PAGE" "151"
					( Origin gFrontEnd )
				)
				( attribute "POP" "NOPOP"
					( Origin gFrontEnd )
				)
				( attribute "RATED" "1/16W"
					( Origin gFrontEnd )
				)
				( attribute "ROT" "1"
					( Origin gFrontEnd )
				)
				( attribute "SEC" "1"
					( Origin gFrontEnd )
				)
				( attribute "SEC_TYPE" "RCL_GP"
					( Origin gFrontEnd )
				)
				( attribute "TOLERANCE" "1%"
					( Origin gFrontEnd )
				)
				( attribute "VALUE" "120R2F-GP"
					( Origin gFrontEnd )
				)
				( attribute "VER" "1"
					( Origin gFrontEnd )
				)
				( attribute "XY" "(-3025,1575)"
					( Origin gFrontEnd )
				)
				( attribute "CHIPS_PART_NAME" "120R2F-GP"
					( Origin gPackager )
				)
				( attribute "CDS_PART_NAME" "120R2F-GP_RCL_GP-120R2F-GP,64.A"
					( Origin gPackager )
				)
				( attribute "PACK_SIZE" "0402"
					( Origin gFrontEnd )
				)
				( attribute "CDS_LOCATION" "R25W3"
					( Origin gPackager )
				)
				( attribute "CDS_SEC" "1"
					( Origin gPackager )
				)
				( objectStatus "R25W3" )
			)
			( gate "@baseboard_fab2_lib.baseboard_fab2(sch_1):page151_i251"
				( attribute "ATTRIBUTE" "120OHM"
					( Origin gFrontEnd )
				)
				( attribute "CDS_LIB" "w_hdl"
					( Origin gPackager )
				)
				( attribute "CDS_LMAN_SYM_OUTLINE" "-50,75,50,-75"
					( Origin gPackager )
				)
				( attribute "LOCATION" "R25W4"
					( Origin gFrontEnd )
				)
				( attribute "PACK_TYPE" "RCL_GP"
					( Origin gFrontEnd )
				)
				( attribute "PART_NUMBER" "64.12005.6DL"
					( Origin gFrontEnd )
				)
				( attribute "PHYS_PAGE" "151"
					( Origin gFrontEnd )
				)
				( attribute "POP" "NOPOP"
					( Origin gFrontEnd )
				)
				( attribute "RATED" "1/16W"
					( Origin gFrontEnd )
				)
				( attribute "ROT" "1"
					( Origin gFrontEnd )
				)
				( attribute "SEC" "1"
					( Origin gFrontEnd )
				)
				( attribute "SEC_TYPE" "RCL_GP"
					( Origin gFrontEnd )
				)
				( attribute "TOLERANCE" "1%"
					( Origin gFrontEnd )
				)
				( attribute "VALUE" "120R2F-GP"
					( Origin gFrontEnd )
				)
				( attribute "VER" "1"
					( Origin gFrontEnd )
				)
				( attribute "XY" "(-3025,1525)"
					( Origin gFrontEnd )
				)
				( attribute "CHIPS_PART_NAME" "120R2F-GP"
					( Origin gPackager )
				)
				( attribute "CDS_PART_NAME" "120R2F-GP_RCL_GP-120R2F-GP,64.A"
					( Origin gPackager )
				)
				( attribute "PACK_SIZE" "0402"
					( Origin gFrontEnd )
				)
				( attribute "CDS_LOCATION" "R25W4"
					( Origin gPackager )
				)
				( attribute "CDS_SEC" "1"
					( Origin gPackager )
				)
				( objectStatus "R25W4" )
			)
			( gate "@baseboard_fab2_lib.baseboard_fab2(sch_1):page151_i252"
				( attribute "ATTRIBUTE" "120OHM"
					( Origin gFrontEnd )
				)
				( attribute "CDS_LIB" "w_hdl"
					( Origin gPackager )
				)
				( attribute "CDS_LMAN_SYM_OUTLINE" "-50,75,50,-75"
					( Origin gPackager )
				)
				( attribute "LOCATION" "R25W5"
					( Origin gFrontEnd )
				)
				( attribute "PACK_TYPE" "RCL_GP"
					( Origin gFrontEnd )
				)
				( attribute "PART_NUMBER" "64.12005.6DL"
					( Origin gFrontEnd )
				)
				( attribute "PHYS_PAGE" "151"
					( Origin gFrontEnd )
				)
				( attribute "RATED" "1/16W"
					( Origin gFrontEnd )
				)
				( attribute "ROT" "1"
					( Origin gFrontEnd )
				)
				( attribute "SEC" "1"
					( Origin gFrontEnd )
				)
				( attribute "SEC_TYPE" "RCL_GP"
					( Origin gFrontEnd )
				)
				( attribute "TOLERANCE" "1%"
					( Origin gFrontEnd )
				)
				( attribute "VALUE" "120R2F-GP"
					( Origin gFrontEnd )
				)
				( attribute "VER" "1"
					( Origin gFrontEnd )
				)
				( attribute "XY" "(-3025,1475)"
					( Origin gFrontEnd )
				)
				( attribute "CHIPS_PART_NAME" "120R2F-GP"
					( Origin gPackager )
				)
				( attribute "CDS_PART_NAME" "120R2F-GP_RCL_GP-120R2F-GP,64.A"
					( Origin gPackager )
				)
				( attribute "PACK_SIZE" "0402"
					( Origin gFrontEnd )
				)
				( attribute "CDS_LOCATION" "R25W5"
					( Origin gPackager )
				)
				( attribute "CDS_SEC" "1"
					( Origin gPackager )
				)
				( objectStatus "R25W5" )
			)
			( gate "@baseboard_fab2_lib.baseboard_fab2(sch_1):page151_i253"
				( attribute "ATTRIBUTE" "120OHM"
					( Origin gFrontEnd )
				)
				( attribute "CDS_LIB" "w_hdl"
					( Origin gPackager )
				)
				( attribute "CDS_LMAN_SYM_OUTLINE" "-50,75,50,-75"
					( Origin gPackager )
				)
				( attribute "LOCATION" "R25W6"
					( Origin gFrontEnd )
				)
				( attribute "PACK_TYPE" "RCL_GP"
					( Origin gFrontEnd )
				)
				( attribute "PART_NUMBER" "64.12005.6DL"
					( Origin gFrontEnd )
				)
				( attribute "PHYS_PAGE" "151"
					( Origin gFrontEnd )
				)
				( attribute "RATED" "1/16W"
					( Origin gFrontEnd )
				)
				( attribute "ROT" "1"
					( Origin gFrontEnd )
				)
				( attribute "SEC" "1"
					( Origin gFrontEnd )
				)
				( attribute "SEC_TYPE" "RCL_GP"
					( Origin gFrontEnd )
				)
				( attribute "TOLERANCE" "1%"
					( Origin gFrontEnd )
				)
				( attribute "VALUE" "120R2F-GP"
					( Origin gFrontEnd )
				)
				( attribute "VER" "1"
					( Origin gFrontEnd )
				)
				( attribute "XY" "(-3025,1425)"
					( Origin gFrontEnd )
				)
				( attribute "CHIPS_PART_NAME" "120R2F-GP"
					( Origin gPackager )
				)
				( attribute "CDS_PART_NAME" "120R2F-GP_RCL_GP-120R2F-GP,64.A"
					( Origin gPackager )
				)
				( attribute "PACK_SIZE" "0402"
					( Origin gFrontEnd )
				)
				( attribute "CDS_LOCATION" "R25W6"
					( Origin gPackager )
				)
				( attribute "CDS_SEC" "1"
					( Origin gPackager )
				)
				( objectStatus "R25W6" )
			)
			( gate "@baseboard_fab2_lib.baseboard_fab2(sch_1):page151_i254"
				( attribute "ATTRIBUTE" "120OHM"
					( Origin gFrontEnd )
				)
				( attribute "CDS_LIB" "w_hdl"
					( Origin gPackager )
				)
				( attribute "CDS_LMAN_SYM_OUTLINE" "-50,75,50,-75"
					( Origin gPackager )
				)
				( attribute "LOCATION" "R25W7"
					( Origin gFrontEnd )
				)
				( attribute "PACK_TYPE" "RCL_GP"
					( Origin gFrontEnd )
				)
				( attribute "PART_NUMBER" "64.12005.6DL"
					( Origin gFrontEnd )
				)
				( attribute "PHYS_PAGE" "151"
					( Origin gFrontEnd )
				)
				( attribute "RATED" "1/16W"
					( Origin gFrontEnd )
				)
				( attribute "ROT" "1"
					( Origin gFrontEnd )
				)
				( attribute "SEC" "1"
					( Origin gFrontEnd )
				)
				( attribute "SEC_TYPE" "RCL_GP"
					( Origin gFrontEnd )
				)
				( attribute "TOLERANCE" "1%"
					( Origin gFrontEnd )
				)
				( attribute "VALUE" "120R2F-GP"
					( Origin gFrontEnd )
				)
				( attribute "VER" "1"
					( Origin gFrontEnd )
				)
				( attribute "XY" "(-3025,1375)"
					( Origin gFrontEnd )
				)
				( attribute "CHIPS_PART_NAME" "120R2F-GP"
					( Origin gPackager )
				)
				( attribute "CDS_PART_NAME" "120R2F-GP_RCL_GP-120R2F-GP,64.A"
					( Origin gPackager )
				)
				( attribute "PACK_SIZE" "0402"
					( Origin gFrontEnd )
				)
				( attribute "CDS_LOCATION" "R25W7"
					( Origin gPackager )
				)
				( attribute "CDS_SEC" "1"
					( Origin gPackager )
				)
				( objectStatus "R25W7" )
			)
			( gate "@baseboard_fab2_lib.baseboard_fab2(sch_1):page151_i255"
				( attribute "ATTRIBUTE" "120OHM"
					( Origin gFrontEnd )
				)
				( attribute "CDS_LIB" "w_hdl"
					( Origin gPackager )
				)
				( attribute "CDS_LMAN_SYM_OUTLINE" "-50,75,50,-75"
					( Origin gPackager )
				)
				( attribute "LOCATION" "R25W8"
					( Origin gFrontEnd )
				)
				( attribute "PACK_TYPE" "RCL_GP"
					( Origin gFrontEnd )
				)
				( attribute "PART_NUMBER" "64.12005.6DL"
					( Origin gFrontEnd )
				)
				( attribute "PHYS_PAGE" "151"
					( Origin gFrontEnd )
				)
				( attribute "RATED" "1/16W"
					( Origin gFrontEnd )
				)
				( attribute "ROT" "1"
					( Origin gFrontEnd )
				)
				( attribute "SEC" "1"
					( Origin gFrontEnd )
				)
				( attribute "SEC_TYPE" "RCL_GP"
					( Origin gFrontEnd )
				)
				( attribute "TOLERANCE" "1%"
					( Origin gFrontEnd )
				)
				( attribute "VALUE" "120R2F-GP"
					( Origin gFrontEnd )
				)
				( attribute "VER" "1"
					( Origin gFrontEnd )
				)
				( attribute "XY" "(-3025,1325)"
					( Origin gFrontEnd )
				)
				( attribute "CHIPS_PART_NAME" "120R2F-GP"
					( Origin gPackager )
				)
				( attribute "CDS_PART_NAME" "120R2F-GP_RCL_GP-120R2F-GP,64.A"
					( Origin gPackager )
				)
				( attribute "PACK_SIZE" "0402"
					( Origin gFrontEnd )
				)
				( attribute "CDS_LOCATION" "R25W8"
					( Origin gPackager )
				)
				( attribute "CDS_SEC" "1"
					( Origin gPackager )
				)
				( objectStatus "R25W8" )
			)
			( gate "@baseboard_fab2_lib.baseboard_fab2(sch_1):page151_i256"
				( attribute "ATTRIBUTE" "120OHM"
					( Origin gFrontEnd )
				)
				( attribute "CDS_LIB" "w_hdl"
					( Origin gPackager )
				)
				( attribute "CDS_LMAN_SYM_OUTLINE" "-50,75,50,-75"
					( Origin gPackager )
				)
				( attribute "LOCATION" "R25W12"
					( Origin gFrontEnd )
				)
				( attribute "PACK_TYPE" "RCL_GP"
					( Origin gFrontEnd )
				)
				( attribute "PART_NUMBER" "64.12005.6DL"
					( Origin gFrontEnd )
				)
				( attribute "PHYS_PAGE" "151"
					( Origin gFrontEnd )
				)
				( attribute "RATED" "1/16W"
					( Origin gFrontEnd )
				)
				( attribute "ROT" "1"
					( Origin gFrontEnd )
				)
				( attribute "SEC" "1"
					( Origin gFrontEnd )
				)
				( attribute "SEC_TYPE" "RCL_GP"
					( Origin gFrontEnd )
				)
				( attribute "TOLERANCE" "1%"
					( Origin gFrontEnd )
				)
				( attribute "VALUE" "120R2F-GP"
					( Origin gFrontEnd )
				)
				( attribute "VER" "1"
					( Origin gFrontEnd )
				)
				( attribute "XY" "(-3025,1125)"
					( Origin gFrontEnd )
				)
				( attribute "CHIPS_PART_NAME" "120R2F-GP"
					( Origin gPackager )
				)
				( attribute "CDS_PART_NAME" "120R2F-GP_RCL_GP-120R2F-GP,64.A"
					( Origin gPackager )
				)
				( attribute "PACK_SIZE" "0402"
					( Origin gFrontEnd )
				)
				( attribute "CDS_LOCATION" "R25W12"
					( Origin gPackager )
				)
				( attribute "CDS_SEC" "1"
					( Origin gPackager )
				)
				( objectStatus "R25W12" )
			)
			( gate "@baseboard_fab2_lib.baseboard_fab2(sch_1):page151_i257"
				( attribute "ATTRIBUTE" "120OHM"
					( Origin gFrontEnd )
				)
				( attribute "CDS_LIB" "w_hdl"
					( Origin gPackager )
				)
				( attribute "CDS_LMAN_SYM_OUTLINE" "-50,75,50,-75"
					( Origin gPackager )
				)
				( attribute "LOCATION" "R25W11"
					( Origin gFrontEnd )
				)
				( attribute "PACK_TYPE" "RCL_GP"
					( Origin gFrontEnd )
				)
				( attribute "PART_NUMBER" "64.12005.6DL"
					( Origin gFrontEnd )
				)
				( attribute "PHYS_PAGE" "151"
					( Origin gFrontEnd )
				)
				( attribute "RATED" "1/16W"
					( Origin gFrontEnd )
				)
				( attribute "ROT" "1"
					( Origin gFrontEnd )
				)
				( attribute "SEC" "1"
					( Origin gFrontEnd )
				)
				( attribute "SEC_TYPE" "RCL_GP"
					( Origin gFrontEnd )
				)
				( attribute "TOLERANCE" "1%"
					( Origin gFrontEnd )
				)
				( attribute "VALUE" "120R2F-GP"
					( Origin gFrontEnd )
				)
				( attribute "VER" "1"
					( Origin gFrontEnd )
				)
				( attribute "XY" "(-3025,1175)"
					( Origin gFrontEnd )
				)
				( attribute "CHIPS_PART_NAME" "120R2F-GP"
					( Origin gPackager )
				)
				( attribute "CDS_PART_NAME" "120R2F-GP_RCL_GP-120R2F-GP,64.A"
					( Origin gPackager )
				)
				( attribute "PACK_SIZE" "0402"
					( Origin gFrontEnd )
				)
				( attribute "CDS_LOCATION" "R25W11"
					( Origin gPackager )
				)
				( attribute "CDS_SEC" "1"
					( Origin gPackager )
				)
				( objectStatus "R25W11" )
			)
			( gate "@baseboard_fab2_lib.baseboard_fab2(sch_1):page151_i258"
				( attribute "ATTRIBUTE" "120OHM"
					( Origin gFrontEnd )
				)
				( attribute "CDS_LIB" "w_hdl"
					( Origin gPackager )
				)
				( attribute "CDS_LMAN_SYM_OUTLINE" "-50,75,50,-75"
					( Origin gPackager )
				)
				( attribute "LOCATION" "R25W9"
					( Origin gFrontEnd )
				)
				( attribute "PACK_TYPE" "RCL_GP"
					( Origin gFrontEnd )
				)
				( attribute "PART_NUMBER" "64.12005.6DL"
					( Origin gFrontEnd )
				)
				( attribute "PHYS_PAGE" "151"
					( Origin gFrontEnd )
				)
				( attribute "RATED" "1/16W"
					( Origin gFrontEnd )
				)
				( attribute "ROT" "1"
					( Origin gFrontEnd )
				)
				( attribute "SEC" "1"
					( Origin gFrontEnd )
				)
				( attribute "SEC_TYPE" "RCL_GP"
					( Origin gFrontEnd )
				)
				( attribute "TOLERANCE" "1%"
					( Origin gFrontEnd )
				)
				( attribute "VALUE" "120R2F-GP"
					( Origin gFrontEnd )
				)
				( attribute "VER" "1"
					( Origin gFrontEnd )
				)
				( attribute "XY" "(-3025,1275)"
					( Origin gFrontEnd )
				)
				( attribute "CHIPS_PART_NAME" "120R2F-GP"
					( Origin gPackager )
				)
				( attribute "CDS_PART_NAME" "120R2F-GP_RCL_GP-120R2F-GP,64.A"
					( Origin gPackager )
				)
				( attribute "PACK_SIZE" "0402"
					( Origin gFrontEnd )
				)
				( attribute "CDS_LOCATION" "R25W9"
					( Origin gPackager )
				)
				( attribute "CDS_SEC" "1"
					( Origin gPackager )
				)
				( objectStatus "R25W9" )
			)
			( gate "@baseboard_fab2_lib.baseboard_fab2(sch_1):page151_i259"
				( attribute "ATTRIBUTE" "120OHM"
					( Origin gFrontEnd )
				)
				( attribute "CDS_LIB" "w_hdl"
					( Origin gPackager )
				)
				( attribute "CDS_LMAN_SYM_OUTLINE" "-50,75,50,-75"
					( Origin gPackager )
				)
				( attribute "LOCATION" "R25W10"
					( Origin gFrontEnd )
				)
				( attribute "PACK_TYPE" "RCL_GP"
					( Origin gFrontEnd )
				)
				( attribute "PART_NUMBER" "64.12005.6DL"
					( Origin gFrontEnd )
				)
				( attribute "PHYS_PAGE" "151"
					( Origin gFrontEnd )
				)
				( attribute "RATED" "1/16W"
					( Origin gFrontEnd )
				)
				( attribute "ROT" "1"
					( Origin gFrontEnd )
				)
				( attribute "SEC" "1"
					( Origin gFrontEnd )
				)
				( attribute "SEC_TYPE" "RCL_GP"
					( Origin gFrontEnd )
				)
				( attribute "TOLERANCE" "1%"
					( Origin gFrontEnd )
				)
				( attribute "VALUE" "120R2F-GP"
					( Origin gFrontEnd )
				)
				( attribute "VER" "1"
					( Origin gFrontEnd )
				)
				( attribute "XY" "(-3025,1225)"
					( Origin gFrontEnd )
				)
				( attribute "CHIPS_PART_NAME" "120R2F-GP"
					( Origin gPackager )
				)
				( attribute "CDS_PART_NAME" "120R2F-GP_RCL_GP-120R2F-GP,64.A"
					( Origin gPackager )
				)
				( attribute "PACK_SIZE" "0402"
					( Origin gFrontEnd )
				)
				( attribute "CDS_LOCATION" "R25W10"
					( Origin gPackager )
				)
				( attribute "CDS_SEC" "1"
					( Origin gPackager )
				)
				( objectStatus "R25W10" )
			)
			( gate "@baseboard_fab2_lib.baseboard_fab2(sch_1):page151_i260"
				( attribute "ATTRIBUTE" "120OHM"
					( Origin gFrontEnd )
				)
				( attribute "CDS_LIB" "w_hdl"
					( Origin gPackager )
				)
				( attribute "CDS_LMAN_SYM_OUTLINE" "-50,75,50,-75"
					( Origin gPackager )
				)
				( attribute "LOCATION" "R25W13"
					( Origin gFrontEnd )
				)
				( attribute "PACK_TYPE" "RCL_GP"
					( Origin gFrontEnd )
				)
				( attribute "PART_NUMBER" "64.12005.6DL"
					( Origin gFrontEnd )
				)
				( attribute "PHYS_PAGE" "151"
					( Origin gFrontEnd )
				)
				( attribute "RATED" "1/16W"
					( Origin gFrontEnd )
				)
				( attribute "ROT" "1"
					( Origin gFrontEnd )
				)
				( attribute "SEC" "1"
					( Origin gFrontEnd )
				)
				( attribute "SEC_TYPE" "RCL_GP"
					( Origin gFrontEnd )
				)
				( attribute "TOLERANCE" "1%"
					( Origin gFrontEnd )
				)
				( attribute "VALUE" "120R2F-GP"
					( Origin gFrontEnd )
				)
				( attribute "VER" "1"
					( Origin gFrontEnd )
				)
				( attribute "XY" "(-3025,1075)"
					( Origin gFrontEnd )
				)
				( attribute "CHIPS_PART_NAME" "120R2F-GP"
					( Origin gPackager )
				)
				( attribute "CDS_PART_NAME" "120R2F-GP_RCL_GP-120R2F-GP,64.A"
					( Origin gPackager )
				)
				( attribute "PACK_SIZE" "0402"
					( Origin gFrontEnd )
				)
				( attribute "CDS_LOCATION" "R25W13"
					( Origin gPackager )
				)
				( attribute "CDS_SEC" "1"
					( Origin gPackager )
				)
				( objectStatus "R25W13" )
			)
			( gate "@baseboard_fab2_lib.baseboard_fab2(sch_1):page151_i261"
				( attribute "ATTRIBUTE" "120OHM"
					( Origin gFrontEnd )
				)
				( attribute "CDS_LIB" "w_hdl"
					( Origin gPackager )
				)
				( attribute "CDS_LMAN_SYM_OUTLINE" "-50,75,50,-75"
					( Origin gPackager )
				)
				( attribute "LOCATION" "R25W16"
					( Origin gFrontEnd )
				)
				( attribute "PACK_TYPE" "RCL_GP"
					( Origin gFrontEnd )
				)
				( attribute "PART_NUMBER" "64.12005.6DL"
					( Origin gFrontEnd )
				)
				( attribute "PHYS_PAGE" "151"
					( Origin gFrontEnd )
				)
				( attribute "RATED" "1/16W"
					( Origin gFrontEnd )
				)
				( attribute "ROT" "1"
					( Origin gFrontEnd )
				)
				( attribute "SEC" "1"
					( Origin gFrontEnd )
				)
				( attribute "SEC_TYPE" "RCL_GP"
					( Origin gFrontEnd )
				)
				( attribute "TOLERANCE" "1%"
					( Origin gFrontEnd )
				)
				( attribute "VALUE" "120R2F-GP"
					( Origin gFrontEnd )
				)
				( attribute "VER" "1"
					( Origin gFrontEnd )
				)
				( attribute "XY" "(-3025,925)"
					( Origin gFrontEnd )
				)
				( attribute "CHIPS_PART_NAME" "120R2F-GP"
					( Origin gPackager )
				)
				( attribute "CDS_PART_NAME" "120R2F-GP_RCL_GP-120R2F-GP,64.A"
					( Origin gPackager )
				)
				( attribute "PACK_SIZE" "0402"
					( Origin gFrontEnd )
				)
				( attribute "CDS_LOCATION" "R25W16"
					( Origin gPackager )
				)
				( attribute "CDS_SEC" "1"
					( Origin gPackager )
				)
				( objectStatus "R25W16" )
			)
			( gate "@baseboard_fab2_lib.baseboard_fab2(sch_1):page151_i262"
				( attribute "ATTRIBUTE" "120OHM"
					( Origin gFrontEnd )
				)
				( attribute "CDS_LIB" "w_hdl"
					( Origin gPackager )
				)
				( attribute "CDS_LMAN_SYM_OUTLINE" "-50,75,50,-75"
					( Origin gPackager )
				)
				( attribute "LOCATION" "R25W15"
					( Origin gFrontEnd )
				)
				( attribute "PACK_TYPE" "RCL_GP"
					( Origin gFrontEnd )
				)
				( attribute "PART_NUMBER" "64.12005.6DL"
					( Origin gFrontEnd )
				)
				( attribute "PHYS_PAGE" "151"
					( Origin gFrontEnd )
				)
				( attribute "RATED" "1/16W"
					( Origin gFrontEnd )
				)
				( attribute "ROT" "1"
					( Origin gFrontEnd )
				)
				( attribute "SEC" "1"
					( Origin gFrontEnd )
				)
				( attribute "SEC_TYPE" "RCL_GP"
					( Origin gFrontEnd )
				)
				( attribute "TOLERANCE" "1%"
					( Origin gFrontEnd )
				)
				( attribute "VALUE" "120R2F-GP"
					( Origin gFrontEnd )
				)
				( attribute "VER" "1"
					( Origin gFrontEnd )
				)
				( attribute "XY" "(-3025,975)"
					( Origin gFrontEnd )
				)
				( attribute "CHIPS_PART_NAME" "120R2F-GP"
					( Origin gPackager )
				)
				( attribute "CDS_PART_NAME" "120R2F-GP_RCL_GP-120R2F-GP,64.A"
					( Origin gPackager )
				)
				( attribute "PACK_SIZE" "0402"
					( Origin gFrontEnd )
				)
				( attribute "CDS_LOCATION" "R25W15"
					( Origin gPackager )
				)
				( attribute "CDS_SEC" "1"
					( Origin gPackager )
				)
				( objectStatus "R25W15" )
			)
			( gate "@baseboard_fab2_lib.baseboard_fab2(sch_1):page151_i263"
				( attribute "ATTRIBUTE" "120OHM"
					( Origin gFrontEnd )
				)
				( attribute "CDS_LIB" "w_hdl"
					( Origin gPackager )
				)
				( attribute "CDS_LMAN_SYM_OUTLINE" "-50,75,50,-75"
					( Origin gPackager )
				)
				( attribute "LOCATION" "R25W14"
					( Origin gFrontEnd )
				)
				( attribute "PACK_TYPE" "RCL_GP"
					( Origin gFrontEnd )
				)
				( attribute "PART_NUMBER" "64.12005.6DL"
					( Origin gFrontEnd )
				)
				( attribute "PHYS_PAGE" "151"
					( Origin gFrontEnd )
				)
				( attribute "RATED" "1/16W"
					( Origin gFrontEnd )
				)
				( attribute "ROT" "1"
					( Origin gFrontEnd )
				)
				( attribute "SEC" "1"
					( Origin gFrontEnd )
				)
				( attribute "SEC_TYPE" "RCL_GP"
					( Origin gFrontEnd )
				)
				( attribute "TOLERANCE" "1%"
					( Origin gFrontEnd )
				)
				( attribute "VALUE" "120R2F-GP"
					( Origin gFrontEnd )
				)
				( attribute "VER" "1"
					( Origin gFrontEnd )
				)
				( attribute "XY" "(-3025,1025)"
					( Origin gFrontEnd )
				)
				( attribute "CHIPS_PART_NAME" "120R2F-GP"
					( Origin gPackager )
				)
				( attribute "CDS_PART_NAME" "120R2F-GP_RCL_GP-120R2F-GP,64.A"
					( Origin gPackager )
				)
				( attribute "PACK_SIZE" "0402"
					( Origin gFrontEnd )
				)
				( attribute "CDS_LOCATION" "R25W14"
					( Origin gPackager )
				)
				( attribute "CDS_SEC" "1"
					( Origin gPackager )
				)
				( objectStatus "R25W14" )
			)
			( gate "@baseboard_fab2_lib.baseboard_fab2(sch_1):page151_i264"
				( attribute "ATTRIBUTE" "120OHM"
					( Origin gFrontEnd )
				)
				( attribute "CDS_LIB" "w_hdl"
					( Origin gPackager )
				)
				( attribute "CDS_LMAN_SYM_OUTLINE" "-50,75,50,-75"
					( Origin gPackager )
				)
				( attribute "LOCATION" "R25W17"
					( Origin gFrontEnd )
				)
				( attribute "PACK_TYPE" "RCL_GP"
					( Origin gFrontEnd )
				)
				( attribute "PART_NUMBER" "64.12005.6DL"
					( Origin gFrontEnd )
				)
				( attribute "PHYS_PAGE" "151"
					( Origin gFrontEnd )
				)
				( attribute "RATED" "1/16W"
					( Origin gFrontEnd )
				)
				( attribute "ROT" "1"
					( Origin gFrontEnd )
				)
				( attribute "SEC" "1"
					( Origin gFrontEnd )
				)
				( attribute "SEC_TYPE" "RCL_GP"
					( Origin gFrontEnd )
				)
				( attribute "TOLERANCE" "1%"
					( Origin gFrontEnd )
				)
				( attribute "VALUE" "120R2F-GP"
					( Origin gFrontEnd )
				)
				( attribute "VER" "1"
					( Origin gFrontEnd )
				)
				( attribute "XY" "(-3025,875)"
					( Origin gFrontEnd )
				)
				( attribute "CHIPS_PART_NAME" "120R2F-GP"
					( Origin gPackager )
				)
				( attribute "CDS_PART_NAME" "120R2F-GP_RCL_GP-120R2F-GP,64.A"
					( Origin gPackager )
				)
				( attribute "PACK_SIZE" "0402"
					( Origin gFrontEnd )
				)
				( attribute "CDS_LOCATION" "R25W17"
					( Origin gPackager )
				)
				( attribute "CDS_SEC" "1"
					( Origin gPackager )
				)
				( objectStatus "R25W17" )
			)
			( gate "@baseboard_fab2_lib.baseboard_fab2(sch_1):page151_i265"
				( attribute "ATTRIBUTE" "120OHM"
					( Origin gFrontEnd )
				)
				( attribute "CDS_LIB" "w_hdl"
					( Origin gPackager )
				)
				( attribute "CDS_LMAN_SYM_OUTLINE" "-50,75,50,-75"
					( Origin gPackager )
				)
				( attribute "LOCATION" "R25W18"
					( Origin gFrontEnd )
				)
				( attribute "PACK_TYPE" "RCL_GP"
					( Origin gFrontEnd )
				)
				( attribute "PART_NUMBER" "64.12005.6DL"
					( Origin gFrontEnd )
				)
				( attribute "PHYS_PAGE" "151"
					( Origin gFrontEnd )
				)
				( attribute "RATED" "1/16W"
					( Origin gFrontEnd )
				)
				( attribute "ROT" "1"
					( Origin gFrontEnd )
				)
				( attribute "SEC" "1"
					( Origin gFrontEnd )
				)
				( attribute "SEC_TYPE" "RCL_GP"
					( Origin gFrontEnd )
				)
				( attribute "TOLERANCE" "1%"
					( Origin gFrontEnd )
				)
				( attribute "VALUE" "120R2F-GP"
					( Origin gFrontEnd )
				)
				( attribute "VER" "1"
					( Origin gFrontEnd )
				)
				( attribute "XY" "(-3025,825)"
					( Origin gFrontEnd )
				)
				( attribute "CHIPS_PART_NAME" "120R2F-GP"
					( Origin gPackager )
				)
				( attribute "CDS_PART_NAME" "120R2F-GP_RCL_GP-120R2F-GP,64.A"
					( Origin gPackager )
				)
				( attribute "PACK_SIZE" "0402"
					( Origin gFrontEnd )
				)
				( attribute "CDS_LOCATION" "R25W18"
					( Origin gPackager )
				)
				( attribute "CDS_SEC" "1"
					( Origin gPackager )
				)
				( objectStatus "R25W18" )
			)
			( gate "@baseboard_fab2_lib.baseboard_fab2(sch_1):page151_i266"
				( attribute "ATTRIBUTE" "120OHM"
					( Origin gFrontEnd )
				)
				( attribute "CDS_LIB" "w_hdl"
					( Origin gPackager )
				)
				( attribute "CDS_LMAN_SYM_OUTLINE" "-50,75,50,-75"
					( Origin gPackager )
				)
				( attribute "LOCATION" "R25W20"
					( Origin gFrontEnd )
				)
				( attribute "PACK_TYPE" "RCL_GP"
					( Origin gFrontEnd )
				)
				( attribute "PART_NUMBER" "64.12005.6DL"
					( Origin gFrontEnd )
				)
				( attribute "PHYS_PAGE" "151"
					( Origin gFrontEnd )
				)
				( attribute "RATED" "1/16W"
					( Origin gFrontEnd )
				)
				( attribute "ROT" "1"
					( Origin gFrontEnd )
				)
				( attribute "SEC" "1"
					( Origin gFrontEnd )
				)
				( attribute "SEC_TYPE" "RCL_GP"
					( Origin gFrontEnd )
				)
				( attribute "TOLERANCE" "1%"
					( Origin gFrontEnd )
				)
				( attribute "VALUE" "120R2F-GP"
					( Origin gFrontEnd )
				)
				( attribute "VER" "1"
					( Origin gFrontEnd )
				)
				( attribute "XY" "(-3025,725)"
					( Origin gFrontEnd )
				)
				( attribute "CHIPS_PART_NAME" "120R2F-GP"
					( Origin gPackager )
				)
				( attribute "CDS_PART_NAME" "120R2F-GP_RCL_GP-120R2F-GP,64.A"
					( Origin gPackager )
				)
				( attribute "PACK_SIZE" "0402"
					( Origin gFrontEnd )
				)
				( attribute "CDS_LOCATION" "R25W20"
					( Origin gPackager )
				)
				( attribute "CDS_SEC" "1"
					( Origin gPackager )
				)
				( objectStatus "R25W20" )
			)
			( gate "@baseboard_fab2_lib.baseboard_fab2(sch_1):page151_i267"
				( attribute "ATTRIBUTE" "120OHM"
					( Origin gFrontEnd )
				)
				( attribute "CDS_LIB" "w_hdl"
					( Origin gPackager )
				)
				( attribute "CDS_LMAN_SYM_OUTLINE" "-50,75,50,-75"
					( Origin gPackager )
				)
				( attribute "LOCATION" "R25W19"
					( Origin gFrontEnd )
				)
				( attribute "PACK_TYPE" "RCL_GP"
					( Origin gFrontEnd )
				)
				( attribute "PART_NUMBER" "64.12005.6DL"
					( Origin gFrontEnd )
				)
				( attribute "PHYS_PAGE" "151"
					( Origin gFrontEnd )
				)
				( attribute "RATED" "1/16W"
					( Origin gFrontEnd )
				)
				( attribute "ROT" "1"
					( Origin gFrontEnd )
				)
				( attribute "SEC" "1"
					( Origin gFrontEnd )
				)
				( attribute "SEC_TYPE" "RCL_GP"
					( Origin gFrontEnd )
				)
				( attribute "TOLERANCE" "1%"
					( Origin gFrontEnd )
				)
				( attribute "VALUE" "120R2F-GP"
					( Origin gFrontEnd )
				)
				( attribute "VER" "1"
					( Origin gFrontEnd )
				)
				( attribute "XY" "(-3025,775)"
					( Origin gFrontEnd )
				)
				( attribute "CHIPS_PART_NAME" "120R2F-GP"
					( Origin gPackager )
				)
				( attribute "CDS_PART_NAME" "120R2F-GP_RCL_GP-120R2F-GP,64.A"
					( Origin gPackager )
				)
				( attribute "PACK_SIZE" "0402"
					( Origin gFrontEnd )
				)
				( attribute "CDS_LOCATION" "R25W19"
					( Origin gPackager )
				)
				( attribute "CDS_SEC" "1"
					( Origin gPackager )
				)
				( objectStatus "R25W19" )
			)
			( gate "@baseboard_fab2_lib.baseboard_fab2(sch_1):page151_i268"
				( attribute "ATTRIBUTE" "120OHM"
					( Origin gFrontEnd )
				)
				( attribute "CDS_LIB" "w_hdl"
					( Origin gPackager )
				)
				( attribute "CDS_LMAN_SYM_OUTLINE" "-50,75,50,-75"
					( Origin gPackager )
				)
				( attribute "LOCATION" "R25W24"
					( Origin gFrontEnd )
				)
				( attribute "PACK_TYPE" "RCL_GP"
					( Origin gFrontEnd )
				)
				( attribute "PART_NUMBER" "64.12005.6DL"
					( Origin gFrontEnd )
				)
				( attribute "PHYS_PAGE" "151"
					( Origin gFrontEnd )
				)
				( attribute "RATED" "1/16W"
					( Origin gFrontEnd )
				)
				( attribute "ROT" "1"
					( Origin gFrontEnd )
				)
				( attribute "SEC" "1"
					( Origin gFrontEnd )
				)
				( attribute "SEC_TYPE" "RCL_GP"
					( Origin gFrontEnd )
				)
				( attribute "TOLERANCE" "1%"
					( Origin gFrontEnd )
				)
				( attribute "VALUE" "120R2F-GP"
					( Origin gFrontEnd )
				)
				( attribute "VER" "1"
					( Origin gFrontEnd )
				)
				( attribute "XY" "(-3025,525)"
					( Origin gFrontEnd )
				)
				( attribute "CHIPS_PART_NAME" "120R2F-GP"
					( Origin gPackager )
				)
				( attribute "CDS_PART_NAME" "120R2F-GP_RCL_GP-120R2F-GP,64.A"
					( Origin gPackager )
				)
				( attribute "PACK_SIZE" "0402"
					( Origin gFrontEnd )
				)
				( attribute "CDS_LOCATION" "R25W24"
					( Origin gPackager )
				)
				( attribute "CDS_SEC" "1"
					( Origin gPackager )
				)
				( objectStatus "R25W24" )
			)
			( gate "@baseboard_fab2_lib.baseboard_fab2(sch_1):page151_i211"
				( attribute "CDS_LIB" "mstr_discrete"
					( Origin gPackager )
				)
				( attribute "CDS_LOCATION" "R25W118"
					( Origin gPackager )
				)
				( attribute "LOCATION" "R25W118"
					( Origin gFrontEnd )
				)
				( attribute "MATERIAL" "CHIP"
					( Origin gFrontEnd )
				)
				( attribute "PACK_TYPE" "0402"
					( Origin gFrontEnd )
				)
				( attribute "PART_NUMBER" "G21497-005"
					( Origin gFrontEnd )
				)
				( attribute "PHYS_PAGE" "151"
					( Origin gFrontEnd )
				)
				( attribute "ROOM" "HOT_SWAP"
					( Origin gFrontEnd )
				)
				( attribute "ROT" "5"
					( Origin gFrontEnd )
				)
				( attribute "SEC" "1"
					( Origin gFrontEnd )
				)
				( attribute "SEC_TYPE" "0402"
					( Origin gFrontEnd )
				)
				( attribute "TOLERANCE" "5%"
					( Origin gFrontEnd )
				)
				( attribute "VALUE" "0.0"
					( Origin gFrontEnd )
				)
				( attribute "VER" "1"
					( Origin gFrontEnd )
				)
				( attribute "WATTAGE" "1/16W"
					( Origin gFrontEnd )
				)
				( attribute "XY" "(-150,-1950)"
					( Origin gFrontEnd )
				)
				( attribute "CHIPS_PART_NAME" "RES"
					( Origin gPackager )
				)
				( attribute "CDS_PART_NAME" "RES_0402-0.0,5%,1/16W,CHIP,G21A"
					( Origin gPackager )
				)
				( attribute "CDS_SEC" "1"
					( Origin gPackager )
				)
				( objectStatus "R25W118" )
			)
			( gate "@baseboard_fab2_lib.baseboard_fab2(sch_1):page151_i145"
				( attribute "BOM_COST" "SM_CONTROLLER"
					( Origin gFrontEnd )
				)
				( attribute "CDS_LIB" "mstr_discrete"
					( Origin gPackager )
				)
				( attribute "CDS_LOCATION" "Q9E1"
					( Origin gPackager )
				)
				( attribute "CDS_SEC" "2"
					( Origin gPackager )
				)
				( attribute "LOCATION" "Q9E1"
					( Origin gFrontEnd )
				)
				( attribute "MATERIAL" "FET"
					( Origin gFrontEnd )
				)
				( attribute "PACK_TYPE" "SMLF"
					( Origin gFrontEnd )
				)
				( attribute "PART_NUMBER" "E40049-001"
					( Origin gFrontEnd )
				)
				( attribute "PHYS_PAGE" "151"
					( Origin gFrontEnd )
				)
				( attribute "ROOM" "BMC"
					( Origin gFrontEnd )
				)
				( attribute "ROT" "0"
					( Origin gFrontEnd )
				)
				( attribute "SEC" "2"
					( Origin gFrontEnd )
				)
				( attribute "SEC_TYPE" "SMLF"
					( Origin gFrontEnd )
				)
				( attribute "VALUE" "NTJD4001N"
					( Origin gFrontEnd )
				)
				( attribute "VER" "5"
					( Origin gFrontEnd )
				)
				( attribute "XY" "(-1100,-375)"
					( Origin gFrontEnd )
				)
				( attribute "CHIPS_PART_NAME" "FET_N_DUAL"
					( Origin gPackager )
				)
				( attribute "CDS_PART_NAME" "FET_N_DUAL_SMLF-NTJD4001N,FET,A"
					( Origin gPackager )
				)
				( objectStatus "Q9E1" )
			)
			( gate "@baseboard_fab2_lib.baseboard_fab2(sch_1):page151_i144"
				( attribute "BOM_COST" "SM_CONTROLLER"
					( Origin gFrontEnd )
				)
				( attribute "CDS_LIB" "mstr_discrete"
					( Origin gPackager )
				)
				( attribute "CDS_LOCATION" "DS9E1"
					( Origin gPackager )
				)
				( attribute "CDS_SEC" "1"
					( Origin gPackager )
				)
				( attribute "COLOR" "GREEN"
					( Origin gFrontEnd )
				)
				( attribute "LOCATION" "DS9E1"
					( Origin gFrontEnd )
				)
				( attribute "MATERIAL" "IC"
					( Origin gFrontEnd )
				)
				( attribute "PACK_TYPE" "A1LF"
					( Origin gFrontEnd )
				)
				( attribute "PART_NUMBER" "C97278-010"
					( Origin gFrontEnd )
				)
				( attribute "PHYS_PAGE" "151"
					( Origin gFrontEnd )
				)
				( attribute "ROOM" "BMC"
					( Origin gFrontEnd )
				)
				( attribute "ROT" "0"
					( Origin gFrontEnd )
				)
				( attribute "SEC" "1"
					( Origin gFrontEnd )
				)
				( attribute "SEC_TYPE" "A1LF"
					( Origin gFrontEnd )
				)
				( attribute "VER" "3"
					( Origin gFrontEnd )
				)
				( attribute "XY" "(-900,0)"
					( Origin gFrontEnd )
				)
				( attribute "CHIPS_PART_NAME" "LED"
					( Origin gPackager )
				)
				( attribute "CDS_PART_NAME" "LED_A1LF-GREEN,IC,C97278-010"
					( Origin gPackager )
				)
				( objectStatus "DS9E1" )
			)
			( gate "@baseboard_fab2_lib.baseboard_fab2(sch_1):page151_i58"
				( attribute "BOM_COST" "SM_CONTROLLER"
					( Origin gFrontEnd )
				)
				( attribute "CDS_LIB" "mstr_discrete"
					( Origin gPackager )
				)
				( attribute "CDS_LOCATION" "C25W16"
					( Origin gPackager )
				)
				( attribute "LOCATION" "C25W16"
					( Origin gFrontEnd )
				)
				( attribute "MATERIAL" "COG"
					( Origin gFrontEnd )
				)
				( attribute "PACK_TYPE" "0402LF"
					( Origin gFrontEnd )
				)
				( attribute "PART_NUMBER" "A36095-026"
					( Origin gFrontEnd )
				)
				( attribute "PHYS_PAGE" "151"
					( Origin gFrontEnd )
				)
				( attribute "ROOM" "BMC"
					( Origin gFrontEnd )
				)
				( attribute "ROT" "0"
					( Origin gFrontEnd )
				)
				( attribute "SEC" "1"
					( Origin gFrontEnd )
				)
				( attribute "TOLERANCE" "5%"
					( Origin gFrontEnd )
				)
				( attribute "VALUE" "100.0PF"
					( Origin gFrontEnd )
				)
				( attribute "VER" "1"
					( Origin gFrontEnd )
				)
				( attribute "VOLTAGE" "50V"
					( Units "uVoltage" "V" 1.000000)
					( Origin gFrontEnd )
				)
				( attribute "XY" "(-2075,2100)"
					( Origin gFrontEnd )
				)
				( attribute "CHIPS_PART_NAME" "CAP"
					( Origin gPackager )
				)
				( attribute "CDS_PART_NAME" "CAP_0402LF-100.0PF,50V,5%,COG,A"
					( Origin gPackager )
				)
				( attribute "SEC_TYPE" "0402LF"
					( Origin gFrontEnd )
				)
				( attribute "CDS_SEC" "1"
					( Origin gPackager )
				)
				( objectStatus "C25W16" )
			)
			( gate "@baseboard_fab2_lib.baseboard_fab2(sch_1):page147_i75"
				( attribute "BOM_COST" "SM_CONTROLLER"
					( Origin gFrontEnd )
				)
				( attribute "CDS_LIB" "mstr_discrete"
					( Origin gPackager )
				)
				( attribute "LOCATION" "R2N13"
					( Origin gFrontEnd )
				)
				( attribute "MATERIAL" "CHIP"
					( Origin gFrontEnd )
				)
				( attribute "PACK_TYPE" "0402"
					( Origin gFrontEnd )
				)
				( attribute "PART_NUMBER" "G21796-016"
					( Origin gFrontEnd )
				)
				( attribute "PHYS_PAGE" "147"
					( Origin gFrontEnd )
				)
				( attribute "ROOM" "BMC"
					( Origin gFrontEnd )
				)
				( attribute "ROT" "0"
					( Origin gFrontEnd )
				)
				( attribute "TOLERANCE" "1%"
					( Origin gFrontEnd )
				)
				( attribute "VALUE" "10.0K"
					( Origin gFrontEnd )
				)
				( attribute "VER" "2"
					( Origin gFrontEnd )
				)
				( attribute "WATTAGE" "1/16W"
					( Origin gFrontEnd )
				)
				( attribute "XY" "(-150,1950)"
					( Origin gFrontEnd )
				)
				( attribute "CHIPS_PART_NAME" "RES"
					( Origin gPackager )
				)
				( attribute "CDS_PART_NAME" "RES_0402-10.0K,1%,1/16W,CHIP,GA"
					( Origin gPackager )
				)
				( attribute "CDS_LOCATION" "R2N13"
					( Origin gPackager )
				)
				( attribute "SEC" "1"
					( Origin gFrontEnd )
				)
				( attribute "SEC_TYPE" "0402"
					( Origin gFrontEnd )
				)
				( attribute "CDS_SEC" "1"
					( Origin gPackager )
				)
				( objectStatus "R2N13" )
			)
			( gate "@baseboard_fab2_lib.baseboard_fab2(sch_1):page146_i123"
				( attribute "BOM_COST" "SM_CONTROLLER"
					( Origin gFrontEnd )
				)
				( attribute "CDS_LIB" "mstr_discrete"
					( Origin gPackager )
				)
				( attribute "CDS_LOCATION" "R25W78"
					( Origin gPackager )
				)
				( attribute "CDS_SEC" "1"
					( Origin gPackager )
				)
				( attribute "LOCATION" "R25W78"
					( Origin gFrontEnd )
				)
				( attribute "MATERIAL" "CHIP"
					( Origin gFrontEnd )
				)
				( attribute "PACK_TYPE" "0402"
					( Origin gFrontEnd )
				)
				( attribute "PART_NUMBER" "G21796-250"
					( Origin gFrontEnd )
				)
				( attribute "PHYS_PAGE" "146"
					( Origin gFrontEnd )
				)
				( attribute "ROOM" "BMC"
					( Origin gFrontEnd )
				)
				( attribute "ROT" "0"
					( Origin gFrontEnd )
				)
				( attribute "SEC" "1"
					( Origin gFrontEnd )
				)
				( attribute "SEC_TYPE" "0402"
					( Origin gFrontEnd )
				)
				( attribute "TOLERANCE" "1.0%"
					( Origin gFrontEnd )
				)
				( attribute "VALUE" "22.1"
					( Origin gFrontEnd )
				)
				( attribute "VER" "1"
					( Origin gFrontEnd )
				)
				( attribute "WATTAGE" "1/16W"
					( Origin gFrontEnd )
				)
				( attribute "XY" "(-1450,2050)"
					( Origin gFrontEnd )
				)
				( attribute "CHIPS_PART_NAME" "RES"
					( Origin gPackager )
				)
				( attribute "CDS_PART_NAME" "RES_0402-22.1,1.0%,1/16W,CHIP,A"
					( Origin gPackager )
				)
				( objectStatus "R25W78" )
			)
			( gate "@baseboard_fab2_lib.baseboard_fab2(sch_1):page145_i100"
				( attribute "CDS_LIB" "mstr_discrete"
					( Origin gPackager )
				)
				( attribute "LOCATION" "R1T15"
					( Origin gFrontEnd )
				)
				( attribute "MATERIAL" "EMPTY"
					( Origin gFrontEnd )
				)
				( attribute "PACK_TYPE" "0402"
					( Origin gFrontEnd )
				)
				( attribute "PART_NUMBER" "G21497-005"
					( Origin gFrontEnd )
				)
				( attribute "PHYS_PAGE" "145"
					( Origin gFrontEnd )
				)
				( attribute "ROT" "0"
					( Origin gFrontEnd )
				)
				( attribute "TOLERANCE" "5%"
					( Origin gFrontEnd )
				)
				( attribute "VALUE" "0.0"
					( Origin gFrontEnd )
				)
				( attribute "VER" "1"
					( Origin gFrontEnd )
				)
				( attribute "WATTAGE" "1/16W"
					( Origin gFrontEnd )
				)
				( attribute "XY" "(-7300,-3975)"
					( Origin gFrontEnd )
				)
				( attribute "CHIPS_PART_NAME" "RES"
					( Origin gPackager )
				)
				( attribute "CDS_PART_NAME" "RES_0402-0.0,5%,1/16W,EMPTY,G2A"
					( Origin gPackager )
				)
				( attribute "CDS_LOCATION" "R1T15"
					( Origin gPackager )
				)
				( attribute "SEC" "1"
					( Origin gFrontEnd )
				)
				( attribute "SEC_TYPE" "0402"
					( Origin gFrontEnd )
				)
				( attribute "CDS_SEC" "1"
					( Origin gPackager )
				)
				( objectStatus "R1T15" )
			)
			( gate "@baseboard_fab2_lib.baseboard_fab2(sch_1):page145_i101"
				( attribute "CDS_LIB" "mstr_discrete"
					( Origin gPackager )
				)
				( attribute "LOCATION" "R1T23"
					( Origin gFrontEnd )
				)
				( attribute "MATERIAL" "EMPTY"
					( Origin gFrontEnd )
				)
				( attribute "PACK_TYPE" "0402"
					( Origin gFrontEnd )
				)
				( attribute "PART_NUMBER" "G21497-005"
					( Origin gFrontEnd )
				)
				( attribute "PHYS_PAGE" "145"
					( Origin gFrontEnd )
				)
				( attribute "ROT" "5"
					( Origin gFrontEnd )
				)
				( attribute "TOLERANCE" "5%"
					( Origin gFrontEnd )
				)
				( attribute "VALUE" "0.0"
					( Origin gFrontEnd )
				)
				( attribute "VER" "1"
					( Origin gFrontEnd )
				)
				( attribute "WATTAGE" "1/16W"
					( Origin gFrontEnd )
				)
				( attribute "XY" "(-7050,-4200)"
					( Origin gFrontEnd )
				)
				( attribute "CHIPS_PART_NAME" "RES"
					( Origin gPackager )
				)
				( attribute "CDS_PART_NAME" "RES_0402-0.0,5%,1/16W,EMPTY,G2A"
					( Origin gPackager )
				)
				( attribute "CDS_LOCATION" "R1T23"
					( Origin gPackager )
				)
				( attribute "SEC" "1"
					( Origin gFrontEnd )
				)
				( attribute "SEC_TYPE" "0402"
					( Origin gFrontEnd )
				)
				( attribute "CDS_SEC" "1"
					( Origin gPackager )
				)
				( objectStatus "R1T23" )
			)
			( gate "@baseboard_fab2_lib.baseboard_fab2(sch_1):page247_i85"
				( attribute "BOM_COST" "SM_THERM"
					( Origin gFrontEnd )
				)
				( attribute "CDS_LIB" "dev_discrete"
					( Origin gPackager )
				)
				( attribute "CDS_LOCATION" "C6W3"
					( Origin gPackager )
				)
				( attribute "CDS_SEC" "1"
					( Origin gPackager )
				)
				( attribute "LOCATION" "C6W3"
					( Origin gFrontEnd )
				)
				( attribute "MATERIAL" "X7R"
					( Origin gFrontEnd )
				)
				( attribute "PACK_TYPE" "0402V"
					( Origin gFrontEnd )
				)
				( attribute "PART_NUMBER" "A36096-030"
					( Origin gFrontEnd )
				)
				( attribute "PHYS_PAGE" "247"
					( Origin gFrontEnd )
				)
				( attribute "ROOM" "TEMP_SENSORS"
					( Origin gFrontEnd )
				)
				( attribute "ROT" "0"
					( Origin gFrontEnd )
				)
				( attribute "SEC" "1"
					( Origin gFrontEnd )
				)
				( attribute "SEC_TYPE" "0402V"
					( Origin gFrontEnd )
				)
				( attribute "TOLERANCE" "10%"
					( Origin gFrontEnd )
				)
				( attribute "VALUE" "0.1UF"
					( Origin gFrontEnd )
				)
				( attribute "VER" "1"
					( Origin gFrontEnd )
				)
				( attribute "VOLTAGE" "16V"
					( Units "uVoltage" "V" 1.000000)
					( Origin gFrontEnd )
				)
				( attribute "XY" "(-1775,2300)"
					( Origin gFrontEnd )
				)
				( attribute "CHIPS_PART_NAME" "CAP_A"
					( Origin gPackager )
				)
				( attribute "CDS_PART_NAME" "CAP_A_0402V-0.1UF,16V,10%,X7R,A"
					( Origin gPackager )
				)
				( objectStatus "C6W3" )
			)
			( gate "@baseboard_fab2_lib.baseboard_fab2(sch_1):page247_i87"
				( attribute "BOM_COST" "SM_THERM"
					( Origin gFrontEnd )
				)
				( attribute "CDS_LIB" "mstr_discrete"
					( Origin gPackager )
				)
				( attribute "CDS_LOCATION" "R6W20"
					( Origin gPackager )
				)
				( attribute "LOCATION" "R6W20"
					( Origin gFrontEnd )
				)
				( attribute "MATERIAL" "CHIP"
					( Origin gFrontEnd )
				)
				( attribute "PACK_TYPE" "0402"
					( Origin gFrontEnd )
				)
				( attribute "PART_NUMBER" "G21796-173"
					( Origin gFrontEnd )
				)
				( attribute "PHYS_PAGE" "247"
					( Origin gFrontEnd )
				)
				( attribute "ROOM" "TEMP_SENSORS"
					( Origin gFrontEnd )
				)
				( attribute "ROT" "0"
					( Origin gFrontEnd )
				)
				( attribute "SEC" "1"
					( Origin gFrontEnd )
				)
				( attribute "TOLERANCE" "1%"
					( Origin gFrontEnd )
				)
				( attribute "VALUE" "20.0"
					( Origin gFrontEnd )
				)
				( attribute "VER" "1"
					( Origin gFrontEnd )
				)
				( attribute "WATTAGE" "1/16W"
					( Origin gFrontEnd )
				)
				( attribute "XY" "(-1025,1750)"
					( Origin gFrontEnd )
				)
				( attribute "CHIPS_PART_NAME" "RES"
					( Origin gPackager )
				)
				( attribute "CDS_PART_NAME" "RES_0402-20.0,1%,1/16W,CHIP,G2A"
					( Origin gPackager )
				)
				( attribute "SEC_TYPE" "0402"
					( Origin gFrontEnd )
				)
				( attribute "CDS_SEC" "1"
					( Origin gPackager )
				)
				( objectStatus "R6W20" )
			)
			( gate "@baseboard_fab2_lib.baseboard_fab2(sch_1):page247_i89"
				( attribute "BOM_COST" "SM_THERM"
					( Origin gFrontEnd )
				)
				( attribute "CDS_LIB" "mstr_memory"
					( Origin gPackager )
				)
				( attribute "CDS_LOCATION" "U6W3"
					( Origin gPackager )
				)
				( attribute "LOCATION" "U6W3"
					( Origin gFrontEnd )
				)
				( attribute "MATERIAL" "IC"
					( Origin gFrontEnd )
				)
				( attribute "PACK_TYPE" "SOICLF"
					( Origin gFrontEnd )
				)
				( attribute "PART_NUMBER" "C47049-001"
					( Origin gFrontEnd )
				)
				( attribute "PHYS_PAGE" "247"
					( Origin gFrontEnd )
				)
				( attribute "ROOM" "TEMP_SENSORS"
					( Origin gFrontEnd )
				)
				( attribute "ROT" "0"
					( Origin gFrontEnd )
				)
				( attribute "SEC" "1"
					( Origin gFrontEnd )
				)
				( attribute "SEC_TYPE" "SOICLF"
					( Origin gFrontEnd )
				)
				( attribute "VER" "1"
					( Origin gFrontEnd )
				)
				( attribute "XY" "(-2200,1850)"
					( Origin gFrontEnd )
				)
				( attribute "CHIPS_PART_NAME" "AT24C64"
					( Origin gPackager )
				)
				( attribute "CDS_PART_NAME" "AT24C64_SOICLF-IC,C47049-001-VA"
					( Origin gPackager )
				)
				( attribute "CDS_SEC" "1"
					( Origin gPackager )
				)
				( objectStatus "U6W3" )
			)
			( gate "@baseboard_fab2_lib.baseboard_fab2(sch_1):page247_i90"
				( attribute "BOM_COST" "SM_THERM"
					( Origin gFrontEnd )
				)
				( attribute "CDS_LIB" "mstr_discrete"
					( Origin gPackager )
				)
				( attribute "CDS_LOCATION" "R6W21"
					( Origin gPackager )
				)
				( attribute "CDS_SEC" "1"
					( Origin gPackager )
				)
				( attribute "LOCATION" "R6W21"
					( Origin gFrontEnd )
				)
				( attribute "MATERIAL" "CHIP"
					( Origin gFrontEnd )
				)
				( attribute "PACK_TYPE" "0402"
					( Origin gFrontEnd )
				)
				( attribute "PART_NUMBER" "G21796-026"
					( Origin gFrontEnd )
				)
				( attribute "PHYS_PAGE" "247"
					( Origin gFrontEnd )
				)
				( attribute "ROOM" "TEMP_SENSORS"
					( Origin gFrontEnd )
				)
				( attribute "ROT" "0"
					( Origin gFrontEnd )
				)
				( attribute "SEC" "1"
					( Origin gFrontEnd )
				)
				( attribute "SEC_TYPE" "0402"
					( Origin gFrontEnd )
				)
				( attribute "TOLERANCE" "1%"
					( Origin gFrontEnd )
				)
				( attribute "VALUE" "1.00K"
					( Origin gFrontEnd )
				)
				( attribute "VER" "2"
					( Origin gFrontEnd )
				)
				( attribute "WATTAGE" "1/16W"
					( Origin gFrontEnd )
				)
				( attribute "XY" "(-3200,2200)"
					( Origin gFrontEnd )
				)
				( attribute "CHIPS_PART_NAME" "RES"
					( Origin gPackager )
				)
				( attribute "CDS_PART_NAME" "RES_0402-1.00K,1%,1/16W,CHIP,GA"
					( Origin gPackager )
				)
				( objectStatus "R6W21" )
			)
			( gate "@baseboard_fab2_lib.baseboard_fab2(sch_1):page247_i92"
				( attribute "BOM_COST" "SM_THERM"
					( Origin gFrontEnd )
				)
				( attribute "CDS_LIB" "mstr_discrete"
					( Origin gPackager )
				)
				( attribute "CDS_LOCATION" "R6W23"
					( Origin gPackager )
				)
				( attribute "CDS_SEC" "1"
					( Origin gPackager )
				)
				( attribute "LOCATION" "R6W23"
					( Origin gFrontEnd )
				)
				( attribute "MATERIAL" "CHIP"
					( Origin gFrontEnd )
				)
				( attribute "PACK_TYPE" "0402"
					( Origin gFrontEnd )
				)
				( attribute "PART_NUMBER" "G21796-026"
					( Origin gFrontEnd )
				)
				( attribute "PHYS_PAGE" "247"
					( Origin gFrontEnd )
				)
				( attribute "ROOM" "TEMP_SENSORS"
					( Origin gFrontEnd )
				)
				( attribute "ROT" "0"
					( Origin gFrontEnd )
				)
				( attribute "SEC" "1"
					( Origin gFrontEnd )
				)
				( attribute "SEC_TYPE" "0402"
					( Origin gFrontEnd )
				)
				( attribute "TOLERANCE" "1%"
					( Origin gFrontEnd )
				)
				( attribute "VALUE" "1.00K"
					( Origin gFrontEnd )
				)
				( attribute "VER" "2"
					( Origin gFrontEnd )
				)
				( attribute "WATTAGE" "1/16W"
					( Origin gFrontEnd )
				)
				( attribute "XY" "(-3200,1500)"
					( Origin gFrontEnd )
				)
				( attribute "CHIPS_PART_NAME" "RES"
					( Origin gPackager )
				)
				( attribute "CDS_PART_NAME" "RES_0402-1.00K,1%,1/16W,CHIP,GA"
					( Origin gPackager )
				)
				( objectStatus "R6W23" )
			)
			( gate "@baseboard_fab2_lib.baseboard_fab2(sch_1):page247_i94"
				( attribute "BOM_COST" "SM_THERM"
					( Origin gFrontEnd )
				)
				( attribute "CDS_LIB" "mstr_discrete"
					( Origin gPackager )
				)
				( attribute "CDS_LOCATION" "R6W22"
					( Origin gPackager )
				)
				( attribute "CDS_SEC" "1"
					( Origin gPackager )
				)
				( attribute "LOCATION" "R6W22"
					( Origin gFrontEnd )
				)
				( attribute "MATERIAL" "CHIP"
					( Origin gFrontEnd )
				)
				( attribute "PACK_TYPE" "0402"
					( Origin gFrontEnd )
				)
				( attribute "PART_NUMBER" "G21796-173"
					( Origin gFrontEnd )
				)
				( attribute "PHYS_PAGE" "247"
					( Origin gFrontEnd )
				)
				( attribute "ROOM" "TEMP_SENSORS"
					( Origin gFrontEnd )
				)
				( attribute "ROT" "0"
					( Origin gFrontEnd )
				)
				( attribute "SEC" "1"
					( Origin gFrontEnd )
				)
				( attribute "SEC_TYPE" "0402"
					( Origin gFrontEnd )
				)
				( attribute "TOLERANCE" "1%"
					( Origin gFrontEnd )
				)
				( attribute "VALUE" "20.0"
					( Origin gFrontEnd )
				)
				( attribute "VER" "1"
					( Origin gFrontEnd )
				)
				( attribute "WATTAGE" "1/16W"
					( Origin gFrontEnd )
				)
				( attribute "XY" "(-3425,1750)"
					( Origin gFrontEnd )
				)
				( attribute "CHIPS_PART_NAME" "RES"
					( Origin gPackager )
				)
				( attribute "CDS_PART_NAME" "RES_0402-20.0,1%,1/16W,CHIP,G2A"
					( Origin gPackager )
				)
				( objectStatus "R6W22" )
			)
			( gate "@baseboard_fab2_lib.baseboard_fab2(sch_1):page143_i63"
				( attribute "CDS_LIB" "w_hdl"
					( Origin gPackager )
				)
				( attribute "CDS_LMAN_SYM_OUTLINE" "-575,1050,575,-1050"
					( Origin gPackager )
				)
				( attribute "LOCATION" "U25W4"
					( Origin gFrontEnd )
				)
				( attribute "PACK_TYPE" "ASIC2-GB1"
					( Origin gFrontEnd )
				)
				( attribute "PART_NUMBER" "071.2520A.M001"
					( Origin gFrontEnd )
				)
				( attribute "PHYS_PAGE" "143"
					( Origin gFrontEnd )
				)
				( attribute "ROT" "0"
					( Origin gFrontEnd )
				)
				( attribute "VALUE" "AST2520A1-GP-GP"
					( Origin gFrontEnd )
				)
				( attribute "VER" "1"
					( Origin gFrontEnd )
				)
				( attribute "XY" "(-12850,-1850)"
					( Origin gFrontEnd )
				)
				( attribute "CHIPS_PART_NAME" "AST2520A1-GP-GP"
					( Origin gPackager )
				)
				( attribute "CDS_PART_NAME" "AST2520A1-GP-GP_ASIC2-GB1-AST2A"
					( Origin gPackager )
				)
				( attribute "CDS_LOCATION" "U25W4"
					( Origin gPackager )
				)
				( attribute "CDS_SEC" "1"
					( Origin gPackager )
				)
				( attribute "SEC" "1"
					( Origin gPackager )
				)
				( objectStatus "U25W4" )
			)
			( gate "@baseboard_fab2_lib.baseboard_fab2(sch_1):page146_i105"
				( attribute "CDS_LIB" "w_hdl"
					( Origin gPackager )
				)
				( attribute "CDS_LMAN_SYM_OUTLINE" "-1325,950,1325,-950"
					( Origin gPackager )
				)
				( attribute "LOCATION" "U25W4"
					( Origin gFrontEnd )
				)
				( attribute "PACK_TYPE" "ASIC2-GB1"
					( Origin gFrontEnd )
				)
				( attribute "PART_NUMBER" "071.2520A.M001"
					( Origin gFrontEnd )
				)
				( attribute "PHYS_PAGE" "146"
					( Origin gFrontEnd )
				)
				( attribute "ROT" "0"
					( Origin gFrontEnd )
				)
				( attribute "VALUE" "AST2520A1-GP-GP"
					( Origin gFrontEnd )
				)
				( attribute "VER" "5"
					( Origin gFrontEnd )
				)
				( attribute "XY" "(-4025,1850)"
					( Origin gFrontEnd )
				)
				( attribute "CHIPS_PART_NAME" "AST2520A1-GP-GP"
					( Origin gPackager )
				)
				( attribute "CDS_PART_NAME" "AST2520A1-GP-GP_ASIC2-GB1-AST2A"
					( Origin gPackager )
				)
				( attribute "CDS_LOCATION" "U25W4"
					( Origin gPackager )
				)
				( attribute "CDS_SEC" "5"
					( Origin gPackager )
				)
				( attribute "SEC" "5"
					( Origin gPackager )
				)
				( objectStatus "U25W4" )
			)
			( gate "@baseboard_fab2_lib.baseboard_fab2(sch_1):page255_i89"
				( attribute "CDS_LIB" "w_hdl"
					( Origin gPackager )
				)
				( attribute "CDS_LMAN_SYM_OUTLINE" "-125,50,125,-50"
					( Origin gPackager )
				)
				( attribute "CONFIG" "069.50007.0071"
					( Origin gFrontEnd )
				)
				( attribute "LOCATION" "F25W1"
					( Origin gFrontEnd )
				)
				( attribute "PACK_TYPE" "DISCRET-GA1"
					( Origin gFrontEnd )
				)
				( attribute "PART_NUMBER" "69.50011.051"
					( Origin gFrontEnd )
				)
				( attribute "PHYS_PAGE" "252"
					( Origin gFrontEnd )
				)
				( attribute "ROT" "0"
					( Origin gFrontEnd )
				)
				( attribute "SEC" "1"
					( Origin gFrontEnd )
				)
				( attribute "SEC_TYPE" "DISCRET-GA1"
					( Origin gFrontEnd )
				)
				( attribute "VALUE" "POLYSW-D5A6V-2-GP-U"
					( Origin gFrontEnd )
				)
				( attribute "VER" "1"
					( Origin gFrontEnd )
				)
				( attribute "XY" "(-2775,2850)"
					( Origin gFrontEnd )
				)
				( attribute "CHIPS_PART_NAME" "POLYSW-D5A6V-2-GP-U"
					( Origin gPackager )
				)
				( attribute "CDS_PART_NAME" "POLYSW-D5A6V-2-GP-U_DISCRET-GAA"
					( Origin gPackager )
				)
				( attribute "CDS_LOCATION" "F25W1"
					( Origin gPackager )
				)
				( attribute "CDS_SEC" "1"
					( Origin gPackager )
				)
				( attribute "GROUP" "AST2500"
					( Origin gFrontEnd )
				)
				( objectStatus "F25W1" )
			)
			( gate "@baseboard_fab2_lib.baseboard_fab2(sch_1):page247_i98"
				( attribute "CDS_LIB" "mstr_discrete"
					( Origin gPackager )
				)
				( attribute "MATERIAL" "CHIP"
					( Origin gFrontEnd )
				)
				( attribute "PACK_TYPE" "0402"
					( Origin gFrontEnd )
				)
				( attribute "PART_NUMBER" "G21796-072"
					( Origin gFrontEnd )
				)
				( attribute "PHYS_PAGE" "247"
					( Origin gFrontEnd )
				)
				( attribute "ROT" "1"
					( Origin gFrontEnd )
				)
				( attribute "TOLERANCE" "1%"
					( Origin gFrontEnd )
				)
				( attribute "VALUE" "4.75K"
					( Origin gFrontEnd )
				)
				( attribute "VER" "1"
					( Origin gFrontEnd )
				)
				( attribute "WATTAGE" "1/16W"
					( Origin gFrontEnd )
				)
				( attribute "XY" "(-7350,3350)"
					( Origin gFrontEnd )
				)
				( attribute "CHIPS_PART_NAME" "RES"
					( Origin gPackager )
				)
				( attribute "CDS_PART_NAME" "RES_0402-4.75K,1%,1/16W,CHIP,GA"
					( Origin gPackager )
				)
				( attribute "LOCATION" "R6W11"
					( Origin gFrontEnd )
				)
				( attribute "CDS_LOCATION" "R6W11"
					( Origin gPackager )
				)
				( attribute "SEC" "1"
					( Origin gFrontEnd )
				)
				( attribute "SEC_TYPE" "0402"
					( Origin gFrontEnd )
				)
				( attribute "CDS_SEC" "1"
					( Origin gPackager )
				)
				( objectStatus "R6W11" )
			)
			( gate "@baseboard_fab2_lib.baseboard_fab2(sch_1):page247_i110"
				( attribute "CHIPS_PART_NAME" "PCA9517"
					( Origin gPackager )
				)
			)
			( gate "@baseboard_fab2_lib.baseboard_fab2(sch_1):page247_i107"
				( attribute "CDS_LIB" "dev_discrete"
					( Origin gPackager )
				)
				( attribute "CDS_LOCATION" "C6W2"
					( Origin gPackager )
				)
				( attribute "CDS_SEC" "1"
					( Origin gPackager )
				)
				( attribute "LOCATION" "C6W2"
					( Origin gFrontEnd )
				)
				( attribute "MATERIAL" "X7R"
					( Origin gFrontEnd )
				)
				( attribute "PACK_TYPE" "0402V"
					( Origin gFrontEnd )
				)
				( attribute "PART_NUMBER" "A36096-030"
					( Origin gFrontEnd )
				)
				( attribute "PHYS_PAGE" "247"
					( Origin gFrontEnd )
				)
				( attribute "ROOM" "SMB_PE_HP_CPU1"
					( Origin gFrontEnd )
				)
				( attribute "ROT" "2"
					( Origin gFrontEnd )
				)
				( attribute "SEC" "1"
					( Origin gFrontEnd )
				)
				( attribute "SEC_TYPE" "0402V"
					( Origin gFrontEnd )
				)
				( attribute "TOLERANCE" "10%"
					( Origin gFrontEnd )
				)
				( attribute "VALUE" "0.1UF"
					( Origin gFrontEnd )
				)
				( attribute "VER" "1"
					( Origin gFrontEnd )
				)
				( attribute "VOLTAGE" "16V"
					( Units "uVoltage" "V" 1.000000)
					( Origin gFrontEnd )
				)
				( attribute "XY" "(-5500,1250)"
					( Origin gFrontEnd )
				)
				( attribute "CHIPS_PART_NAME" "CAP_A"
					( Origin gPackager )
				)
				( attribute "CDS_PART_NAME" "CAP_A_0402V-0.1UF,16V,10%,X7R,A"
					( Origin gPackager )
				)
				( objectStatus "C6W2" )
			)
			( gate "@baseboard_fab2_lib.baseboard_fab2(sch_1):page105_i257"
				( attribute "CDS_LIB" "mstr_discrete"
					( Origin gPackager )
				)
				( attribute "CDS_LOCATION" "C7G19"
					( Origin gPackager )
				)
				( attribute "CDS_SEC" "1"
					( Origin gPackager )
				)
				( attribute "LOCATION" "C7G19"
					( Origin gFrontEnd )
				)
				( attribute "MATERIAL" "X7R"
					( Origin gFrontEnd )
				)
				( attribute "PACK_TYPE" "0402"
					( Origin gFrontEnd )
				)
				( attribute "PART_NUMBER" "A36096-155"
					( Origin gFrontEnd )
				)
				( attribute "PHYS_PAGE" "105"
					( Origin gFrontEnd )
				)
				( attribute "ROOM" "OCP_STEERING"
					( Origin gFrontEnd )
				)
				( attribute "ROT" "2"
					( Origin gFrontEnd )
				)
				( attribute "SEC" "1"
					( Origin gFrontEnd )
				)
				( attribute "SEC_TYPE" "0402"
					( Origin gFrontEnd )
				)
				( attribute "TOLERANCE" "10%"
					( Origin gFrontEnd )
				)
				( attribute "VALUE" "0.22UF"
					( Origin gFrontEnd )
				)
				( attribute "VER" "1"
					( Origin gFrontEnd )
				)
				( attribute "VOLTAGE" "16V"
					( Units "uVoltage" "V" 1.000000)
					( Origin gFrontEnd )
				)
				( attribute "XY" "(700,3650)"
					( Origin gFrontEnd )
				)
				( attribute "CHIPS_PART_NAME" "CAP"
					( Origin gPackager )
				)
				( attribute "CDS_PART_NAME" "CAP_0402-0.22UF,16V,10%,X7R,A3A"
					( Origin gPackager )
				)
				( objectStatus "C7G19" )
			)
			( gate "@baseboard_fab2_lib.baseboard_fab2(sch_1):page105_i258"
				( attribute "CDS_LIB" "mstr_discrete"
					( Origin gPackager )
				)
				( attribute "CDS_LOCATION" "C7G20"
					( Origin gPackager )
				)
				( attribute "CDS_SEC" "1"
					( Origin gPackager )
				)
				( attribute "LOCATION" "C7G20"
					( Origin gFrontEnd )
				)
				( attribute "MATERIAL" "X7R"
					( Origin gFrontEnd )
				)
				( attribute "PACK_TYPE" "0402"
					( Origin gFrontEnd )
				)
				( attribute "PART_NUMBER" "A36096-155"
					( Origin gFrontEnd )
				)
				( attribute "PHYS_PAGE" "105"
					( Origin gFrontEnd )
				)
				( attribute "ROOM" "OCP_STEERING"
					( Origin gFrontEnd )
				)
				( attribute "ROT" "2"
					( Origin gFrontEnd )
				)
				( attribute "SEC" "1"
					( Origin gFrontEnd )
				)
				( attribute "SEC_TYPE" "0402"
					( Origin gFrontEnd )
				)
				( attribute "TOLERANCE" "10%"
					( Origin gFrontEnd )
				)
				( attribute "VALUE" "0.22UF"
					( Origin gFrontEnd )
				)
				( attribute "VER" "1"
					( Origin gFrontEnd )
				)
				( attribute "VOLTAGE" "16V"
					( Units "uVoltage" "V" 1.000000)
					( Origin gFrontEnd )
				)
				( attribute "XY" "(650,4650)"
					( Origin gFrontEnd )
				)
				( attribute "CHIPS_PART_NAME" "CAP"
					( Origin gPackager )
				)
				( attribute "CDS_PART_NAME" "CAP_0402-0.22UF,16V,10%,X7R,A3A"
					( Origin gPackager )
				)
				( objectStatus "C7G20" )
			)
			( gate "@baseboard_fab2_lib.baseboard_fab2(sch_1):page145_i118"
				( attribute "CDS_LIB" "w_hdl"
					( Origin gPackager )
				)
				( attribute "CDS_LMAN_SYM_OUTLINE" "-50,75,50,-75"
					( Origin gPackager )
				)
				( attribute "LOCATION" "R25W67"
					( Origin gFrontEnd )
				)
				( attribute "PACK_TYPE" "SMD-RG4"
					( Origin gFrontEnd )
				)
				( attribute "PART_NUMBER" "64.20005.L0L"
					( Origin gFrontEnd )
				)
				( attribute "PHYS_PAGE" "145"
					( Origin gFrontEnd )
				)
				( attribute "ROT" "1"
					( Origin gFrontEnd )
				)
				( attribute "VALUE" "200R2F-L1-GP"
					( Origin gFrontEnd )
				)
				( attribute "VER" "1"
					( Origin gFrontEnd )
				)
				( attribute "XY" "(-1625,-3200)"
					( Origin gFrontEnd )
				)
				( attribute "CHIPS_PART_NAME" "200R2F-L1-GP"
					( Origin gPackager )
				)
				( attribute "CDS_PART_NAME" "200R2F-L1-GP_SMD-RG4-200R2F-L1A"
					( Origin gPackager )
				)
				( attribute "CDS_LOCATION" "R25W67"
					( Origin gPackager )
				)
				( attribute "CDS_SEC" "1"
					( Origin gPackager )
				)
				( attribute "SEC" "1"
					( Origin gPackager )
				)
				( attribute "ATTRIBUTE" "200 OHM"
					( Origin gFrontEnd )
				)
				( attribute "PACK_SIZE" "0402"
					( Origin gFrontEnd )
				)
				( attribute "RATED" "1/16W"
					( Origin gFrontEnd )
				)
				( attribute "TOLERANCE" "1%"
					( Origin gFrontEnd )
				)
				( attribute "GROUP" "AST2500"
					( Origin gFrontEnd )
				)
				( objectStatus "R25W67" )
			)
			( gate "@baseboard_fab2_lib.baseboard_fab2(sch_1):page145_i119"
				( attribute "BOM_COST" "MIO_USB"
					( Origin gFrontEnd )
				)
				( attribute "CDS_LIB" "mstr_discrete"
					( Origin gPackager )
				)
				( attribute "LOCATION" "R6W18"
					( Origin gFrontEnd )
				)
				( attribute "MATERIAL" "CHIP"
					( Origin gFrontEnd )
				)
				( attribute "PACK_TYPE" "0402"
					( Origin gFrontEnd )
				)
				( attribute "PART_NUMBER" "G21497-005"
					( Origin gFrontEnd )
				)
				( attribute "PHYS_PAGE" "145"
					( Origin gFrontEnd )
				)
				( attribute "ROOM" "USB"
					( Origin gFrontEnd )
				)
				( attribute "ROT" "0"
					( Origin gFrontEnd )
				)
				( attribute "TOLERANCE" "5%"
					( Origin gFrontEnd )
				)
				( attribute "VALUE" "0.0"
					( Origin gFrontEnd )
				)
				( attribute "VER" "1"
					( Origin gFrontEnd )
				)
				( attribute "WATTAGE" "1/16W"
					( Origin gFrontEnd )
				)
				( attribute "XY" "(-6450,-2300)"
					( Origin gFrontEnd )
				)
				( attribute "CHIPS_PART_NAME" "RES"
					( Origin gPackager )
				)
				( attribute "CDS_PART_NAME" "RES_0402-0.0,5%,1/16W,CHIP,G21A"
					( Origin gPackager )
				)
				( attribute "CDS_LOCATION" "R6W18"
					( Origin gPackager )
				)
				( attribute "SEC" "1"
					( Origin gFrontEnd )
				)
				( attribute "SEC_TYPE" "0402"
					( Origin gFrontEnd )
				)
				( attribute "CDS_SEC" "1"
					( Origin gPackager )
				)
				( objectStatus "R6W18" )
			)
			( gate "@baseboard_fab2_lib.baseboard_fab2(sch_1):page201_i172"
				( attribute "CDS_LIB" "w_hdl"
					( Origin gPackager )
				)
				( attribute "CDS_LMAN_SYM_OUTLINE" "-50,25,50,-25"
					( Origin gPackager )
				)
				( attribute "LOCATION" "CF5"
					( Origin gFrontEnd )
				)
				( attribute "PACK_TYPE" "SMD-BCG"
					( Origin gFrontEnd )
				)
				( attribute "PART_NUMBER" "78.22034.1FL"
					( Origin gFrontEnd )
				)
				( attribute "PHYS_PAGE" "201"
					( Origin gFrontEnd )
				)
				( attribute "ROT" "1"
					( Origin gFrontEnd )
				)
				( attribute "VALUE" "SC22P50V2JN-4GP"
					( Origin gFrontEnd )
				)
				( attribute "VER" "1"
					( Origin gFrontEnd )
				)
				( attribute "XY" "(-5025,3350)"
					( Origin gFrontEnd )
				)
				( attribute "CHIPS_PART_NAME" "SC22P50V2JN-4GP"
					( Origin gPackager )
				)
				( attribute "CDS_PART_NAME" "SC22P50V2JN-4GP_SMD-BCG-SC22P5A"
					( Origin gPackager )
				)
				( attribute "CDS_LOCATION" "CF5"
					( Origin gPackager )
				)
				( attribute "CDS_SEC" "1"
					( Origin gPackager )
				)
				( attribute "SEC" "1"
					( Origin gPackager )
				)
				( attribute "ATTRIBUTE" "22PF"
					( Origin gFrontEnd )
				)
				( attribute "PACK_SIZE" "0402"
					( Origin gFrontEnd )
				)
				( attribute "RATED" "50V"
					( Origin gFrontEnd )
				)
				( attribute "TOLERANCE" "5%"
					( Origin gFrontEnd )
				)
				( attribute "TYPE" "NPO"
					( Origin gFrontEnd )
				)
				( attribute "GROUP" "POWER_FAIR"
					( Origin gFrontEnd )
				)
				( objectStatus "CF5" )
			)
			( gate "@baseboard_fab2_lib.baseboard_fab2(sch_1):page201_i171"
				( attribute "CDS_LIB" "w_hdl"
					( Origin gPackager )
				)
				( attribute "CDS_LMAN_SYM_OUTLINE" "-50,25,50,-25"
					( Origin gPackager )
				)
				( attribute "LOCATION" "CF4"
					( Origin gFrontEnd )
				)
				( attribute "PACK_TYPE" "SMD-BCG"
					( Origin gFrontEnd )
				)
				( attribute "PART_NUMBER" "78.22034.1FL"
					( Origin gFrontEnd )
				)
				( attribute "PHYS_PAGE" "201"
					( Origin gFrontEnd )
				)
				( attribute "ROT" "1"
					( Origin gFrontEnd )
				)
				( attribute "VALUE" "SC22P50V2JN-4GP"
					( Origin gFrontEnd )
				)
				( attribute "VER" "1"
					( Origin gFrontEnd )
				)
				( attribute "XY" "(-5425,3350)"
					( Origin gFrontEnd )
				)
				( attribute "CHIPS_PART_NAME" "SC22P50V2JN-4GP"
					( Origin gPackager )
				)
				( attribute "CDS_PART_NAME" "SC22P50V2JN-4GP_SMD-BCG-SC22P5A"
					( Origin gPackager )
				)
				( attribute "CDS_LOCATION" "CF4"
					( Origin gPackager )
				)
				( attribute "CDS_SEC" "1"
					( Origin gPackager )
				)
				( attribute "SEC" "1"
					( Origin gPackager )
				)
				( attribute "ATTRIBUTE" "22PF"
					( Origin gFrontEnd )
				)
				( attribute "PACK_SIZE" "0402"
					( Origin gFrontEnd )
				)
				( attribute "RATED" "50V"
					( Origin gFrontEnd )
				)
				( attribute "TOLERANCE" "5%"
					( Origin gFrontEnd )
				)
				( attribute "TYPE" "NPO"
					( Origin gFrontEnd )
				)
				( attribute "GROUP" "POWER_FAIR"
					( Origin gFrontEnd )
				)
				( objectStatus "CF4" )
			)
			( gate "@baseboard_fab2_lib.baseboard_fab2(sch_1):page201_i170"
				( attribute "CDS_LIB" "w_hdl"
					( Origin gPackager )
				)
				( attribute "CDS_LMAN_SYM_OUTLINE" "-50,25,50,-25"
					( Origin gPackager )
				)
				( attribute "LOCATION" "CF3"
					( Origin gFrontEnd )
				)
				( attribute "PACK_TYPE" "SMD-BCG"
					( Origin gFrontEnd )
				)
				( attribute "PART_NUMBER" "78.22034.1FL"
					( Origin gFrontEnd )
				)
				( attribute "PHYS_PAGE" "201"
					( Origin gFrontEnd )
				)
				( attribute "ROT" "1"
					( Origin gFrontEnd )
				)
				( attribute "VALUE" "SC22P50V2JN-4GP"
					( Origin gFrontEnd )
				)
				( attribute "VER" "1"
					( Origin gFrontEnd )
				)
				( attribute "XY" "(-5825,3350)"
					( Origin gFrontEnd )
				)
				( attribute "CHIPS_PART_NAME" "SC22P50V2JN-4GP"
					( Origin gPackager )
				)
				( attribute "CDS_PART_NAME" "SC22P50V2JN-4GP_SMD-BCG-SC22P5A"
					( Origin gPackager )
				)
				( attribute "CDS_LOCATION" "CF3"
					( Origin gPackager )
				)
				( attribute "CDS_SEC" "1"
					( Origin gPackager )
				)
				( attribute "SEC" "1"
					( Origin gPackager )
				)
				( attribute "ATTRIBUTE" "22PF"
					( Origin gFrontEnd )
				)
				( attribute "PACK_SIZE" "0402"
					( Origin gFrontEnd )
				)
				( attribute "RATED" "50V"
					( Origin gFrontEnd )
				)
				( attribute "TOLERANCE" "5%"
					( Origin gFrontEnd )
				)
				( attribute "TYPE" "NPO"
					( Origin gFrontEnd )
				)
				( attribute "GROUP" "POWER_FAIR"
					( Origin gFrontEnd )
				)
				( objectStatus "CF3" )
			)
			( gate "@baseboard_fab2_lib.baseboard_fab2(sch_1):page201_i169"
				( attribute "CDS_LIB" "w_hdl"
					( Origin gPackager )
				)
				( attribute "CDS_LMAN_SYM_OUTLINE" "-50,25,50,-25"
					( Origin gPackager )
				)
				( attribute "LOCATION" "CF2"
					( Origin gFrontEnd )
				)
				( attribute "PACK_TYPE" "SMD-BCG"
					( Origin gFrontEnd )
				)
				( attribute "PART_NUMBER" "78.22034.1FL"
					( Origin gFrontEnd )
				)
				( attribute "PHYS_PAGE" "201"
					( Origin gFrontEnd )
				)
				( attribute "ROT" "1"
					( Origin gFrontEnd )
				)
				( attribute "VALUE" "SC22P50V2JN-4GP"
					( Origin gFrontEnd )
				)
				( attribute "VER" "1"
					( Origin gFrontEnd )
				)
				( attribute "XY" "(-6300,3350)"
					( Origin gFrontEnd )
				)
				( attribute "CHIPS_PART_NAME" "SC22P50V2JN-4GP"
					( Origin gPackager )
				)
				( attribute "CDS_PART_NAME" "SC22P50V2JN-4GP_SMD-BCG-SC22P5A"
					( Origin gPackager )
				)
				( attribute "CDS_LOCATION" "CF2"
					( Origin gPackager )
				)
				( attribute "CDS_SEC" "1"
					( Origin gPackager )
				)
				( attribute "SEC" "1"
					( Origin gPackager )
				)
				( attribute "ATTRIBUTE" "22PF"
					( Origin gFrontEnd )
				)
				( attribute "PACK_SIZE" "0402"
					( Origin gFrontEnd )
				)
				( attribute "RATED" "50V"
					( Origin gFrontEnd )
				)
				( attribute "TOLERANCE" "5%"
					( Origin gFrontEnd )
				)
				( attribute "TYPE" "NPO"
					( Origin gFrontEnd )
				)
				( attribute "GROUP" "POWER_FAIR"
					( Origin gFrontEnd )
				)
				( objectStatus "CF2" )
			)
			( gate "@baseboard_fab2_lib.baseboard_fab2(sch_1):page201_i168"
				( attribute "CDS_LIB" "w_hdl"
					( Origin gPackager )
				)
				( attribute "CDS_LMAN_SYM_OUTLINE" "-50,25,50,-25"
					( Origin gPackager )
				)
				( attribute "LOCATION" "CF1"
					( Origin gFrontEnd )
				)
				( attribute "PACK_TYPE" "SMD-BCG"
					( Origin gFrontEnd )
				)
				( attribute "PART_NUMBER" "78.22034.1FL"
					( Origin gFrontEnd )
				)
				( attribute "PHYS_PAGE" "201"
					( Origin gFrontEnd )
				)
				( attribute "ROT" "1"
					( Origin gFrontEnd )
				)
				( attribute "VALUE" "SC22P50V2JN-4GP"
					( Origin gFrontEnd )
				)
				( attribute "VER" "1"
					( Origin gFrontEnd )
				)
				( attribute "XY" "(-6750,3350)"
					( Origin gFrontEnd )
				)
				( attribute "CHIPS_PART_NAME" "SC22P50V2JN-4GP"
					( Origin gPackager )
				)
				( attribute "CDS_PART_NAME" "SC22P50V2JN-4GP_SMD-BCG-SC22P5A"
					( Origin gPackager )
				)
				( attribute "CDS_LOCATION" "CF1"
					( Origin gPackager )
				)
				( attribute "CDS_SEC" "1"
					( Origin gPackager )
				)
				( attribute "SEC" "1"
					( Origin gPackager )
				)
				( attribute "ATTRIBUTE" "22PF"
					( Origin gFrontEnd )
				)
				( attribute "PACK_SIZE" "0402"
					( Origin gFrontEnd )
				)
				( attribute "RATED" "50V"
					( Origin gFrontEnd )
				)
				( attribute "TOLERANCE" "5%"
					( Origin gFrontEnd )
				)
				( attribute "TYPE" "NPO"
					( Origin gFrontEnd )
				)
				( attribute "GROUP" "POWER_FAIR"
					( Origin gFrontEnd )
				)
				( objectStatus "CF1" )
			)
			( gate "@baseboard_fab2_lib.baseboard_fab2(sch_1):page206_i149"
				( attribute "CDS_LIB" "mstr_discrete"
					( Origin gPackager )
				)
				( attribute "LOCATION" "RF12"
					( Origin gFrontEnd )
				)
				( attribute "MATERIAL" "CHIP"
					( Origin gFrontEnd )
				)
				( attribute "PACK_TYPE" "0402"
					( Origin gFrontEnd )
				)
				( attribute "PART_NUMBER" "G85996-004"
					( Origin gFrontEnd )
				)
				( attribute "PHYS_PAGE" "206"
					( Origin gFrontEnd )
				)
				( attribute "ROOM" "SB"
					( Origin gFrontEnd )
				)
				( attribute "ROT" "0"
					( Origin gFrontEnd )
				)
				( attribute "TOLERANCE" "0.1%"
					( Origin gFrontEnd )
				)
				( attribute "VALUE" "1.0K"
					( Origin gFrontEnd )
				)
				( attribute "VER" "1"
					( Origin gFrontEnd )
				)
				( attribute "WATTAGE" "1/16W"
					( Origin gFrontEnd )
				)
				( attribute "XY" "(-6500,1425)"
					( Origin gFrontEnd )
				)
				( attribute "CHIPS_PART_NAME" "RES"
					( Origin gPackager )
				)
				( attribute "CDS_PART_NAME" "RES_0402-1.0K,0.1%,1/16W,CHIP,A"
					( Origin gPackager )
				)
				( attribute "CDS_LOCATION" "RF12"
					( Origin gPackager )
				)
				( attribute "SEC" "1"
					( Origin gFrontEnd )
				)
				( attribute "SEC_TYPE" "0402"
					( Origin gFrontEnd )
				)
				( attribute "CDS_SEC" "1"
					( Origin gPackager )
				)
				( attribute "GROUP" "POWER_FAIR"
					( Origin gFrontEnd )
				)
				( attribute "FAIR_SS" "064.1101D.M001"
					( Origin gFrontEnd )
				)
				( objectStatus "RF12" )
			)
			( gate "@baseboard_fab2_lib.baseboard_fab2(sch_1):page206_i150"
				( attribute "CDS_LIB" "mstr_discrete"
					( Origin gPackager )
				)
				( attribute "LOCATION" "RF7"
					( Origin gFrontEnd )
				)
				( attribute "MATERIAL" "CHIP"
					( Origin gFrontEnd )
				)
				( attribute "PACK_TYPE" "0402"
					( Origin gFrontEnd )
				)
				( attribute "PART_NUMBER" "G85996-004"
					( Origin gFrontEnd )
				)
				( attribute "PHYS_PAGE" "206"
					( Origin gFrontEnd )
				)
				( attribute "ROOM" "SB"
					( Origin gFrontEnd )
				)
				( attribute "ROT" "0"
					( Origin gFrontEnd )
				)
				( attribute "TOLERANCE" "0.1%"
					( Origin gFrontEnd )
				)
				( attribute "VALUE" "1.0K"
					( Origin gFrontEnd )
				)
				( attribute "VER" "1"
					( Origin gFrontEnd )
				)
				( attribute "WATTAGE" "1/16W"
					( Origin gFrontEnd )
				)
				( attribute "XY" "(-6775,3500)"
					( Origin gFrontEnd )
				)
				( attribute "CHIPS_PART_NAME" "RES"
					( Origin gPackager )
				)
				( attribute "CDS_PART_NAME" "RES_0402-1.0K,0.1%,1/16W,CHIP,A"
					( Origin gPackager )
				)
				( attribute "CDS_LOCATION" "RF7"
					( Origin gPackager )
				)
				( attribute "SEC" "1"
					( Origin gFrontEnd )
				)
				( attribute "SEC_TYPE" "0402"
					( Origin gFrontEnd )
				)
				( attribute "CDS_SEC" "1"
					( Origin gPackager )
				)
				( attribute "GROUP" "POWER_FAIR"
					( Origin gFrontEnd )
				)
				( attribute "FAIR_SS" "064.9530D.M001"
					( Origin gFrontEnd )
				)
				( objectStatus "RF7" )
			)
			( gate "@baseboard_fab2_lib.baseboard_fab2(sch_1):page206_i151"
				( attribute "CDS_LIB" "mstr_discrete"
					( Origin gPackager )
				)
				( attribute "LOCATION" "RF8"
					( Origin gFrontEnd )
				)
				( attribute "MATERIAL" "CHIP"
					( Origin gFrontEnd )
				)
				( attribute "PACK_TYPE" "0402"
					( Origin gFrontEnd )
				)
				( attribute "PART_NUMBER" "G85996-004"
					( Origin gFrontEnd )
				)
				( attribute "PHYS_PAGE" "206"
					( Origin gFrontEnd )
				)
				( attribute "ROOM" "SB"
					( Origin gFrontEnd )
				)
				( attribute "ROT" "0"
					( Origin gFrontEnd )
				)
				( attribute "TOLERANCE" "0.1%"
					( Origin gFrontEnd )
				)
				( attribute "VALUE" "1.0K"
					( Origin gFrontEnd )
				)
				( attribute "VER" "1"
					( Origin gFrontEnd )
				)
				( attribute "WATTAGE" "1/16W"
					( Origin gFrontEnd )
				)
				( attribute "XY" "(-6375,3500)"
					( Origin gFrontEnd )
				)
				( attribute "CHIPS_PART_NAME" "RES"
					( Origin gPackager )
				)
				( attribute "CDS_PART_NAME" "RES_0402-1.0K,0.1%,1/16W,CHIP,A"
					( Origin gPackager )
				)
				( attribute "CDS_LOCATION" "RF8"
					( Origin gPackager )
				)
				( attribute "SEC" "1"
					( Origin gFrontEnd )
				)
				( attribute "SEC_TYPE" "0402"
					( Origin gFrontEnd )
				)
				( attribute "CDS_SEC" "1"
					( Origin gPackager )
				)
				( attribute "GROUP" "POWER_FAIR"
					( Origin gFrontEnd )
				)
				( attribute "FAIR_SS" "064.9530D.M001"
					( Origin gFrontEnd )
				)
				( objectStatus "RF8" )
			)
			( gate "@baseboard_fab2_lib.baseboard_fab2(sch_1):page206_i152"
				( attribute "CDS_LIB" "mstr_discrete"
					( Origin gPackager )
				)
				( attribute "LOCATION" "RF9"
					( Origin gFrontEnd )
				)
				( attribute "MATERIAL" "CHIP"
					( Origin gFrontEnd )
				)
				( attribute "PACK_TYPE" "0402"
					( Origin gFrontEnd )
				)
				( attribute "PART_NUMBER" "G85996-004"
					( Origin gFrontEnd )
				)
				( attribute "PHYS_PAGE" "206"
					( Origin gFrontEnd )
				)
				( attribute "ROOM" "SB"
					( Origin gFrontEnd )
				)
				( attribute "ROT" "0"
					( Origin gFrontEnd )
				)
				( attribute "TOLERANCE" "0.1%"
					( Origin gFrontEnd )
				)
				( attribute "VALUE" "1.0K"
					( Origin gFrontEnd )
				)
				( attribute "VER" "1"
					( Origin gFrontEnd )
				)
				( attribute "WATTAGE" "1/16W"
					( Origin gFrontEnd )
				)
				( attribute "XY" "(-6000,3500)"
					( Origin gFrontEnd )
				)
				( attribute "CHIPS_PART_NAME" "RES"
					( Origin gPackager )
				)
				( attribute "CDS_PART_NAME" "RES_0402-1.0K,0.1%,1/16W,CHIP,A"
					( Origin gPackager )
				)
				( attribute "CDS_LOCATION" "RF9"
					( Origin gPackager )
				)
				( attribute "SEC" "1"
					( Origin gFrontEnd )
				)
				( attribute "SEC_TYPE" "0402"
					( Origin gFrontEnd )
				)
				( attribute "CDS_SEC" "1"
					( Origin gPackager )
				)
				( attribute "GROUP" "POWER_FAIR"
					( Origin gFrontEnd )
				)
				( attribute "FAIR_SS" "064.9530D.M001"
					( Origin gFrontEnd )
				)
				( objectStatus "RF9" )
			)
			( gate "@baseboard_fab2_lib.baseboard_fab2(sch_1):page206_i153"
				( attribute "CDS_LIB" "mstr_discrete"
					( Origin gPackager )
				)
				( attribute "LOCATION" "RF10"
					( Origin gFrontEnd )
				)
				( attribute "MATERIAL" "CHIP"
					( Origin gFrontEnd )
				)
				( attribute "PACK_TYPE" "0402"
					( Origin gFrontEnd )
				)
				( attribute "PART_NUMBER" "G85996-004"
					( Origin gFrontEnd )
				)
				( attribute "PHYS_PAGE" "206"
					( Origin gFrontEnd )
				)
				( attribute "ROOM" "SB"
					( Origin gFrontEnd )
				)
				( attribute "ROT" "0"
					( Origin gFrontEnd )
				)
				( attribute "TOLERANCE" "0.1%"
					( Origin gFrontEnd )
				)
				( attribute "VALUE" "1.0K"
					( Origin gFrontEnd )
				)
				( attribute "VER" "1"
					( Origin gFrontEnd )
				)
				( attribute "WATTAGE" "1/16W"
					( Origin gFrontEnd )
				)
				( attribute "XY" "(-5550,3500)"
					( Origin gFrontEnd )
				)
				( attribute "CHIPS_PART_NAME" "RES"
					( Origin gPackager )
				)
				( attribute "CDS_PART_NAME" "RES_0402-1.0K,0.1%,1/16W,CHIP,A"
					( Origin gPackager )
				)
				( attribute "CDS_LOCATION" "RF10"
					( Origin gPackager )
				)
				( attribute "SEC" "1"
					( Origin gFrontEnd )
				)
				( attribute "SEC_TYPE" "0402"
					( Origin gFrontEnd )
				)
				( attribute "CDS_SEC" "1"
					( Origin gPackager )
				)
				( attribute "GROUP" "POWER_FAIR"
					( Origin gFrontEnd )
				)
				( attribute "FAIR_SS" "064.9530D.M001"
					( Origin gFrontEnd )
				)
				( objectStatus "RF10" )
			)
			( gate "@baseboard_fab2_lib.baseboard_fab2(sch_1):page206_i154"
				( attribute "CDS_LIB" "mstr_discrete"
					( Origin gPackager )
				)
				( attribute "LOCATION" "RF11"
					( Origin gFrontEnd )
				)
				( attribute "MATERIAL" "CHIP"
					( Origin gFrontEnd )
				)
				( attribute "PACK_TYPE" "0402"
					( Origin gFrontEnd )
				)
				( attribute "PART_NUMBER" "G85996-004"
					( Origin gFrontEnd )
				)
				( attribute "PHYS_PAGE" "206"
					( Origin gFrontEnd )
				)
				( attribute "ROOM" "SB"
					( Origin gFrontEnd )
				)
				( attribute "ROT" "0"
					( Origin gFrontEnd )
				)
				( attribute "TOLERANCE" "0.1%"
					( Origin gFrontEnd )
				)
				( attribute "VALUE" "1.0K"
					( Origin gFrontEnd )
				)
				( attribute "VER" "1"
					( Origin gFrontEnd )
				)
				( attribute "WATTAGE" "1/16W"
					( Origin gFrontEnd )
				)
				( attribute "XY" "(-5100,3500)"
					( Origin gFrontEnd )
				)
				( attribute "CHIPS_PART_NAME" "RES"
					( Origin gPackager )
				)
				( attribute "CDS_PART_NAME" "RES_0402-1.0K,0.1%,1/16W,CHIP,A"
					( Origin gPackager )
				)
				( attribute "CDS_LOCATION" "RF11"
					( Origin gPackager )
				)
				( attribute "SEC" "1"
					( Origin gFrontEnd )
				)
				( attribute "SEC_TYPE" "0402"
					( Origin gFrontEnd )
				)
				( attribute "CDS_SEC" "1"
					( Origin gPackager )
				)
				( attribute "GROUP" "POWER_FAIR"
					( Origin gFrontEnd )
				)
				( attribute "FAIR_SS" "064.9530D.M001"
					( Origin gFrontEnd )
				)
				( objectStatus "RF11" )
			)
			( gate "@baseboard_fab2_lib.baseboard_fab2(sch_1):page213_i99"
				( attribute "CDS_LIB" "mstr_discrete"
					( Origin gPackager )
				)
				( attribute "LOCATION" "RF14"
					( Origin gFrontEnd )
				)
				( attribute "MATERIAL" "CHIP"
					( Origin gFrontEnd )
				)
				( attribute "PACK_TYPE" "0402"
					( Origin gFrontEnd )
				)
				( attribute "PART_NUMBER" "G85996-004"
					( Origin gFrontEnd )
				)
				( attribute "PHYS_PAGE" "213"
					( Origin gFrontEnd )
				)
				( attribute "ROOM" "SB"
					( Origin gFrontEnd )
				)
				( attribute "ROT" "0"
					( Origin gFrontEnd )
				)
				( attribute "TOLERANCE" "0.1%"
					( Origin gFrontEnd )
				)
				( attribute "VALUE" "1.0K"
					( Origin gFrontEnd )
				)
				( attribute "VER" "1"
					( Origin gFrontEnd )
				)
				( attribute "WATTAGE" "1/16W"
					( Origin gFrontEnd )
				)
				( attribute "XY" "(-1900,3725)"
					( Origin gFrontEnd )
				)
				( attribute "CHIPS_PART_NAME" "RES"
					( Origin gPackager )
				)
				( attribute "CDS_PART_NAME" "RES_0402-1.0K,0.1%,1/16W,CHIP,A"
					( Origin gPackager )
				)
				( attribute "CDS_LOCATION" "RF14"
					( Origin gPackager )
				)
				( attribute "SEC" "1"
					( Origin gFrontEnd )
				)
				( attribute "SEC_TYPE" "0402"
					( Origin gFrontEnd )
				)
				( attribute "CDS_SEC" "1"
					( Origin gPackager )
				)
				( attribute "GROUP" "POWER_FAIR"
					( Origin gFrontEnd )
				)
				( attribute "FAIR_SS" "064.9090D.M001"
					( Origin gFrontEnd )
				)
				( objectStatus "RF14" )
			)
			( gate "@baseboard_fab2_lib.baseboard_fab2(sch_1):page221_i4"
				( attribute "BOM_COST" "MEM_VRD_VTT_ABC"
					( Origin gFrontEnd )
				)
				( attribute "CDS_LIB" "mstr_discrete"
					( Origin gPackager )
				)
				( attribute "CDS_LOCATION" "R4G23"
					( Origin gPackager )
				)
				( attribute "CDS_SEC" "1"
					( Origin gPackager )
				)
				( attribute "LOCATION" "R4G23"
					( Origin gFrontEnd )
				)
				( attribute "MATERIAL" "CHIP"
					( Origin gFrontEnd )
				)
				( attribute "PACK_TYPE" "0402"
					( Origin gFrontEnd )
				)
				( attribute "PART_NUMBER" "G21497-005"
					( Origin gFrontEnd )
				)
				( attribute "PHYS_PAGE" "221"
					( Origin gFrontEnd )
				)
				( attribute "ROOM" "VTT_ABC_PWR_VR"
					( Origin gFrontEnd )
				)
				( attribute "ROT" "0"
					( Origin gFrontEnd )
				)
				( attribute "SEC" "1"
					( Origin gFrontEnd )
				)
				( attribute "SEC_TYPE" "0402"
					( Origin gFrontEnd )
				)
				( attribute "TOLERANCE" "5%"
					( Origin gFrontEnd )
				)
				( attribute "VALUE" "0.0"
					( Origin gFrontEnd )
				)
				( attribute "VER" "1"
					( Origin gFrontEnd )
				)
				( attribute "WATTAGE" "1/16W"
					( Origin gFrontEnd )
				)
				( attribute "XY" "(-800,50)"
					( Origin gFrontEnd )
				)
				( attribute "CHIPS_PART_NAME" "RES"
					( Origin gPackager )
				)
				( attribute "CDS_PART_NAME" "RES_0402-0.0,5%,1/16W,CHIP,G21A"
					( Origin gPackager )
				)
				( objectStatus "R4G23" )
			)
			( gate "@baseboard_fab2_lib.baseboard_fab2(sch_1):page222_i2"
				( attribute "BOM_COST" "MEM_VRD_VTT_DEF"
					( Origin gFrontEnd )
				)
				( attribute "CDS_LIB" "mstr_discrete"
					( Origin gPackager )
				)
				( attribute "CDS_LOCATION" "C4A2"
					( Origin gPackager )
				)
				( attribute "CDS_SEC" "1"
					( Origin gPackager )
				)
				( attribute "LOCATION" "C4A2"
					( Origin gFrontEnd )
				)
				( attribute "MATERIAL" "EMPTY"
					( Origin gFrontEnd )
				)
				( attribute "PACK_TYPE" "0402LF"
					( Origin gFrontEnd )
				)
				( attribute "PART_NUMBER" "A36096-046"
					( Origin gFrontEnd )
				)
				( attribute "PHYS_PAGE" "222"
					( Origin gFrontEnd )
				)
				( attribute "ROOM" "VTT_DEF_PWR_VR"
					( Origin gFrontEnd )
				)
				( attribute "ROT" "2"
					( Origin gFrontEnd )
				)
				( attribute "SEC" "1"
					( Origin gFrontEnd )
				)
				( attribute "SEC_TYPE" "0402LF"
					( Origin gFrontEnd )
				)
				( attribute "TOLERANCE" "10%"
					( Origin gFrontEnd )
				)
				( attribute "VALUE" "1000PF"
					( Origin gFrontEnd )
				)
				( attribute "VER" "1"
					( Origin gFrontEnd )
				)
				( attribute "VOLTAGE" "50V"
					( Units "uVoltage" "V" 1.000000)
					( Origin gFrontEnd )
				)
				( attribute "XY" "(-1150,-850)"
					( Origin gFrontEnd )
				)
				( attribute "CHIPS_PART_NAME" "CAP"
					( Origin gPackager )
				)
				( attribute "CDS_PART_NAME" "CAP_0402LF-1000PF,50V,10%,EMPTA"
					( Origin gPackager )
				)
				( objectStatus "C4A2" )
			)
			( gate "@baseboard_fab2_lib.baseboard_fab2(sch_1):page222_i4"
				( attribute "BOM_COST" "MEM_VRD_VTT_DEF"
					( Origin gFrontEnd )
				)
				( attribute "CDS_LIB" "mstr_discrete"
					( Origin gPackager )
				)
				( attribute "CDS_LOCATION" "R4A2"
					( Origin gPackager )
				)
				( attribute "CDS_SEC" "1"
					( Origin gPackager )
				)
				( attribute "LOCATION" "R4A2"
					( Origin gFrontEnd )
				)
				( attribute "MATERIAL" "CHIP"
					( Origin gFrontEnd )
				)
				( attribute "PACK_TYPE" "0402"
					( Origin gFrontEnd )
				)
				( attribute "PART_NUMBER" "G21497-005"
					( Origin gFrontEnd )
				)
				( attribute "PHYS_PAGE" "222"
					( Origin gFrontEnd )
				)
				( attribute "ROOM" "VTT_DEF_PWR_VR"
					( Origin gFrontEnd )
				)
				( attribute "ROT" "0"
					( Origin gFrontEnd )
				)
				( attribute "SEC" "1"
					( Origin gFrontEnd )
				)
				( attribute "SEC_TYPE" "0402"
					( Origin gFrontEnd )
				)
				( attribute "TOLERANCE" "5%"
					( Origin gFrontEnd )
				)
				( attribute "VALUE" "0.0"
					( Origin gFrontEnd )
				)
				( attribute "VER" "1"
					( Origin gFrontEnd )
				)
				( attribute "WATTAGE" "1/16W"
					( Origin gFrontEnd )
				)
				( attribute "XY" "(-1300,-325)"
					( Origin gFrontEnd )
				)
				( attribute "CHIPS_PART_NAME" "RES"
					( Origin gPackager )
				)
				( attribute "CDS_PART_NAME" "RES_0402-0.0,5%,1/16W,CHIP,G21A"
					( Origin gPackager )
				)
				( objectStatus "R4A2" )
			)
			( gate "@baseboard_fab2_lib.baseboard_fab2(sch_1):page229_i2"
				( attribute "BOM_COST" "MEM_VRD_VTT_GHJ"
					( Origin gFrontEnd )
				)
				( attribute "CDS_LIB" "mstr_discrete"
					( Origin gPackager )
				)
				( attribute "CDS_LOCATION" "C4G12"
					( Origin gPackager )
				)
				( attribute "CDS_SEC" "1"
					( Origin gPackager )
				)
				( attribute "LOCATION" "C4G12"
					( Origin gFrontEnd )
				)
				( attribute "MATERIAL" "EMPTY"
					( Origin gFrontEnd )
				)
				( attribute "PACK_TYPE" "0402LF"
					( Origin gFrontEnd )
				)
				( attribute "PART_NUMBER" "A36096-046"
					( Origin gFrontEnd )
				)
				( attribute "PHYS_PAGE" "229"
					( Origin gFrontEnd )
				)
				( attribute "ROOM" "VTT_GHJ_PWR_VR"
					( Origin gFrontEnd )
				)
				( attribute "ROT" "2"
					( Origin gFrontEnd )
				)
				( attribute "SEC" "1"
					( Origin gFrontEnd )
				)
				( attribute "SEC_TYPE" "0402LF"
					( Origin gFrontEnd )
				)
				( attribute "TOLERANCE" "10%"
					( Origin gFrontEnd )
				)
				( attribute "VALUE" "1000PF"
					( Origin gFrontEnd )
				)
				( attribute "VER" "1"
					( Origin gFrontEnd )
				)
				( attribute "VOLTAGE" "50V"
					( Units "uVoltage" "V" 1.000000)
					( Origin gFrontEnd )
				)
				( attribute "XY" "(-475,-550)"
					( Origin gFrontEnd )
				)
				( attribute "CHIPS_PART_NAME" "CAP"
					( Origin gPackager )
				)
				( attribute "CDS_PART_NAME" "CAP_0402LF-1000PF,50V,10%,EMPTA"
					( Origin gPackager )
				)
				( objectStatus "C4G12" )
			)
			( gate "@baseboard_fab2_lib.baseboard_fab2(sch_1):page229_i4"
				( attribute "BOM_COST" "MEM_VRD_VTT_GHJ"
					( Origin gFrontEnd )
				)
				( attribute "CDS_LIB" "mstr_discrete"
					( Origin gPackager )
				)
				( attribute "CDS_LOCATION" "R4G16"
					( Origin gPackager )
				)
				( attribute "CDS_SEC" "1"
					( Origin gPackager )
				)
				( attribute "LOCATION" "R4G16"
					( Origin gFrontEnd )
				)
				( attribute "MATERIAL" "CHIP"
					( Origin gFrontEnd )
				)
				( attribute "PACK_TYPE" "0402"
					( Origin gFrontEnd )
				)
				( attribute "PART_NUMBER" "G21497-005"
					( Origin gFrontEnd )
				)
				( attribute "PHYS_PAGE" "229"
					( Origin gFrontEnd )
				)
				( attribute "ROOM" "VTT_GHJ_PWR_VR"
					( Origin gFrontEnd )
				)
				( attribute "ROT" "0"
					( Origin gFrontEnd )
				)
				( attribute "SEC" "1"
					( Origin gFrontEnd )
				)
				( attribute "SEC_TYPE" "0402"
					( Origin gFrontEnd )
				)
				( attribute "TOLERANCE" "5%"
					( Origin gFrontEnd )
				)
				( attribute "VALUE" "0.0"
					( Origin gFrontEnd )
				)
				( attribute "VER" "1"
					( Origin gFrontEnd )
				)
				( attribute "WATTAGE" "1/16W"
					( Origin gFrontEnd )
				)
				( attribute "XY" "(-650,-25)"
					( Origin gFrontEnd )
				)
				( attribute "CHIPS_PART_NAME" "RES"
					( Origin gPackager )
				)
				( attribute "CDS_PART_NAME" "RES_0402-0.0,5%,1/16W,CHIP,G21A"
					( Origin gPackager )
				)
				( objectStatus "R4G16" )
			)
			( gate "@baseboard_fab2_lib.baseboard_fab2(sch_1):page197_i1"
				( attribute "BOM_COST" "SM_HM"
					( Origin gFrontEnd )
				)
				( attribute "CDS_LIB" "mstr_discrete"
					( Origin gPackager )
				)
				( attribute "CDS_LOCATION" "C12W2"
					( Origin gPackager )
				)
				( attribute "CDS_SEC" "1"
					( Origin gPackager )
				)
				( attribute "LOCATION" "C12W2"
					( Origin gFrontEnd )
				)
				( attribute "MATERIAL" "COG"
					( Origin gFrontEnd )
				)
				( attribute "PACK_TYPE" "0402LF"
					( Origin gFrontEnd )
				)
				( attribute "PART_NUMBER" "A36095-025"
					( Origin gFrontEnd )
				)
				( attribute "PHYS_PAGE" "197"
					( Origin gFrontEnd )
				)
				( attribute "ROOM" "BMC_VOLT_MONITOR"
					( Origin gFrontEnd )
				)
				( attribute "ROT" "1"
					( Origin gFrontEnd )
				)
				( attribute "SEC" "1"
					( Origin gFrontEnd )
				)
				( attribute "SEC_TYPE" "0402LF"
					( Origin gFrontEnd )
				)
				( attribute "TOLERANCE" "5%"
					( Origin gFrontEnd )
				)
				( attribute "VALUE" "47.0PF"
					( Origin gFrontEnd )
				)
				( attribute "VER" "1"
					( Origin gFrontEnd )
				)
				( attribute "VOLTAGE" "50V"
					( Units "uVoltage" "V" 1.000000)
					( Origin gFrontEnd )
				)
				( attribute "XY" "(-4275,1450)"
					( Origin gFrontEnd )
				)
				( attribute "CHIPS_PART_NAME" "CAP"
					( Origin gPackager )
				)
				( attribute "CDS_PART_NAME" "CAP_0402LF-47.0PF,50V,5%,COG,AA"
					( Origin gPackager )
				)
				( objectStatus "C12W2" )
			)
			( gate "@baseboard_fab2_lib.baseboard_fab2(sch_1):page235_i242"
				( attribute "CDS_LIB" "mstr_discrete"
					( Origin gPackager )
				)
				( attribute "LOCATION" "RF24"
					( Origin gFrontEnd )
				)
				( attribute "MATERIAL" "CHIP"
					( Origin gFrontEnd )
				)
				( attribute "PACK_TYPE" "0402"
					( Origin gFrontEnd )
				)
				( attribute "PART_NUMBER" "G85996-004"
					( Origin gFrontEnd )
				)
				( attribute "PHYS_PAGE" "235"
					( Origin gFrontEnd )
				)
				( attribute "ROOM" "SB"
					( Origin gFrontEnd )
				)
				( attribute "ROT" "0"
					( Origin gFrontEnd )
				)
				( attribute "TOLERANCE" "0.1%"
					( Origin gFrontEnd )
				)
				( attribute "VALUE" "1.0K"
					( Origin gFrontEnd )
				)
				( attribute "VER" "1"
					( Origin gFrontEnd )
				)
				( attribute "WATTAGE" "1/16W"
					( Origin gFrontEnd )
				)
				( attribute "XY" "(-11100,3000)"
					( Origin gFrontEnd )
				)
				( attribute "CHIPS_PART_NAME" "RES"
					( Origin gPackager )
				)
				( attribute "CDS_PART_NAME" "RES_0402-1.0K,0.1%,1/16W,CHIP,A"
					( Origin gPackager )
				)
				( attribute "SEC" "1"
					( Origin gFrontEnd )
				)
				( attribute "SEC_TYPE" "0402"
					( Origin gFrontEnd )
				)
				( attribute "GROUP" "POWER_FAIR"
					( Origin gFrontEnd )
				)
				( attribute "CDS_LOCATION" "RF24"
					( Origin gPackager )
				)
				( attribute "CDS_SEC" "1"
					( Origin gPackager )
				)
				( objectStatus "RF24" )
			)
			( gate "@baseboard_fab2_lib.baseboard_fab2(sch_1):page235_i241"
				( attribute "CDS_LIB" "mstr_discrete"
					( Origin gPackager )
				)
				( attribute "LOCATION" "RF23"
					( Origin gFrontEnd )
				)
				( attribute "MATERIAL" "CHIP"
					( Origin gFrontEnd )
				)
				( attribute "PACK_TYPE" "0402"
					( Origin gFrontEnd )
				)
				( attribute "PART_NUMBER" "G85996-004"
					( Origin gFrontEnd )
				)
				( attribute "PHYS_PAGE" "235"
					( Origin gFrontEnd )
				)
				( attribute "ROOM" "SB"
					( Origin gFrontEnd )
				)
				( attribute "ROT" "0"
					( Origin gFrontEnd )
				)
				( attribute "TOLERANCE" "0.1%"
					( Origin gFrontEnd )
				)
				( attribute "VALUE" "1.0K"
					( Origin gFrontEnd )
				)
				( attribute "VER" "1"
					( Origin gFrontEnd )
				)
				( attribute "WATTAGE" "1/16W"
					( Origin gFrontEnd )
				)
				( attribute "XY" "(-11775,4650)"
					( Origin gFrontEnd )
				)
				( attribute "CHIPS_PART_NAME" "RES"
					( Origin gPackager )
				)
				( attribute "CDS_PART_NAME" "RES_0402-1.0K,0.1%,1/16W,CHIP,A"
					( Origin gPackager )
				)
				( attribute "CDS_LOCATION" "RF23"
					( Origin gPackager )
				)
				( attribute "SEC" "1"
					( Origin gFrontEnd )
				)
				( attribute "SEC_TYPE" "0402"
					( Origin gFrontEnd )
				)
				( attribute "CDS_SEC" "1"
					( Origin gPackager )
				)
				( attribute "GROUP" "POWER_FAIR"
					( Origin gFrontEnd )
				)
				( objectStatus "RF23" )
			)
			( gate "@baseboard_fab2_lib.baseboard_fab2(sch_1):page247_i99"
				( attribute "CDS_LIB" "mstr_discrete"
					( Origin gPackager )
				)
				( attribute "LOCATION" "R6W12"
					( Origin gFrontEnd )
				)
				( attribute "MATERIAL" "CHIP"
					( Origin gFrontEnd )
				)
				( attribute "PACK_TYPE" "0402"
					( Origin gFrontEnd )
				)
				( attribute "PART_NUMBER" "G21796-072"
					( Origin gFrontEnd )
				)
				( attribute "PHYS_PAGE" "247"
					( Origin gFrontEnd )
				)
				( attribute "ROT" "1"
					( Origin gFrontEnd )
				)
				( attribute "TOLERANCE" "1%"
					( Origin gFrontEnd )
				)
				( attribute "VALUE" "4.75K"
					( Origin gFrontEnd )
				)
				( attribute "VER" "1"
					( Origin gFrontEnd )
				)
				( attribute "WATTAGE" "1/16W"
					( Origin gFrontEnd )
				)
				( attribute "XY" "(-7050,3350)"
					( Origin gFrontEnd )
				)
				( attribute "CHIPS_PART_NAME" "RES"
					( Origin gPackager )
				)
				( attribute "CDS_PART_NAME" "RES_0402-4.75K,1%,1/16W,CHIP,GA"
					( Origin gPackager )
				)
				( attribute "CDS_LOCATION" "R6W12"
					( Origin gPackager )
				)
				( attribute "SEC" "1"
					( Origin gFrontEnd )
				)
				( attribute "SEC_TYPE" "0402"
					( Origin gFrontEnd )
				)
				( attribute "CDS_SEC" "1"
					( Origin gPackager )
				)
				( objectStatus "R6W12" )
			)
			( gate "@baseboard_fab2_lib.baseboard_fab2(sch_1):page248_i7"
				( attribute "CHIPS_PART_NAME" "ADM809"
					( Origin gPackager )
				)
			)
			( gate "@baseboard_fab2_lib.baseboard_fab2(sch_1):page248_i13"
				( attribute "BOM_COST" "SM_THERM"
					( Origin gFrontEnd )
				)
				( attribute "CDS_LIB" "dev_discrete"
					( Origin gPackager )
				)
				( attribute "CDS_LOCATION" "C14W1"
					( Origin gPackager )
				)
				( attribute "CDS_SEC" "1"
					( Origin gPackager )
				)
				( attribute "LOCATION" "C14W1"
					( Origin gFrontEnd )
				)
				( attribute "MATERIAL" "X7R"
					( Origin gFrontEnd )
				)
				( attribute "PACK_TYPE" "0402V"
					( Origin gFrontEnd )
				)
				( attribute "PART_NUMBER" "A36096-030"
					( Origin gFrontEnd )
				)
				( attribute "PHYS_PAGE" "248"
					( Origin gFrontEnd )
				)
				( attribute "ROOM" "CPUFANS"
					( Origin gFrontEnd )
				)
				( attribute "ROT" "0"
					( Origin gFrontEnd )
				)
				( attribute "SEC" "1"
					( Origin gFrontEnd )
				)
				( attribute "SEC_TYPE" "0402V"
					( Origin gFrontEnd )
				)
				( attribute "TOLERANCE" "10%"
					( Origin gFrontEnd )
				)
				( attribute "VALUE" "0.1UF"
					( Origin gFrontEnd )
				)
				( attribute "VER" "1"
					( Origin gFrontEnd )
				)
				( attribute "VOLTAGE" "16V"
					( Units "uVoltage" "V" 1.000000)
					( Origin gFrontEnd )
				)
				( attribute "XY" "(-2750,2025)"
					( Origin gFrontEnd )
				)
				( attribute "CHIPS_PART_NAME" "CAP_A"
					( Origin gPackager )
				)
				( attribute "CDS_PART_NAME" "CAP_A_0402V-0.1UF,16V,10%,X7R,A"
					( Origin gPackager )
				)
				( objectStatus "C14W1" )
			)
			( gate "@baseboard_fab2_lib.baseboard_fab2(sch_1):page248_i17"
				( attribute "BOM_COST" "SM_THERM"
					( Origin gFrontEnd )
				)
				( attribute "CDS_LIB" "dev_discrete"
					( Origin gPackager )
				)
				( attribute "CDS_LOCATION" "C14W2"
					( Origin gPackager )
				)
				( attribute "CDS_SEC" "1"
					( Origin gPackager )
				)
				( attribute "LOCATION" "C14W2"
					( Origin gFrontEnd )
				)
				( attribute "MATERIAL" "X7R"
					( Origin gFrontEnd )
				)
				( attribute "PACK_TYPE" "0402V"
					( Origin gFrontEnd )
				)
				( attribute "PART_NUMBER" "A36096-030"
					( Origin gFrontEnd )
				)
				( attribute "PHYS_PAGE" "248"
					( Origin gFrontEnd )
				)
				( attribute "ROOM" "CPUFANS"
					( Origin gFrontEnd )
				)
				( attribute "ROT" "0"
					( Origin gFrontEnd )
				)
				( attribute "SEC" "1"
					( Origin gFrontEnd )
				)
				( attribute "SEC_TYPE" "0402V"
					( Origin gFrontEnd )
				)
				( attribute "TOLERANCE" "10%"
					( Origin gFrontEnd )
				)
				( attribute "VALUE" "0.1UF"
					( Origin gFrontEnd )
				)
				( attribute "VER" "1"
					( Origin gFrontEnd )
				)
				( attribute "VOLTAGE" "16V"
					( Units "uVoltage" "V" 1.000000)
					( Origin gFrontEnd )
				)
				( attribute "XY" "(-3700,1175)"
					( Origin gFrontEnd )
				)
				( attribute "CHIPS_PART_NAME" "CAP_A"
					( Origin gPackager )
				)
				( attribute "CDS_PART_NAME" "CAP_A_0402V-0.1UF,16V,10%,X7R,A"
					( Origin gPackager )
				)
				( objectStatus "C14W2" )
			)
			( gate "@baseboard_fab2_lib.baseboard_fab2(sch_1):page175_i92"
				( attribute "BOM_COST" "MIO_CHASSIS"
					( Origin gFrontEnd )
				)
				( attribute "CDS_LIB" "mstr_misc"
					( Origin gPackager )
				)
				( attribute "CDS_LMAN_SYM_OUTLINE" "-100,125,100,-75"
					( Origin gPackager )
				)
				( attribute "LOCATION" "S9A2"
					( Origin gFrontEnd )
				)
				( attribute "MATERIAL" "IC"
					( Origin gFrontEnd )
				)
				( attribute "PACK_TYPE" "SM"
					( Origin gFrontEnd )
				)
				( attribute "PART_NUMBER" "D37771-002"
					( Origin gFrontEnd )
				)
				( attribute "PHYS_PAGE" "175"
					( Origin gFrontEnd )
				)
				( attribute "ROOM" "MIO_CHASSIS"
					( Origin gFrontEnd )
				)
				( attribute "ROT" "2"
					( Origin gFrontEnd )
				)
				( attribute "SEC" "1"
					( Origin gFrontEnd )
				)
				( attribute "SEC_TYPE" "SM"
					( Origin gFrontEnd )
				)
				( attribute "VER" "1"
					( Origin gFrontEnd )
				)
				( attribute "XY" "(-7200,4150)"
					( Origin gFrontEnd )
				)
				( attribute "CHIPS_PART_NAME" "SWITCH_D37771002"
					( Origin gPackager )
				)
				( attribute "CDS_PART_NAME" "SWITCH_D37771002_SM-IC,D37771-A"
					( Origin gPackager )
				)
				( attribute "CDS_LOCATION" "S9A2"
					( Origin gPackager )
				)
				( attribute "CDS_SEC" "1"
					( Origin gPackager )
				)
				( objectStatus "S9A2" )
			)
			( gate "@baseboard_fab2_lib.baseboard_fab2(sch_1):page201_i186"
				( attribute "CDS_LIB" "mstr_discrete"
					( Origin gPackager )
				)
				( attribute "LOCATION" "RF5"
					( Origin gFrontEnd )
				)
				( attribute "MATERIAL" "CHIP"
					( Origin gFrontEnd )
				)
				( attribute "PACK_TYPE" "0402"
					( Origin gFrontEnd )
				)
				( attribute "PART_NUMBER" "G85996-004"
					( Origin gFrontEnd )
				)
				( attribute "PHYS_PAGE" "201"
					( Origin gFrontEnd )
				)
				( attribute "ROOM" "SB"
					( Origin gFrontEnd )
				)
				( attribute "ROT" "0"
					( Origin gFrontEnd )
				)
				( attribute "TOLERANCE" "0.1%"
					( Origin gFrontEnd )
				)
				( attribute "VALUE" "1.0K"
					( Origin gFrontEnd )
				)
				( attribute "VER" "1"
					( Origin gFrontEnd )
				)
				( attribute "WATTAGE" "1/16W"
					( Origin gFrontEnd )
				)
				( attribute "XY" "(-5025,3500)"
					( Origin gFrontEnd )
				)
				( attribute "CHIPS_PART_NAME" "RES"
					( Origin gPackager )
				)
				( attribute "CDS_PART_NAME" "RES_0402-1.0K,0.1%,1/16W,CHIP,A"
					( Origin gPackager )
				)
				( attribute "CDS_LOCATION" "RF5"
					( Origin gPackager )
				)
				( attribute "SEC" "1"
					( Origin gFrontEnd )
				)
				( attribute "SEC_TYPE" "0402"
					( Origin gFrontEnd )
				)
				( attribute "CDS_SEC" "1"
					( Origin gPackager )
				)
				( attribute "GROUP" "POWER_FAIR"
					( Origin gFrontEnd )
				)
				( attribute "FAIR_SS" "064.9530D.M001"
					( Origin gFrontEnd )
				)
				( objectStatus "RF5" )
			)
			( gate "@baseboard_fab2_lib.baseboard_fab2(sch_1):page201_i184"
				( attribute "CDS_LIB" "mstr_discrete"
					( Origin gPackager )
				)
				( attribute "LOCATION" "RF3"
					( Origin gFrontEnd )
				)
				( attribute "MATERIAL" "CHIP"
					( Origin gFrontEnd )
				)
				( attribute "PACK_TYPE" "0402"
					( Origin gFrontEnd )
				)
				( attribute "PART_NUMBER" "G85996-004"
					( Origin gFrontEnd )
				)
				( attribute "PHYS_PAGE" "201"
					( Origin gFrontEnd )
				)
				( attribute "ROOM" "SB"
					( Origin gFrontEnd )
				)
				( attribute "ROT" "0"
					( Origin gFrontEnd )
				)
				( attribute "TOLERANCE" "0.1%"
					( Origin gFrontEnd )
				)
				( attribute "VALUE" "1.0K"
					( Origin gFrontEnd )
				)
				( attribute "VER" "1"
					( Origin gFrontEnd )
				)
				( attribute "WATTAGE" "1/16W"
					( Origin gFrontEnd )
				)
				( attribute "XY" "(-5825,3500)"
					( Origin gFrontEnd )
				)
				( attribute "CHIPS_PART_NAME" "RES"
					( Origin gPackager )
				)
				( attribute "CDS_PART_NAME" "RES_0402-1.0K,0.1%,1/16W,CHIP,A"
					( Origin gPackager )
				)
				( attribute "CDS_LOCATION" "RF3"
					( Origin gPackager )
				)
				( attribute "SEC" "1"
					( Origin gFrontEnd )
				)
				( attribute "SEC_TYPE" "0402"
					( Origin gFrontEnd )
				)
				( attribute "CDS_SEC" "1"
					( Origin gPackager )
				)
				( attribute "GROUP" "POWER_FAIR"
					( Origin gFrontEnd )
				)
				( attribute "FAIR_SS" "064.9530D.M001"
					( Origin gFrontEnd )
				)
				( objectStatus "RF3" )
			)
			( gate "@baseboard_fab2_lib.baseboard_fab2(sch_1):page201_i183"
				( attribute "CDS_LIB" "mstr_discrete"
					( Origin gPackager )
				)
				( attribute "LOCATION" "RF2"
					( Origin gFrontEnd )
				)
				( attribute "MATERIAL" "CHIP"
					( Origin gFrontEnd )
				)
				( attribute "PACK_TYPE" "0402"
					( Origin gFrontEnd )
				)
				( attribute "PART_NUMBER" "G85996-004"
					( Origin gFrontEnd )
				)
				( attribute "PHYS_PAGE" "201"
					( Origin gFrontEnd )
				)
				( attribute "ROOM" "SB"
					( Origin gFrontEnd )
				)
				( attribute "ROT" "0"
					( Origin gFrontEnd )
				)
				( attribute "TOLERANCE" "0.1%"
					( Origin gFrontEnd )
				)
				( attribute "VALUE" "1.0K"
					( Origin gFrontEnd )
				)
				( attribute "VER" "1"
					( Origin gFrontEnd )
				)
				( attribute "WATTAGE" "1/16W"
					( Origin gFrontEnd )
				)
				( attribute "XY" "(-6300,3500)"
					( Origin gFrontEnd )
				)
				( attribute "CHIPS_PART_NAME" "RES"
					( Origin gPackager )
				)
				( attribute "CDS_PART_NAME" "RES_0402-1.0K,0.1%,1/16W,CHIP,A"
					( Origin gPackager )
				)
				( attribute "CDS_LOCATION" "RF2"
					( Origin gPackager )
				)
				( attribute "SEC" "1"
					( Origin gFrontEnd )
				)
				( attribute "SEC_TYPE" "0402"
					( Origin gFrontEnd )
				)
				( attribute "CDS_SEC" "1"
					( Origin gPackager )
				)
				( attribute "GROUP" "POWER_FAIR"
					( Origin gFrontEnd )
				)
				( attribute "FAIR_SS" "064.9530D.M001"
					( Origin gFrontEnd )
				)
				( objectStatus "RF2" )
			)
			( gate "@baseboard_fab2_lib.baseboard_fab2(sch_1):page201_i182"
				( attribute "CDS_LIB" "mstr_discrete"
					( Origin gPackager )
				)
				( attribute "LOCATION" "RF1"
					( Origin gFrontEnd )
				)
				( attribute "MATERIAL" "CHIP"
					( Origin gFrontEnd )
				)
				( attribute "PACK_TYPE" "0402"
					( Origin gFrontEnd )
				)
				( attribute "PART_NUMBER" "G85996-004"
					( Origin gFrontEnd )
				)
				( attribute "PHYS_PAGE" "201"
					( Origin gFrontEnd )
				)
				( attribute "ROOM" "SB"
					( Origin gFrontEnd )
				)
				( attribute "ROT" "0"
					( Origin gFrontEnd )
				)
				( attribute "TOLERANCE" "0.1%"
					( Origin gFrontEnd )
				)
				( attribute "VALUE" "1.0K"
					( Origin gFrontEnd )
				)
				( attribute "VER" "1"
					( Origin gFrontEnd )
				)
				( attribute "WATTAGE" "1/16W"
					( Origin gFrontEnd )
				)
				( attribute "XY" "(-6750,3500)"
					( Origin gFrontEnd )
				)
				( attribute "CHIPS_PART_NAME" "RES"
					( Origin gPackager )
				)
				( attribute "CDS_PART_NAME" "RES_0402-1.0K,0.1%,1/16W,CHIP,A"
					( Origin gPackager )
				)
				( attribute "CDS_LOCATION" "RF1"
					( Origin gPackager )
				)
				( attribute "SEC" "1"
					( Origin gFrontEnd )
				)
				( attribute "SEC_TYPE" "0402"
					( Origin gFrontEnd )
				)
				( attribute "CDS_SEC" "1"
					( Origin gPackager )
				)
				( attribute "GROUP" "POWER_FAIR"
					( Origin gFrontEnd )
				)
				( attribute "FAIR_SS" "064.9530D.M001"
					( Origin gFrontEnd )
				)
				( objectStatus "RF1" )
			)
			( gate "@baseboard_fab2_lib.baseboard_fab2(sch_1):page201_i180"
				( attribute "CDS_LIB" "mstr_discrete"
					( Origin gPackager )
				)
				( attribute "LOCATION" "RF6"
					( Origin gFrontEnd )
				)
				( attribute "MATERIAL" "CHIP"
					( Origin gFrontEnd )
				)
				( attribute "PACK_TYPE" "0402"
					( Origin gFrontEnd )
				)
				( attribute "PART_NUMBER" "G85996-004"
					( Origin gFrontEnd )
				)
				( attribute "PHYS_PAGE" "201"
					( Origin gFrontEnd )
				)
				( attribute "ROOM" "SB"
					( Origin gFrontEnd )
				)
				( attribute "ROT" "0"
					( Origin gFrontEnd )
				)
				( attribute "TOLERANCE" "0.1%"
					( Origin gFrontEnd )
				)
				( attribute "VALUE" "1.0K"
					( Origin gFrontEnd )
				)
				( attribute "VER" "1"
					( Origin gFrontEnd )
				)
				( attribute "WATTAGE" "1/16W"
					( Origin gFrontEnd )
				)
				( attribute "XY" "(-5800,1425)"
					( Origin gFrontEnd )
				)
				( attribute "CHIPS_PART_NAME" "RES"
					( Origin gPackager )
				)
				( attribute "CDS_PART_NAME" "RES_0402-1.0K,0.1%,1/16W,CHIP,A"
					( Origin gPackager )
				)
				( attribute "CDS_LOCATION" "RF6"
					( Origin gPackager )
				)
				( attribute "SEC" "1"
					( Origin gFrontEnd )
				)
				( attribute "SEC_TYPE" "0402"
					( Origin gFrontEnd )
				)
				( attribute "CDS_SEC" "1"
					( Origin gPackager )
				)
				( attribute "GROUP" "POWER_FAIR"
					( Origin gFrontEnd )
				)
				( objectStatus "RF6" )
			)
			( gate "@baseboard_fab2_lib.baseboard_fab2(sch_1):page201_i173"
				( attribute "CDS_LIB" "w_hdl"
					( Origin gPackager )
				)
				( attribute "CDS_LMAN_SYM_OUTLINE" "-50,25,50,-25"
					( Origin gPackager )
				)
				( attribute "LOCATION" "CF6"
					( Origin gFrontEnd )
				)
				( attribute "PACK_TYPE" "SMD-BCG"
					( Origin gFrontEnd )
				)
				( attribute "PART_NUMBER" "78.22034.1FL"
					( Origin gFrontEnd )
				)
				( attribute "PHYS_PAGE" "201"
					( Origin gFrontEnd )
				)
				( attribute "ROT" "1"
					( Origin gFrontEnd )
				)
				( attribute "VALUE" "SC22P50V2JN-4GP"
					( Origin gFrontEnd )
				)
				( attribute "VER" "1"
					( Origin gFrontEnd )
				)
				( attribute "XY" "(-5800,1325)"
					( Origin gFrontEnd )
				)
				( attribute "CHIPS_PART_NAME" "SC22P50V2JN-4GP"
					( Origin gPackager )
				)
				( attribute "CDS_PART_NAME" "SC22P50V2JN-4GP_SMD-BCG-SC22P5A"
					( Origin gPackager )
				)
				( attribute "CDS_LOCATION" "CF6"
					( Origin gPackager )
				)
				( attribute "CDS_SEC" "1"
					( Origin gPackager )
				)
				( attribute "SEC" "1"
					( Origin gPackager )
				)
				( attribute "ATTRIBUTE" "22PF"
					( Origin gFrontEnd )
				)
				( attribute "PACK_SIZE" "0402"
					( Origin gFrontEnd )
				)
				( attribute "RATED" "50V"
					( Origin gFrontEnd )
				)
				( attribute "TOLERANCE" "5%"
					( Origin gFrontEnd )
				)
				( attribute "TYPE" "NPO"
					( Origin gFrontEnd )
				)
				( attribute "GROUP" "POWER_FAIR"
					( Origin gFrontEnd )
				)
				( objectStatus "CF6" )
			)
			( gate "@baseboard_fab2_lib.baseboard_fab2(sch_1):page206_i137"
				( attribute "CDS_LIB" "w_hdl"
					( Origin gPackager )
				)
				( attribute "CDS_LMAN_SYM_OUTLINE" "-50,25,50,-25"
					( Origin gPackager )
				)
				( attribute "PACK_TYPE" "SMD-BCG"
					( Origin gFrontEnd )
				)
				( attribute "PART_NUMBER" "78.22034.1FL"
					( Origin gFrontEnd )
				)
				( attribute "PHYS_PAGE" "206"
					( Origin gFrontEnd )
				)
				( attribute "ROT" "1"
					( Origin gFrontEnd )
				)
				( attribute "VALUE" "SC22P50V2JN-4GP"
					( Origin gFrontEnd )
				)
				( attribute "VER" "1"
					( Origin gFrontEnd )
				)
				( attribute "XY" "(-6775,3350)"
					( Origin gFrontEnd )
				)
				( attribute "CHIPS_PART_NAME" "SC22P50V2JN-4GP"
					( Origin gPackager )
				)
				( attribute "CDS_PART_NAME" "SC22P50V2JN-4GP_SMD-BCG-SC22P5A"
					( Origin gPackager )
				)
				( attribute "LOCATION" "CF7"
					( Origin gFrontEnd )
				)
				( attribute "CDS_LOCATION" "CF7"
					( Origin gPackager )
				)
				( attribute "CDS_SEC" "1"
					( Origin gPackager )
				)
				( attribute "SEC" "1"
					( Origin gPackager )
				)
				( attribute "ATTRIBUTE" "22PF"
					( Origin gFrontEnd )
				)
				( attribute "PACK_SIZE" "0402"
					( Origin gFrontEnd )
				)
				( attribute "RATED" "50V"
					( Origin gFrontEnd )
				)
				( attribute "TOLERANCE" "5%"
					( Origin gFrontEnd )
				)
				( attribute "TYPE" "NPO"
					( Origin gFrontEnd )
				)
				( attribute "GROUP" "POWER_FAIR"
					( Origin gFrontEnd )
				)
				( objectStatus "CF7" )
			)
			( gate "@baseboard_fab2_lib.baseboard_fab2(sch_1):page206_i138"
				( attribute "CDS_LIB" "w_hdl"
					( Origin gPackager )
				)
				( attribute "CDS_LMAN_SYM_OUTLINE" "-50,25,50,-25"
					( Origin gPackager )
				)
				( attribute "PACK_TYPE" "SMD-BCG"
					( Origin gFrontEnd )
				)
				( attribute "PART_NUMBER" "78.22034.1FL"
					( Origin gFrontEnd )
				)
				( attribute "PHYS_PAGE" "206"
					( Origin gFrontEnd )
				)
				( attribute "ROT" "1"
					( Origin gFrontEnd )
				)
				( attribute "VALUE" "SC22P50V2JN-4GP"
					( Origin gFrontEnd )
				)
				( attribute "VER" "1"
					( Origin gFrontEnd )
				)
				( attribute "XY" "(-6375,3350)"
					( Origin gFrontEnd )
				)
				( attribute "CHIPS_PART_NAME" "SC22P50V2JN-4GP"
					( Origin gPackager )
				)
				( attribute "CDS_PART_NAME" "SC22P50V2JN-4GP_SMD-BCG-SC22P5A"
					( Origin gPackager )
				)
				( attribute "LOCATION" "CF8"
					( Origin gFrontEnd )
				)
				( attribute "SEC" "1"
					( Origin gFrontEnd )
				)
				( attribute "SEC_TYPE" "SMD-BCG"
					( Origin gFrontEnd )
				)
				( attribute "CDS_LOCATION" "CF8"
					( Origin gPackager )
				)
				( attribute "CDS_SEC" "1"
					( Origin gPackager )
				)
				( attribute "ATTRIBUTE" "22PF"
					( Origin gFrontEnd )
				)
				( attribute "PACK_SIZE" "0402"
					( Origin gFrontEnd )
				)
				( attribute "RATED" "50V"
					( Origin gFrontEnd )
				)
				( attribute "TOLERANCE" "5%"
					( Origin gFrontEnd )
				)
				( attribute "TYPE" "NPO"
					( Origin gFrontEnd )
				)
				( attribute "GROUP" "POWER_FAIR"
					( Origin gFrontEnd )
				)
				( objectStatus "CF8" )
			)
			( gate "@baseboard_fab2_lib.baseboard_fab2(sch_1):page206_i139"
				( attribute "CDS_LIB" "w_hdl"
					( Origin gPackager )
				)
				( attribute "CDS_LMAN_SYM_OUTLINE" "-50,25,50,-25"
					( Origin gPackager )
				)
				( attribute "PACK_TYPE" "SMD-BCG"
					( Origin gFrontEnd )
				)
				( attribute "PART_NUMBER" "78.22034.1FL"
					( Origin gFrontEnd )
				)
				( attribute "PHYS_PAGE" "206"
					( Origin gFrontEnd )
				)
				( attribute "ROT" "1"
					( Origin gFrontEnd )
				)
				( attribute "VALUE" "SC22P50V2JN-4GP"
					( Origin gFrontEnd )
				)
				( attribute "VER" "1"
					( Origin gFrontEnd )
				)
				( attribute "XY" "(-6000,3350)"
					( Origin gFrontEnd )
				)
				( attribute "CHIPS_PART_NAME" "SC22P50V2JN-4GP"
					( Origin gPackager )
				)
				( attribute "CDS_PART_NAME" "SC22P50V2JN-4GP_SMD-BCG-SC22P5A"
					( Origin gPackager )
				)
				( attribute "LOCATION" "CF9"
					( Origin gFrontEnd )
				)
				( attribute "CDS_LOCATION" "CF9"
					( Origin gPackager )
				)
				( attribute "CDS_SEC" "1"
					( Origin gPackager )
				)
				( attribute "SEC" "1"
					( Origin gPackager )
				)
				( attribute "ATTRIBUTE" "22PF"
					( Origin gFrontEnd )
				)
				( attribute "PACK_SIZE" "0402"
					( Origin gFrontEnd )
				)
				( attribute "RATED" "50V"
					( Origin gFrontEnd )
				)
				( attribute "TOLERANCE" "5%"
					( Origin gFrontEnd )
				)
				( attribute "TYPE" "NPO"
					( Origin gFrontEnd )
				)
				( attribute "GROUP" "POWER_FAIR"
					( Origin gFrontEnd )
				)
				( objectStatus "CF9" )
			)
			( gate "@baseboard_fab2_lib.baseboard_fab2(sch_1):page206_i140"
				( attribute "CDS_LIB" "w_hdl"
					( Origin gPackager )
				)
				( attribute "CDS_LMAN_SYM_OUTLINE" "-50,25,50,-25"
					( Origin gPackager )
				)
				( attribute "PACK_TYPE" "SMD-BCG"
					( Origin gFrontEnd )
				)
				( attribute "PART_NUMBER" "78.22034.1FL"
					( Origin gFrontEnd )
				)
				( attribute "PHYS_PAGE" "206"
					( Origin gFrontEnd )
				)
				( attribute "ROT" "1"
					( Origin gFrontEnd )
				)
				( attribute "VALUE" "SC22P50V2JN-4GP"
					( Origin gFrontEnd )
				)
				( attribute "VER" "1"
					( Origin gFrontEnd )
				)
				( attribute "XY" "(-5550,3350)"
					( Origin gFrontEnd )
				)
				( attribute "CHIPS_PART_NAME" "SC22P50V2JN-4GP"
					( Origin gPackager )
				)
				( attribute "CDS_PART_NAME" "SC22P50V2JN-4GP_SMD-BCG-SC22P5A"
					( Origin gPackager )
				)
				( attribute "LOCATION" "CF10"
					( Origin gFrontEnd )
				)
				( attribute "CDS_LOCATION" "CF10"
					( Origin gPackager )
				)
				( attribute "CDS_SEC" "1"
					( Origin gPackager )
				)
				( attribute "SEC" "1"
					( Origin gPackager )
				)
				( attribute "ATTRIBUTE" "22PF"
					( Origin gFrontEnd )
				)
				( attribute "PACK_SIZE" "0402"
					( Origin gFrontEnd )
				)
				( attribute "RATED" "50V"
					( Origin gFrontEnd )
				)
				( attribute "TOLERANCE" "5%"
					( Origin gFrontEnd )
				)
				( attribute "TYPE" "NPO"
					( Origin gFrontEnd )
				)
				( attribute "GROUP" "POWER_FAIR"
					( Origin gFrontEnd )
				)
				( objectStatus "CF10" )
			)
			( gate "@baseboard_fab2_lib.baseboard_fab2(sch_1):page206_i141"
				( attribute "CDS_LIB" "w_hdl"
					( Origin gPackager )
				)
				( attribute "CDS_LMAN_SYM_OUTLINE" "-50,25,50,-25"
					( Origin gPackager )
				)
				( attribute "PACK_TYPE" "SMD-BCG"
					( Origin gFrontEnd )
				)
				( attribute "PART_NUMBER" "78.22034.1FL"
					( Origin gFrontEnd )
				)
				( attribute "PHYS_PAGE" "206"
					( Origin gFrontEnd )
				)
				( attribute "ROT" "1"
					( Origin gFrontEnd )
				)
				( attribute "VALUE" "SC22P50V2JN-4GP"
					( Origin gFrontEnd )
				)
				( attribute "VER" "1"
					( Origin gFrontEnd )
				)
				( attribute "XY" "(-5100,3350)"
					( Origin gFrontEnd )
				)
				( attribute "CHIPS_PART_NAME" "SC22P50V2JN-4GP"
					( Origin gPackager )
				)
				( attribute "CDS_PART_NAME" "SC22P50V2JN-4GP_SMD-BCG-SC22P5A"
					( Origin gPackager )
				)
				( attribute "LOCATION" "CF11"
					( Origin gFrontEnd )
				)
				( attribute "CDS_LOCATION" "CF11"
					( Origin gPackager )
				)
				( attribute "CDS_SEC" "1"
					( Origin gPackager )
				)
				( attribute "SEC" "1"
					( Origin gPackager )
				)
				( attribute "ATTRIBUTE" "22PF"
					( Origin gFrontEnd )
				)
				( attribute "PACK_SIZE" "0402"
					( Origin gFrontEnd )
				)
				( attribute "RATED" "50V"
					( Origin gFrontEnd )
				)
				( attribute "TOLERANCE" "5%"
					( Origin gFrontEnd )
				)
				( attribute "TYPE" "NPO"
					( Origin gFrontEnd )
				)
				( attribute "GROUP" "POWER_FAIR"
					( Origin gFrontEnd )
				)
				( objectStatus "CF11" )
			)
			( gate "@baseboard_fab2_lib.baseboard_fab2(sch_1):page206_i142"
				( attribute "CDS_LIB" "w_hdl"
					( Origin gPackager )
				)
				( attribute "CDS_LMAN_SYM_OUTLINE" "-50,25,50,-25"
					( Origin gPackager )
				)
				( attribute "PACK_TYPE" "SMD-BCG"
					( Origin gFrontEnd )
				)
				( attribute "PART_NUMBER" "78.22034.1FL"
					( Origin gFrontEnd )
				)
				( attribute "PHYS_PAGE" "206"
					( Origin gFrontEnd )
				)
				( attribute "ROT" "1"
					( Origin gFrontEnd )
				)
				( attribute "VALUE" "SC22P50V2JN-4GP"
					( Origin gFrontEnd )
				)
				( attribute "VER" "1"
					( Origin gFrontEnd )
				)
				( attribute "XY" "(-6525,1275)"
					( Origin gFrontEnd )
				)
				( attribute "CHIPS_PART_NAME" "SC22P50V2JN-4GP"
					( Origin gPackager )
				)
				( attribute "CDS_PART_NAME" "SC22P50V2JN-4GP_SMD-BCG-SC22P5A"
					( Origin gPackager )
				)
				( attribute "LOCATION" "CF12"
					( Origin gFrontEnd )
				)
				( attribute "CDS_LOCATION" "CF12"
					( Origin gPackager )
				)
				( attribute "CDS_SEC" "1"
					( Origin gPackager )
				)
				( attribute "SEC" "1"
					( Origin gPackager )
				)
				( attribute "ATTRIBUTE" "22PF"
					( Origin gFrontEnd )
				)
				( attribute "PACK_SIZE" "0402"
					( Origin gFrontEnd )
				)
				( attribute "RATED" "50V"
					( Origin gFrontEnd )
				)
				( attribute "TOLERANCE" "5%"
					( Origin gFrontEnd )
				)
				( attribute "TYPE" "NPO"
					( Origin gFrontEnd )
				)
				( attribute "GROUP" "POWER_FAIR"
					( Origin gFrontEnd )
				)
				( objectStatus "CF12" )
			)
			( gate "@baseboard_fab2_lib.baseboard_fab2(sch_1):page211_i95"
				( attribute "CDS_LIB" "w_hdl"
					( Origin gPackager )
				)
				( attribute "CDS_LMAN_SYM_OUTLINE" "-50,25,50,-25"
					( Origin gPackager )
				)
				( attribute "LOCATION" "CF13"
					( Origin gFrontEnd )
				)
				( attribute "PACK_TYPE" "SMD-BCG"
					( Origin gFrontEnd )
				)
				( attribute "PART_NUMBER" "78.22034.1FL"
					( Origin gFrontEnd )
				)
				( attribute "PHYS_PAGE" "211"
					( Origin gFrontEnd )
				)
				( attribute "ROT" "1"
					( Origin gFrontEnd )
				)
				( attribute "VALUE" "SC22P50V2JN-4GP"
					( Origin gFrontEnd )
				)
				( attribute "VER" "1"
					( Origin gFrontEnd )
				)
				( attribute "XY" "(-1975,3600)"
					( Origin gFrontEnd )
				)
				( attribute "CHIPS_PART_NAME" "SC22P50V2JN-4GP"
					( Origin gPackager )
				)
				( attribute "CDS_PART_NAME" "SC22P50V2JN-4GP_SMD-BCG-SC22P5A"
					( Origin gPackager )
				)
				( attribute "CDS_LOCATION" "CF13"
					( Origin gPackager )
				)
				( attribute "CDS_SEC" "1"
					( Origin gPackager )
				)
				( attribute "SEC" "1"
					( Origin gPackager )
				)
				( attribute "ATTRIBUTE" "22PF"
					( Origin gFrontEnd )
				)
				( attribute "PACK_SIZE" "0402"
					( Origin gFrontEnd )
				)
				( attribute "RATED" "50V"
					( Origin gFrontEnd )
				)
				( attribute "TOLERANCE" "5%"
					( Origin gFrontEnd )
				)
				( attribute "TYPE" "NPO"
					( Origin gFrontEnd )
				)
				( attribute "GROUP" "POWER_FAIR"
					( Origin gFrontEnd )
				)
				( objectStatus "CF13" )
			)
			( gate "@baseboard_fab2_lib.baseboard_fab2(sch_1):page221_i6"
				( attribute "BOM_COST" "MEM_VRD_VTT_ABC"
					( Origin gFrontEnd )
				)
				( attribute "CDS_LIB" "mstr_discrete"
					( Origin gPackager )
				)
				( attribute "CDS_LOCATION" "R6U5"
					( Origin gPackager )
				)
				( attribute "CDS_SEC" "1"
					( Origin gPackager )
				)
				( attribute "LOCATION" "R6U5"
					( Origin gFrontEnd )
				)
				( attribute "MATERIAL" "CHIP"
					( Origin gFrontEnd )
				)
				( attribute "NO_XNET_CONNECTION" "1"
					( Origin gFrontEnd )
				)
				( attribute "PACK_TYPE" "0402"
					( Origin gFrontEnd )
				)
				( attribute "PART_NUMBER" "G21497-005"
					( Origin gFrontEnd )
				)
				( attribute "PHYS_PAGE" "221"
					( Origin gFrontEnd )
				)
				( attribute "ROOM" "VTT_ABC_PWR_VR"
					( Origin gFrontEnd )
				)
				( attribute "ROT" "1"
					( Origin gFrontEnd )
				)
				( attribute "SEC" "1"
					( Origin gFrontEnd )
				)
				( attribute "SEC_TYPE" "0402"
					( Origin gFrontEnd )
				)
				( attribute "TOLERANCE" "5%"
					( Origin gFrontEnd )
				)
				( attribute "VALUE" "0.0"
					( Origin gFrontEnd )
				)
				( attribute "VER" "2"
					( Origin gFrontEnd )
				)
				( attribute "WATTAGE" "1/16W"
					( Origin gFrontEnd )
				)
				( attribute "XY" "(-1050,1450)"
					( Origin gFrontEnd )
				)
				( attribute "CHIPS_PART_NAME" "RES"
					( Origin gPackager )
				)
				( attribute "CDS_PART_NAME" "RES_0402-0.0,5%,1/16W,CHIP,G21A"
					( Origin gPackager )
				)
				( objectStatus "R6U5" )
			)
			( gate "@baseboard_fab2_lib.baseboard_fab2(sch_1):page221_i5"
				( attribute "BOM_COST" "MEM_VRD_VTT_ABC"
					( Origin gFrontEnd )
				)
				( attribute "CDS_LIB" "mstr_discrete"
					( Origin gPackager )
				)
				( attribute "CDS_LOCATION" "R6U15"
					( Origin gPackager )
				)
				( attribute "CDS_SEC" "1"
					( Origin gPackager )
				)
				( attribute "LOCATION" "R6U15"
					( Origin gFrontEnd )
				)
				( attribute "MATERIAL" "EMPTY"
					( Origin gFrontEnd )
				)
				( attribute "PACK_TYPE" "0402"
					( Origin gFrontEnd )
				)
				( attribute "PART_NUMBER" "G21796-021"
					( Origin gFrontEnd )
				)
				( attribute "PHYS_PAGE" "221"
					( Origin gFrontEnd )
				)
				( attribute "ROOM" "VTT_ABC_PWR_VR"
					( Origin gFrontEnd )
				)
				( attribute "ROT" "2"
					( Origin gFrontEnd )
				)
				( attribute "SEC" "1"
					( Origin gFrontEnd )
				)
				( attribute "SEC_TYPE" "0402"
					( Origin gFrontEnd )
				)
				( attribute "TOLERANCE" "1%"
					( Origin gFrontEnd )
				)
				( attribute "VALUE" "1.0M"
					( Origin gFrontEnd )
				)
				( attribute "VER" "2"
					( Origin gFrontEnd )
				)
				( attribute "WATTAGE" "1/16W"
					( Origin gFrontEnd )
				)
				( attribute "XY" "(-600,575)"
					( Origin gFrontEnd )
				)
				( attribute "CHIPS_PART_NAME" "RES"
					( Origin gPackager )
				)
				( attribute "CDS_PART_NAME" "RES_0402-1.0M,1%,1/16W,EMPTY,GA"
					( Origin gPackager )
				)
				( objectStatus "R6U15" )
			)
			( gate "@baseboard_fab2_lib.baseboard_fab2(sch_1):page213_i98"
				( attribute "CDS_LIB" "w_hdl"
					( Origin gPackager )
				)
				( attribute "CDS_LMAN_SYM_OUTLINE" "-50,25,50,-25"
					( Origin gPackager )
				)
				( attribute "LOCATION" "CF14"
					( Origin gFrontEnd )
				)
				( attribute "PACK_TYPE" "SMD-BCG"
					( Origin gFrontEnd )
				)
				( attribute "PART_NUMBER" "78.22034.1FL"
					( Origin gFrontEnd )
				)
				( attribute "PHYS_PAGE" "213"
					( Origin gFrontEnd )
				)
				( attribute "ROT" "1"
					( Origin gFrontEnd )
				)
				( attribute "VALUE" "SC22P50V2JN-4GP"
					( Origin gFrontEnd )
				)
				( attribute "VER" "1"
					( Origin gFrontEnd )
				)
				( attribute "XY" "(-1900,3500)"
					( Origin gFrontEnd )
				)
				( attribute "CHIPS_PART_NAME" "SC22P50V2JN-4GP"
					( Origin gPackager )
				)
				( attribute "CDS_PART_NAME" "SC22P50V2JN-4GP_SMD-BCG-SC22P5A"
					( Origin gPackager )
				)
				( attribute "CDS_LOCATION" "CF14"
					( Origin gPackager )
				)
				( attribute "CDS_SEC" "1"
					( Origin gPackager )
				)
				( attribute "SEC" "1"
					( Origin gPackager )
				)
				( attribute "ATTRIBUTE" "22PF"
					( Origin gFrontEnd )
				)
				( attribute "PACK_SIZE" "0402"
					( Origin gFrontEnd )
				)
				( attribute "RATED" "50V"
					( Origin gFrontEnd )
				)
				( attribute "TOLERANCE" "5%"
					( Origin gFrontEnd )
				)
				( attribute "TYPE" "NPO"
					( Origin gFrontEnd )
				)
				( attribute "GROUP" "POWER_FAIR"
					( Origin gFrontEnd )
				)
				( objectStatus "CF14" )
			)
			( gate "@baseboard_fab2_lib.baseboard_fab2(sch_1):page222_i6"
				( attribute "BOM_COST" "MEM_VRD_VTT_DEF"
					( Origin gFrontEnd )
				)
				( attribute "CDS_LIB" "mstr_discrete"
					( Origin gPackager )
				)
				( attribute "CDS_LOCATION" "R6L10"
					( Origin gPackager )
				)
				( attribute "CDS_SEC" "1"
					( Origin gPackager )
				)
				( attribute "LOCATION" "R6L10"
					( Origin gFrontEnd )
				)
				( attribute "MATERIAL" "CHIP"
					( Origin gFrontEnd )
				)
				( attribute "NO_XNET_CONNECTION" "1"
					( Origin gFrontEnd )
				)
				( attribute "PACK_TYPE" "0402"
					( Origin gFrontEnd )
				)
				( attribute "PART_NUMBER" "G21497-005"
					( Origin gFrontEnd )
				)
				( attribute "PHYS_PAGE" "222"
					( Origin gFrontEnd )
				)
				( attribute "ROOM" "VTT_DEF_PWR_VR"
					( Origin gFrontEnd )
				)
				( attribute "ROT" "1"
					( Origin gFrontEnd )
				)
				( attribute "SEC" "1"
					( Origin gFrontEnd )
				)
				( attribute "SEC_TYPE" "0402"
					( Origin gFrontEnd )
				)
				( attribute "TOLERANCE" "5%"
					( Origin gFrontEnd )
				)
				( attribute "VALUE" "0.0"
					( Origin gFrontEnd )
				)
				( attribute "VER" "2"
					( Origin gFrontEnd )
				)
				( attribute "WATTAGE" "1/16W"
					( Origin gFrontEnd )
				)
				( attribute "XY" "(-1500,1100)"
					( Origin gFrontEnd )
				)
				( attribute "CHIPS_PART_NAME" "RES"
					( Origin gPackager )
				)
				( attribute "CDS_PART_NAME" "RES_0402-0.0,5%,1/16W,CHIP,G21A"
					( Origin gPackager )
				)
				( objectStatus "R6L10" )
			)
			( gate "@baseboard_fab2_lib.baseboard_fab2(sch_1):page222_i5"
				( attribute "BOM_COST" "MEM_VRD_VTT_DEF"
					( Origin gFrontEnd )
				)
				( attribute "CDS_LIB" "mstr_discrete"
					( Origin gPackager )
				)
				( attribute "CDS_LOCATION" "R6L4"
					( Origin gPackager )
				)
				( attribute "CDS_SEC" "1"
					( Origin gPackager )
				)
				( attribute "LOCATION" "R6L4"
					( Origin gFrontEnd )
				)
				( attribute "MATERIAL" "EMPTY"
					( Origin gFrontEnd )
				)
				( attribute "PACK_TYPE" "0402"
					( Origin gFrontEnd )
				)
				( attribute "PART_NUMBER" "G21796-021"
					( Origin gFrontEnd )
				)
				( attribute "PHYS_PAGE" "222"
					( Origin gFrontEnd )
				)
				( attribute "ROOM" "VTT_DEF_PWR_VR"
					( Origin gFrontEnd )
				)
				( attribute "ROT" "2"
					( Origin gFrontEnd )
				)
				( attribute "SEC" "1"
					( Origin gFrontEnd )
				)
				( attribute "SEC_TYPE" "0402"
					( Origin gFrontEnd )
				)
				( attribute "TOLERANCE" "1%"
					( Origin gFrontEnd )
				)
				( attribute "VALUE" "1.0M"
					( Origin gFrontEnd )
				)
				( attribute "VER" "2"
					( Origin gFrontEnd )
				)
				( attribute "WATTAGE" "1/16W"
					( Origin gFrontEnd )
				)
				( attribute "XY" "(-1100,200)"
					( Origin gFrontEnd )
				)
				( attribute "CHIPS_PART_NAME" "RES"
					( Origin gPackager )
				)
				( attribute "CDS_PART_NAME" "RES_0402-1.0M,1%,1/16W,EMPTY,GA"
					( Origin gPackager )
				)
				( objectStatus "R6L4" )
			)
			( gate "@baseboard_fab2_lib.baseboard_fab2(sch_1):page229_i6"
				( attribute "BOM_COST" "MEM_VRD_VTT_GHJ"
					( Origin gFrontEnd )
				)
				( attribute "CDS_LIB" "mstr_discrete"
					( Origin gPackager )
				)
				( attribute "CDS_LOCATION" "R6U6"
					( Origin gPackager )
				)
				( attribute "CDS_SEC" "1"
					( Origin gPackager )
				)
				( attribute "LOCATION" "R6U6"
					( Origin gFrontEnd )
				)
				( attribute "MATERIAL" "CHIP"
					( Origin gFrontEnd )
				)
				( attribute "NO_XNET_CONNECTION" "1"
					( Origin gFrontEnd )
				)
				( attribute "PACK_TYPE" "0402"
					( Origin gFrontEnd )
				)
				( attribute "PART_NUMBER" "G21497-005"
					( Origin gFrontEnd )
				)
				( attribute "PHYS_PAGE" "229"
					( Origin gFrontEnd )
				)
				( attribute "ROOM" "VTT_GHJ_PWR_VR"
					( Origin gFrontEnd )
				)
				( attribute "ROT" "1"
					( Origin gFrontEnd )
				)
				( attribute "SEC" "1"
					( Origin gFrontEnd )
				)
				( attribute "SEC_TYPE" "0402"
					( Origin gFrontEnd )
				)
				( attribute "TOLERANCE" "5%"
					( Origin gFrontEnd )
				)
				( attribute "VALUE" "0.0"
					( Origin gFrontEnd )
				)
				( attribute "VER" "2"
					( Origin gFrontEnd )
				)
				( attribute "WATTAGE" "1/16W"
					( Origin gFrontEnd )
				)
				( attribute "XY" "(-850,1400)"
					( Origin gFrontEnd )
				)
				( attribute "CHIPS_PART_NAME" "RES"
					( Origin gPackager )
				)
				( attribute "CDS_PART_NAME" "RES_0402-0.0,5%,1/16W,CHIP,G21A"
					( Origin gPackager )
				)
				( objectStatus "R6U6" )
			)
			( gate "@baseboard_fab2_lib.baseboard_fab2(sch_1):page229_i5"
				( attribute "BOM_COST" "MEM_VRD_VTT_GHJ"
					( Origin gFrontEnd )
				)
				( attribute "CDS_LIB" "mstr_discrete"
					( Origin gPackager )
				)
				( attribute "CDS_LOCATION" "R6U3"
					( Origin gPackager )
				)
				( attribute "CDS_SEC" "1"
					( Origin gPackager )
				)
				( attribute "LOCATION" "R6U3"
					( Origin gFrontEnd )
				)
				( attribute "MATERIAL" "EMPTY"
					( Origin gFrontEnd )
				)
				( attribute "PACK_TYPE" "0402"
					( Origin gFrontEnd )
				)
				( attribute "PART_NUMBER" "G21796-021"
					( Origin gFrontEnd )
				)
				( attribute "PHYS_PAGE" "229"
					( Origin gFrontEnd )
				)
				( attribute "ROOM" "VTT_GHJ_PWR_VR"
					( Origin gFrontEnd )
				)
				( attribute "ROT" "2"
					( Origin gFrontEnd )
				)
				( attribute "SEC" "1"
					( Origin gFrontEnd )
				)
				( attribute "SEC_TYPE" "0402"
					( Origin gFrontEnd )
				)
				( attribute "TOLERANCE" "1%"
					( Origin gFrontEnd )
				)
				( attribute "VALUE" "1.0M"
					( Origin gFrontEnd )
				)
				( attribute "VER" "2"
					( Origin gFrontEnd )
				)
				( attribute "WATTAGE" "1/16W"
					( Origin gFrontEnd )
				)
				( attribute "XY" "(-425,500)"
					( Origin gFrontEnd )
				)
				( attribute "CHIPS_PART_NAME" "RES"
					( Origin gPackager )
				)
				( attribute "CDS_PART_NAME" "RES_0402-1.0M,1%,1/16W,EMPTY,GA"
					( Origin gPackager )
				)
				( objectStatus "R6U3" )
			)
			( gate "@baseboard_fab2_lib.baseboard_fab2(sch_1):page197_i116"
				( attribute "ATTRIBUTE" "4.02OHM"
					( Origin gFrontEnd )
				)
				( attribute "CDS_LIB" "w_hdl"
					( Origin gPackager )
				)
				( attribute "CDS_LMAN_SYM_OUTLINE" "-50,75,50,-75"
					( Origin gPackager )
				)
				( attribute "LOCATION" "R12W13"
					( Origin gFrontEnd )
				)
				( attribute "PACK_TYPE" "SMD-RG2"
					( Origin gFrontEnd )
				)
				( attribute "PART_NUMBER" "64.4R025.6DL"
					( Origin gFrontEnd )
				)
				( attribute "PHYS_PAGE" "197"
					( Origin gFrontEnd )
				)
				( attribute "RATED" "1/16W"
					( Origin gFrontEnd )
				)
				( attribute "ROT" "1"
					( Origin gFrontEnd )
				)
				( attribute "SEC" "1"
					( Origin gFrontEnd )
				)
				( attribute "SEC_TYPE" "SMD-RG2"
					( Origin gFrontEnd )
				)
				( attribute "TOLERANCE" "1%"
					( Origin gFrontEnd )
				)
				( attribute "VALUE" "4D02R2F-GP"
					( Origin gFrontEnd )
				)
				( attribute "VER" "1"
					( Origin gFrontEnd )
				)
				( attribute "XY" "(-1700,4550)"
					( Origin gFrontEnd )
				)
				( attribute "CHIPS_PART_NAME" "4D02R2F-GP"
					( Origin gPackager )
				)
				( attribute "CDS_PART_NAME" "4D02R2F-GP_SMD-RG2-4D02R2F-GP,A"
					( Origin gPackager )
				)
				( attribute "PACK_SIZE" "0402"
					( Origin gFrontEnd )
				)
				( attribute "CDS_LOCATION" "R12W13"
					( Origin gPackager )
				)
				( attribute "CDS_SEC" "1"
					( Origin gPackager )
				)
				( objectStatus "R12W13" )
			)
			( gate "@baseboard_fab2_lib.baseboard_fab2(sch_1):page235_i239"
				( attribute "CDS_LIB" "w_hdl"
					( Origin gPackager )
				)
				( attribute "CDS_LMAN_SYM_OUTLINE" "-50,25,50,-25"
					( Origin gPackager )
				)
				( attribute "LOCATION" "CF23"
					( Origin gFrontEnd )
				)
				( attribute "PACK_TYPE" "SMD-BCG"
					( Origin gFrontEnd )
				)
				( attribute "PART_NUMBER" "78.22034.1FL"
					( Origin gFrontEnd )
				)
				( attribute "PHYS_PAGE" "235"
					( Origin gFrontEnd )
				)
				( attribute "ROT" "1"
					( Origin gFrontEnd )
				)
				( attribute "VALUE" "SC22P50V2JN-4GP"
					( Origin gFrontEnd )
				)
				( attribute "VER" "1"
					( Origin gFrontEnd )
				)
				( attribute "XY" "(-11800,4450)"
					( Origin gFrontEnd )
				)
				( attribute "CHIPS_PART_NAME" "SC22P50V2JN-4GP"
					( Origin gPackager )
				)
				( attribute "CDS_PART_NAME" "SC22P50V2JN-4GP_SMD-BCG-SC22P5A"
					( Origin gPackager )
				)
				( attribute "CDS_LOCATION" "CF23"
					( Origin gPackager )
				)
				( attribute "CDS_SEC" "1"
					( Origin gPackager )
				)
				( attribute "SEC" "1"
					( Origin gPackager )
				)
				( attribute "ATTRIBUTE" "22PF"
					( Origin gFrontEnd )
				)
				( attribute "PACK_SIZE" "0402"
					( Origin gFrontEnd )
				)
				( attribute "RATED" "50V"
					( Origin gFrontEnd )
				)
				( attribute "TOLERANCE" "5%"
					( Origin gFrontEnd )
				)
				( attribute "TYPE" "NPO"
					( Origin gFrontEnd )
				)
				( attribute "GROUP" "POWER_FAIR"
					( Origin gFrontEnd )
				)
				( objectStatus "CF23" )
			)
			( gate "@baseboard_fab2_lib.baseboard_fab2(sch_1):page235_i240"
				( attribute "CDS_LIB" "w_hdl"
					( Origin gPackager )
				)
				( attribute "CDS_LMAN_SYM_OUTLINE" "-50,25,50,-25"
					( Origin gPackager )
				)
				( attribute "LOCATION" "CF24"
					( Origin gFrontEnd )
				)
				( attribute "PACK_TYPE" "SMD-BCG"
					( Origin gFrontEnd )
				)
				( attribute "PART_NUMBER" "78.22034.1FL"
					( Origin gFrontEnd )
				)
				( attribute "PHYS_PAGE" "235"
					( Origin gFrontEnd )
				)
				( attribute "ROT" "1"
					( Origin gFrontEnd )
				)
				( attribute "VALUE" "SC22P50V2JN-4GP"
					( Origin gFrontEnd )
				)
				( attribute "VER" "1"
					( Origin gFrontEnd )
				)
				( attribute "XY" "(-11100,2900)"
					( Origin gFrontEnd )
				)
				( attribute "CHIPS_PART_NAME" "SC22P50V2JN-4GP"
					( Origin gPackager )
				)
				( attribute "CDS_PART_NAME" "SC22P50V2JN-4GP_SMD-BCG-SC22P5A"
					( Origin gPackager )
				)
				( attribute "CDS_LOCATION" "CF24"
					( Origin gPackager )
				)
				( attribute "CDS_SEC" "1"
					( Origin gPackager )
				)
				( attribute "SEC" "1"
					( Origin gPackager )
				)
				( attribute "ATTRIBUTE" "22PF"
					( Origin gFrontEnd )
				)
				( attribute "PACK_SIZE" "0402"
					( Origin gFrontEnd )
				)
				( attribute "RATED" "50V"
					( Origin gFrontEnd )
				)
				( attribute "TOLERANCE" "5%"
					( Origin gFrontEnd )
				)
				( attribute "TYPE" "NPO"
					( Origin gFrontEnd )
				)
				( attribute "GROUP" "POWER_FAIR"
					( Origin gFrontEnd )
				)
				( objectStatus "CF24" )
			)
			( gate "@baseboard_fab2_lib.baseboard_fab2(sch_1):page151_i223"
				( attribute "ATTRIBUTE" "120OHM"
					( Origin gFrontEnd )
				)
				( attribute "CDS_LIB" "w_hdl"
					( Origin gPackager )
				)
				( attribute "CDS_LMAN_SYM_OUTLINE" "-50,75,50,-75"
					( Origin gPackager )
				)
				( attribute "LOCATION" "R25W27"
					( Origin gFrontEnd )
				)
				( attribute "PACK_TYPE" "RCL_GP"
					( Origin gFrontEnd )
				)
				( attribute "PART_NUMBER" "64.12005.6DL"
					( Origin gFrontEnd )
				)
				( attribute "PHYS_PAGE" "151"
					( Origin gFrontEnd )
				)
				( attribute "RATED" "1/16W"
					( Origin gFrontEnd )
				)
				( attribute "ROT" "1"
					( Origin gFrontEnd )
				)
				( attribute "SEC" "1"
					( Origin gFrontEnd )
				)
				( attribute "SEC_TYPE" "RCL_GP"
					( Origin gFrontEnd )
				)
				( attribute "TOLERANCE" "1%"
					( Origin gFrontEnd )
				)
				( attribute "VALUE" "120R2F-GP"
					( Origin gFrontEnd )
				)
				( attribute "VER" "1"
					( Origin gFrontEnd )
				)
				( attribute "XY" "(-950,1675)"
					( Origin gFrontEnd )
				)
				( attribute "CHIPS_PART_NAME" "120R2F-GP"
					( Origin gPackager )
				)
				( attribute "CDS_PART_NAME" "120R2F-GP_RCL_GP-120R2F-GP,64.A"
					( Origin gPackager )
				)
				( attribute "PACK_SIZE" "0402"
					( Origin gFrontEnd )
				)
				( attribute "CDS_LOCATION" "R25W27"
					( Origin gPackager )
				)
				( attribute "CDS_SEC" "1"
					( Origin gPackager )
				)
				( objectStatus "R25W27" )
			)
			( gate "@baseboard_fab2_lib.baseboard_fab2(sch_1):page144_i114"
				( attribute "BOM_COST" "SM_CONTROLLER"
					( Origin gFrontEnd )
				)
				( attribute "CDS_LIB" "mstr_discrete"
					( Origin gPackager )
				)
				( attribute "CDS_LOCATION" "R25W70"
					( Origin gPackager )
				)
				( attribute "CDS_SEC" "1"
					( Origin gPackager )
				)
				( attribute "LOCATION" "R25W70"
					( Origin gFrontEnd )
				)
				( attribute "MATERIAL" "CHIP"
					( Origin gFrontEnd )
				)
				( attribute "PACK_TYPE" "0402"
					( Origin gFrontEnd )
				)
				( attribute "PART_NUMBER" "G21796-074"
					( Origin gFrontEnd )
				)
				( attribute "PHYS_PAGE" "144"
					( Origin gFrontEnd )
				)
				( attribute "ROOM" "BMC"
					( Origin gFrontEnd )
				)
				( attribute "ROT" "0"
					( Origin gFrontEnd )
				)
				( attribute "SEC" "1"
					( Origin gFrontEnd )
				)
				( attribute "SEC_TYPE" "0402"
					( Origin gFrontEnd )
				)
				( attribute "TOLERANCE" "1%"
					( Origin gFrontEnd )
				)
				( attribute "VALUE" "33.2"
					( Origin gFrontEnd )
				)
				( attribute "VER" "1"
					( Origin gFrontEnd )
				)
				( attribute "WATTAGE" "1/16W"
					( Origin gFrontEnd )
				)
				( attribute "XY" "(-1750,-2800)"
					( Origin gFrontEnd )
				)
				( attribute "CHIPS_PART_NAME" "RES"
					( Origin gPackager )
				)
				( attribute "CDS_PART_NAME" "RES_0402-33.2,1%,1/16W,CHIP,G2A"
					( Origin gPackager )
				)
				( objectStatus "R25W70" )
			)
			( gate "@baseboard_fab2_lib.baseboard_fab2(sch_1):page144_i118"
				( attribute "BOM_COST" "SM_CONTROLLER"
					( Origin gFrontEnd )
				)
				( attribute "CDS_LIB" "mstr_discrete"
					( Origin gPackager )
				)
				( attribute "CDS_LOCATION" "R25W75"
					( Origin gPackager )
				)
				( attribute "CDS_SEC" "1"
					( Origin gPackager )
				)
				( attribute "LOCATION" "R25W75"
					( Origin gFrontEnd )
				)
				( attribute "MATERIAL" "CHIP"
					( Origin gFrontEnd )
				)
				( attribute "PACK_TYPE" "0402"
					( Origin gFrontEnd )
				)
				( attribute "PART_NUMBER" "G21796-074"
					( Origin gFrontEnd )
				)
				( attribute "PHYS_PAGE" "144"
					( Origin gFrontEnd )
				)
				( attribute "ROOM" "BMC"
					( Origin gFrontEnd )
				)
				( attribute "ROT" "0"
					( Origin gFrontEnd )
				)
				( attribute "SEC" "1"
					( Origin gFrontEnd )
				)
				( attribute "SEC_TYPE" "0402"
					( Origin gFrontEnd )
				)
				( attribute "TOLERANCE" "1%"
					( Origin gFrontEnd )
				)
				( attribute "VALUE" "33.2"
					( Origin gFrontEnd )
				)
				( attribute "VER" "1"
					( Origin gFrontEnd )
				)
				( attribute "WATTAGE" "1/16W"
					( Origin gFrontEnd )
				)
				( attribute "XY" "(-1750,-2750)"
					( Origin gFrontEnd )
				)
				( attribute "CHIPS_PART_NAME" "RES"
					( Origin gPackager )
				)
				( attribute "CDS_PART_NAME" "RES_0402-33.2,1%,1/16W,CHIP,G2A"
					( Origin gPackager )
				)
				( objectStatus "R25W75" )
			)
			( gate "@baseboard_fab2_lib.baseboard_fab2(sch_1):page228_i313"
				( attribute "BOM_COST" "MEM_VRD_PVDDQ_CD"
					( Origin gFrontEnd )
				)
				( attribute "CDS_LIB" "mstr_discrete"
					( Origin gPackager )
				)
				( attribute "CDS_LOCATION" "C2A16"
					( Origin gPackager )
				)
				( attribute "CDS_SEC" "1"
					( Origin gPackager )
				)
				( attribute "LOCATION" "C2A16"
					( Origin gFrontEnd )
				)
				( attribute "MATERIAL" "X5R"
					( Origin gFrontEnd )
				)
				( attribute "NEW_MATERIAL" "X6S"
					( Origin gFrontEnd )
				)
				( attribute "PACK_TYPE" "0805"
					( Origin gFrontEnd )
				)
				( attribute "PART_NUMBER" "602433-112"
					( Origin gFrontEnd )
				)
				( attribute "PHYS_PAGE" "228"
					( Origin gFrontEnd )
				)
				( attribute "ROOM" "VDDQ_ABC_PWR_VR"
					( Origin gFrontEnd )
				)
				( attribute "ROT" "0"
					( Origin gFrontEnd )
				)
				( attribute "SEC" "1"
					( Origin gFrontEnd )
				)
				( attribute "SEC_TYPE" "0805"
					( Origin gFrontEnd )
				)
				( attribute "TOLERANCE" "20%"
					( Origin gFrontEnd )
				)
				( attribute "VALUE" "100UF"
					( Origin gFrontEnd )
				)
				( attribute "VER" "1"
					( Origin gFrontEnd )
				)
				( attribute "VOLTAGE" "4V"
					( Units "uVoltage" "V" 1.000000)
					( Origin gFrontEnd )
				)
				( attribute "XY" "(3850,2825)"
					( Origin gFrontEnd )
				)
				( attribute "CHIPS_PART_NAME" "CAP"
					( Origin gPackager )
				)
				( attribute "CDS_PART_NAME" "CAP_0805-100UF,4V,20%,X5R,6024A"
					( Origin gPackager )
				)
				( attribute "GROUP" "PWR_MLCC_CAP"
					( Origin gFrontEnd )
				)
				( attribute "NEW_PN" "078.1071T.M002"
					( Origin gFrontEnd )
				)
				( attribute "BOM_SS" "NOPOP"
					( Origin gFrontEnd )
				)
				( objectStatus "C2A16" )
			)
			( gate "@baseboard_fab2_lib.baseboard_fab2(sch_1):page228_i304"
				( attribute "BOM_COST" "MEM_VRD_PVDDQ_CD"
					( Origin gFrontEnd )
				)
				( attribute "CDS_LIB" "mstr_discrete"
					( Origin gPackager )
				)
				( attribute "CDS_LOCATION" "C8P1"
					( Origin gPackager )
				)
				( attribute "CDS_SEC" "1"
					( Origin gPackager )
				)
				( attribute "LOCATION" "C8P1"
					( Origin gFrontEnd )
				)
				( attribute "MATERIAL" "X5R"
					( Origin gFrontEnd )
				)
				( attribute "NEW_MATERIAL" "X6S"
					( Origin gFrontEnd )
				)
				( attribute "PACK_TYPE" "0805"
					( Origin gFrontEnd )
				)
				( attribute "PART_NUMBER" "602433-112"
					( Origin gFrontEnd )
				)
				( attribute "PHYS_PAGE" "228"
					( Origin gFrontEnd )
				)
				( attribute "ROOM" "VDDQ_ABC_PWR_VR"
					( Origin gFrontEnd )
				)
				( attribute "ROT" "0"
					( Origin gFrontEnd )
				)
				( attribute "SEC" "1"
					( Origin gFrontEnd )
				)
				( attribute "SEC_TYPE" "0805"
					( Origin gFrontEnd )
				)
				( attribute "TOLERANCE" "20%"
					( Origin gFrontEnd )
				)
				( attribute "VALUE" "100UF"
					( Origin gFrontEnd )
				)
				( attribute "VER" "1"
					( Origin gFrontEnd )
				)
				( attribute "VOLTAGE" "4V"
					( Units "uVoltage" "V" 1.000000)
					( Origin gFrontEnd )
				)
				( attribute "XY" "(-1925,2975)"
					( Origin gFrontEnd )
				)
				( attribute "CHIPS_PART_NAME" "CAP"
					( Origin gPackager )
				)
				( attribute "CDS_PART_NAME" "CAP_0805-100UF,4V,20%,X5R,6024A"
					( Origin gPackager )
				)
				( attribute "GROUP" "PWR_MLCC_CAP"
					( Origin gFrontEnd )
				)
				( attribute "NEW_PN" "078.1071T.M002"
					( Origin gFrontEnd )
				)
				( attribute "BOM_SS" "NOPOP"
					( Origin gFrontEnd )
				)
				( objectStatus "C8P1" )
			)
			( gate "@baseboard_fab2_lib.baseboard_fab2(sch_1):page149_i17"
				( attribute "CDS_LIB" "mstr_discrete"
					( Origin gPackager )
				)
				( attribute "CDS_LOCATION" "C25W69"
					( Origin gPackager )
				)
				( attribute "CDS_SEC" "1"
					( Origin gPackager )
				)
				( attribute "LOCATION" "C25W69"
					( Origin gFrontEnd )
				)
				( attribute "MATERIAL" "X6S"
					( Origin gFrontEnd )
				)
				( attribute "PACK_TYPE" "0603"
					( Origin gFrontEnd )
				)
				( attribute "PART_NUMBER" "E15431-003"
					( Origin gFrontEnd )
				)
				( attribute "PHYS_PAGE" "149"
					( Origin gFrontEnd )
				)
				( attribute "ROT" "0"
					( Origin gFrontEnd )
				)
				( attribute "SEC" "1"
					( Origin gPackager )
				)
				( attribute "TOLERANCE" "10%"
					( Origin gFrontEnd )
				)
				( attribute "VALUE" "4.7UF"
					( Origin gFrontEnd )
				)
				( attribute "VER" "1"
					( Origin gFrontEnd )
				)
				( attribute "VOLTAGE" "6.3V"
					( Units "uVoltage" "V" 1.000000)
					( Origin gFrontEnd )
				)
				( attribute "XY" "(3100,5175)"
					( Origin gFrontEnd )
				)
				( attribute "CHIPS_PART_NAME" "CAP"
					( Origin gPackager )
				)
				( attribute "CDS_PART_NAME" "CAP_0603-4.7UF,6.3V,10%,X6S,E1A"
					( Origin gPackager )
				)
				( objectStatus "C25W69" )
			)
			( gate "@baseboard_fab2_lib.baseboard_fab2(sch_1):page247_i151"
				( attribute "CDS_LIB" "dev_discrete"
					( Origin gPackager )
				)
				( attribute "CDS_LOCATION" "C6W1"
					( Origin gPackager )
				)
				( attribute "CDS_SEC" "1"
					( Origin gPackager )
				)
				( attribute "LOCATION" "C6W1"
					( Origin gFrontEnd )
				)
				( attribute "MATERIAL" "X7R"
					( Origin gFrontEnd )
				)
				( attribute "PACK_TYPE" "0402V"
					( Origin gFrontEnd )
				)
				( attribute "PART_NUMBER" "A36096-030"
					( Origin gFrontEnd )
				)
				( attribute "PHYS_PAGE" "247"
					( Origin gFrontEnd )
				)
				( attribute "ROOM" "VDDQ_KLM_PWR_VR"
					( Origin gFrontEnd )
				)
				( attribute "ROT" "0"
					( Origin gFrontEnd )
				)
				( attribute "SEC" "1"
					( Origin gFrontEnd )
				)
				( attribute "SEC_TYPE" "0402V"
					( Origin gFrontEnd )
				)
				( attribute "TOLERANCE" "10%"
					( Origin gFrontEnd )
				)
				( attribute "VALUE" "0.1UF"
					( Origin gFrontEnd )
				)
				( attribute "VER" "1"
					( Origin gFrontEnd )
				)
				( attribute "VOLTAGE" "16V"
					( Units "uVoltage" "V" 1.000000)
					( Origin gFrontEnd )
				)
				( attribute "XY" "(-5200,4200)"
					( Origin gFrontEnd )
				)
				( attribute "CHIPS_PART_NAME" "CAP_A"
					( Origin gPackager )
				)
				( attribute "CDS_PART_NAME" "CAP_A_0402V-0.1UF,16V,10%,X7R,A"
					( Origin gPackager )
				)
				( objectStatus "C6W1" )
			)
			( gate "@baseboard_fab2_lib.baseboard_fab2(sch_1):page149_i22"
				( attribute "CDS_LIB" "w_hdl"
					( Origin gPackager )
				)
				( attribute "CDS_LMAN_SYM_OUTLINE" "-50,100,50,-100"
					( Origin gPackager )
				)
				( attribute "CDS_LOCATION" "FB2T1"
					( Origin gPackager )
				)
				( attribute "CDS_SEC" "1"
					( Origin gPackager )
				)
				( attribute "LOCATION" "FB2T1"
					( Origin gFrontEnd )
				)
				( attribute "PACK_TYPE" "DISCRET-G9"
					( Origin gFrontEnd )
				)
				( attribute "PART_NUMBER" "68.00230.231"
					( Origin gFrontEnd )
				)
				( attribute "PHYS_PAGE" "149"
					( Origin gFrontEnd )
				)
				( attribute "ROT" "1"
					( Origin gFrontEnd )
				)
				( attribute "SEC" "1"
					( Origin gPackager )
				)
				( attribute "VALUE" "HCB1608KF-800T30-GP"
					( Origin gFrontEnd )
				)
				( attribute "VER" "1"
					( Origin gFrontEnd )
				)
				( attribute "XY" "(1500,5500)"
					( Origin gFrontEnd )
				)
				( attribute "CHIPS_PART_NAME" "HCB1608KF-800T30-GP"
					( Origin gPackager )
				)
				( attribute "CDS_PART_NAME" "HCB1608KF-800T30-GP_DISCRET-G9A"
					( Origin gPackager )
				)
				( attribute "ATTRIBUTE" "80OHM@100MHZ"
					( Origin gFrontEnd )
				)
				( attribute "PACK_SIZE" "DCR=4MOHM"
					( Origin gFrontEnd )
				)
				( attribute "RATED" "3A"
					( Origin gFrontEnd )
				)
				( objectStatus "FB2T1" )
			)
			( gate "@baseboard_fab2_lib.baseboard_fab2(sch_1):page149_i25"
				( attribute "CDS_LIB" "mstr_discrete"
					( Origin gPackager )
				)
				( attribute "CDS_LOCATION" "C25W39"
					( Origin gPackager )
				)
				( attribute "CDS_SEC" "1"
					( Origin gPackager )
				)
				( attribute "LOCATION" "C25W39"
					( Origin gFrontEnd )
				)
				( attribute "MATERIAL" "X6S"
					( Origin gFrontEnd )
				)
				( attribute "PACK_TYPE" "0603"
					( Origin gFrontEnd )
				)
				( attribute "PART_NUMBER" "E15431-003"
					( Origin gFrontEnd )
				)
				( attribute "PHYS_PAGE" "149"
					( Origin gFrontEnd )
				)
				( attribute "ROT" "0"
					( Origin gFrontEnd )
				)
				( attribute "SEC" "1"
					( Origin gPackager )
				)
				( attribute "TOLERANCE" "10%"
					( Origin gFrontEnd )
				)
				( attribute "VALUE" "4.7UF"
					( Origin gFrontEnd )
				)
				( attribute "VER" "1"
					( Origin gFrontEnd )
				)
				( attribute "VOLTAGE" "6.3V"
					( Units "uVoltage" "V" 1.000000)
					( Origin gFrontEnd )
				)
				( attribute "XY" "(3725,3975)"
					( Origin gFrontEnd )
				)
				( attribute "CHIPS_PART_NAME" "CAP"
					( Origin gPackager )
				)
				( attribute "CDS_PART_NAME" "CAP_0603-4.7UF,6.3V,10%,X6S,E1A"
					( Origin gPackager )
				)
				( objectStatus "C25W39" )
			)
			( gate "@baseboard_fab2_lib.baseboard_fab2(sch_1):page149_i31"
				( attribute "CDS_LIB" "mstr_discrete"
					( Origin gPackager )
				)
				( attribute "CDS_LOCATION" "C25W50"
					( Origin gPackager )
				)
				( attribute "CDS_SEC" "1"
					( Origin gPackager )
				)
				( attribute "LOCATION" "C25W50"
					( Origin gFrontEnd )
				)
				( attribute "MATERIAL" "X6S"
					( Origin gFrontEnd )
				)
				( attribute "PACK_TYPE" "0603"
					( Origin gFrontEnd )
				)
				( attribute "PART_NUMBER" "E15431-003"
					( Origin gFrontEnd )
				)
				( attribute "PHYS_PAGE" "149"
					( Origin gFrontEnd )
				)
				( attribute "ROT" "0"
					( Origin gFrontEnd )
				)
				( attribute "SEC" "1"
					( Origin gPackager )
				)
				( attribute "TOLERANCE" "10%"
					( Origin gFrontEnd )
				)
				( attribute "VALUE" "4.7UF"
					( Origin gFrontEnd )
				)
				( attribute "VER" "1"
					( Origin gFrontEnd )
				)
				( attribute "VOLTAGE" "6.3V"
					( Units "uVoltage" "V" 1.000000)
					( Origin gFrontEnd )
				)
				( attribute "XY" "(3275,3000)"
					( Origin gFrontEnd )
				)
				( attribute "CHIPS_PART_NAME" "CAP"
					( Origin gPackager )
				)
				( attribute "CDS_PART_NAME" "CAP_0603-4.7UF,6.3V,10%,X6S,E1A"
					( Origin gPackager )
				)
				( objectStatus "C25W50" )
			)
			( gate "@baseboard_fab2_lib.baseboard_fab2(sch_1):page149_i40"
				( attribute "CDS_LIB" "mstr_discrete"
					( Origin gPackager )
				)
				( attribute "CDS_LOCATION" "C25W62"
					( Origin gPackager )
				)
				( attribute "CDS_SEC" "1"
					( Origin gPackager )
				)
				( attribute "LOCATION" "C25W62"
					( Origin gFrontEnd )
				)
				( attribute "MATERIAL" "X6S"
					( Origin gFrontEnd )
				)
				( attribute "PACK_TYPE" "0603"
					( Origin gFrontEnd )
				)
				( attribute "PART_NUMBER" "E15431-003"
					( Origin gFrontEnd )
				)
				( attribute "PHYS_PAGE" "149"
					( Origin gFrontEnd )
				)
				( attribute "ROT" "0"
					( Origin gFrontEnd )
				)
				( attribute "SEC" "1"
					( Origin gPackager )
				)
				( attribute "TOLERANCE" "10%"
					( Origin gFrontEnd )
				)
				( attribute "VALUE" "4.7UF"
					( Origin gFrontEnd )
				)
				( attribute "VER" "1"
					( Origin gFrontEnd )
				)
				( attribute "VOLTAGE" "6.3V"
					( Units "uVoltage" "V" 1.000000)
					( Origin gFrontEnd )
				)
				( attribute "XY" "(2425,1750)"
					( Origin gFrontEnd )
				)
				( attribute "CHIPS_PART_NAME" "CAP"
					( Origin gPackager )
				)
				( attribute "CDS_PART_NAME" "CAP_0603-4.7UF,6.3V,10%,X6S,E1A"
					( Origin gPackager )
				)
				( objectStatus "C25W62" )
			)
			( gate "@baseboard_fab2_lib.baseboard_fab2(sch_1):page149_i42"
				( attribute "CDS_LIB" "w_hdl"
					( Origin gPackager )
				)
				( attribute "CDS_LMAN_SYM_OUTLINE" "-50,100,50,-100"
					( Origin gPackager )
				)
				( attribute "CDS_LOCATION" "FB2T7"
					( Origin gPackager )
				)
				( attribute "CDS_SEC" "1"
					( Origin gPackager )
				)
				( attribute "LOCATION" "FB2T7"
					( Origin gFrontEnd )
				)
				( attribute "PACK_TYPE" "DISCRET-G9"
					( Origin gFrontEnd )
				)
				( attribute "PART_NUMBER" "68.00230.231"
					( Origin gFrontEnd )
				)
				( attribute "PHYS_PAGE" "149"
					( Origin gFrontEnd )
				)
				( attribute "ROT" "1"
					( Origin gFrontEnd )
				)
				( attribute "SEC" "1"
					( Origin gPackager )
				)
				( attribute "VALUE" "HCB1608KF-800T30-GP"
					( Origin gFrontEnd )
				)
				( attribute "VER" "1"
					( Origin gFrontEnd )
				)
				( attribute "XY" "(2325,4300)"
					( Origin gFrontEnd )
				)
				( attribute "CHIPS_PART_NAME" "HCB1608KF-800T30-GP"
					( Origin gPackager )
				)
				( attribute "CDS_PART_NAME" "HCB1608KF-800T30-GP_DISCRET-G9A"
					( Origin gPackager )
				)
				( attribute "ATTRIBUTE" "80OHM@100MHZ"
					( Origin gFrontEnd )
				)
				( attribute "PACK_SIZE" "DCR=4MOHM"
					( Origin gFrontEnd )
				)
				( attribute "RATED" "3A"
					( Origin gFrontEnd )
				)
				( objectStatus "FB2T7" )
			)
			( gate "@baseboard_fab2_lib.baseboard_fab2(sch_1):page149_i46"
				( attribute "CDS_LIB" "mstr_discrete"
					( Origin gPackager )
				)
				( attribute "CDS_LOCATION" "C25W36"
					( Origin gPackager )
				)
				( attribute "CDS_SEC" "1"
					( Origin gPackager )
				)
				( attribute "LOCATION" "C25W36"
					( Origin gFrontEnd )
				)
				( attribute "MATERIAL" "X6S"
					( Origin gFrontEnd )
				)
				( attribute "PACK_TYPE" "0603"
					( Origin gFrontEnd )
				)
				( attribute "PART_NUMBER" "E15431-003"
					( Origin gFrontEnd )
				)
				( attribute "PHYS_PAGE" "149"
					( Origin gFrontEnd )
				)
				( attribute "ROT" "0"
					( Origin gFrontEnd )
				)
				( attribute "SEC" "1"
					( Origin gPackager )
				)
				( attribute "TOLERANCE" "10%"
					( Origin gFrontEnd )
				)
				( attribute "VALUE" "4.7UF"
					( Origin gFrontEnd )
				)
				( attribute "VER" "1"
					( Origin gFrontEnd )
				)
				( attribute "VOLTAGE" "6.3V"
					( Units "uVoltage" "V" 1.000000)
					( Origin gFrontEnd )
				)
				( attribute "XY" "(1125,4000)"
					( Origin gFrontEnd )
				)
				( attribute "CHIPS_PART_NAME" "CAP"
					( Origin gPackager )
				)
				( attribute "CDS_PART_NAME" "CAP_0603-4.7UF,6.3V,10%,X6S,E1A"
					( Origin gPackager )
				)
				( objectStatus "C25W36" )
			)
			( gate "@baseboard_fab2_lib.baseboard_fab2(sch_1):page149_i126"
				( attribute "CDS_LIB" "dev_discrete"
					( Origin gPackager )
				)
				( attribute "CDS_LOCATION" "C25W61"
					( Origin gPackager )
				)
				( attribute "CDS_SEC" "1"
					( Origin gPackager )
				)
				( attribute "LOCATION" "C25W61"
					( Origin gFrontEnd )
				)
				( attribute "MATERIAL" "X7R"
					( Origin gFrontEnd )
				)
				( attribute "PACK_TYPE" "0402V"
					( Origin gFrontEnd )
				)
				( attribute "PART_NUMBER" "A36096-030"
					( Origin gFrontEnd )
				)
				( attribute "PHYS_PAGE" "149"
					( Origin gFrontEnd )
				)
				( attribute "ROOM" "VDDQ_KLM_PWR_VR"
					( Origin gFrontEnd )
				)
				( attribute "ROT" "0"
					( Origin gFrontEnd )
				)
				( attribute "SEC" "1"
					( Origin gFrontEnd )
				)
				( attribute "SEC_TYPE" "0402V"
					( Origin gFrontEnd )
				)
				( attribute "TOLERANCE" "10%"
					( Origin gFrontEnd )
				)
				( attribute "VALUE" "0.1UF"
					( Origin gFrontEnd )
				)
				( attribute "VER" "1"
					( Origin gFrontEnd )
				)
				( attribute "VOLTAGE" "16V"
					( Units "uVoltage" "V" 1.000000)
					( Origin gFrontEnd )
				)
				( attribute "XY" "(2025,1750)"
					( Origin gFrontEnd )
				)
				( attribute "CHIPS_PART_NAME" "CAP_A"
					( Origin gPackager )
				)
				( attribute "CDS_PART_NAME" "CAP_A_0402V-0.1UF,16V,10%,X7R,A"
					( Origin gPackager )
				)
				( objectStatus "C25W61" )
			)
			( gate "@baseboard_fab2_lib.baseboard_fab2(sch_1):page149_i50"
				( attribute "CDS_LIB" "mstr_discrete"
					( Origin gPackager )
				)
				( attribute "CDS_LOCATION" "C25W47"
					( Origin gPackager )
				)
				( attribute "CDS_SEC" "1"
					( Origin gPackager )
				)
				( attribute "LOCATION" "C25W47"
					( Origin gFrontEnd )
				)
				( attribute "MATERIAL" "X6S"
					( Origin gFrontEnd )
				)
				( attribute "PACK_TYPE" "0603"
					( Origin gFrontEnd )
				)
				( attribute "PART_NUMBER" "E15431-003"
					( Origin gFrontEnd )
				)
				( attribute "PHYS_PAGE" "149"
					( Origin gFrontEnd )
				)
				( attribute "ROT" "0"
					( Origin gFrontEnd )
				)
				( attribute "SEC" "1"
					( Origin gPackager )
				)
				( attribute "TOLERANCE" "10%"
					( Origin gFrontEnd )
				)
				( attribute "VALUE" "4.7UF"
					( Origin gFrontEnd )
				)
				( attribute "VER" "1"
					( Origin gFrontEnd )
				)
				( attribute "VOLTAGE" "6.3V"
					( Units "uVoltage" "V" 1.000000)
					( Origin gFrontEnd )
				)
				( attribute "XY" "(550,2900)"
					( Origin gFrontEnd )
				)
				( attribute "CHIPS_PART_NAME" "CAP"
					( Origin gPackager )
				)
				( attribute "CDS_PART_NAME" "CAP_0603-4.7UF,6.3V,10%,X6S,E1A"
					( Origin gPackager )
				)
				( objectStatus "C25W47" )
			)
			( gate "@baseboard_fab2_lib.baseboard_fab2(sch_1):page149_i51"
				( attribute "BOM_COST" "SM_CONTROLLER"
					( Origin gFrontEnd )
				)
				( attribute "CDS_LIB" "mstr_discrete"
					( Origin gPackager )
				)
				( attribute "CDS_LOCATION" "C25W46"
					( Origin gPackager )
				)
				( attribute "CDS_SEC" "1"
					( Origin gPackager )
				)
				( attribute "LOCATION" "C25W46"
					( Origin gFrontEnd )
				)
				( attribute "MATERIAL" "X6S"
					( Origin gFrontEnd )
				)
				( attribute "PACK_TYPE" "0805"
					( Origin gFrontEnd )
				)
				( attribute "PART_NUMBER" "C95333-007"
					( Origin gFrontEnd )
				)
				( attribute "PHYS_PAGE" "149"
					( Origin gFrontEnd )
				)
				( attribute "ROOM" "BMC"
					( Origin gFrontEnd )
				)
				( attribute "ROT" "0"
					( Origin gFrontEnd )
				)
				( attribute "SEC" "1"
					( Origin gPackager )
				)
				( attribute "TOLERANCE" "10%"
					( Origin gFrontEnd )
				)
				( attribute "VALUE" "10UF"
					( Origin gFrontEnd )
				)
				( attribute "VER" "1"
					( Origin gFrontEnd )
				)
				( attribute "VOLTAGE" "16V"
					( Units "uVoltage" "V" 1.000000)
					( Origin gFrontEnd )
				)
				( attribute "XY" "(250,2900)"
					( Origin gFrontEnd )
				)
				( attribute "CHIPS_PART_NAME" "CAP"
					( Origin gPackager )
				)
				( attribute "CDS_PART_NAME" "CAP_0805-10UF,16V,10%,X6S,C953A"
					( Origin gPackager )
				)
				( objectStatus "C25W46" )
			)
			( gate "@baseboard_fab2_lib.baseboard_fab2(sch_1):page149_i128"
				( attribute "CDS_LIB" "dev_discrete"
					( Origin gPackager )
				)
				( attribute "CDS_LOCATION" "C25W68"
					( Origin gPackager )
				)
				( attribute "CDS_SEC" "1"
					( Origin gPackager )
				)
				( attribute "LOCATION" "C25W68"
					( Origin gFrontEnd )
				)
				( attribute "MATERIAL" "X7R"
					( Origin gFrontEnd )
				)
				( attribute "PACK_TYPE" "0402V"
					( Origin gFrontEnd )
				)
				( attribute "PART_NUMBER" "A36096-030"
					( Origin gFrontEnd )
				)
				( attribute "PHYS_PAGE" "149"
					( Origin gFrontEnd )
				)
				( attribute "ROOM" "VDDQ_KLM_PWR_VR"
					( Origin gFrontEnd )
				)
				( attribute "ROT" "0"
					( Origin gFrontEnd )
				)
				( attribute "SEC" "1"
					( Origin gFrontEnd )
				)
				( attribute "SEC_TYPE" "0402V"
					( Origin gFrontEnd )
				)
				( attribute "TOLERANCE" "10%"
					( Origin gFrontEnd )
				)
				( attribute "VALUE" "0.1UF"
					( Origin gFrontEnd )
				)
				( attribute "VER" "1"
					( Origin gFrontEnd )
				)
				( attribute "VOLTAGE" "16V"
					( Units "uVoltage" "V" 1.000000)
					( Origin gFrontEnd )
				)
				( attribute "XY" "(2700,5175)"
					( Origin gFrontEnd )
				)
				( attribute "CHIPS_PART_NAME" "CAP_A"
					( Origin gPackager )
				)
				( attribute "CDS_PART_NAME" "CAP_A_0402V-0.1UF,16V,10%,X7R,A"
					( Origin gPackager )
				)
				( objectStatus "C25W68" )
			)
			( gate "@baseboard_fab2_lib.baseboard_fab2(sch_1):page268_i36"
				( attribute "ATTRIBUTE" "374 OHM"
					( Origin gFrontEnd )
				)
				( attribute "CDS_LIB" "w_hdl"
					( Origin gPackager )
				)
				( attribute "CDS_LMAN_SYM_OUTLINE" "-50,75,50,-75"
					( Origin gPackager )
				)
				( attribute "CDS_LOCATION" "R25W183"
					( Origin gPackager )
				)
				( attribute "CDS_SEC" "1"
					( Origin gPackager )
				)
				( attribute "LOCATION" "R25W183"
					( Origin gFrontEnd )
				)
				( attribute "PACK_SIZE" "0402"
					( Origin gFrontEnd )
				)
				( attribute "PACK_TYPE" "SMD-RG"
					( Origin gFrontEnd )
				)
				( attribute "PART_NUMBER" "64.37405.6DL"
					( Origin gFrontEnd )
				)
				( attribute "PHYS_PAGE" "255"
					( Origin gFrontEnd )
				)
				( attribute "RATED" "1/16W"
					( Origin gFrontEnd )
				)
				( attribute "ROT" "0"
					( Origin gFrontEnd )
				)
				( attribute "SEC" "1"
					( Origin gPackager )
				)
				( attribute "TOLERANCE" "1%"
					( Origin gFrontEnd )
				)
				( attribute "VALUE" "374R2F-1-GP"
					( Origin gFrontEnd )
				)
				( attribute "VER" "1"
					( Origin gFrontEnd )
				)
				( attribute "XY" "(-5150,6225)"
					( Origin gFrontEnd )
				)
				( attribute "CHIPS_PART_NAME" "374R2F-1-GP"
					( Origin gPackager )
				)
				( attribute "CDS_PART_NAME" "374R2F-1-GP_SMD-RG-374R2F-1-GPA"
					( Origin gPackager )
				)
				( objectStatus "R25W183" )
			)
			( gate "@baseboard_fab2_lib.baseboard_fab2(sch_1):page149_i125"
				( attribute "CDS_LIB" "dev_discrete"
					( Origin gPackager )
				)
				( attribute "CDS_LOCATION" "C25W58"
					( Origin gPackager )
				)
				( attribute "CDS_SEC" "1"
					( Origin gPackager )
				)
				( attribute "LOCATION" "C25W58"
					( Origin gFrontEnd )
				)
				( attribute "MATERIAL" "X7R"
					( Origin gFrontEnd )
				)
				( attribute "PACK_TYPE" "0402V"
					( Origin gFrontEnd )
				)
				( attribute "PART_NUMBER" "A36096-030"
					( Origin gFrontEnd )
				)
				( attribute "PHYS_PAGE" "149"
					( Origin gFrontEnd )
				)
				( attribute "ROOM" "VDDQ_KLM_PWR_VR"
					( Origin gFrontEnd )
				)
				( attribute "ROT" "0"
					( Origin gFrontEnd )
				)
				( attribute "SEC" "1"
					( Origin gFrontEnd )
				)
				( attribute "SEC_TYPE" "0402V"
					( Origin gFrontEnd )
				)
				( attribute "TOLERANCE" "10%"
					( Origin gFrontEnd )
				)
				( attribute "VALUE" "0.1UF"
					( Origin gFrontEnd )
				)
				( attribute "VER" "1"
					( Origin gFrontEnd )
				)
				( attribute "VOLTAGE" "16V"
					( Units "uVoltage" "V" 1.000000)
					( Origin gFrontEnd )
				)
				( attribute "XY" "(-1150,1850)"
					( Origin gFrontEnd )
				)
				( attribute "CHIPS_PART_NAME" "CAP_A"
					( Origin gPackager )
				)
				( attribute "CDS_PART_NAME" "CAP_A_0402V-0.1UF,16V,10%,X7R,A"
					( Origin gPackager )
				)
				( objectStatus "C25W58" )
			)
			( gate "@baseboard_fab2_lib.baseboard_fab2(sch_1):page149_i79"
				( attribute "CDS_LIB" "mstr_discrete"
					( Origin gPackager )
				)
				( attribute "CDS_LOCATION" "C25W59"
					( Origin gPackager )
				)
				( attribute "LOCATION" "C25W59"
					( Origin gFrontEnd )
				)
				( attribute "MATERIAL" "X6S"
					( Origin gFrontEnd )
				)
				( attribute "PACK_TYPE" "0603"
					( Origin gFrontEnd )
				)
				( attribute "PART_NUMBER" "E15431-003"
					( Origin gFrontEnd )
				)
				( attribute "PHYS_PAGE" "149"
					( Origin gFrontEnd )
				)
				( attribute "ROT" "0"
					( Origin gFrontEnd )
				)
				( attribute "SEC" "1"
					( Origin gFrontEnd )
				)
				( attribute "TOLERANCE" "10%"
					( Origin gFrontEnd )
				)
				( attribute "VALUE" "4.7UF"
					( Origin gFrontEnd )
				)
				( attribute "VER" "1"
					( Origin gFrontEnd )
				)
				( attribute "VOLTAGE" "6.3V"
					( Units "uVoltage" "V" 1.000000)
					( Origin gFrontEnd )
				)
				( attribute "XY" "(-550,1850)"
					( Origin gFrontEnd )
				)
				( attribute "CHIPS_PART_NAME" "CAP"
					( Origin gPackager )
				)
				( attribute "CDS_PART_NAME" "CAP_0603-4.7UF,6.3V,10%,X6S,E1A"
					( Origin gPackager )
				)
				( attribute "SEC_TYPE" "0603"
					( Origin gFrontEnd )
				)
				( attribute "CDS_SEC" "1"
					( Origin gPackager )
				)
				( attribute "POP" "NOPOP"
					( Origin gFrontEnd )
				)
				( objectStatus "C25W59" )
			)
			( gate "@baseboard_fab2_lib.baseboard_fab2(sch_1):page143_i67"
				( attribute "CDS_LIB" "dev_discrete"
					( Origin gPackager )
				)
				( attribute "CDS_LOCATION" "C25W22"
					( Origin gPackager )
				)
				( attribute "CDS_SEC" "1"
					( Origin gPackager )
				)
				( attribute "LOCATION" "C25W22"
					( Origin gFrontEnd )
				)
				( attribute "MATERIAL" "X7R"
					( Origin gFrontEnd )
				)
				( attribute "PACK_TYPE" "0402V"
					( Origin gFrontEnd )
				)
				( attribute "PART_NUMBER" "A36096-030"
					( Origin gFrontEnd )
				)
				( attribute "PHYS_PAGE" "143"
					( Origin gFrontEnd )
				)
				( attribute "ROOM" "VDDQ_KLM_PWR_VR"
					( Origin gFrontEnd )
				)
				( attribute "ROT" "0"
					( Origin gFrontEnd )
				)
				( attribute "SEC" "1"
					( Origin gFrontEnd )
				)
				( attribute "SEC_TYPE" "0402V"
					( Origin gFrontEnd )
				)
				( attribute "TOLERANCE" "10%"
					( Origin gFrontEnd )
				)
				( attribute "VALUE" "0.1UF"
					( Origin gFrontEnd )
				)
				( attribute "VER" "1"
					( Origin gFrontEnd )
				)
				( attribute "VOLTAGE" "16V"
					( Units "uVoltage" "V" 1.000000)
					( Origin gFrontEnd )
				)
				( attribute "XY" "(-10550,-2450)"
					( Origin gFrontEnd )
				)
				( attribute "CHIPS_PART_NAME" "CAP_A"
					( Origin gPackager )
				)
				( attribute "CDS_PART_NAME" "CAP_A_0402V-0.1UF,16V,10%,X7R,A"
					( Origin gPackager )
				)
				( objectStatus "C25W22" )
			)
			( gate "@baseboard_fab2_lib.baseboard_fab2(sch_1):page250_i12"
				( attribute "BOM_COST" "DEBUG"
					( Origin gFrontEnd )
				)
				( attribute "CDS_LIB" "mstr_discrete"
					( Origin gPackager )
				)
				( attribute "CDS_LOCATION" "Q1W2"
					( Origin gPackager )
				)
				( attribute "CDS_SEC" "2"
					( Origin gPackager )
				)
				( attribute "LOCATION" "Q1W2"
					( Origin gFrontEnd )
				)
				( attribute "MATERIAL" "FET"
					( Origin gFrontEnd )
				)
				( attribute "PACK_TYPE" "SMLF"
					( Origin gFrontEnd )
				)
				( attribute "PART_NUMBER" "D24280-001"
					( Origin gFrontEnd )
				)
				( attribute "PHYS_PAGE" "250"
					( Origin gFrontEnd )
				)
				( attribute "ROOM" "UART_MUX"
					( Origin gFrontEnd )
				)
				( attribute "ROT" "0"
					( Origin gFrontEnd )
				)
				( attribute "SEC" "2"
					( Origin gFrontEnd )
				)
				( attribute "SEC_TYPE" "SMLF"
					( Origin gFrontEnd )
				)
				( attribute "VALUE" "2N7002DW"
					( Origin gFrontEnd )
				)
				( attribute "VER" "5"
					( Origin gFrontEnd )
				)
				( attribute "XY" "(-6525,4125)"
					( Origin gFrontEnd )
				)
				( attribute "CHIPS_PART_NAME" "FET_N_DUAL"
					( Origin gPackager )
				)
				( attribute "CDS_PART_NAME" "FET_N_DUAL_SMLF-2N7002DW,FET,DA"
					( Origin gPackager )
				)
				( objectStatus "Q1W2" )
			)
			( gate "@baseboard_fab2_lib.baseboard_fab2(sch_1):page149_i85"
				( attribute "CDS_LIB" "w_hdl"
					( Origin gPackager )
				)
				( attribute "CDS_LMAN_SYM_OUTLINE" "-50,100,50,-100"
					( Origin gPackager )
				)
				( attribute "CDS_LOCATION" "FB2T3"
					( Origin gPackager )
				)
				( attribute "CDS_SEC" "1"
					( Origin gPackager )
				)
				( attribute "LOCATION" "FB2T3"
					( Origin gFrontEnd )
				)
				( attribute "PACK_TYPE" "DISCRET-G9"
					( Origin gFrontEnd )
				)
				( attribute "PART_NUMBER" "68.00230.231"
					( Origin gFrontEnd )
				)
				( attribute "PHYS_PAGE" "149"
					( Origin gFrontEnd )
				)
				( attribute "ROT" "1"
					( Origin gFrontEnd )
				)
				( attribute "SEC" "1"
					( Origin gPackager )
				)
				( attribute "VALUE" "HCB1608KF-800T30-GP"
					( Origin gFrontEnd )
				)
				( attribute "VER" "1"
					( Origin gFrontEnd )
				)
				( attribute "XY" "(-2075,4400)"
					( Origin gFrontEnd )
				)
				( attribute "CHIPS_PART_NAME" "HCB1608KF-800T30-GP"
					( Origin gPackager )
				)
				( attribute "CDS_PART_NAME" "HCB1608KF-800T30-GP_DISCRET-G9A"
					( Origin gPackager )
				)
				( attribute "ATTRIBUTE" "80OHM@100MHZ"
					( Origin gFrontEnd )
				)
				( attribute "PACK_SIZE" "DCR=4MOHM"
					( Origin gFrontEnd )
				)
				( attribute "RATED" "3A"
					( Origin gFrontEnd )
				)
				( objectStatus "FB2T3" )
			)
			( gate "@baseboard_fab2_lib.baseboard_fab2(sch_1):page149_i86"
				( attribute "CDS_LIB" "w_hdl"
					( Origin gPackager )
				)
				( attribute "CDS_LMAN_SYM_OUTLINE" "-50,100,50,-100"
					( Origin gPackager )
				)
				( attribute "CDS_LOCATION" "FB2T4"
					( Origin gPackager )
				)
				( attribute "CDS_SEC" "1"
					( Origin gPackager )
				)
				( attribute "LOCATION" "FB2T4"
					( Origin gFrontEnd )
				)
				( attribute "PACK_TYPE" "DISCRET-G9"
					( Origin gFrontEnd )
				)
				( attribute "PART_NUMBER" "68.00230.231"
					( Origin gFrontEnd )
				)
				( attribute "PHYS_PAGE" "149"
					( Origin gFrontEnd )
				)
				( attribute "ROT" "1"
					( Origin gFrontEnd )
				)
				( attribute "SEC" "1"
					( Origin gPackager )
				)
				( attribute "VALUE" "HCB1608KF-800T30-GP"
					( Origin gFrontEnd )
				)
				( attribute "VER" "1"
					( Origin gFrontEnd )
				)
				( attribute "XY" "(-2050,3200)"
					( Origin gFrontEnd )
				)
				( attribute "CHIPS_PART_NAME" "HCB1608KF-800T30-GP"
					( Origin gPackager )
				)
				( attribute "CDS_PART_NAME" "HCB1608KF-800T30-GP_DISCRET-G9A"
					( Origin gPackager )
				)
				( attribute "ATTRIBUTE" "80OHM@100MHZ"
					( Origin gFrontEnd )
				)
				( attribute "PACK_SIZE" "DCR=4MOHM"
					( Origin gFrontEnd )
				)
				( attribute "RATED" "3A"
					( Origin gFrontEnd )
				)
				( objectStatus "FB2T4" )
			)
			( gate "@baseboard_fab2_lib.baseboard_fab2(sch_1):page149_i88"
				( attribute "CDS_LIB" "w_hdl"
					( Origin gPackager )
				)
				( attribute "CDS_LMAN_SYM_OUTLINE" "-50,100,50,-100"
					( Origin gPackager )
				)
				( attribute "CDS_LOCATION" "FB2T5"
					( Origin gPackager )
				)
				( attribute "CDS_SEC" "1"
					( Origin gPackager )
				)
				( attribute "LOCATION" "FB2T5"
					( Origin gFrontEnd )
				)
				( attribute "PACK_TYPE" "DISCRET-G9"
					( Origin gFrontEnd )
				)
				( attribute "PART_NUMBER" "68.00230.231"
					( Origin gFrontEnd )
				)
				( attribute "PHYS_PAGE" "149"
					( Origin gFrontEnd )
				)
				( attribute "ROT" "1"
					( Origin gFrontEnd )
				)
				( attribute "SEC" "1"
					( Origin gPackager )
				)
				( attribute "VALUE" "HCB1608KF-800T30-GP"
					( Origin gFrontEnd )
				)
				( attribute "VER" "1"
					( Origin gFrontEnd )
				)
				( attribute "XY" "(-2025,2150)"
					( Origin gFrontEnd )
				)
				( attribute "CHIPS_PART_NAME" "HCB1608KF-800T30-GP"
					( Origin gPackager )
				)
				( attribute "CDS_PART_NAME" "HCB1608KF-800T30-GP_DISCRET-G9A"
					( Origin gPackager )
				)
				( attribute "ATTRIBUTE" "80OHM@100MHZ"
					( Origin gFrontEnd )
				)
				( attribute "PACK_SIZE" "DCR=4MOHM"
					( Origin gFrontEnd )
				)
				( attribute "RATED" "3A"
					( Origin gFrontEnd )
				)
				( objectStatus "FB2T5" )
			)
			( gate "@baseboard_fab2_lib.baseboard_fab2(sch_1):page202_i115"
				( attribute "ATTRIBUTE" "1 OHM"
					( Origin gFrontEnd )
				)
				( attribute "CDS_LIB" "w_hdl"
					( Origin gPackager )
				)
				( attribute "CDS_LMAN_SYM_OUTLINE" "-50,75,50,-75"
					( Origin gPackager )
				)
				( attribute "LOCATION" "RT4"
					( Origin gFrontEnd )
				)
				( attribute "PACK_TYPE" "RCL_GP"
					( Origin gFrontEnd )
				)
				( attribute "PART_NUMBER" "64.1R005.55L"
					( Origin gFrontEnd )
				)
				( attribute "PHYS_PAGE" "202"
					( Origin gFrontEnd )
				)
				( attribute "POP" "NOPOP"
					( Origin gFrontEnd )
				)
				( attribute "RATED" "1/10W"
					( Origin gFrontEnd )
				)
				( attribute "ROT" "0"
					( Origin gFrontEnd )
				)
				( attribute "SEC" "1"
					( Origin gFrontEnd )
				)
				( attribute "SEC_TYPE" "RCL_GP"
					( Origin gFrontEnd )
				)
				( attribute "TOLERANCE" "1%"
					( Origin gFrontEnd )
				)
				( attribute "VALUE" "1R3F-GP"
					( Origin gFrontEnd )
				)
				( attribute "VER" "1"
					( Origin gFrontEnd )
				)
				( attribute "XY" "(-2550,525)"
					( Origin gFrontEnd )
				)
				( attribute "CHIPS_PART_NAME" "1R3F-GP"
					( Origin gPackager )
				)
				( attribute "CDS_PART_NAME" "1R3F-GP_RCL_GP-1R3F-GP,64.1R00A"
					( Origin gPackager )
				)
				( attribute "PACK_SIZE" "0603"
					( Origin gFrontEnd )
				)
				( attribute "CDS_LOCATION" "RT4"
					( Origin gPackager )
				)
				( attribute "CDS_SEC" "1"
					( Origin gPackager )
				)
				( objectStatus "RT4" )
			)
			( gate "@baseboard_fab2_lib.baseboard_fab2(sch_1):page200_i249"
				( attribute "ATTRIBUTE" "270KOHM"
					( Origin gFrontEnd )
				)
				( attribute "CDS_LIB" "w_hdl"
					( Origin gPackager )
				)
				( attribute "CDS_LMAN_SYM_OUTLINE" "-50,75,50,-75"
					( Origin gPackager )
				)
				( attribute "LOCATION" "R9P13"
					( Origin gFrontEnd )
				)
				( attribute "PACK_TYPE" "RCL_GP"
					( Origin gFrontEnd )
				)
				( attribute "PART_NUMBER" "64.27035.6DL"
					( Origin gFrontEnd )
				)
				( attribute "PHYS_PAGE" "200"
					( Origin gFrontEnd )
				)
				( attribute "RATED" "1/16W"
					( Origin gFrontEnd )
				)
				( attribute "ROT" "0"
					( Origin gFrontEnd )
				)
				( attribute "SEC" "1"
					( Origin gFrontEnd )
				)
				( attribute "SEC_TYPE" "RCL_GP"
					( Origin gFrontEnd )
				)
				( attribute "TOLERANCE" "1%"
					( Origin gFrontEnd )
				)
				( attribute "VALUE" "270KR2F-GP"
					( Origin gFrontEnd )
				)
				( attribute "VER" "1"
					( Origin gFrontEnd )
				)
				( attribute "XY" "(-1650,275)"
					( Origin gFrontEnd )
				)
				( attribute "CHIPS_PART_NAME" "270KR2F-GP"
					( Origin gPackager )
				)
				( attribute "CDS_PART_NAME" "270KR2F-GP_RCL_GP-270KR2F-GP,6A"
					( Origin gPackager )
				)
				( attribute "PACK_SIZE" "0402"
					( Origin gFrontEnd )
				)
				( attribute "CDS_LOCATION" "R9P13"
					( Origin gPackager )
				)
				( attribute "CDS_SEC" "1"
					( Origin gPackager )
				)
				( objectStatus "R9P13" )
			)
			( gate "@baseboard_fab2_lib.baseboard_fab2(sch_1):page151_i198"
				( attribute "BOM_COST" "SM_CONTROLLER"
					( Origin gFrontEnd )
				)
				( attribute "CDS_LIB" "mstr_discrete"
					( Origin gPackager )
				)
				( attribute "CDS_LOCATION" "Q9E1"
					( Origin gPackager )
				)
				( attribute "CDS_SEC" "1"
					( Origin gPackager )
				)
				( attribute "LOCATION" "Q9E1"
					( Origin gFrontEnd )
				)
				( attribute "MATERIAL" "FET"
					( Origin gFrontEnd )
				)
				( attribute "PACK_TYPE" "SMLF"
					( Origin gFrontEnd )
				)
				( attribute "PART_NUMBER" "E40049-001"
					( Origin gFrontEnd )
				)
				( attribute "PHYS_PAGE" "151"
					( Origin gFrontEnd )
				)
				( attribute "ROOM" "BMC"
					( Origin gFrontEnd )
				)
				( attribute "ROT" "0"
					( Origin gFrontEnd )
				)
				( attribute "SEC" "1"
					( Origin gFrontEnd )
				)
				( attribute "SEC_TYPE" "SMLF"
					( Origin gFrontEnd )
				)
				( attribute "VALUE" "NTJD4001N"
					( Origin gFrontEnd )
				)
				( attribute "VER" "5"
					( Origin gFrontEnd )
				)
				( attribute "XY" "(-1700,-800)"
					( Origin gFrontEnd )
				)
				( attribute "CHIPS_PART_NAME" "FET_N_DUAL"
					( Origin gPackager )
				)
				( attribute "CDS_PART_NAME" "FET_N_DUAL_SMLF-NTJD4001N,FET,A"
					( Origin gPackager )
				)
				( objectStatus "Q9E1" )
			)
			( gate "@baseboard_fab2_lib.baseboard_fab2(sch_1):page151_i201"
				( attribute "BOM_COST" "SM_MEM"
					( Origin gFrontEnd )
				)
				( attribute "CDS_LIB" "mstr_discrete"
					( Origin gPackager )
				)
				( attribute "CDS_LOCATION" "R1T30"
					( Origin gPackager )
				)
				( attribute "CDS_SEC" "1"
					( Origin gPackager )
				)
				( attribute "LOCATION" "R1T30"
					( Origin gFrontEnd )
				)
				( attribute "MATERIAL" "CHIP"
					( Origin gFrontEnd )
				)
				( attribute "PACK_TYPE" "0402"
					( Origin gFrontEnd )
				)
				( attribute "PART_NUMBER" "G21796-026"
					( Origin gFrontEnd )
				)
				( attribute "PHYS_PAGE" "151"
					( Origin gFrontEnd )
				)
				( attribute "ROOM" "BMC_MEMORY"
					( Origin gFrontEnd )
				)
				( attribute "ROT" "0"
					( Origin gFrontEnd )
				)
				( attribute "SEC" "1"
					( Origin gFrontEnd )
				)
				( attribute "SEC_TYPE" "0402"
					( Origin gFrontEnd )
				)
				( attribute "TOLERANCE" "1%"
					( Origin gFrontEnd )
				)
				( attribute "VALUE" "1.00K"
					( Origin gFrontEnd )
				)
				( attribute "VER" "2"
					( Origin gFrontEnd )
				)
				( attribute "WATTAGE" "1/16W"
					( Origin gFrontEnd )
				)
				( attribute "XY" "(-1675,-1575)"
					( Origin gFrontEnd )
				)
				( attribute "CHIPS_PART_NAME" "RES"
					( Origin gPackager )
				)
				( attribute "CDS_PART_NAME" "RES_0402-1.00K,1%,1/16W,CHIP,GA"
					( Origin gPackager )
				)
				( objectStatus "R1T30" )
			)
			( gate "@baseboard_fab2_lib.baseboard_fab2(sch_1):page151_i202"
				( attribute "BOM_COST" "SM_MEM"
					( Origin gFrontEnd )
				)
				( attribute "CDS_LIB" "mstr_discrete"
					( Origin gPackager )
				)
				( attribute "CDS_LOCATION" "R1T29"
					( Origin gPackager )
				)
				( attribute "CDS_SEC" "1"
					( Origin gPackager )
				)
				( attribute "LOCATION" "R1T29"
					( Origin gFrontEnd )
				)
				( attribute "MATERIAL" "CHIP"
					( Origin gFrontEnd )
				)
				( attribute "PACK_TYPE" "0402"
					( Origin gFrontEnd )
				)
				( attribute "PART_NUMBER" "G21796-026"
					( Origin gFrontEnd )
				)
				( attribute "PHYS_PAGE" "151"
					( Origin gFrontEnd )
				)
				( attribute "ROOM" "BMC_MEMORY"
					( Origin gFrontEnd )
				)
				( attribute "ROT" "0"
					( Origin gFrontEnd )
				)
				( attribute "SEC" "1"
					( Origin gFrontEnd )
				)
				( attribute "SEC_TYPE" "0402"
					( Origin gFrontEnd )
				)
				( attribute "TOLERANCE" "1%"
					( Origin gFrontEnd )
				)
				( attribute "VALUE" "1.00K"
					( Origin gFrontEnd )
				)
				( attribute "VER" "2"
					( Origin gFrontEnd )
				)
				( attribute "WATTAGE" "1/16W"
					( Origin gFrontEnd )
				)
				( attribute "XY" "(-1675,-2000)"
					( Origin gFrontEnd )
				)
				( attribute "CHIPS_PART_NAME" "RES"
					( Origin gPackager )
				)
				( attribute "CDS_PART_NAME" "RES_0402-1.00K,1%,1/16W,CHIP,GA"
					( Origin gPackager )
				)
				( objectStatus "R1T29" )
			)
			( gate "@baseboard_fab2_lib.baseboard_fab2(sch_1):page246_i22"
				( attribute "BOM_COST" "MEM"
					( Origin gFrontEnd )
				)
				( attribute "CDS_LIB" "dev_discrete"
					( Origin gPackager )
				)
				( attribute "CDS_LOCATION" "CN8F2"
					( Origin gPackager )
				)
				( attribute "CDS_SEC" "1"
					( Origin gPackager )
				)
				( attribute "LOCATION" "CN8F2"
					( Origin gFrontEnd )
				)
				( attribute "MATERIAL" "X7R"
					( Origin gFrontEnd )
				)
				( attribute "PACK_TYPE" "0402V"
					( Origin gFrontEnd )
				)
				( attribute "PART_NUMBER" "A36096-045"
					( Origin gFrontEnd )
				)
				( attribute "PHYS_PAGE" "246"
					( Origin gFrontEnd )
				)
				( attribute "ROOM" "DDR4_CH_M"
					( Origin gFrontEnd )
				)
				( attribute "ROT" "2"
					( Origin gFrontEnd )
				)
				( attribute "SEC" "1"
					( Origin gFrontEnd )
				)
				( attribute "SEC_TYPE" "0402V"
					( Origin gFrontEnd )
				)
				( attribute "TOLERANCE" "10%"
					( Origin gFrontEnd )
				)
				( attribute "VALUE" "0.01UF"
					( Origin gFrontEnd )
				)
				( attribute "VER" "1"
					( Origin gFrontEnd )
				)
				( attribute "VOLTAGE" "25V"
					( Units "uVoltage" "V" 1.000000)
					( Origin gFrontEnd )
				)
				( attribute "XY" "(-2700,3275)"
					( Origin gFrontEnd )
				)
				( attribute "CHIPS_PART_NAME" "CAP_A"
					( Origin gPackager )
				)
				( attribute "CDS_PART_NAME" "CAP_A_0402V-0.01UF,25V,10%,X7RA"
					( Origin gPackager )
				)
				( objectStatus "CN8F2" )
			)
			( gate "@baseboard_fab2_lib.baseboard_fab2(sch_1):page151_i216"
				( attribute "CDS_LIB" "dev_discrete"
					( Origin gPackager )
				)
				( attribute "CDS_LOCATION" "C25W15"
					( Origin gPackager )
				)
				( attribute "CDS_SEC" "1"
					( Origin gPackager )
				)
				( attribute "LOCATION" "C25W15"
					( Origin gFrontEnd )
				)
				( attribute "MATERIAL" "X7R"
					( Origin gFrontEnd )
				)
				( attribute "PACK_TYPE" "0402V"
					( Origin gFrontEnd )
				)
				( attribute "PART_NUMBER" "A36096-030"
					( Origin gFrontEnd )
				)
				( attribute "PHYS_PAGE" "151"
					( Origin gFrontEnd )
				)
				( attribute "ROOM" "VDDQ_KLM_PWR_VR"
					( Origin gFrontEnd )
				)
				( attribute "ROT" "0"
					( Origin gFrontEnd )
				)
				( attribute "SEC" "1"
					( Origin gFrontEnd )
				)
				( attribute "SEC_TYPE" "0402V"
					( Origin gFrontEnd )
				)
				( attribute "TOLERANCE" "10%"
					( Origin gFrontEnd )
				)
				( attribute "VALUE" "0.1UF"
					( Origin gFrontEnd )
				)
				( attribute "VER" "1"
					( Origin gFrontEnd )
				)
				( attribute "VOLTAGE" "16V"
					( Units "uVoltage" "V" 1.000000)
					( Origin gFrontEnd )
				)
				( attribute "XY" "(1450,550)"
					( Origin gFrontEnd )
				)
				( attribute "CHIPS_PART_NAME" "CAP_A"
					( Origin gPackager )
				)
				( attribute "CDS_PART_NAME" "CAP_A_0402V-0.1UF,16V,10%,X7R,A"
					( Origin gPackager )
				)
				( objectStatus "C25W15" )
			)
			( gate "@baseboard_fab2_lib.baseboard_fab2(sch_1):page151_i215"
				( attribute "CDS_LIB" "dev_discrete"
					( Origin gPackager )
				)
				( attribute "CDS_LOCATION" "C25W14"
					( Origin gPackager )
				)
				( attribute "CDS_SEC" "1"
					( Origin gPackager )
				)
				( attribute "LOCATION" "C25W14"
					( Origin gFrontEnd )
				)
				( attribute "MATERIAL" "X7R"
					( Origin gFrontEnd )
				)
				( attribute "PACK_TYPE" "0402V"
					( Origin gFrontEnd )
				)
				( attribute "PART_NUMBER" "A36096-030"
					( Origin gFrontEnd )
				)
				( attribute "PHYS_PAGE" "151"
					( Origin gFrontEnd )
				)
				( attribute "ROOM" "VDDQ_KLM_PWR_VR"
					( Origin gFrontEnd )
				)
				( attribute "ROT" "0"
					( Origin gFrontEnd )
				)
				( attribute "SEC" "1"
					( Origin gFrontEnd )
				)
				( attribute "SEC_TYPE" "0402V"
					( Origin gFrontEnd )
				)
				( attribute "TOLERANCE" "10%"
					( Origin gFrontEnd )
				)
				( attribute "VALUE" "0.1UF"
					( Origin gFrontEnd )
				)
				( attribute "VER" "1"
					( Origin gFrontEnd )
				)
				( attribute "VOLTAGE" "16V"
					( Units "uVoltage" "V" 1.000000)
					( Origin gFrontEnd )
				)
				( attribute "XY" "(1100,550)"
					( Origin gFrontEnd )
				)
				( attribute "CHIPS_PART_NAME" "CAP_A"
					( Origin gPackager )
				)
				( attribute "CDS_PART_NAME" "CAP_A_0402V-0.1UF,16V,10%,X7R,A"
					( Origin gPackager )
				)
				( objectStatus "C25W14" )
			)
			( gate "@baseboard_fab2_lib.baseboard_fab2(sch_1):page248_i19"
				( attribute "BOM_COST" "MIO_CHASSIS"
					( Origin gFrontEnd )
				)
				( attribute "CDS_LIB" "mstr_ttl"
					( Origin gPackager )
				)
				( attribute "LOCATION" "U14E3"
					( Origin gFrontEnd )
				)
				( attribute "MATERIAL" "IC"
					( Origin gFrontEnd )
				)
				( attribute "PACK_TYPE" "SOTLF"
					( Origin gFrontEnd )
				)
				( attribute "PART_NUMBER" "D10321-001"
					( Origin gFrontEnd )
				)
				( attribute "PHYS_PAGE" "248"
					( Origin gFrontEnd )
				)
				( attribute "ROOM" "MIO_CHASSIS"
					( Origin gFrontEnd )
				)
				( attribute "ROT" "0"
					( Origin gFrontEnd )
				)
				( attribute "VALUE" "NC7SZ08"
					( Origin gFrontEnd )
				)
				( attribute "VER" "1"
					( Origin gFrontEnd )
				)
				( attribute "XY" "(-4050,1275)"
					( Origin gFrontEnd )
				)
				( attribute "CHIPS_PART_NAME" "TTL1G08"
					( Origin gPackager )
				)
				( attribute "CDS_PART_NAME" "TTL1G08_SOTLF-NC7SZ08,IC,D1032C"
					( Origin gPackager )
				)
				( attribute "CDS_LOCATION" "U14E3"
					( Origin gPackager )
				)
				( attribute "CDS_SEC" "1"
					( Origin gPackager )
				)
				( attribute "SEC" "1"
					( Origin gPackager )
				)
				( objectStatus "U14E3" )
			)
			( gate "@baseboard_fab2_lib.baseboard_fab2(sch_1):page207_i111"
				( attribute "ATTRIBUTE" "1 OHM"
					( Origin gFrontEnd )
				)
				( attribute "CDS_LIB" "w_hdl"
					( Origin gPackager )
				)
				( attribute "CDS_LMAN_SYM_OUTLINE" "-50,75,50,-75"
					( Origin gPackager )
				)
				( attribute "LOCATION" "RT16"
					( Origin gFrontEnd )
				)
				( attribute "PACK_TYPE" "RCL_GP"
					( Origin gFrontEnd )
				)
				( attribute "PART_NUMBER" "64.1R005.55L"
					( Origin gFrontEnd )
				)
				( attribute "PHYS_PAGE" "207"
					( Origin gFrontEnd )
				)
				( attribute "POP" "NOPOP"
					( Origin gFrontEnd )
				)
				( attribute "RATED" "1/10W"
					( Origin gFrontEnd )
				)
				( attribute "ROT" "0"
					( Origin gFrontEnd )
				)
				( attribute "SEC" "1"
					( Origin gFrontEnd )
				)
				( attribute "SEC_TYPE" "RCL_GP"
					( Origin gFrontEnd )
				)
				( attribute "TOLERANCE" "1%"
					( Origin gFrontEnd )
				)
				( attribute "VALUE" "1R3F-GP"
					( Origin gFrontEnd )
				)
				( attribute "VER" "1"
					( Origin gFrontEnd )
				)
				( attribute "XY" "(-2225,3050)"
					( Origin gFrontEnd )
				)
				( attribute "CHIPS_PART_NAME" "1R3F-GP"
					( Origin gPackager )
				)
				( attribute "CDS_PART_NAME" "1R3F-GP_RCL_GP-1R3F-GP,64.1R00A"
					( Origin gPackager )
				)
				( attribute "PACK_SIZE" "0603"
					( Origin gFrontEnd )
				)
				( attribute "CDS_LOCATION" "RT16"
					( Origin gPackager )
				)
				( attribute "CDS_SEC" "1"
					( Origin gPackager )
				)
				( objectStatus "RT16" )
			)
			( gate "@baseboard_fab2_lib.baseboard_fab2(sch_1):page248_i24"
				( attribute "CDS_LIB" "mstr_discrete"
					( Origin gPackager )
				)
				( attribute "CDS_LOCATION" "R6W26"
					( Origin gPackager )
				)
				( attribute "CDS_SEC" "1"
					( Origin gPackager )
				)
				( attribute "LOCATION" "R6W26"
					( Origin gFrontEnd )
				)
				( attribute "MATERIAL" "CHIP"
					( Origin gFrontEnd )
				)
				( attribute "PACK_TYPE" "0402"
					( Origin gFrontEnd )
				)
				( attribute "PART_NUMBER" "G21796-066"
					( Origin gFrontEnd )
				)
				( attribute "PHYS_PAGE" "248"
					( Origin gFrontEnd )
				)
				( attribute "ROOM" "CPU1"
					( Origin gFrontEnd )
				)
				( attribute "ROT" "0"
					( Origin gFrontEnd )
				)
				( attribute "SEC" "1"
					( Origin gFrontEnd )
				)
				( attribute "SEC_TYPE" "0402"
					( Origin gFrontEnd )
				)
				( attribute "TOLERANCE" "1%"
					( Origin gFrontEnd )
				)
				( attribute "VALUE" "10.0"
					( Origin gFrontEnd )
				)
				( attribute "VER" "1"
					( Origin gFrontEnd )
				)
				( attribute "WATTAGE" "1/16W"
					( Origin gFrontEnd )
				)
				( attribute "XY" "(-6250,3525)"
					( Origin gFrontEnd )
				)
				( attribute "CHIPS_PART_NAME" "RES"
					( Origin gPackager )
				)
				( attribute "CDS_PART_NAME" "RES_0402-10.0,1%,1/16W,CHIP,G2A"
					( Origin gPackager )
				)
				( objectStatus "R6W26" )
			)
			( gate "@baseboard_fab2_lib.baseboard_fab2(sch_1):page248_i25"
				( attribute "CDS_LIB" "mstr_discrete"
					( Origin gPackager )
				)
				( attribute "CDS_LOCATION" "R6W27"
					( Origin gPackager )
				)
				( attribute "CDS_SEC" "1"
					( Origin gPackager )
				)
				( attribute "LOCATION" "R6W27"
					( Origin gFrontEnd )
				)
				( attribute "MATERIAL" "CHIP"
					( Origin gFrontEnd )
				)
				( attribute "PACK_TYPE" "0402"
					( Origin gFrontEnd )
				)
				( attribute "PART_NUMBER" "G21796-066"
					( Origin gFrontEnd )
				)
				( attribute "PHYS_PAGE" "248"
					( Origin gFrontEnd )
				)
				( attribute "ROOM" "CPU1"
					( Origin gFrontEnd )
				)
				( attribute "ROT" "0"
					( Origin gFrontEnd )
				)
				( attribute "SEC" "1"
					( Origin gFrontEnd )
				)
				( attribute "SEC_TYPE" "0402"
					( Origin gFrontEnd )
				)
				( attribute "TOLERANCE" "1%"
					( Origin gFrontEnd )
				)
				( attribute "VALUE" "10.0"
					( Origin gFrontEnd )
				)
				( attribute "VER" "1"
					( Origin gFrontEnd )
				)
				( attribute "WATTAGE" "1/16W"
					( Origin gFrontEnd )
				)
				( attribute "XY" "(-5900,3475)"
					( Origin gFrontEnd )
				)
				( attribute "CHIPS_PART_NAME" "RES"
					( Origin gPackager )
				)
				( attribute "CDS_PART_NAME" "RES_0402-10.0,1%,1/16W,CHIP,G2A"
					( Origin gPackager )
				)
				( objectStatus "R6W27" )
			)
			( gate "@baseboard_fab2_lib.baseboard_fab2(sch_1):page248_i26"
				( attribute "CDS_LIB" "mstr_discrete"
					( Origin gPackager )
				)
				( attribute "CDS_LOCATION" "R9W19"
					( Origin gPackager )
				)
				( attribute "CDS_SEC" "1"
					( Origin gPackager )
				)
				( attribute "LOCATION" "R9W19"
					( Origin gFrontEnd )
				)
				( attribute "MATERIAL" "CHIP"
					( Origin gFrontEnd )
				)
				( attribute "PACK_TYPE" "0402"
					( Origin gFrontEnd )
				)
				( attribute "PART_NUMBER" "G21796-294"
					( Origin gFrontEnd )
				)
				( attribute "PHYS_PAGE" "248"
					( Origin gFrontEnd )
				)
				( attribute "ROOM" "SMB_PE_HP_CPU1"
					( Origin gFrontEnd )
				)
				( attribute "ROT" "2"
					( Origin gFrontEnd )
				)
				( attribute "SEC" "1"
					( Origin gFrontEnd )
				)
				( attribute "SEC_TYPE" "0402"
					( Origin gFrontEnd )
				)
				( attribute "TOLERANCE" "1.0%"
					( Origin gFrontEnd )
				)
				( attribute "VALUE" "240"
					( Origin gFrontEnd )
				)
				( attribute "VER" "2"
					( Origin gFrontEnd )
				)
				( attribute "WATTAGE" "1/16W"
					( Origin gFrontEnd )
				)
				( attribute "XY" "(-4750,3875)"
					( Origin gFrontEnd )
				)
				( attribute "CHIPS_PART_NAME" "RES"
					( Origin gPackager )
				)
				( attribute "CDS_PART_NAME" "RES_0402-240,1.0%,1/16W,CHIP,GA"
					( Origin gPackager )
				)
				( objectStatus "R9W19" )
			)
			( gate "@baseboard_fab2_lib.baseboard_fab2(sch_1):page248_i27"
				( attribute "CDS_LIB" "mstr_discrete"
					( Origin gPackager )
				)
				( attribute "CDS_LOCATION" "R9W18"
					( Origin gPackager )
				)
				( attribute "CDS_SEC" "1"
					( Origin gPackager )
				)
				( attribute "LOCATION" "R9W18"
					( Origin gFrontEnd )
				)
				( attribute "MATERIAL" "CHIP"
					( Origin gFrontEnd )
				)
				( attribute "PACK_TYPE" "0402"
					( Origin gFrontEnd )
				)
				( attribute "PART_NUMBER" "G21796-294"
					( Origin gFrontEnd )
				)
				( attribute "PHYS_PAGE" "248"
					( Origin gFrontEnd )
				)
				( attribute "ROOM" "SMB_PE_HP_CPU1"
					( Origin gFrontEnd )
				)
				( attribute "ROT" "0"
					( Origin gFrontEnd )
				)
				( attribute "SEC" "1"
					( Origin gFrontEnd )
				)
				( attribute "SEC_TYPE" "0402"
					( Origin gFrontEnd )
				)
				( attribute "TOLERANCE" "1.0%"
					( Origin gFrontEnd )
				)
				( attribute "VALUE" "240"
					( Origin gFrontEnd )
				)
				( attribute "VER" "2"
					( Origin gFrontEnd )
				)
				( attribute "WATTAGE" "1/16W"
					( Origin gFrontEnd )
				)
				( attribute "XY" "(-4600,3875)"
					( Origin gFrontEnd )
				)
				( attribute "CHIPS_PART_NAME" "RES"
					( Origin gPackager )
				)
				( attribute "CDS_PART_NAME" "RES_0402-240,1.0%,1/16W,CHIP,GA"
					( Origin gPackager )
				)
				( objectStatus "R9W18" )
			)
			( gate "@baseboard_fab2_lib.baseboard_fab2(sch_1):page248_i30"
				( attribute "CDS_LIB" "dev_discrete"
					( Origin gPackager )
				)
				( attribute "CDS_LOCATION" "C9W8"
					( Origin gPackager )
				)
				( attribute "CDS_SEC" "1"
					( Origin gPackager )
				)
				( attribute "LOCATION" "C9W8"
					( Origin gFrontEnd )
				)
				( attribute "MATERIAL" "X7R"
					( Origin gFrontEnd )
				)
				( attribute "PACK_TYPE" "0402V"
					( Origin gFrontEnd )
				)
				( attribute "PART_NUMBER" "A36096-030"
					( Origin gFrontEnd )
				)
				( attribute "PHYS_PAGE" "248"
					( Origin gFrontEnd )
				)
				( attribute "ROOM" "SMB_PE_HP_CPU1"
					( Origin gFrontEnd )
				)
				( attribute "ROT" "0"
					( Origin gFrontEnd )
				)
				( attribute "SEC" "1"
					( Origin gFrontEnd )
				)
				( attribute "SEC_TYPE" "0402V"
					( Origin gFrontEnd )
				)
				( attribute "TOLERANCE" "10%"
					( Origin gFrontEnd )
				)
				( attribute "VALUE" "0.1UF"
					( Origin gFrontEnd )
				)
				( attribute "VER" "1"
					( Origin gFrontEnd )
				)
				( attribute "VOLTAGE" "16V"
					( Units "uVoltage" "V" 1.000000)
					( Origin gFrontEnd )
				)
				( attribute "XY" "(-4200,4050)"
					( Origin gFrontEnd )
				)
				( attribute "CHIPS_PART_NAME" "CAP_A"
					( Origin gPackager )
				)
				( attribute "CDS_PART_NAME" "CAP_A_0402V-0.1UF,16V,10%,X7R,A"
					( Origin gPackager )
				)
				( objectStatus "C9W8" )
			)
			( gate "@baseboard_fab2_lib.baseboard_fab2(sch_1):page248_i32"
				( attribute "CDS_LIB" "dev_discrete"
					( Origin gPackager )
				)
				( attribute "CDS_LOCATION" "C9W7"
					( Origin gPackager )
				)
				( attribute "CDS_SEC" "1"
					( Origin gPackager )
				)
				( attribute "LOCATION" "C9W7"
					( Origin gFrontEnd )
				)
				( attribute "MATERIAL" "X7R"
					( Origin gFrontEnd )
				)
				( attribute "PACK_TYPE" "0402V"
					( Origin gFrontEnd )
				)
				( attribute "PART_NUMBER" "A36096-030"
					( Origin gFrontEnd )
				)
				( attribute "PHYS_PAGE" "248"
					( Origin gFrontEnd )
				)
				( attribute "ROOM" "SMB_PE_HP_CPU1"
					( Origin gFrontEnd )
				)
				( attribute "ROT" "2"
					( Origin gFrontEnd )
				)
				( attribute "SEC" "1"
					( Origin gFrontEnd )
				)
				( attribute "SEC_TYPE" "0402V"
					( Origin gFrontEnd )
				)
				( attribute "TOLERANCE" "10%"
					( Origin gFrontEnd )
				)
				( attribute "VALUE" "0.1UF"
					( Origin gFrontEnd )
				)
				( attribute "VER" "1"
					( Origin gFrontEnd )
				)
				( attribute "VOLTAGE" "16V"
					( Units "uVoltage" "V" 1.000000)
					( Origin gFrontEnd )
				)
				( attribute "XY" "(-3525,4050)"
					( Origin gFrontEnd )
				)
				( attribute "CHIPS_PART_NAME" "CAP_A"
					( Origin gPackager )
				)
				( attribute "CDS_PART_NAME" "CAP_A_0402V-0.1UF,16V,10%,X7R,A"
					( Origin gPackager )
				)
				( objectStatus "C9W7" )
			)
			( gate "@baseboard_fab2_lib.baseboard_fab2(sch_1):page248_i34"
				( attribute "CDS_LIB" "mstr_discrete"
					( Origin gPackager )
				)
				( attribute "CDS_LOCATION" "R9W16"
					( Origin gPackager )
				)
				( attribute "CDS_SEC" "1"
					( Origin gPackager )
				)
				( attribute "LOCATION" "R9W16"
					( Origin gFrontEnd )
				)
				( attribute "MATERIAL" "CHIP"
					( Origin gFrontEnd )
				)
				( attribute "PACK_TYPE" "0402"
					( Origin gFrontEnd )
				)
				( attribute "PART_NUMBER" "G21796-001"
					( Origin gFrontEnd )
				)
				( attribute "PHYS_PAGE" "248"
					( Origin gFrontEnd )
				)
				( attribute "ROOM" "SMB_PE_HP_CPU1"
					( Origin gFrontEnd )
				)
				( attribute "ROT" "0"
					( Origin gFrontEnd )
				)
				( attribute "SEC" "1"
					( Origin gFrontEnd )
				)
				( attribute "SEC_TYPE" "0402"
					( Origin gFrontEnd )
				)
				( attribute "TOLERANCE" "1%"
					( Origin gFrontEnd )
				)
				( attribute "VALUE" "2.0K"
					( Origin gFrontEnd )
				)
				( attribute "VER" "2"
					( Origin gFrontEnd )
				)
				( attribute "WATTAGE" "1/16W"
					( Origin gFrontEnd )
				)
				( attribute "XY" "(-2850,3875)"
					( Origin gFrontEnd )
				)
				( attribute "CHIPS_PART_NAME" "RES"
					( Origin gPackager )
				)
				( attribute "CDS_PART_NAME" "RES_0402-2.0K,1%,1/16W,CHIP,G2A"
					( Origin gPackager )
				)
				( objectStatus "R9W16" )
			)
			( gate "@baseboard_fab2_lib.baseboard_fab2(sch_1):page248_i35"
				( attribute "CDS_LIB" "mstr_discrete"
					( Origin gPackager )
				)
				( attribute "CDS_LOCATION" "R9W17"
					( Origin gPackager )
				)
				( attribute "CDS_SEC" "1"
					( Origin gPackager )
				)
				( attribute "LOCATION" "R9W17"
					( Origin gFrontEnd )
				)
				( attribute "MATERIAL" "CHIP"
					( Origin gFrontEnd )
				)
				( attribute "PACK_TYPE" "0402"
					( Origin gFrontEnd )
				)
				( attribute "PART_NUMBER" "G21796-001"
					( Origin gFrontEnd )
				)
				( attribute "PHYS_PAGE" "248"
					( Origin gFrontEnd )
				)
				( attribute "ROOM" "SMB_PE_HP_CPU1"
					( Origin gFrontEnd )
				)
				( attribute "ROT" "2"
					( Origin gFrontEnd )
				)
				( attribute "SEC" "1"
					( Origin gFrontEnd )
				)
				( attribute "SEC_TYPE" "0402"
					( Origin gFrontEnd )
				)
				( attribute "TOLERANCE" "1%"
					( Origin gFrontEnd )
				)
				( attribute "VALUE" "2.0K"
					( Origin gFrontEnd )
				)
				( attribute "VER" "2"
					( Origin gFrontEnd )
				)
				( attribute "WATTAGE" "1/16W"
					( Origin gFrontEnd )
				)
				( attribute "XY" "(-3000,3875)"
					( Origin gFrontEnd )
				)
				( attribute "CHIPS_PART_NAME" "RES"
					( Origin gPackager )
				)
				( attribute "CDS_PART_NAME" "RES_0402-2.0K,1%,1/16W,CHIP,G2A"
					( Origin gPackager )
				)
				( objectStatus "R9W17" )
			)
			( gate "@baseboard_fab2_lib.baseboard_fab2(sch_1):page248_i37"
				( attribute "CDS_LIB" "mstr_discrete"
					( Origin gPackager )
				)
				( attribute "CDS_LOCATION" "R9W14"
					( Origin gPackager )
				)
				( attribute "LOCATION" "R9W14"
					( Origin gFrontEnd )
				)
				( attribute "MATERIAL" "CHIP"
					( Origin gFrontEnd )
				)
				( attribute "PACK_TYPE" "0402"
					( Origin gFrontEnd )
				)
				( attribute "PART_NUMBER" "G21796-173"
					( Origin gFrontEnd )
				)
				( attribute "PHYS_PAGE" "248"
					( Origin gFrontEnd )
				)
				( attribute "ROOM" "SMB_PE_HP_CPU1"
					( Origin gFrontEnd )
				)
				( attribute "ROT" "0"
					( Origin gFrontEnd )
				)
				( attribute "SEC" "1"
					( Origin gFrontEnd )
				)
				( attribute "TOLERANCE" "1%"
					( Origin gFrontEnd )
				)
				( attribute "VALUE" "20.0"
					( Origin gFrontEnd )
				)
				( attribute "VER" "1"
					( Origin gFrontEnd )
				)
				( attribute "WATTAGE" "1/16W"
					( Origin gFrontEnd )
				)
				( attribute "XY" "(-2450,3525)"
					( Origin gFrontEnd )
				)
				( attribute "CHIPS_PART_NAME" "RES"
					( Origin gPackager )
				)
				( attribute "CDS_PART_NAME" "RES_0402-20.0,1%,1/16W,CHIP,G2A"
					( Origin gPackager )
				)
				( attribute "SEC_TYPE" "0402"
					( Origin gFrontEnd )
				)
				( attribute "CDS_SEC" "1"
					( Origin gPackager )
				)
				( objectStatus "R9W14" )
			)
			( gate "@baseboard_fab2_lib.baseboard_fab2(sch_1):page248_i38"
				( attribute "CDS_LIB" "mstr_discrete"
					( Origin gPackager )
				)
				( attribute "CDS_LOCATION" "R9W13"
					( Origin gPackager )
				)
				( attribute "LOCATION" "R9W13"
					( Origin gFrontEnd )
				)
				( attribute "MATERIAL" "CHIP"
					( Origin gFrontEnd )
				)
				( attribute "PACK_TYPE" "0402"
					( Origin gFrontEnd )
				)
				( attribute "PART_NUMBER" "G21796-173"
					( Origin gFrontEnd )
				)
				( attribute "PHYS_PAGE" "248"
					( Origin gFrontEnd )
				)
				( attribute "ROOM" "SMB_PE_HP_CPU1"
					( Origin gFrontEnd )
				)
				( attribute "ROT" "0"
					( Origin gFrontEnd )
				)
				( attribute "SEC" "1"
					( Origin gFrontEnd )
				)
				( attribute "TOLERANCE" "1%"
					( Origin gFrontEnd )
				)
				( attribute "VALUE" "20.0"
					( Origin gFrontEnd )
				)
				( attribute "VER" "1"
					( Origin gFrontEnd )
				)
				( attribute "WATTAGE" "1/16W"
					( Origin gFrontEnd )
				)
				( attribute "XY" "(-2200,3475)"
					( Origin gFrontEnd )
				)
				( attribute "CHIPS_PART_NAME" "RES"
					( Origin gPackager )
				)
				( attribute "CDS_PART_NAME" "RES_0402-20.0,1%,1/16W,CHIP,G2A"
					( Origin gPackager )
				)
				( attribute "SEC_TYPE" "0402"
					( Origin gFrontEnd )
				)
				( attribute "CDS_SEC" "1"
					( Origin gPackager )
				)
				( objectStatus "R9W13" )
			)
			( gate "@baseboard_fab2_lib.baseboard_fab2(sch_1):page249_i34"
				( attribute "CDS_LIB" "mstr_discrete"
					( Origin gPackager )
				)
				( attribute "LOCATION" "R8W1"
					( Origin gFrontEnd )
				)
				( attribute "MATERIAL" "CHIP"
					( Origin gFrontEnd )
				)
				( attribute "PACK_TYPE" "0402"
					( Origin gFrontEnd )
				)
				( attribute "PART_NUMBER" "G21497-005"
					( Origin gFrontEnd )
				)
				( attribute "PHYS_PAGE" "249"
					( Origin gFrontEnd )
				)
				( attribute "ROOM" "PVCCIN_CPU0_VR"
					( Origin gFrontEnd )
				)
				( attribute "ROT" "0"
					( Origin gFrontEnd )
				)
				( attribute "TOLERANCE" "5%"
					( Origin gFrontEnd )
				)
				( attribute "VALUE" "0.0"
					( Origin gFrontEnd )
				)
				( attribute "VER" "1"
					( Origin gFrontEnd )
				)
				( attribute "WATTAGE" "1/16W"
					( Origin gFrontEnd )
				)
				( attribute "XY" "(-6150,3350)"
					( Origin gFrontEnd )
				)
				( attribute "CHIPS_PART_NAME" "RES"
					( Origin gPackager )
				)
				( attribute "CDS_PART_NAME" "RES_0402-0.0,5%,1/16W,CHIP,G21A"
					( Origin gPackager )
				)
				( attribute "CDS_LOCATION" "R8W1"
					( Origin gPackager )
				)
				( attribute "SEC" "1"
					( Origin gFrontEnd )
				)
				( attribute "POP" "NOPOP"
					( Origin gFrontEnd )
				)
				( attribute "SEC_TYPE" "0402"
					( Origin gFrontEnd )
				)
				( attribute "CDS_SEC" "1"
					( Origin gPackager )
				)
				( objectStatus "R8W1" )
			)
			( gate "@baseboard_fab2_lib.baseboard_fab2(sch_1):page248_i46"
				( attribute "CHIPS_PART_NAME" "PCA9517"
					( Origin gPackager )
				)
			)
			( gate "@baseboard_fab2_lib.baseboard_fab2(sch_1):page216_i152"
				( attribute "ATTRIBUTE" "1 OHM"
					( Origin gFrontEnd )
				)
				( attribute "CDS_LIB" "w_hdl"
					( Origin gPackager )
				)
				( attribute "CDS_LMAN_SYM_OUTLINE" "-50,75,50,-75"
					( Origin gPackager )
				)
				( attribute "LOCATION" "RT35"
					( Origin gFrontEnd )
				)
				( attribute "PACK_TYPE" "RCL_GP"
					( Origin gFrontEnd )
				)
				( attribute "PART_NUMBER" "64.1R005.55L"
					( Origin gFrontEnd )
				)
				( attribute "PHYS_PAGE" "216"
					( Origin gFrontEnd )
				)
				( attribute "POP" "NOPOP"
					( Origin gFrontEnd )
				)
				( attribute "RATED" "1/10W"
					( Origin gFrontEnd )
				)
				( attribute "ROT" "0"
					( Origin gFrontEnd )
				)
				( attribute "SEC" "1"
					( Origin gFrontEnd )
				)
				( attribute "SEC_TYPE" "RCL_GP"
					( Origin gFrontEnd )
				)
				( attribute "TOLERANCE" "1%"
					( Origin gFrontEnd )
				)
				( attribute "VALUE" "1R3F-GP"
					( Origin gFrontEnd )
				)
				( attribute "VER" "1"
					( Origin gFrontEnd )
				)
				( attribute "XY" "(2900,-850)"
					( Origin gFrontEnd )
				)
				( attribute "CHIPS_PART_NAME" "1R3F-GP"
					( Origin gPackager )
				)
				( attribute "CDS_PART_NAME" "1R3F-GP_RCL_GP-1R3F-GP,64.1R00A"
					( Origin gPackager )
				)
				( attribute "PACK_SIZE" "0603"
					( Origin gFrontEnd )
				)
				( attribute "CDS_LOCATION" "RT35"
					( Origin gPackager )
				)
				( attribute "CDS_SEC" "1"
					( Origin gPackager )
				)
				( attribute "BOM_SS" "NOPOP"
					( Origin gFrontEnd )
				)
				( objectStatus "RT35" )
			)
			( gate "@baseboard_fab2_lib.baseboard_fab2(sch_1):page250_i27"
				( attribute "CDS_LIB" "w_hdl"
					( Origin gPackager )
				)
				( attribute "CDS_LMAN_SYM_OUTLINE" "-50,75,50,-75"
					( Origin gPackager )
				)
				( attribute "CDS_LOCATION" "R1W3"
					( Origin gPackager )
				)
				( attribute "CDS_SEC" "1"
					( Origin gPackager )
				)
				( attribute "LOCATION" "R1W3"
					( Origin gFrontEnd )
				)
				( attribute "PACK_TYPE" "SMD-RG1"
					( Origin gFrontEnd )
				)
				( attribute "PART_NUMBER" "64.10045.L1L"
					( Origin gFrontEnd )
				)
				( attribute "PHYS_PAGE" "250"
					( Origin gFrontEnd )
				)
				( attribute "ROT" "0"
					( Origin gFrontEnd )
				)
				( attribute "SEC" "1"
					( Origin gPackager )
				)
				( attribute "VALUE" "1MR2F-L-GP"
					( Origin gFrontEnd )
				)
				( attribute "VER" "1"
					( Origin gFrontEnd )
				)
				( attribute "XY" "(-8300,4350)"
					( Origin gFrontEnd )
				)
				( attribute "CHIPS_PART_NAME" "1MR2F-L-GP"
					( Origin gPackager )
				)
				( attribute "CDS_PART_NAME" "1MR2F-L-GP_SMD-RG1-1MR2F-L-GP,A"
					( Origin gPackager )
				)
				( attribute "ATTRIBUTE" "1MOHM"
					( Origin gFrontEnd )
				)
				( attribute "RATED" "1/16W"
					( Origin gFrontEnd )
				)
				( attribute "TOLERANCE" "1%"
					( Origin gFrontEnd )
				)
				( attribute "PACK_SIZE" "0402"
					( Origin gFrontEnd )
				)
				( objectStatus "R1W3" )
			)
			( gate "@baseboard_fab2_lib.baseboard_fab2(sch_1):page250_i24"
				( attribute "BOM_COST" "DEBUG"
					( Origin gFrontEnd )
				)
				( attribute "CDS_LIB" "mstr_discrete"
					( Origin gPackager )
				)
				( attribute "CDS_LOCATION" "Q1W2"
					( Origin gPackager )
				)
				( attribute "CDS_SEC" "1"
					( Origin gPackager )
				)
				( attribute "LOCATION" "Q1W2"
					( Origin gFrontEnd )
				)
				( attribute "MATERIAL" "FET"
					( Origin gFrontEnd )
				)
				( attribute "PACK_TYPE" "SMLF"
					( Origin gFrontEnd )
				)
				( attribute "PART_NUMBER" "D24280-001"
					( Origin gFrontEnd )
				)
				( attribute "PHYS_PAGE" "250"
					( Origin gFrontEnd )
				)
				( attribute "ROOM" "UART_MUX"
					( Origin gFrontEnd )
				)
				( attribute "ROT" "0"
					( Origin gFrontEnd )
				)
				( attribute "SEC" "1"
					( Origin gFrontEnd )
				)
				( attribute "SEC_TYPE" "SMLF"
					( Origin gFrontEnd )
				)
				( attribute "VALUE" "2N7002DW"
					( Origin gFrontEnd )
				)
				( attribute "VER" "5"
					( Origin gFrontEnd )
				)
				( attribute "XY" "(-7350,4250)"
					( Origin gFrontEnd )
				)
				( attribute "CHIPS_PART_NAME" "FET_N_DUAL"
					( Origin gPackager )
				)
				( attribute "CDS_PART_NAME" "FET_N_DUAL_SMLF-2N7002DW,FET,DA"
					( Origin gPackager )
				)
				( objectStatus "Q1W2" )
			)
			( gate "@baseboard_fab2_lib.baseboard_fab2(sch_1):page250_i22"
				( attribute "CDS_LIB" "mstr_discrete"
					( Origin gPackager )
				)
				( attribute "CDS_LOCATION" "R1W4"
					( Origin gPackager )
				)
				( attribute "CDS_SEC" "1"
					( Origin gPackager )
				)
				( attribute "LOCATION" "R1W4"
					( Origin gFrontEnd )
				)
				( attribute "MATERIAL" "CHIP"
					( Origin gFrontEnd )
				)
				( attribute "PACK_TYPE" "0402"
					( Origin gFrontEnd )
				)
				( attribute "PART_NUMBER" "G21796-016"
					( Origin gFrontEnd )
				)
				( attribute "PHYS_PAGE" "250"
					( Origin gFrontEnd )
				)
				( attribute "ROOM" "SB"
					( Origin gFrontEnd )
				)
				( attribute "ROT" "1"
					( Origin gFrontEnd )
				)
				( attribute "SEC" "1"
					( Origin gFrontEnd )
				)
				( attribute "SEC_TYPE" "0402"
					( Origin gFrontEnd )
				)
				( attribute "TOLERANCE" "1%"
					( Origin gFrontEnd )
				)
				( attribute "VALUE" "10.0K"
					( Origin gFrontEnd )
				)
				( attribute "VER" "1"
					( Origin gFrontEnd )
				)
				( attribute "WATTAGE" "1/16W"
					( Origin gFrontEnd )
				)
				( attribute "XY" "(-7350,4700)"
					( Origin gFrontEnd )
				)
				( attribute "CHIPS_PART_NAME" "RES"
					( Origin gPackager )
				)
				( attribute "CDS_PART_NAME" "RES_0402-10.0K,1%,1/16W,CHIP,GA"
					( Origin gPackager )
				)
				( objectStatus "R1W4" )
			)
			( gate "@baseboard_fab2_lib.baseboard_fab2(sch_1):page199_i130"
				( attribute "CDS_LIB" "mstr_discrete"
					( Origin gPackager )
				)
				( attribute "CDS_LOCATION" "Q1W5"
					( Origin gPackager )
				)
				( attribute "CDS_SEC" "1"
					( Origin gPackager )
				)
				( attribute "LOCATION" "Q1W5"
					( Origin gFrontEnd )
				)
				( attribute "MATERIAL" "FET"
					( Origin gFrontEnd )
				)
				( attribute "PACK_TYPE" "SOT23LF"
					( Origin gFrontEnd )
				)
				( attribute "PART_NUMBER" "C79254-001"
					( Origin gFrontEnd )
				)
				( attribute "PHYS_PAGE" "199"
					( Origin gFrontEnd )
				)
				( attribute "ROOM" "HOT_SWAP"
					( Origin gFrontEnd )
				)
				( attribute "ROT" "0"
					( Origin gFrontEnd )
				)
				( attribute "SEC" "1"
					( Origin gFrontEnd )
				)
				( attribute "SEC_TYPE" "SOT23LF"
					( Origin gFrontEnd )
				)
				( attribute "VALUE" "2N7002"
					( Origin gFrontEnd )
				)
				( attribute "VER" "8"
					( Origin gFrontEnd )
				)
				( attribute "XY" "(-3350,200)"
					( Origin gFrontEnd )
				)
				( attribute "CHIPS_PART_NAME" "FET_N"
					( Origin gPackager )
				)
				( attribute "CDS_PART_NAME" "FET_N_SOT23LF-2N7002,FET,C7925A"
					( Origin gPackager )
				)
				( objectStatus "Q1W5" )
			)
			( gate "@baseboard_fab2_lib.baseboard_fab2(sch_1):page250_i18"
				( attribute "CDS_LIB" "w_hdl"
					( Origin gPackager )
				)
				( attribute "CDS_LMAN_SYM_OUTLINE" "-50,75,50,-75"
					( Origin gPackager )
				)
				( attribute "CDS_LOCATION" "R1W1"
					( Origin gPackager )
				)
				( attribute "CDS_SEC" "1"
					( Origin gPackager )
				)
				( attribute "LOCATION" "R1W1"
					( Origin gFrontEnd )
				)
				( attribute "PACK_TYPE" "SMD-RG1"
					( Origin gFrontEnd )
				)
				( attribute "PART_NUMBER" "64.10045.L1L"
					( Origin gFrontEnd )
				)
				( attribute "PHYS_PAGE" "250"
					( Origin gFrontEnd )
				)
				( attribute "ROT" "0"
					( Origin gFrontEnd )
				)
				( attribute "SEC" "1"
					( Origin gPackager )
				)
				( attribute "VALUE" "1MR2F-L-GP"
					( Origin gFrontEnd )
				)
				( attribute "VER" "1"
					( Origin gFrontEnd )
				)
				( attribute "XY" "(-8300,5500)"
					( Origin gFrontEnd )
				)
				( attribute "CHIPS_PART_NAME" "1MR2F-L-GP"
					( Origin gPackager )
				)
				( attribute "CDS_PART_NAME" "1MR2F-L-GP_SMD-RG1-1MR2F-L-GP,A"
					( Origin gPackager )
				)
				( attribute "ATTRIBUTE" "1MOHM"
					( Origin gFrontEnd )
				)
				( attribute "RATED" "1/16W"
					( Origin gFrontEnd )
				)
				( attribute "TOLERANCE" "1%"
					( Origin gFrontEnd )
				)
				( attribute "PACK_SIZE" "0402"
					( Origin gFrontEnd )
				)
				( objectStatus "R1W1" )
			)
			( gate "@baseboard_fab2_lib.baseboard_fab2(sch_1):page164_i34"
				( attribute "BOM_COST" "SM_CONTROLLER"
					( Origin gFrontEnd )
				)
				( attribute "CDS_LIB" "mstr_discrete"
					( Origin gPackager )
				)
				( attribute "CDS_LOCATION" "R1U23"
					( Origin gPackager )
				)
				( attribute "CDS_SEC" "1"
					( Origin gPackager )
				)
				( attribute "LOCATION" "R1U23"
					( Origin gFrontEnd )
				)
				( attribute "MATERIAL" "CHIP"
					( Origin gFrontEnd )
				)
				( attribute "PACK_TYPE" "0402"
					( Origin gFrontEnd )
				)
				( attribute "PART_NUMBER" "G21796-344"
					( Origin gFrontEnd )
				)
				( attribute "PHYS_PAGE" "164"
					( Origin gFrontEnd )
				)
				( attribute "ROOM" "BMC_MISC"
					( Origin gFrontEnd )
				)
				( attribute "ROT" "0"
					( Origin gFrontEnd )
				)
				( attribute "SEC" "1"
					( Origin gFrontEnd )
				)
				( attribute "SEC_TYPE" "0402"
					( Origin gFrontEnd )
				)
				( attribute "TOLERANCE" "1%"
					( Origin gFrontEnd )
				)
				( attribute "VALUE" "2.7K"
					( Origin gFrontEnd )
				)
				( attribute "VER" "1"
					( Origin gFrontEnd )
				)
				( attribute "WATTAGE" "1/16W"
					( Origin gFrontEnd )
				)
				( attribute "XY" "(-7175,3675)"
					( Origin gFrontEnd )
				)
				( attribute "CHIPS_PART_NAME" "RES"
					( Origin gPackager )
				)
				( attribute "CDS_PART_NAME" "RES_0402-2.7K,1%,1/16W,CHIP,G2A"
					( Origin gPackager )
				)
				( attribute "GROUP" "PU_SKU_ID0"
					( Origin gFrontEnd )
				)
				( objectStatus "R1U23" )
			)
			( gate "@baseboard_fab2_lib.baseboard_fab2(sch_1):page164_i37"
				( attribute "BOM_COST" "SM_CONTROLLER"
					( Origin gFrontEnd )
				)
				( attribute "CDS_LIB" "mstr_discrete"
					( Origin gPackager )
				)
				( attribute "CDS_LOCATION" "R1U16"
					( Origin gPackager )
				)
				( attribute "LOCATION" "R1U16"
					( Origin gFrontEnd )
				)
				( attribute "MATERIAL" "CHIP"
					( Origin gFrontEnd )
				)
				( attribute "PACK_TYPE" "0402"
					( Origin gFrontEnd )
				)
				( attribute "PART_NUMBER" "G21796-026"
					( Origin gFrontEnd )
				)
				( attribute "PHYS_PAGE" "164"
					( Origin gFrontEnd )
				)
				( attribute "ROOM" "BMC_MISC"
					( Origin gFrontEnd )
				)
				( attribute "ROT" "0"
					( Origin gFrontEnd )
				)
				( attribute "SEC" "1"
					( Origin gFrontEnd )
				)
				( attribute "SEC_TYPE" "0402"
					( Origin gFrontEnd )
				)
				( attribute "TOLERANCE" "1%"
					( Origin gFrontEnd )
				)
				( attribute "VALUE" "1.00K"
					( Origin gFrontEnd )
				)
				( attribute "VER" "2"
					( Origin gFrontEnd )
				)
				( attribute "WATTAGE" "1/16W"
					( Origin gFrontEnd )
				)
				( attribute "XY" "(-5725,3350)"
					( Origin gFrontEnd )
				)
				( attribute "CHIPS_PART_NAME" "RES"
					( Origin gPackager )
				)
				( attribute "CDS_PART_NAME" "RES_0402-1.00K,1%,1/16W,CHIP,GA"
					( Origin gPackager )
				)
				( attribute "CDS_SEC" "1"
					( Origin gPackager )
				)
				( attribute "GROUP" "PD_SKU_ID1"
					( Origin gFrontEnd )
				)
				( objectStatus "R1U16" )
			)
			( gate "@baseboard_fab2_lib.baseboard_fab2(sch_1):page247_i112"
				( attribute "BOM_COST" "SM_THERM"
					( Origin gFrontEnd )
				)
				( attribute "CDS_LIB" "mstr_discrete"
					( Origin gPackager )
				)
				( attribute "LOCATION" "R6W28"
					( Origin gFrontEnd )
				)
				( attribute "MATERIAL" "CHIP"
					( Origin gFrontEnd )
				)
				( attribute "PACK_TYPE" "0402"
					( Origin gFrontEnd )
				)
				( attribute "PART_NUMBER" "G21796-072"
					( Origin gFrontEnd )
				)
				( attribute "PHYS_PAGE" "247"
					( Origin gFrontEnd )
				)
				( attribute "ROOM" "CPU_FANS"
					( Origin gFrontEnd )
				)
				( attribute "ROT" "2"
					( Origin gFrontEnd )
				)
				( attribute "TOLERANCE" "1%"
					( Origin gFrontEnd )
				)
				( attribute "VALUE" "4.75K"
					( Origin gFrontEnd )
				)
				( attribute "VER" "2"
					( Origin gFrontEnd )
				)
				( attribute "WATTAGE" "1/16W"
					( Origin gFrontEnd )
				)
				( attribute "XY" "(-6850,1950)"
					( Origin gFrontEnd )
				)
				( attribute "CHIPS_PART_NAME" "RES"
					( Origin gPackager )
				)
				( attribute "CDS_PART_NAME" "RES_0402-4.75K,1%,1/16W,CHIP,GA"
					( Origin gPackager )
				)
				( attribute "CDS_LOCATION" "R6W28"
					( Origin gPackager )
				)
				( attribute "SEC" "1"
					( Origin gFrontEnd )
				)
				( attribute "SEC_TYPE" "0402"
					( Origin gFrontEnd )
				)
				( attribute "CDS_SEC" "1"
					( Origin gPackager )
				)
				( objectStatus "R6W28" )
			)
			( gate "@baseboard_fab2_lib.baseboard_fab2(sch_1):page149_i91"
				( attribute "BOM_COST" "NT_GBE_BASE"
					( Origin gFrontEnd )
				)
				( attribute "CDS_LIB" "mstr_discrete"
					( Origin gPackager )
				)
				( attribute "LOCATION" "R25W120"
					( Origin gFrontEnd )
				)
				( attribute "MATERIAL" "CHIP"
					( Origin gFrontEnd )
				)
				( attribute "PACK_TYPE" "0603"
					( Origin gFrontEnd )
				)
				( attribute "PART_NUMBER" "G22178-002"
					( Origin gFrontEnd )
				)
				( attribute "PHYS_PAGE" "149"
					( Origin gFrontEnd )
				)
				( attribute "ROOM" "NIC_SPRV"
					( Origin gFrontEnd )
				)
				( attribute "ROT" "0"
					( Origin gFrontEnd )
				)
				( attribute "TOLERANCE" "5.0%"
					( Origin gFrontEnd )
				)
				( attribute "VALUE" "0"
					( Origin gFrontEnd )
				)
				( attribute "VER" "1"
					( Origin gFrontEnd )
				)
				( attribute "WATTAGE" "1/10W"
					( Origin gFrontEnd )
				)
				( attribute "XY" "(4100,5500)"
					( Origin gFrontEnd )
				)
				( attribute "CHIPS_PART_NAME" "RES"
					( Origin gPackager )
				)
				( attribute "CDS_PART_NAME" "RES_0603-0,5.0%,1/10W,CHIP,G22A"
					( Origin gPackager )
				)
				( attribute "CDS_LOCATION" "R25W120"
					( Origin gPackager )
				)
				( attribute "CDS_SEC" "1"
					( Origin gPackager )
				)
				( attribute "SEC" "1"
					( Origin gPackager )
				)
				( objectStatus "R25W120" )
			)
			( gate "@baseboard_fab2_lib.baseboard_fab2(sch_1):page107_i500"
				( attribute "CDS_LIB" "mstr_discrete"
					( Origin gPackager )
				)
				( attribute "LOCATION" "R2U28"
					( Origin gFrontEnd )
				)
				( attribute "MATERIAL" "CHIP"
					( Origin gFrontEnd )
				)
				( attribute "PACK_TYPE" "0402"
					( Origin gFrontEnd )
				)
				( attribute "PART_NUMBER" "G21497-005"
					( Origin gFrontEnd )
				)
				( attribute "PHYS_PAGE" "107"
					( Origin gFrontEnd )
				)
				( attribute "ROT" "1"
					( Origin gFrontEnd )
				)
				( attribute "TOLERANCE" "5%"
					( Origin gFrontEnd )
				)
				( attribute "VALUE" "0.0"
					( Origin gFrontEnd )
				)
				( attribute "VER" "1"
					( Origin gFrontEnd )
				)
				( attribute "WATTAGE" "1/16W"
					( Origin gFrontEnd )
				)
				( attribute "XY" "(-2200,2800)"
					( Origin gFrontEnd )
				)
				( attribute "CHIPS_PART_NAME" "RES"
					( Origin gPackager )
				)
				( attribute "CDS_PART_NAME" "RES_0402-0.0,5%,1/16W,CHIP,G21A"
					( Origin gPackager )
				)
				( attribute "CDS_LOCATION" "R2U28"
					( Origin gPackager )
				)
				( attribute "CDS_SEC" "1"
					( Origin gPackager )
				)
				( attribute "SEC" "1"
					( Origin gPackager )
				)
				( attribute "GROUP" "PCIE_RISER"
					( Origin gFrontEnd )
				)
				( objectStatus "R2U28" )
			)
			( gate "@baseboard_fab2_lib.baseboard_fab2(sch_1):page107_i499"
				( attribute "CDS_LIB" "mstr_discrete"
					( Origin gPackager )
				)
				( attribute "LOCATION" "R2U14"
					( Origin gFrontEnd )
				)
				( attribute "MATERIAL" "CHIP"
					( Origin gFrontEnd )
				)
				( attribute "PACK_TYPE" "0402"
					( Origin gFrontEnd )
				)
				( attribute "PART_NUMBER" "G21497-005"
					( Origin gFrontEnd )
				)
				( attribute "PHYS_PAGE" "107"
					( Origin gFrontEnd )
				)
				( attribute "ROT" "1"
					( Origin gFrontEnd )
				)
				( attribute "TOLERANCE" "5%"
					( Origin gFrontEnd )
				)
				( attribute "VALUE" "0.0"
					( Origin gFrontEnd )
				)
				( attribute "VER" "1"
					( Origin gFrontEnd )
				)
				( attribute "WATTAGE" "1/16W"
					( Origin gFrontEnd )
				)
				( attribute "XY" "(-800,3100)"
					( Origin gFrontEnd )
				)
				( attribute "CHIPS_PART_NAME" "RES"
					( Origin gPackager )
				)
				( attribute "CDS_PART_NAME" "RES_0402-0.0,5%,1/16W,CHIP,G21A"
					( Origin gPackager )
				)
				( attribute "CDS_LOCATION" "R2U14"
					( Origin gPackager )
				)
				( attribute "CDS_SEC" "1"
					( Origin gPackager )
				)
				( attribute "SEC" "1"
					( Origin gPackager )
				)
				( attribute "GROUP" "PCIE_RISER"
					( Origin gFrontEnd )
				)
				( objectStatus "R2U14" )
			)
			( gate "@baseboard_fab2_lib.baseboard_fab2(sch_1):page107_i498"
				( attribute "CDS_LIB" "mstr_discrete"
					( Origin gPackager )
				)
				( attribute "LOCATION" "R2U26"
					( Origin gFrontEnd )
				)
				( attribute "MATERIAL" "CHIP"
					( Origin gFrontEnd )
				)
				( attribute "PACK_TYPE" "0402"
					( Origin gFrontEnd )
				)
				( attribute "PART_NUMBER" "G21497-005"
					( Origin gFrontEnd )
				)
				( attribute "PHYS_PAGE" "107"
					( Origin gFrontEnd )
				)
				( attribute "ROT" "1"
					( Origin gFrontEnd )
				)
				( attribute "TOLERANCE" "5%"
					( Origin gFrontEnd )
				)
				( attribute "VALUE" "0.0"
					( Origin gFrontEnd )
				)
				( attribute "VER" "1"
					( Origin gFrontEnd )
				)
				( attribute "WATTAGE" "1/16W"
					( Origin gFrontEnd )
				)
				( attribute "XY" "(-2000,3100)"
					( Origin gFrontEnd )
				)
				( attribute "CHIPS_PART_NAME" "RES"
					( Origin gPackager )
				)
				( attribute "CDS_PART_NAME" "RES_0402-0.0,5%,1/16W,CHIP,G21A"
					( Origin gPackager )
				)
				( attribute "CDS_LOCATION" "R2U26"
					( Origin gPackager )
				)
				( attribute "CDS_SEC" "1"
					( Origin gPackager )
				)
				( attribute "SEC" "1"
					( Origin gPackager )
				)
				( attribute "GROUP" "PCIE_RISER"
					( Origin gFrontEnd )
				)
				( objectStatus "R2U26" )
			)
			( gate "@baseboard_fab2_lib.baseboard_fab2(sch_1):page107_i481"
				( attribute "CDS_LIB" "mstr_discrete"
					( Origin gPackager )
				)
				( attribute "LOCATION" "C3P12"
					( Origin gFrontEnd )
				)
				( attribute "MATERIAL" "X7R"
					( Origin gFrontEnd )
				)
				( attribute "PACK_TYPE" "0402"
					( Origin gFrontEnd )
				)
				( attribute "PART_NUMBER" "A36096-155"
					( Origin gFrontEnd )
				)
				( attribute "PHYS_PAGE" "107"
					( Origin gFrontEnd )
				)
				( attribute "ROT" "0"
					( Origin gFrontEnd )
				)
				( attribute "TOLERANCE" "10%"
					( Origin gFrontEnd )
				)
				( attribute "VALUE" "0.22UF"
					( Origin gFrontEnd )
				)
				( attribute "VER" "1"
					( Origin gFrontEnd )
				)
				( attribute "VOLTAGE" "16V"
					( Units "uVoltage" "V" 1.000000)
					( Origin gFrontEnd )
				)
				( attribute "XY" "(-4300,3975)"
					( Origin gFrontEnd )
				)
				( attribute "CHIPS_PART_NAME" "CAP"
					( Origin gPackager )
				)
				( attribute "CDS_PART_NAME" "CAP_0402-0.22UF,16V,10%,X7R,A3A"
					( Origin gPackager )
				)
				( attribute "CDS_LOCATION" "C3P12"
					( Origin gPackager )
				)
				( attribute "CDS_SEC" "1"
					( Origin gPackager )
				)
				( attribute "SEC" "1"
					( Origin gPackager )
				)
				( attribute "GROUP" "PCIE_RISER"
					( Origin gFrontEnd )
				)
				( objectStatus "C3P12" )
			)
			( gate "@baseboard_fab2_lib.baseboard_fab2(sch_1):page107_i480"
				( attribute "CDS_LIB" "mstr_discrete"
					( Origin gPackager )
				)
				( attribute "LOCATION" "C3P21"
					( Origin gFrontEnd )
				)
				( attribute "MATERIAL" "X7R"
					( Origin gFrontEnd )
				)
				( attribute "PACK_TYPE" "0402"
					( Origin gFrontEnd )
				)
				( attribute "PART_NUMBER" "A36096-155"
					( Origin gFrontEnd )
				)
				( attribute "PHYS_PAGE" "107"
					( Origin gFrontEnd )
				)
				( attribute "ROT" "0"
					( Origin gFrontEnd )
				)
				( attribute "TOLERANCE" "10%"
					( Origin gFrontEnd )
				)
				( attribute "VALUE" "0.22UF"
					( Origin gFrontEnd )
				)
				( attribute "VER" "1"
					( Origin gFrontEnd )
				)
				( attribute "VOLTAGE" "16V"
					( Units "uVoltage" "V" 1.000000)
					( Origin gFrontEnd )
				)
				( attribute "XY" "(-4700,3975)"
					( Origin gFrontEnd )
				)
				( attribute "CHIPS_PART_NAME" "CAP"
					( Origin gPackager )
				)
				( attribute "CDS_PART_NAME" "CAP_0402-0.22UF,16V,10%,X7R,A3A"
					( Origin gPackager )
				)
				( attribute "CDS_LOCATION" "C3P21"
					( Origin gPackager )
				)
				( attribute "CDS_SEC" "1"
					( Origin gPackager )
				)
				( attribute "SEC" "1"
					( Origin gPackager )
				)
				( attribute "GROUP" "PCIE_RISER"
					( Origin gFrontEnd )
				)
				( objectStatus "C3P21" )
			)
			( gate "@baseboard_fab2_lib.baseboard_fab2(sch_1):page107_i479"
				( attribute "CDS_LIB" "mstr_discrete"
					( Origin gPackager )
				)
				( attribute "LOCATION" "C3P24"
					( Origin gFrontEnd )
				)
				( attribute "MATERIAL" "X7R"
					( Origin gFrontEnd )
				)
				( attribute "PACK_TYPE" "0402"
					( Origin gFrontEnd )
				)
				( attribute "PART_NUMBER" "A36096-155"
					( Origin gFrontEnd )
				)
				( attribute "PHYS_PAGE" "107"
					( Origin gFrontEnd )
				)
				( attribute "ROT" "0"
					( Origin gFrontEnd )
				)
				( attribute "TOLERANCE" "10%"
					( Origin gFrontEnd )
				)
				( attribute "VALUE" "0.22UF"
					( Origin gFrontEnd )
				)
				( attribute "VER" "1"
					( Origin gFrontEnd )
				)
				( attribute "VOLTAGE" "16V"
					( Units "uVoltage" "V" 1.000000)
					( Origin gFrontEnd )
				)
				( attribute "XY" "(-4900,3675)"
					( Origin gFrontEnd )
				)
				( attribute "CHIPS_PART_NAME" "CAP"
					( Origin gPackager )
				)
				( attribute "CDS_PART_NAME" "CAP_0402-0.22UF,16V,10%,X7R,A3A"
					( Origin gPackager )
				)
				( attribute "CDS_LOCATION" "C3P24"
					( Origin gPackager )
				)
				( attribute "CDS_SEC" "1"
					( Origin gPackager )
				)
				( attribute "SEC" "1"
					( Origin gPackager )
				)
				( attribute "GROUP" "PCIE_RISER"
					( Origin gFrontEnd )
				)
				( objectStatus "C3P24" )
			)
			( gate "@baseboard_fab2_lib.baseboard_fab2(sch_1):page107_i478"
				( attribute "CDS_LIB" "mstr_discrete"
					( Origin gPackager )
				)
				( attribute "LOCATION" "C3P29"
					( Origin gFrontEnd )
				)
				( attribute "MATERIAL" "X7R"
					( Origin gFrontEnd )
				)
				( attribute "PACK_TYPE" "0402"
					( Origin gFrontEnd )
				)
				( attribute "PART_NUMBER" "A36096-155"
					( Origin gFrontEnd )
				)
				( attribute "PHYS_PAGE" "107"
					( Origin gFrontEnd )
				)
				( attribute "ROT" "0"
					( Origin gFrontEnd )
				)
				( attribute "TOLERANCE" "10%"
					( Origin gFrontEnd )
				)
				( attribute "VALUE" "0.22UF"
					( Origin gFrontEnd )
				)
				( attribute "VER" "1"
					( Origin gFrontEnd )
				)
				( attribute "VOLTAGE" "16V"
					( Units "uVoltage" "V" 1.000000)
					( Origin gFrontEnd )
				)
				( attribute "XY" "(-5100,3975)"
					( Origin gFrontEnd )
				)
				( attribute "CHIPS_PART_NAME" "CAP"
					( Origin gPackager )
				)
				( attribute "CDS_PART_NAME" "CAP_0402-0.22UF,16V,10%,X7R,A3A"
					( Origin gPackager )
				)
				( attribute "CDS_LOCATION" "C3P29"
					( Origin gPackager )
				)
				( attribute "CDS_SEC" "1"
					( Origin gPackager )
				)
				( attribute "SEC" "1"
					( Origin gPackager )
				)
				( attribute "GROUP" "PCIE_RISER"
					( Origin gFrontEnd )
				)
				( objectStatus "C3P29" )
			)
			( gate "@baseboard_fab2_lib.baseboard_fab2(sch_1):page185_i142"
				( attribute "CDS_LIB" "dev_discrete"
					( Origin gPackager )
				)
				( attribute "LOCATION" "C8F15"
					( Origin gFrontEnd )
				)
				( attribute "MATERIAL" "X7R"
					( Origin gFrontEnd )
				)
				( attribute "PACK_TYPE" "0402V"
					( Origin gFrontEnd )
				)
				( attribute "PART_NUMBER" "A36096-045"
					( Origin gFrontEnd )
				)
				( attribute "PHYS_PAGE" "185"
					( Origin gFrontEnd )
				)
				( attribute "ROT" "1"
					( Origin gFrontEnd )
				)
				( attribute "SEC" "1"
					( Origin gFrontEnd )
				)
				( attribute "SEC_TYPE" "0402V"
					( Origin gFrontEnd )
				)
				( attribute "TOLERANCE" "10%"
					( Origin gFrontEnd )
				)
				( attribute "VALUE" "0.01UF"
					( Origin gFrontEnd )
				)
				( attribute "VER" "1"
					( Origin gFrontEnd )
				)
				( attribute "VOLTAGE" "25V"
					( Units "uVoltage" "V" 1.000000)
					( Origin gFrontEnd )
				)
				( attribute "XY" "(-2575,750)"
					( Origin gFrontEnd )
				)
				( attribute "CHIPS_PART_NAME" "CAP_A"
					( Origin gPackager )
				)
				( attribute "CDS_PART_NAME" "CAP_A_0402V-0.01UF,25V,10%,X7RA"
					( Origin gPackager )
				)
				( attribute "CDS_LOCATION" "C8F15"
					( Origin gPackager )
				)
				( attribute "CDS_SEC" "1"
					( Origin gPackager )
				)
				( attribute "GROUP" "M2_SATA"
					( Origin gFrontEnd )
				)
				( objectStatus "C8F15" )
			)
			( gate "@baseboard_fab2_lib.baseboard_fab2(sch_1):page185_i141"
				( attribute "CDS_LIB" "dev_discrete"
					( Origin gPackager )
				)
				( attribute "LOCATION" "C8F13"
					( Origin gFrontEnd )
				)
				( attribute "MATERIAL" "X7R"
					( Origin gFrontEnd )
				)
				( attribute "PACK_TYPE" "0402V"
					( Origin gFrontEnd )
				)
				( attribute "PART_NUMBER" "A36096-045"
					( Origin gFrontEnd )
				)
				( attribute "PHYS_PAGE" "185"
					( Origin gFrontEnd )
				)
				( attribute "ROT" "1"
					( Origin gFrontEnd )
				)
				( attribute "SEC" "1"
					( Origin gFrontEnd )
				)
				( attribute "SEC_TYPE" "0402V"
					( Origin gFrontEnd )
				)
				( attribute "TOLERANCE" "10%"
					( Origin gFrontEnd )
				)
				( attribute "VALUE" "0.01UF"
					( Origin gFrontEnd )
				)
				( attribute "VER" "1"
					( Origin gFrontEnd )
				)
				( attribute "VOLTAGE" "25V"
					( Units "uVoltage" "V" 1.000000)
					( Origin gFrontEnd )
				)
				( attribute "XY" "(-2600,1175)"
					( Origin gFrontEnd )
				)
				( attribute "CHIPS_PART_NAME" "CAP_A"
					( Origin gPackager )
				)
				( attribute "CDS_PART_NAME" "CAP_A_0402V-0.01UF,25V,10%,X7RA"
					( Origin gPackager )
				)
				( attribute "CDS_LOCATION" "C8F13"
					( Origin gPackager )
				)
				( attribute "CDS_SEC" "1"
					( Origin gPackager )
				)
				( attribute "GROUP" "M2_SATA"
					( Origin gFrontEnd )
				)
				( objectStatus "C8F13" )
			)
			( gate "@baseboard_fab2_lib.baseboard_fab2(sch_1):page185_i140"
				( attribute "BOM_COST" "ST_FLASH"
					( Origin gFrontEnd )
				)
				( attribute "CDS_LIB" "mstr_discrete"
					( Origin gPackager )
				)
				( attribute "CDS_LOCATION" "C8F12"
					( Origin gPackager )
				)
				( attribute "CDS_SEC" "1"
					( Origin gPackager )
				)
				( attribute "LOCATION" "C8F12"
					( Origin gFrontEnd )
				)
				( attribute "MATERIAL" "X7R"
					( Origin gFrontEnd )
				)
				( attribute "PACK_TYPE" "0402"
					( Origin gFrontEnd )
				)
				( attribute "PART_NUMBER" "A36096-155"
					( Origin gFrontEnd )
				)
				( attribute "PHYS_PAGE" "185"
					( Origin gFrontEnd )
				)
				( attribute "ROOM" "M_2"
					( Origin gFrontEnd )
				)
				( attribute "ROT" "0"
					( Origin gFrontEnd )
				)
				( attribute "SEC" "1"
					( Origin gFrontEnd )
				)
				( attribute "SEC_TYPE" "0402"
					( Origin gFrontEnd )
				)
				( attribute "TOLERANCE" "10%"
					( Origin gFrontEnd )
				)
				( attribute "VALUE" "0.22UF"
					( Origin gFrontEnd )
				)
				( attribute "VER" "2"
					( Origin gFrontEnd )
				)
				( attribute "VOLTAGE" "16V"
					( Units "uVoltage" "V" 1.000000)
					( Origin gFrontEnd )
				)
				( attribute "XY" "(-2600,1375)"
					( Origin gFrontEnd )
				)
				( attribute "CHIPS_PART_NAME" "CAP"
					( Origin gPackager )
				)
				( attribute "CDS_PART_NAME" "CAP_0402-0.22UF,16V,10%,X7R,A3A"
					( Origin gPackager )
				)
				( attribute "GROUP" "M2_PCIE"
					( Origin gFrontEnd )
				)
				( objectStatus "C8F12" )
			)
			( gate "@baseboard_fab2_lib.baseboard_fab2(sch_1):page185_i138"
				( attribute "CDS_LIB" "dev_discrete"
					( Origin gPackager )
				)
				( attribute "LOCATION" "C8F6"
					( Origin gFrontEnd )
				)
				( attribute "MATERIAL" "X7R"
					( Origin gFrontEnd )
				)
				( attribute "PACK_TYPE" "0402V"
					( Origin gFrontEnd )
				)
				( attribute "PART_NUMBER" "A36096-045"
					( Origin gFrontEnd )
				)
				( attribute "PHYS_PAGE" "185"
					( Origin gFrontEnd )
				)
				( attribute "ROT" "1"
					( Origin gFrontEnd )
				)
				( attribute "TOLERANCE" "10%"
					( Origin gFrontEnd )
				)
				( attribute "VALUE" "0.01UF"
					( Origin gFrontEnd )
				)
				( attribute "VER" "1"
					( Origin gFrontEnd )
				)
				( attribute "VOLTAGE" "25V"
					( Units "uVoltage" "V" 1.000000)
					( Origin gFrontEnd )
				)
				( attribute "XY" "(-2600,2100)"
					( Origin gFrontEnd )
				)
				( attribute "CHIPS_PART_NAME" "CAP_A"
					( Origin gPackager )
				)
				( attribute "CDS_PART_NAME" "CAP_A_0402V-0.01UF,25V,10%,X7RA"
					( Origin gPackager )
				)
				( attribute "SEC" "1"
					( Origin gFrontEnd )
				)
				( attribute "SEC_TYPE" "0402V"
					( Origin gFrontEnd )
				)
				( attribute "CDS_LOCATION" "C8F6"
					( Origin gPackager )
				)
				( attribute "CDS_SEC" "1"
					( Origin gPackager )
				)
				( attribute "GROUP" "M2_SATA"
					( Origin gFrontEnd )
				)
				( objectStatus "C8F6" )
			)
			( gate "@baseboard_fab2_lib.baseboard_fab2(sch_1):page250_i8"
				( attribute "BOM_COST" "DEBUG"
					( Origin gFrontEnd )
				)
				( attribute "CDS_LIB" "mstr_discrete"
					( Origin gPackager )
				)
				( attribute "CDS_LOCATION" "Q1W4"
					( Origin gPackager )
				)
				( attribute "CDS_SEC" "2"
					( Origin gPackager )
				)
				( attribute "LOCATION" "Q1W4"
					( Origin gFrontEnd )
				)
				( attribute "MATERIAL" "FET"
					( Origin gFrontEnd )
				)
				( attribute "PACK_TYPE" "SMLF"
					( Origin gFrontEnd )
				)
				( attribute "PART_NUMBER" "D24280-001"
					( Origin gFrontEnd )
				)
				( attribute "PHYS_PAGE" "250"
					( Origin gFrontEnd )
				)
				( attribute "ROOM" "UART_MUX"
					( Origin gFrontEnd )
				)
				( attribute "ROT" "0"
					( Origin gFrontEnd )
				)
				( attribute "SEC" "2"
					( Origin gFrontEnd )
				)
				( attribute "SEC_TYPE" "SMLF"
					( Origin gFrontEnd )
				)
				( attribute "VALUE" "2N7002DW"
					( Origin gFrontEnd )
				)
				( attribute "VER" "5"
					( Origin gFrontEnd )
				)
				( attribute "XY" "(-5925,2800)"
					( Origin gFrontEnd )
				)
				( attribute "CHIPS_PART_NAME" "FET_N_DUAL"
					( Origin gPackager )
				)
				( attribute "CDS_PART_NAME" "FET_N_DUAL_SMLF-2N7002DW,FET,DA"
					( Origin gPackager )
				)
				( objectStatus "Q1W4" )
			)
			( gate "@baseboard_fab2_lib.baseboard_fab2(sch_1):page250_i6"
				( attribute "CDS_LIB" "mstr_discrete"
					( Origin gPackager )
				)
				( attribute "CDS_LOCATION" "R1W7"
					( Origin gPackager )
				)
				( attribute "LOCATION" "R1W7"
					( Origin gFrontEnd )
				)
				( attribute "MATERIAL" "CHIP"
					( Origin gFrontEnd )
				)
				( attribute "PACK_TYPE" "0402"
					( Origin gFrontEnd )
				)
				( attribute "PART_NUMBER" "G21796-016"
					( Origin gFrontEnd )
				)
				( attribute "PHYS_PAGE" "250"
					( Origin gFrontEnd )
				)
				( attribute "ROOM" "SB"
					( Origin gFrontEnd )
				)
				( attribute "ROT" "1"
					( Origin gFrontEnd )
				)
				( attribute "SEC" "1"
					( Origin gFrontEnd )
				)
				( attribute "TOLERANCE" "1%"
					( Origin gFrontEnd )
				)
				( attribute "VALUE" "10.0K"
					( Origin gFrontEnd )
				)
				( attribute "VER" "1"
					( Origin gFrontEnd )
				)
				( attribute "WATTAGE" "1/16W"
					( Origin gFrontEnd )
				)
				( attribute "XY" "(-7700,2900)"
					( Origin gFrontEnd )
				)
				( attribute "CHIPS_PART_NAME" "RES"
					( Origin gPackager )
				)
				( attribute "CDS_PART_NAME" "RES_0402-10.0K,1%,1/16W,CHIP,GA"
					( Origin gPackager )
				)
				( attribute "SEC_TYPE" "0402"
					( Origin gFrontEnd )
				)
				( attribute "CDS_SEC" "1"
					( Origin gPackager )
				)
				( objectStatus "R1W7" )
			)
			( gate "@baseboard_fab2_lib.baseboard_fab2(sch_1):page250_i3"
				( attribute "BOM_COST" "DEBUG"
					( Origin gFrontEnd )
				)
				( attribute "CDS_LIB" "mstr_discrete"
					( Origin gPackager )
				)
				( attribute "CDS_LOCATION" "Q1W4"
					( Origin gPackager )
				)
				( attribute "CDS_SEC" "1"
					( Origin gPackager )
				)
				( attribute "LOCATION" "Q1W4"
					( Origin gFrontEnd )
				)
				( attribute "MATERIAL" "FET"
					( Origin gFrontEnd )
				)
				( attribute "PACK_TYPE" "SMLF"
					( Origin gFrontEnd )
				)
				( attribute "PART_NUMBER" "D24280-001"
					( Origin gFrontEnd )
				)
				( attribute "PHYS_PAGE" "250"
					( Origin gFrontEnd )
				)
				( attribute "ROOM" "UART_MUX"
					( Origin gFrontEnd )
				)
				( attribute "ROT" "0"
					( Origin gFrontEnd )
				)
				( attribute "SEC" "1"
					( Origin gFrontEnd )
				)
				( attribute "SEC_TYPE" "SMLF"
					( Origin gFrontEnd )
				)
				( attribute "VALUE" "2N7002DW"
					( Origin gFrontEnd )
				)
				( attribute "VER" "5"
					( Origin gFrontEnd )
				)
				( attribute "XY" "(-7700,2450)"
					( Origin gFrontEnd )
				)
				( attribute "CHIPS_PART_NAME" "FET_N_DUAL"
					( Origin gPackager )
				)
				( attribute "CDS_PART_NAME" "FET_N_DUAL_SMLF-2N7002DW,FET,DA"
					( Origin gPackager )
				)
				( objectStatus "Q1W4" )
			)
			( gate "@baseboard_fab2_lib.baseboard_fab2(sch_1):page250_i2"
				( attribute "CDS_LIB" "w_hdl"
					( Origin gPackager )
				)
				( attribute "CDS_LMAN_SYM_OUTLINE" "-50,75,50,-75"
					( Origin gPackager )
				)
				( attribute "CDS_LOCATION" "R1W6"
					( Origin gPackager )
				)
				( attribute "CDS_SEC" "1"
					( Origin gPackager )
				)
				( attribute "LOCATION" "R1W6"
					( Origin gFrontEnd )
				)
				( attribute "PACK_TYPE" "SMD-RG1"
					( Origin gFrontEnd )
				)
				( attribute "PART_NUMBER" "64.10045.L1L"
					( Origin gFrontEnd )
				)
				( attribute "PHYS_PAGE" "250"
					( Origin gFrontEnd )
				)
				( attribute "ROT" "0"
					( Origin gFrontEnd )
				)
				( attribute "SEC" "1"
					( Origin gPackager )
				)
				( attribute "VALUE" "1MR2F-L-GP"
					( Origin gFrontEnd )
				)
				( attribute "VER" "1"
					( Origin gFrontEnd )
				)
				( attribute "XY" "(-8725,2575)"
					( Origin gFrontEnd )
				)
				( attribute "CHIPS_PART_NAME" "1MR2F-L-GP"
					( Origin gPackager )
				)
				( attribute "CDS_PART_NAME" "1MR2F-L-GP_SMD-RG1-1MR2F-L-GP,A"
					( Origin gPackager )
				)
				( attribute "ATTRIBUTE" "1MOHM"
					( Origin gFrontEnd )
				)
				( attribute "RATED" "1/16W"
					( Origin gFrontEnd )
				)
				( attribute "TOLERANCE" "1%"
					( Origin gFrontEnd )
				)
				( attribute "PACK_SIZE" "0402"
					( Origin gFrontEnd )
				)
				( objectStatus "R1W6" )
			)
			( gate "@baseboard_fab2_lib.baseboard_fab2(sch_1):page107_i501"
				( attribute "CDS_LIB" "mstr_discrete"
					( Origin gPackager )
				)
				( attribute "LOCATION" "R2U16"
					( Origin gFrontEnd )
				)
				( attribute "MATERIAL" "CHIP"
					( Origin gFrontEnd )
				)
				( attribute "PACK_TYPE" "0402"
					( Origin gFrontEnd )
				)
				( attribute "PART_NUMBER" "G21497-005"
					( Origin gFrontEnd )
				)
				( attribute "PHYS_PAGE" "107"
					( Origin gFrontEnd )
				)
				( attribute "ROT" "1"
					( Origin gFrontEnd )
				)
				( attribute "TOLERANCE" "5%"
					( Origin gFrontEnd )
				)
				( attribute "VALUE" "0.0"
					( Origin gFrontEnd )
				)
				( attribute "VER" "1"
					( Origin gFrontEnd )
				)
				( attribute "WATTAGE" "1/16W"
					( Origin gFrontEnd )
				)
				( attribute "XY" "(-1000,2800)"
					( Origin gFrontEnd )
				)
				( attribute "CHIPS_PART_NAME" "RES"
					( Origin gPackager )
				)
				( attribute "CDS_PART_NAME" "RES_0402-0.0,5%,1/16W,CHIP,G21A"
					( Origin gPackager )
				)
				( attribute "CDS_LOCATION" "R2U16"
					( Origin gPackager )
				)
				( attribute "CDS_SEC" "1"
					( Origin gPackager )
				)
				( attribute "SEC" "1"
					( Origin gPackager )
				)
				( attribute "GROUP" "PCIE_RISER"
					( Origin gFrontEnd )
				)
				( objectStatus "R2U16" )
			)
			( gate "@baseboard_fab2_lib.baseboard_fab2(sch_1):page107_i502"
				( attribute "CDS_LIB" "mstr_discrete"
					( Origin gPackager )
				)
				( attribute "LOCATION" "R2U18"
					( Origin gFrontEnd )
				)
				( attribute "MATERIAL" "CHIP"
					( Origin gFrontEnd )
				)
				( attribute "PACK_TYPE" "0402"
					( Origin gFrontEnd )
				)
				( attribute "PART_NUMBER" "G21497-005"
					( Origin gFrontEnd )
				)
				( attribute "PHYS_PAGE" "107"
					( Origin gFrontEnd )
				)
				( attribute "ROT" "1"
					( Origin gFrontEnd )
				)
				( attribute "TOLERANCE" "5%"
					( Origin gFrontEnd )
				)
				( attribute "VALUE" "0.0"
					( Origin gFrontEnd )
				)
				( attribute "VER" "1"
					( Origin gFrontEnd )
				)
				( attribute "WATTAGE" "1/16W"
					( Origin gFrontEnd )
				)
				( attribute "XY" "(-1200,3100)"
					( Origin gFrontEnd )
				)
				( attribute "CHIPS_PART_NAME" "RES"
					( Origin gPackager )
				)
				( attribute "CDS_PART_NAME" "RES_0402-0.0,5%,1/16W,CHIP,G21A"
					( Origin gPackager )
				)
				( attribute "CDS_LOCATION" "R2U18"
					( Origin gPackager )
				)
				( attribute "CDS_SEC" "1"
					( Origin gPackager )
				)
				( attribute "SEC" "1"
					( Origin gPackager )
				)
				( attribute "GROUP" "PCIE_RISER"
					( Origin gFrontEnd )
				)
				( objectStatus "R2U18" )
			)
			( gate "@baseboard_fab2_lib.baseboard_fab2(sch_1):page107_i503"
				( attribute "CDS_LIB" "mstr_discrete"
					( Origin gPackager )
				)
				( attribute "LOCATION" "R2U20"
					( Origin gFrontEnd )
				)
				( attribute "MATERIAL" "CHIP"
					( Origin gFrontEnd )
				)
				( attribute "PACK_TYPE" "0402"
					( Origin gFrontEnd )
				)
				( attribute "PART_NUMBER" "G21497-005"
					( Origin gFrontEnd )
				)
				( attribute "PHYS_PAGE" "107"
					( Origin gFrontEnd )
				)
				( attribute "ROT" "1"
					( Origin gFrontEnd )
				)
				( attribute "TOLERANCE" "5%"
					( Origin gFrontEnd )
				)
				( attribute "VALUE" "0.0"
					( Origin gFrontEnd )
				)
				( attribute "VER" "1"
					( Origin gFrontEnd )
				)
				( attribute "WATTAGE" "1/16W"
					( Origin gFrontEnd )
				)
				( attribute "XY" "(-1400,2800)"
					( Origin gFrontEnd )
				)
				( attribute "CHIPS_PART_NAME" "RES"
					( Origin gPackager )
				)
				( attribute "CDS_PART_NAME" "RES_0402-0.0,5%,1/16W,CHIP,G21A"
					( Origin gPackager )
				)
				( attribute "CDS_LOCATION" "R2U20"
					( Origin gPackager )
				)
				( attribute "CDS_SEC" "1"
					( Origin gPackager )
				)
				( attribute "SEC" "1"
					( Origin gPackager )
				)
				( attribute "GROUP" "PCIE_RISER"
					( Origin gFrontEnd )
				)
				( objectStatus "R2U20" )
			)
			( gate "@baseboard_fab2_lib.baseboard_fab2(sch_1):page107_i504"
				( attribute "CDS_LIB" "mstr_discrete"
					( Origin gPackager )
				)
				( attribute "LOCATION" "R2U22"
					( Origin gFrontEnd )
				)
				( attribute "MATERIAL" "CHIP"
					( Origin gFrontEnd )
				)
				( attribute "PACK_TYPE" "0402"
					( Origin gFrontEnd )
				)
				( attribute "PART_NUMBER" "G21497-005"
					( Origin gFrontEnd )
				)
				( attribute "PHYS_PAGE" "107"
					( Origin gFrontEnd )
				)
				( attribute "ROT" "1"
					( Origin gFrontEnd )
				)
				( attribute "TOLERANCE" "5%"
					( Origin gFrontEnd )
				)
				( attribute "VALUE" "0.0"
					( Origin gFrontEnd )
				)
				( attribute "VER" "1"
					( Origin gFrontEnd )
				)
				( attribute "WATTAGE" "1/16W"
					( Origin gFrontEnd )
				)
				( attribute "XY" "(-1600,3100)"
					( Origin gFrontEnd )
				)
				( attribute "CHIPS_PART_NAME" "RES"
					( Origin gPackager )
				)
				( attribute "CDS_PART_NAME" "RES_0402-0.0,5%,1/16W,CHIP,G21A"
					( Origin gPackager )
				)
				( attribute "CDS_LOCATION" "R2U22"
					( Origin gPackager )
				)
				( attribute "CDS_SEC" "1"
					( Origin gPackager )
				)
				( attribute "SEC" "1"
					( Origin gPackager )
				)
				( attribute "GROUP" "PCIE_RISER"
					( Origin gFrontEnd )
				)
				( objectStatus "R2U22" )
			)
			( gate "@baseboard_fab2_lib.baseboard_fab2(sch_1):page107_i505"
				( attribute "CDS_LIB" "mstr_discrete"
					( Origin gPackager )
				)
				( attribute "LOCATION" "R2U24"
					( Origin gFrontEnd )
				)
				( attribute "MATERIAL" "CHIP"
					( Origin gFrontEnd )
				)
				( attribute "PACK_TYPE" "0402"
					( Origin gFrontEnd )
				)
				( attribute "PART_NUMBER" "G21497-005"
					( Origin gFrontEnd )
				)
				( attribute "PHYS_PAGE" "107"
					( Origin gFrontEnd )
				)
				( attribute "ROT" "1"
					( Origin gFrontEnd )
				)
				( attribute "TOLERANCE" "5%"
					( Origin gFrontEnd )
				)
				( attribute "VALUE" "0.0"
					( Origin gFrontEnd )
				)
				( attribute "VER" "1"
					( Origin gFrontEnd )
				)
				( attribute "WATTAGE" "1/16W"
					( Origin gFrontEnd )
				)
				( attribute "XY" "(-1800,2800)"
					( Origin gFrontEnd )
				)
				( attribute "CHIPS_PART_NAME" "RES"
					( Origin gPackager )
				)
				( attribute "CDS_PART_NAME" "RES_0402-0.0,5%,1/16W,CHIP,G21A"
					( Origin gPackager )
				)
				( attribute "CDS_LOCATION" "R2U24"
					( Origin gPackager )
				)
				( attribute "CDS_SEC" "1"
					( Origin gPackager )
				)
				( attribute "SEC" "1"
					( Origin gPackager )
				)
				( attribute "GROUP" "PCIE_RISER"
					( Origin gFrontEnd )
				)
				( objectStatus "R2U24" )
			)
			( gate "@baseboard_fab2_lib.baseboard_fab2(sch_1):page169_i171"
				( attribute "CDS_LIB" "w_hdl"
					( Origin gPackager )
				)
				( attribute "CDS_LMAN_SYM_OUTLINE" "-50,75,50,-75"
					( Origin gPackager )
				)
				( attribute "LOCATION" "R1U33"
					( Origin gFrontEnd )
				)
				( attribute "PACK_TYPE" "RCL_GP"
					( Origin gFrontEnd )
				)
				( attribute "PART_NUMBER" "64.64905.6DL"
					( Origin gFrontEnd )
				)
				( attribute "PHYS_PAGE" "169"
					( Origin gFrontEnd )
				)
				( attribute "ROT" "0"
					( Origin gFrontEnd )
				)
				( attribute "SEC" "1"
					( Origin gFrontEnd )
				)
				( attribute "SEC_TYPE" "RCL_GP"
					( Origin gFrontEnd )
				)
				( attribute "VALUE" "649R2F-GP"
					( Origin gFrontEnd )
				)
				( attribute "VER" "1"
					( Origin gFrontEnd )
				)
				( attribute "XY" "(-1125,1425)"
					( Origin gFrontEnd )
				)
				( attribute "CHIPS_PART_NAME" "649R2F-GP"
					( Origin gPackager )
				)
				( attribute "CDS_PART_NAME" "649R2F-GP_RCL_GP-649R2F-GP,64.A"
					( Origin gPackager )
				)
				( attribute "CDS_LOCATION" "R1U33"
					( Origin gPackager )
				)
				( attribute "CDS_SEC" "1"
					( Origin gPackager )
				)
				( attribute "ATTRIBUTE" "649OHM"
					( Origin gFrontEnd )
				)
				( attribute "RATED" "1/16W"
					( Origin gFrontEnd )
				)
				( attribute "TOLERANCE" "1%"
					( Origin gFrontEnd )
				)
				( attribute "PACK_SIZE" "0402"
					( Origin gFrontEnd )
				)
				( objectStatus "R1U33" )
			)
			( gate "@baseboard_fab2_lib.baseboard_fab2(sch_1):page169_i172"
				( attribute "CDS_LIB" "mstr_discrete"
					( Origin gPackager )
				)
				( attribute "LOCATION" "R1U38"
					( Origin gFrontEnd )
				)
				( attribute "MATERIAL" "CHIP"
					( Origin gFrontEnd )
				)
				( attribute "PACK_TYPE" "0402"
					( Origin gFrontEnd )
				)
				( attribute "PART_NUMBER" "G21796-279"
					( Origin gFrontEnd )
				)
				( attribute "PHYS_PAGE" "169"
					( Origin gFrontEnd )
				)
				( attribute "ROT" "5"
					( Origin gFrontEnd )
				)
				( attribute "SEC" "1"
					( Origin gFrontEnd )
				)
				( attribute "SEC_TYPE" "0402"
					( Origin gFrontEnd )
				)
				( attribute "TOLERANCE" "1.0%"
					( Origin gFrontEnd )
				)
				( attribute "VALUE" "3.48K"
					( Origin gFrontEnd )
				)
				( attribute "VER" "1"
					( Origin gFrontEnd )
				)
				( attribute "WATTAGE" "1/16W"
					( Origin gFrontEnd )
				)
				( attribute "XY" "(-4825,1400)"
					( Origin gFrontEnd )
				)
				( attribute "CHIPS_PART_NAME" "RES"
					( Origin gPackager )
				)
				( attribute "CDS_PART_NAME" "RES_0402-3.48K,1.0%,1/16W,CHIPA"
					( Origin gPackager )
				)
				( attribute "CDS_LOCATION" "R1U38"
					( Origin gPackager )
				)
				( attribute "CDS_SEC" "1"
					( Origin gPackager )
				)
				( objectStatus "R1U38" )
			)
			( gate "@baseboard_fab2_lib.baseboard_fab2(sch_1):page169_i173"
				( attribute "CDS_LIB" "mstr_discrete"
					( Origin gPackager )
				)
				( attribute "LOCATION" "R1U27"
					( Origin gFrontEnd )
				)
				( attribute "MATERIAL" "CHIP"
					( Origin gFrontEnd )
				)
				( attribute "PACK_TYPE" "0402"
					( Origin gFrontEnd )
				)
				( attribute "PART_NUMBER" "G21796-279"
					( Origin gFrontEnd )
				)
				( attribute "PHYS_PAGE" "169"
					( Origin gFrontEnd )
				)
				( attribute "ROT" "5"
					( Origin gFrontEnd )
				)
				( attribute "SEC" "1"
					( Origin gFrontEnd )
				)
				( attribute "SEC_TYPE" "0402"
					( Origin gFrontEnd )
				)
				( attribute "TOLERANCE" "1.0%"
					( Origin gFrontEnd )
				)
				( attribute "VALUE" "3.48K"
					( Origin gFrontEnd )
				)
				( attribute "VER" "1"
					( Origin gFrontEnd )
				)
				( attribute "WATTAGE" "1/16W"
					( Origin gFrontEnd )
				)
				( attribute "XY" "(-2900,4625)"
					( Origin gFrontEnd )
				)
				( attribute "CHIPS_PART_NAME" "RES"
					( Origin gPackager )
				)
				( attribute "CDS_PART_NAME" "RES_0402-3.48K,1.0%,1/16W,CHIPA"
					( Origin gPackager )
				)
				( attribute "CDS_LOCATION" "R1U27"
					( Origin gPackager )
				)
				( attribute "CDS_SEC" "1"
					( Origin gPackager )
				)
				( objectStatus "R1U27" )
			)
			( gate "@baseboard_fab2_lib.baseboard_fab2(sch_1):page186_i358"
				( attribute "ATTRIBUTE" "887OHM"
					( Origin gFrontEnd )
				)
				( attribute "CDS_LIB" "w_hdl"
					( Origin gPackager )
				)
				( attribute "CDS_LMAN_SYM_OUTLINE" "-50,75,50,-75"
					( Origin gPackager )
				)
				( attribute "LOCATION" "R9B7"
					( Origin gFrontEnd )
				)
				( attribute "PACK_TYPE" "SMD-RG"
					( Origin gFrontEnd )
				)
				( attribute "PART_NUMBER" "64.88705.6DL"
					( Origin gFrontEnd )
				)
				( attribute "PHYS_PAGE" "186"
					( Origin gFrontEnd )
				)
				( attribute "RATED" "1/16W"
					( Origin gFrontEnd )
				)
				( attribute "ROT" "0"
					( Origin gFrontEnd )
				)
				( attribute "SEC" "1"
					( Origin gFrontEnd )
				)
				( attribute "SEC_TYPE" "SMD-RG"
					( Origin gFrontEnd )
				)
				( attribute "TOLERANCE" "1%"
					( Origin gFrontEnd )
				)
				( attribute "VALUE" "887R2F-L-GP"
					( Origin gFrontEnd )
				)
				( attribute "VER" "1"
					( Origin gFrontEnd )
				)
				( attribute "XY" "(6300,3675)"
					( Origin gFrontEnd )
				)
				( attribute "CHIPS_PART_NAME" "887R2F-L-GP"
					( Origin gPackager )
				)
				( attribute "CDS_PART_NAME" "887R2F-L-GP_SMD-RG-887R2F-L-GPA"
					( Origin gPackager )
				)
				( attribute "PACK_SIZE" "0402"
					( Origin gFrontEnd )
				)
				( attribute "CDS_LOCATION" "R9B7"
					( Origin gPackager )
				)
				( attribute "CDS_SEC" "1"
					( Origin gPackager )
				)
				( objectStatus "R9B7" )
			)
			( gate "@baseboard_fab2_lib.baseboard_fab2(sch_1):page187_i175"
				( attribute "ATTRIBUTE" "887OHM"
					( Origin gFrontEnd )
				)
				( attribute "CDS_LIB" "w_hdl"
					( Origin gPackager )
				)
				( attribute "CDS_LMAN_SYM_OUTLINE" "-50,75,50,-75"
					( Origin gPackager )
				)
				( attribute "LOCATION" "R2R8"
					( Origin gFrontEnd )
				)
				( attribute "PACK_TYPE" "SMD-RG"
					( Origin gFrontEnd )
				)
				( attribute "PART_NUMBER" "64.88705.6DL"
					( Origin gFrontEnd )
				)
				( attribute "PHYS_PAGE" "187"
					( Origin gFrontEnd )
				)
				( attribute "RATED" "1/16W"
					( Origin gFrontEnd )
				)
				( attribute "ROT" "0"
					( Origin gFrontEnd )
				)
				( attribute "SEC" "1"
					( Origin gFrontEnd )
				)
				( attribute "SEC_TYPE" "SMD-RG"
					( Origin gFrontEnd )
				)
				( attribute "TOLERANCE" "1%"
					( Origin gFrontEnd )
				)
				( attribute "VALUE" "887R2F-L-GP"
					( Origin gFrontEnd )
				)
				( attribute "VER" "1"
					( Origin gFrontEnd )
				)
				( attribute "XY" "(1950,4325)"
					( Origin gFrontEnd )
				)
				( attribute "CHIPS_PART_NAME" "887R2F-L-GP"
					( Origin gPackager )
				)
				( attribute "CDS_PART_NAME" "887R2F-L-GP_SMD-RG-887R2F-L-GPA"
					( Origin gPackager )
				)
				( attribute "PACK_SIZE" "0402"
					( Origin gFrontEnd )
				)
				( attribute "CDS_LOCATION" "R2R8"
					( Origin gPackager )
				)
				( attribute "CDS_SEC" "1"
					( Origin gPackager )
				)
				( objectStatus "R2R8" )
			)
			( gate "@baseboard_fab2_lib.baseboard_fab2(sch_1):page208_i105"
				( attribute "CDS_LIB" "mstr_discrete"
					( Origin gPackager )
				)
				( attribute "LOCATION" "CT20"
					( Origin gFrontEnd )
				)
				( attribute "MATERIAL" "X7R"
					( Origin gFrontEnd )
				)
				( attribute "PACK_TYPE" "0402LF"
					( Origin gFrontEnd )
				)
				( attribute "PART_NUMBER" "A36096-046"
					( Origin gFrontEnd )
				)
				( attribute "PHYS_PAGE" "208"
					( Origin gFrontEnd )
				)
				( attribute "POP" "NOPOP"
					( Origin gFrontEnd )
				)
				( attribute "ROOM" "VDDQ_KLM_PWR_VR"
					( Origin gFrontEnd )
				)
				( attribute "ROT" "0"
					( Origin gFrontEnd )
				)
				( attribute "TOLERANCE" "10%"
					( Origin gFrontEnd )
				)
				( attribute "VALUE" "1000PF"
					( Origin gFrontEnd )
				)
				( attribute "VER" "1"
					( Origin gFrontEnd )
				)
				( attribute "VOLTAGE" "50V"
					( Units "uVoltage" "V" 1.000000)
					( Origin gFrontEnd )
				)
				( attribute "XY" "(-2075,875)"
					( Origin gFrontEnd )
				)
				( attribute "CHIPS_PART_NAME" "CAP"
					( Origin gPackager )
				)
				( attribute "CDS_PART_NAME" "CAP_0402LF-1000PF,50V,10%,X7R,A"
					( Origin gPackager )
				)
				( attribute "CDS_LOCATION" "CT20"
					( Origin gPackager )
				)
				( attribute "SEC" "1"
					( Origin gFrontEnd )
				)
				( attribute "SEC_TYPE" "0402LF"
					( Origin gFrontEnd )
				)
				( attribute "CDS_SEC" "1"
					( Origin gPackager )
				)
				( objectStatus "CT20" )
			)
			( gate "@baseboard_fab2_lib.baseboard_fab2(sch_1):page243_i89"
				( attribute "BOM_COST" "PROC_SOCKET"
					( Origin gFrontEnd )
				)
				( attribute "CDS_LIB" "mstr_discrete"
					( Origin gPackager )
				)
				( attribute "LOCATION" "C5G115"
					( Origin gFrontEnd )
				)
				( attribute "MATERIAL" "X6S"
					( Origin gFrontEnd )
				)
				( attribute "PACK_TYPE" "0805"
					( Origin gFrontEnd )
				)
				( attribute "PART_NUMBER" "C95333-006"
					( Origin gFrontEnd )
				)
				( attribute "PHYS_PAGE" "243"
					( Origin gFrontEnd )
				)
				( attribute "ROOM" "PVCCIN_CPU0_DECAP_VR"
					( Origin gFrontEnd )
				)
				( attribute "ROT" "0"
					( Origin gFrontEnd )
				)
				( attribute "TOLERANCE" "20%"
					( Origin gFrontEnd )
				)
				( attribute "VALUE" "47UF"
					( Origin gFrontEnd )
				)
				( attribute "VER" "1"
					( Origin gFrontEnd )
				)
				( attribute "VOLTAGE" "4V"
					( Units "uVoltage" "V" 1.000000)
					( Origin gFrontEnd )
				)
				( attribute "XY" "(-3800,3775)"
					( Origin gFrontEnd )
				)
				( attribute "CHIPS_PART_NAME" "CAP"
					( Origin gPackager )
				)
				( attribute "CDS_PART_NAME" "CAP_0805-47UF,4V,20%,X6S,C9533A"
					( Origin gPackager )
				)
				( attribute "CDS_LOCATION" "C5G115"
					( Origin gPackager )
				)
				( attribute "SEC" "1"
					( Origin gFrontEnd )
				)
				( attribute "SEC_TYPE" "0805"
					( Origin gFrontEnd )
				)
				( attribute "CDS_SEC" "1"
					( Origin gPackager )
				)
				( attribute "GROUP" "PWR_MLCC_CAP"
					( Origin gFrontEnd )
				)
				( attribute "POP" "NOPOP"
					( Origin gFrontEnd )
				)
				( objectStatus "C5G115" )
			)
			( gate "@baseboard_fab2_lib.baseboard_fab2(sch_1):page203_i123"
				( attribute "BOM_COST" "NT_GBE_BASE"
					( Origin gFrontEnd )
				)
				( attribute "CDS_LIB" "mstr_discrete"
					( Origin gPackager )
				)
				( attribute "LOCATION" "RT28"
					( Origin gFrontEnd )
				)
				( attribute "MATERIAL" "CHIP"
					( Origin gFrontEnd )
				)
				( attribute "PACK_TYPE" "0603"
					( Origin gFrontEnd )
				)
				( attribute "PART_NUMBER" "G22178-002"
					( Origin gFrontEnd )
				)
				( attribute "PHYS_PAGE" "203"
					( Origin gFrontEnd )
				)
				( attribute "ROOM" "NIC_SPRV"
					( Origin gFrontEnd )
				)
				( attribute "ROT" "0"
					( Origin gFrontEnd )
				)
				( attribute "TOLERANCE" "5.0%"
					( Origin gFrontEnd )
				)
				( attribute "VALUE" "0"
					( Origin gFrontEnd )
				)
				( attribute "VER" "1"
					( Origin gFrontEnd )
				)
				( attribute "WATTAGE" "1/10W"
					( Origin gFrontEnd )
				)
				( attribute "XY" "(-4950,975)"
					( Origin gFrontEnd )
				)
				( attribute "CHIPS_PART_NAME" "RES"
					( Origin gPackager )
				)
				( attribute "CDS_PART_NAME" "RES_0603-0,5.0%,1/10W,CHIP,G22A"
					( Origin gPackager )
				)
				( attribute "CDS_LOCATION" "RT28"
					( Origin gPackager )
				)
				( attribute "SEC" "1"
					( Origin gFrontEnd )
				)
				( attribute "SEC_TYPE" "0603"
					( Origin gFrontEnd )
				)
				( attribute "CDS_SEC" "1"
					( Origin gPackager )
				)
				( objectStatus "RT28" )
			)
			( gate "@baseboard_fab2_lib.baseboard_fab2(sch_1):page203_i122"
				( attribute "BOM_COST" "NT_GBE_BASE"
					( Origin gFrontEnd )
				)
				( attribute "CDS_LIB" "mstr_discrete"
					( Origin gPackager )
				)
				( attribute "LOCATION" "RT25"
					( Origin gFrontEnd )
				)
				( attribute "MATERIAL" "CHIP"
					( Origin gFrontEnd )
				)
				( attribute "PACK_TYPE" "0603"
					( Origin gFrontEnd )
				)
				( attribute "PART_NUMBER" "G22178-002"
					( Origin gFrontEnd )
				)
				( attribute "PHYS_PAGE" "203"
					( Origin gFrontEnd )
				)
				( attribute "ROOM" "NIC_SPRV"
					( Origin gFrontEnd )
				)
				( attribute "ROT" "0"
					( Origin gFrontEnd )
				)
				( attribute "TOLERANCE" "5.0%"
					( Origin gFrontEnd )
				)
				( attribute "VALUE" "0"
					( Origin gFrontEnd )
				)
				( attribute "VER" "1"
					( Origin gFrontEnd )
				)
				( attribute "WATTAGE" "1/10W"
					( Origin gFrontEnd )
				)
				( attribute "XY" "(-4725,3725)"
					( Origin gFrontEnd )
				)
				( attribute "CHIPS_PART_NAME" "RES"
					( Origin gPackager )
				)
				( attribute "CDS_PART_NAME" "RES_0603-0,5.0%,1/10W,CHIP,G22A"
					( Origin gPackager )
				)
				( attribute "CDS_LOCATION" "RT25"
					( Origin gPackager )
				)
				( attribute "SEC" "1"
					( Origin gFrontEnd )
				)
				( attribute "SEC_TYPE" "0603"
					( Origin gFrontEnd )
				)
				( attribute "CDS_SEC" "1"
					( Origin gPackager )
				)
				( objectStatus "RT25" )
			)
			( gate "@baseboard_fab2_lib.baseboard_fab2(sch_1):page202_i98"
				( attribute "CDS_LIB" "mstr_discrete"
					( Origin gPackager )
				)
				( attribute "LOCATION" "CT5"
					( Origin gFrontEnd )
				)
				( attribute "MATERIAL" "X7R"
					( Origin gFrontEnd )
				)
				( attribute "PACK_TYPE" "0402LF"
					( Origin gFrontEnd )
				)
				( attribute "PART_NUMBER" "A36096-046"
					( Origin gFrontEnd )
				)
				( attribute "PHYS_PAGE" "202"
					( Origin gFrontEnd )
				)
				( attribute "POP" "NOPOP"
					( Origin gFrontEnd )
				)
				( attribute "ROOM" "VDDQ_KLM_PWR_VR"
					( Origin gFrontEnd )
				)
				( attribute "ROT" "0"
					( Origin gFrontEnd )
				)
				( attribute "TOLERANCE" "10%"
					( Origin gFrontEnd )
				)
				( attribute "VALUE" "1000PF"
					( Origin gFrontEnd )
				)
				( attribute "VER" "1"
					( Origin gFrontEnd )
				)
				( attribute "VOLTAGE" "50V"
					( Units "uVoltage" "V" 1.000000)
					( Origin gFrontEnd )
				)
				( attribute "XY" "(-2550,825)"
					( Origin gFrontEnd )
				)
				( attribute "CHIPS_PART_NAME" "CAP"
					( Origin gPackager )
				)
				( attribute "CDS_PART_NAME" "CAP_0402LF-1000PF,50V,10%,X7R,A"
					( Origin gPackager )
				)
				( attribute "CDS_LOCATION" "CT5"
					( Origin gPackager )
				)
				( attribute "SEC" "1"
					( Origin gFrontEnd )
				)
				( attribute "SEC_TYPE" "0402LF"
					( Origin gFrontEnd )
				)
				( attribute "CDS_SEC" "1"
					( Origin gPackager )
				)
				( objectStatus "CT5" )
			)
			( gate "@baseboard_fab2_lib.baseboard_fab2(sch_1):page202_i97"
				( attribute "CDS_LIB" "mstr_discrete"
					( Origin gPackager )
				)
				( attribute "LOCATION" "CT3"
					( Origin gFrontEnd )
				)
				( attribute "MATERIAL" "X7R"
					( Origin gFrontEnd )
				)
				( attribute "PACK_TYPE" "0402LF"
					( Origin gFrontEnd )
				)
				( attribute "PART_NUMBER" "A36096-046"
					( Origin gFrontEnd )
				)
				( attribute "PHYS_PAGE" "202"
					( Origin gFrontEnd )
				)
				( attribute "POP" "NOPOP"
					( Origin gFrontEnd )
				)
				( attribute "ROOM" "VDDQ_KLM_PWR_VR"
					( Origin gFrontEnd )
				)
				( attribute "ROT" "0"
					( Origin gFrontEnd )
				)
				( attribute "TOLERANCE" "10%"
					( Origin gFrontEnd )
				)
				( attribute "VALUE" "1000PF"
					( Origin gFrontEnd )
				)
				( attribute "VER" "1"
					( Origin gFrontEnd )
				)
				( attribute "VOLTAGE" "50V"
					( Units "uVoltage" "V" 1.000000)
					( Origin gFrontEnd )
				)
				( attribute "XY" "(-2550,3325)"
					( Origin gFrontEnd )
				)
				( attribute "CHIPS_PART_NAME" "CAP"
					( Origin gPackager )
				)
				( attribute "CDS_PART_NAME" "CAP_0402LF-1000PF,50V,10%,X7R,A"
					( Origin gPackager )
				)
				( attribute "CDS_LOCATION" "CT3"
					( Origin gPackager )
				)
				( attribute "SEC" "1"
					( Origin gFrontEnd )
				)
				( attribute "SEC_TYPE" "0402LF"
					( Origin gFrontEnd )
				)
				( attribute "CDS_SEC" "1"
					( Origin gPackager )
				)
				( objectStatus "CT3" )
			)
			( gate "@baseboard_fab2_lib.baseboard_fab2(sch_1):page186_i356"
				( attribute "BOM_COST" "PROC_SIDEBAND"
					( Origin gFrontEnd )
				)
				( attribute "CDS_LIB" "mstr_discrete"
					( Origin gPackager )
				)
				( attribute "LOCATION" "R9W1"
					( Origin gFrontEnd )
				)
				( attribute "MATERIAL" "CHIP"
					( Origin gFrontEnd )
				)
				( attribute "PACK_TYPE" "0402"
					( Origin gFrontEnd )
				)
				( attribute "PART_NUMBER" "G21796-016"
					( Origin gFrontEnd )
				)
				( attribute "PHYS_PAGE" "186"
					( Origin gFrontEnd )
				)
				( attribute "ROOM" "CPU0"
					( Origin gFrontEnd )
				)
				( attribute "ROT" "0"
					( Origin gFrontEnd )
				)
				( attribute "TOLERANCE" "1%"
					( Origin gFrontEnd )
				)
				( attribute "VALUE" "10.0K"
					( Origin gFrontEnd )
				)
				( attribute "VER" "2"
					( Origin gFrontEnd )
				)
				( attribute "WATTAGE" "1/16W"
					( Origin gFrontEnd )
				)
				( attribute "XY" "(6300,4000)"
					( Origin gFrontEnd )
				)
				( attribute "CHIPS_PART_NAME" "RES"
					( Origin gPackager )
				)
				( attribute "CDS_PART_NAME" "RES_0402-10.0K,1%,1/16W,CHIP,GA"
					( Origin gPackager )
				)
				( attribute "CDS_LOCATION" "R9W1"
					( Origin gPackager )
				)
				( attribute "SEC" "1"
					( Origin gFrontEnd )
				)
				( attribute "SEC_TYPE" "0402"
					( Origin gFrontEnd )
				)
				( attribute "CDS_SEC" "1"
					( Origin gPackager )
				)
				( objectStatus "R9W1" )
			)
			( gate "@baseboard_fab2_lib.baseboard_fab2(sch_1):page187_i174"
				( attribute "BOM_COST" "PROC_SIDEBAND"
					( Origin gFrontEnd )
				)
				( attribute "CDS_LIB" "mstr_discrete"
					( Origin gPackager )
				)
				( attribute "LOCATION" "R2W1"
					( Origin gFrontEnd )
				)
				( attribute "MATERIAL" "CHIP"
					( Origin gFrontEnd )
				)
				( attribute "PACK_TYPE" "0402"
					( Origin gFrontEnd )
				)
				( attribute "PART_NUMBER" "G21796-016"
					( Origin gFrontEnd )
				)
				( attribute "PHYS_PAGE" "187"
					( Origin gFrontEnd )
				)
				( attribute "ROOM" "CPU0"
					( Origin gFrontEnd )
				)
				( attribute "ROT" "0"
					( Origin gFrontEnd )
				)
				( attribute "TOLERANCE" "1%"
					( Origin gFrontEnd )
				)
				( attribute "VALUE" "10.0K"
					( Origin gFrontEnd )
				)
				( attribute "VER" "2"
					( Origin gFrontEnd )
				)
				( attribute "WATTAGE" "1/16W"
					( Origin gFrontEnd )
				)
				( attribute "XY" "(1950,4675)"
					( Origin gFrontEnd )
				)
				( attribute "CHIPS_PART_NAME" "RES"
					( Origin gPackager )
				)
				( attribute "CDS_PART_NAME" "RES_0402-10.0K,1%,1/16W,CHIP,GA"
					( Origin gPackager )
				)
				( attribute "CDS_LOCATION" "R2W1"
					( Origin gPackager )
				)
				( attribute "SEC" "1"
					( Origin gFrontEnd )
				)
				( attribute "SEC_TYPE" "0402"
					( Origin gFrontEnd )
				)
				( attribute "CDS_SEC" "1"
					( Origin gPackager )
				)
				( objectStatus "R2W1" )
			)
			( gate "@baseboard_fab2_lib.baseboard_fab2(sch_1):page208_i121"
				( attribute "ATTRIBUTE" "1 OHM"
					( Origin gFrontEnd )
				)
				( attribute "CDS_LIB" "w_hdl"
					( Origin gPackager )
				)
				( attribute "CDS_LMAN_SYM_OUTLINE" "-50,75,50,-75"
					( Origin gPackager )
				)
				( attribute "LOCATION" "RT13"
					( Origin gFrontEnd )
				)
				( attribute "PACK_TYPE" "RCL_GP"
					( Origin gFrontEnd )
				)
				( attribute "PART_NUMBER" "64.1R005.55L"
					( Origin gFrontEnd )
				)
				( attribute "PHYS_PAGE" "208"
					( Origin gFrontEnd )
				)
				( attribute "POP" "NOPOP"
					( Origin gFrontEnd )
				)
				( attribute "RATED" "1/10W"
					( Origin gFrontEnd )
				)
				( attribute "ROT" "0"
					( Origin gFrontEnd )
				)
				( attribute "SEC" "1"
					( Origin gFrontEnd )
				)
				( attribute "SEC_TYPE" "RCL_GP"
					( Origin gFrontEnd )
				)
				( attribute "TOLERANCE" "1%"
					( Origin gFrontEnd )
				)
				( attribute "VALUE" "1R3F-GP"
					( Origin gFrontEnd )
				)
				( attribute "VER" "1"
					( Origin gFrontEnd )
				)
				( attribute "XY" "(-2075,550)"
					( Origin gFrontEnd )
				)
				( attribute "CHIPS_PART_NAME" "1R3F-GP"
					( Origin gPackager )
				)
				( attribute "CDS_PART_NAME" "1R3F-GP_RCL_GP-1R3F-GP,64.1R00A"
					( Origin gPackager )
				)
				( attribute "PACK_SIZE" "0603"
					( Origin gFrontEnd )
				)
				( attribute "CDS_LOCATION" "RT13"
					( Origin gPackager )
				)
				( attribute "CDS_SEC" "1"
					( Origin gPackager )
				)
				( objectStatus "RT13" )
			)
			( gate "@baseboard_fab2_lib.baseboard_fab2(sch_1):page202_i101"
				( attribute "BOM_COST" "NT_GBE_BASE"
					( Origin gFrontEnd )
				)
				( attribute "CDS_LIB" "mstr_discrete"
					( Origin gPackager )
				)
				( attribute "LOCATION" "RT1"
					( Origin gFrontEnd )
				)
				( attribute "MATERIAL" "CHIP"
					( Origin gFrontEnd )
				)
				( attribute "PACK_TYPE" "0603"
					( Origin gFrontEnd )
				)
				( attribute "PART_NUMBER" "G22178-002"
					( Origin gFrontEnd )
				)
				( attribute "PHYS_PAGE" "202"
					( Origin gFrontEnd )
				)
				( attribute "ROOM" "NIC_SPRV"
					( Origin gFrontEnd )
				)
				( attribute "ROT" "0"
					( Origin gFrontEnd )
				)
				( attribute "TOLERANCE" "5.0%"
					( Origin gFrontEnd )
				)
				( attribute "VALUE" "0"
					( Origin gFrontEnd )
				)
				( attribute "VER" "1"
					( Origin gFrontEnd )
				)
				( attribute "WATTAGE" "1/10W"
					( Origin gFrontEnd )
				)
				( attribute "XY" "(-5025,3575)"
					( Origin gFrontEnd )
				)
				( attribute "CHIPS_PART_NAME" "RES"
					( Origin gPackager )
				)
				( attribute "CDS_PART_NAME" "RES_0603-0,5.0%,1/10W,CHIP,G22A"
					( Origin gPackager )
				)
				( attribute "CDS_LOCATION" "RT1"
					( Origin gPackager )
				)
				( attribute "SEC" "1"
					( Origin gFrontEnd )
				)
				( attribute "SEC_TYPE" "0603"
					( Origin gFrontEnd )
				)
				( attribute "CDS_SEC" "1"
					( Origin gPackager )
				)
				( objectStatus "RT1" )
			)
			( gate "@baseboard_fab2_lib.baseboard_fab2(sch_1):page202_i102"
				( attribute "BOM_COST" "NT_GBE_BASE"
					( Origin gFrontEnd )
				)
				( attribute "CDS_LIB" "mstr_discrete"
					( Origin gPackager )
				)
				( attribute "LOCATION" "RT3"
					( Origin gFrontEnd )
				)
				( attribute "MATERIAL" "CHIP"
					( Origin gFrontEnd )
				)
				( attribute "PACK_TYPE" "0603"
					( Origin gFrontEnd )
				)
				( attribute "PART_NUMBER" "G22178-002"
					( Origin gFrontEnd )
				)
				( attribute "PHYS_PAGE" "202"
					( Origin gFrontEnd )
				)
				( attribute "ROOM" "NIC_SPRV"
					( Origin gFrontEnd )
				)
				( attribute "ROT" "0"
					( Origin gFrontEnd )
				)
				( attribute "TOLERANCE" "5.0%"
					( Origin gFrontEnd )
				)
				( attribute "VALUE" "0"
					( Origin gFrontEnd )
				)
				( attribute "VER" "1"
					( Origin gFrontEnd )
				)
				( attribute "WATTAGE" "1/10W"
					( Origin gFrontEnd )
				)
				( attribute "XY" "(-5025,950)"
					( Origin gFrontEnd )
				)
				( attribute "CHIPS_PART_NAME" "RES"
					( Origin gPackager )
				)
				( attribute "CDS_PART_NAME" "RES_0603-0,5.0%,1/10W,CHIP,G22A"
					( Origin gPackager )
				)
				( attribute "CDS_LOCATION" "RT3"
					( Origin gPackager )
				)
				( attribute "SEC" "1"
					( Origin gFrontEnd )
				)
				( attribute "SEC_TYPE" "0603"
					( Origin gFrontEnd )
				)
				( attribute "CDS_SEC" "1"
					( Origin gPackager )
				)
				( objectStatus "RT3" )
			)
			( gate "@baseboard_fab2_lib.baseboard_fab2(sch_1):page227_i149"
				( attribute "ATTRIBUTE" "1 OHM"
					( Origin gFrontEnd )
				)
				( attribute "CDS_LIB" "w_hdl"
					( Origin gPackager )
				)
				( attribute "CDS_LMAN_SYM_OUTLINE" "-50,75,50,-75"
					( Origin gPackager )
				)
				( attribute "LOCATION" "RT6"
					( Origin gFrontEnd )
				)
				( attribute "PACK_TYPE" "RCL_GP"
					( Origin gFrontEnd )
				)
				( attribute "PART_NUMBER" "64.1R005.55L"
					( Origin gFrontEnd )
				)
				( attribute "PHYS_PAGE" "227"
					( Origin gFrontEnd )
				)
				( attribute "POP" "NOPOP"
					( Origin gFrontEnd )
				)
				( attribute "RATED" "1/10W"
					( Origin gFrontEnd )
				)
				( attribute "ROT" "0"
					( Origin gFrontEnd )
				)
				( attribute "SEC" "1"
					( Origin gFrontEnd )
				)
				( attribute "SEC_TYPE" "RCL_GP"
					( Origin gFrontEnd )
				)
				( attribute "TOLERANCE" "1%"
					( Origin gFrontEnd )
				)
				( attribute "VALUE" "1R3F-GP"
					( Origin gFrontEnd )
				)
				( attribute "VER" "1"
					( Origin gFrontEnd )
				)
				( attribute "XY" "(2825,1325)"
					( Origin gFrontEnd )
				)
				( attribute "CHIPS_PART_NAME" "1R3F-GP"
					( Origin gPackager )
				)
				( attribute "CDS_PART_NAME" "1R3F-GP_RCL_GP-1R3F-GP,64.1R00A"
					( Origin gPackager )
				)
				( attribute "PACK_SIZE" "0603"
					( Origin gFrontEnd )
				)
				( attribute "CDS_LOCATION" "RT6"
					( Origin gPackager )
				)
				( attribute "CDS_SEC" "1"
					( Origin gPackager )
				)
				( objectStatus "RT6" )
			)
			( gate "@baseboard_fab2_lib.baseboard_fab2(sch_1):page149_i92"
				( attribute "BOM_COST" "PROC"
					( Origin gFrontEnd )
				)
				( attribute "CDS_LIB" "mstr_discrete"
					( Origin gPackager )
				)
				( attribute "LOCATION" "C25W53"
					( Origin gFrontEnd )
				)
				( attribute "MATERIAL" "X6S"
					( Origin gFrontEnd )
				)
				( attribute "PACK_TYPE" "0402"
					( Origin gFrontEnd )
				)
				( attribute "PART_NUMBER" "D97712-011"
					( Origin gFrontEnd )
				)
				( attribute "PHYS_PAGE" "149"
					( Origin gFrontEnd )
				)
				( attribute "ROOM" "PROC_SIDEBAND"
					( Origin gFrontEnd )
				)
				( attribute "ROT" "0"
					( Origin gFrontEnd )
				)
				( attribute "SEC" "1"
					( Origin gFrontEnd )
				)
				( attribute "SEC_TYPE" "0402"
					( Origin gFrontEnd )
				)
				( attribute "TOLERANCE" "10%"
					( Origin gFrontEnd )
				)
				( attribute "VALUE" "1.0UF"
					( Origin gFrontEnd )
				)
				( attribute "VER" "1"
					( Origin gFrontEnd )
				)
				( attribute "VOLTAGE" "16V"
					( Units "uVoltage" "V" 1.000000)
					( Origin gFrontEnd )
				)
				( attribute "XY" "(4500,2900)"
					( Origin gFrontEnd )
				)
				( attribute "CHIPS_PART_NAME" "CAP"
					( Origin gPackager )
				)
				( attribute "CDS_PART_NAME" "CAP_0402-1.0UF,16V,10%,X6S,D97A"
					( Origin gPackager )
				)
				( attribute "CDS_LOCATION" "C25W53"
					( Origin gPackager )
				)
				( attribute "CDS_SEC" "1"
					( Origin gPackager )
				)
				( objectStatus "C25W53" )
			)
			( gate "@baseboard_fab2_lib.baseboard_fab2(sch_1):page149_i93"
				( attribute "BOM_COST" "PROC"
					( Origin gFrontEnd )
				)
				( attribute "CDS_LIB" "mstr_discrete"
					( Origin gPackager )
				)
				( attribute "LOCATION" "C25W56"
					( Origin gFrontEnd )
				)
				( attribute "MATERIAL" "X6S"
					( Origin gFrontEnd )
				)
				( attribute "PACK_TYPE" "0402"
					( Origin gFrontEnd )
				)
				( attribute "PART_NUMBER" "D97712-011"
					( Origin gFrontEnd )
				)
				( attribute "PHYS_PAGE" "149"
					( Origin gFrontEnd )
				)
				( attribute "ROOM" "PROC_SIDEBAND"
					( Origin gFrontEnd )
				)
				( attribute "ROT" "0"
					( Origin gFrontEnd )
				)
				( attribute "TOLERANCE" "10%"
					( Origin gFrontEnd )
				)
				( attribute "VALUE" "1.0UF"
					( Origin gFrontEnd )
				)
				( attribute "VER" "1"
					( Origin gFrontEnd )
				)
				( attribute "VOLTAGE" "16V"
					( Units "uVoltage" "V" 1.000000)
					( Origin gFrontEnd )
				)
				( attribute "XY" "(-850,1850)"
					( Origin gFrontEnd )
				)
				( attribute "CHIPS_PART_NAME" "CAP"
					( Origin gPackager )
				)
				( attribute "CDS_PART_NAME" "CAP_0402-1.0UF,16V,10%,X6S,D97A"
					( Origin gPackager )
				)
				( attribute "CDS_LOCATION" "C25W56"
					( Origin gPackager )
				)
				( attribute "CDS_SEC" "1"
					( Origin gPackager )
				)
				( attribute "SEC" "1"
					( Origin gPackager )
				)
				( objectStatus "C25W56" )
			)
			( gate "@baseboard_fab2_lib.baseboard_fab2(sch_1):page149_i95"
				( attribute "BOM_COST" "PROC"
					( Origin gFrontEnd )
				)
				( attribute "CDS_LIB" "mstr_discrete"
					( Origin gPackager )
				)
				( attribute "LOCATION" "C25W54"
					( Origin gFrontEnd )
				)
				( attribute "MATERIAL" "X6S"
					( Origin gFrontEnd )
				)
				( attribute "PACK_TYPE" "0402"
					( Origin gFrontEnd )
				)
				( attribute "PART_NUMBER" "D97712-011"
					( Origin gFrontEnd )
				)
				( attribute "PHYS_PAGE" "149"
					( Origin gFrontEnd )
				)
				( attribute "ROOM" "PROC_SIDEBAND"
					( Origin gFrontEnd )
				)
				( attribute "ROT" "0"
					( Origin gFrontEnd )
				)
				( attribute "TOLERANCE" "10%"
					( Origin gFrontEnd )
				)
				( attribute "VALUE" "1.0UF"
					( Origin gFrontEnd )
				)
				( attribute "VER" "1"
					( Origin gFrontEnd )
				)
				( attribute "VOLTAGE" "16V"
					( Units "uVoltage" "V" 1.000000)
					( Origin gFrontEnd )
				)
				( attribute "XY" "(4750,2900)"
					( Origin gFrontEnd )
				)
				( attribute "CHIPS_PART_NAME" "CAP"
					( Origin gPackager )
				)
				( attribute "CDS_PART_NAME" "CAP_0402-1.0UF,16V,10%,X6S,D97A"
					( Origin gPackager )
				)
				( attribute "CDS_LOCATION" "C25W54"
					( Origin gPackager )
				)
				( attribute "CDS_SEC" "1"
					( Origin gPackager )
				)
				( attribute "SEC" "1"
					( Origin gPackager )
				)
				( objectStatus "C25W54" )
			)
			( gate "@baseboard_fab2_lib.baseboard_fab2(sch_1):page149_i96"
				( attribute "BOM_COST" "PROC"
					( Origin gFrontEnd )
				)
				( attribute "CDS_LIB" "mstr_discrete"
					( Origin gPackager )
				)
				( attribute "LOCATION" "C25W40"
					( Origin gFrontEnd )
				)
				( attribute "MATERIAL" "X6S"
					( Origin gFrontEnd )
				)
				( attribute "PACK_TYPE" "0402"
					( Origin gFrontEnd )
				)
				( attribute "PART_NUMBER" "D97712-011"
					( Origin gFrontEnd )
				)
				( attribute "PHYS_PAGE" "149"
					( Origin gFrontEnd )
				)
				( attribute "ROOM" "PROC_SIDEBAND"
					( Origin gFrontEnd )
				)
				( attribute "ROT" "0"
					( Origin gFrontEnd )
				)
				( attribute "TOLERANCE" "10%"
					( Origin gFrontEnd )
				)
				( attribute "VALUE" "1.0UF"
					( Origin gFrontEnd )
				)
				( attribute "VER" "1"
					( Origin gFrontEnd )
				)
				( attribute "VOLTAGE" "16V"
					( Units "uVoltage" "V" 1.000000)
					( Origin gFrontEnd )
				)
				( attribute "XY" "(-1450,2900)"
					( Origin gFrontEnd )
				)
				( attribute "CHIPS_PART_NAME" "CAP"
					( Origin gPackager )
				)
				( attribute "CDS_PART_NAME" "CAP_0402-1.0UF,16V,10%,X6S,D97A"
					( Origin gPackager )
				)
				( attribute "CDS_LOCATION" "C25W40"
					( Origin gPackager )
				)
				( attribute "CDS_SEC" "1"
					( Origin gPackager )
				)
				( attribute "SEC" "1"
					( Origin gPackager )
				)
				( objectStatus "C25W40" )
			)
			( gate "@baseboard_fab2_lib.baseboard_fab2(sch_1):page149_i97"
				( attribute "BOM_COST" "PROC"
					( Origin gFrontEnd )
				)
				( attribute "CDS_LIB" "mstr_discrete"
					( Origin gPackager )
				)
				( attribute "LOCATION" "C25W41"
					( Origin gFrontEnd )
				)
				( attribute "MATERIAL" "X6S"
					( Origin gFrontEnd )
				)
				( attribute "PACK_TYPE" "0402"
					( Origin gFrontEnd )
				)
				( attribute "PART_NUMBER" "D97712-011"
					( Origin gFrontEnd )
				)
				( attribute "PHYS_PAGE" "149"
					( Origin gFrontEnd )
				)
				( attribute "ROOM" "PROC_SIDEBAND"
					( Origin gFrontEnd )
				)
				( attribute "ROT" "0"
					( Origin gFrontEnd )
				)
				( attribute "TOLERANCE" "10%"
					( Origin gFrontEnd )
				)
				( attribute "VALUE" "1.0UF"
					( Origin gFrontEnd )
				)
				( attribute "VER" "1"
					( Origin gFrontEnd )
				)
				( attribute "VOLTAGE" "16V"
					( Units "uVoltage" "V" 1.000000)
					( Origin gFrontEnd )
				)
				( attribute "XY" "(-1150,2900)"
					( Origin gFrontEnd )
				)
				( attribute "CHIPS_PART_NAME" "CAP"
					( Origin gPackager )
				)
				( attribute "CDS_PART_NAME" "CAP_0402-1.0UF,16V,10%,X6S,D97A"
					( Origin gPackager )
				)
				( attribute "CDS_LOCATION" "C25W41"
					( Origin gPackager )
				)
				( attribute "CDS_SEC" "1"
					( Origin gPackager )
				)
				( attribute "SEC" "1"
					( Origin gPackager )
				)
				( objectStatus "C25W41" )
			)
			( gate "@baseboard_fab2_lib.baseboard_fab2(sch_1):page149_i98"
				( attribute "BOM_COST" "PROC"
					( Origin gFrontEnd )
				)
				( attribute "CDS_LIB" "mstr_discrete"
					( Origin gPackager )
				)
				( attribute "LOCATION" "C25W42"
					( Origin gFrontEnd )
				)
				( attribute "MATERIAL" "X6S"
					( Origin gFrontEnd )
				)
				( attribute "PACK_TYPE" "0402"
					( Origin gFrontEnd )
				)
				( attribute "PART_NUMBER" "D97712-011"
					( Origin gFrontEnd )
				)
				( attribute "PHYS_PAGE" "149"
					( Origin gFrontEnd )
				)
				( attribute "ROOM" "PROC_SIDEBAND"
					( Origin gFrontEnd )
				)
				( attribute "ROT" "0"
					( Origin gFrontEnd )
				)
				( attribute "TOLERANCE" "10%"
					( Origin gFrontEnd )
				)
				( attribute "VALUE" "1.0UF"
					( Origin gFrontEnd )
				)
				( attribute "VER" "1"
					( Origin gFrontEnd )
				)
				( attribute "VOLTAGE" "16V"
					( Units "uVoltage" "V" 1.000000)
					( Origin gFrontEnd )
				)
				( attribute "XY" "(-900,2900)"
					( Origin gFrontEnd )
				)
				( attribute "CHIPS_PART_NAME" "CAP"
					( Origin gPackager )
				)
				( attribute "CDS_PART_NAME" "CAP_0402-1.0UF,16V,10%,X6S,D97A"
					( Origin gPackager )
				)
				( attribute "CDS_LOCATION" "C25W42"
					( Origin gPackager )
				)
				( attribute "CDS_SEC" "1"
					( Origin gPackager )
				)
				( attribute "SEC" "1"
					( Origin gPackager )
				)
				( objectStatus "C25W42" )
			)
			( gate "@baseboard_fab2_lib.baseboard_fab2(sch_1):page149_i99"
				( attribute "BOM_COST" "PROC"
					( Origin gFrontEnd )
				)
				( attribute "CDS_LIB" "mstr_discrete"
					( Origin gPackager )
				)
				( attribute "LOCATION" "C25W32"
					( Origin gFrontEnd )
				)
				( attribute "MATERIAL" "X6S"
					( Origin gFrontEnd )
				)
				( attribute "PACK_TYPE" "0402"
					( Origin gFrontEnd )
				)
				( attribute "PART_NUMBER" "D97712-011"
					( Origin gFrontEnd )
				)
				( attribute "PHYS_PAGE" "149"
					( Origin gFrontEnd )
				)
				( attribute "ROOM" "PROC_SIDEBAND"
					( Origin gFrontEnd )
				)
				( attribute "ROT" "0"
					( Origin gFrontEnd )
				)
				( attribute "TOLERANCE" "10%"
					( Origin gFrontEnd )
				)
				( attribute "VALUE" "1.0UF"
					( Origin gFrontEnd )
				)
				( attribute "VER" "1"
					( Origin gFrontEnd )
				)
				( attribute "VOLTAGE" "16V"
					( Units "uVoltage" "V" 1.000000)
					( Origin gFrontEnd )
				)
				( attribute "XY" "(-1025,4100)"
					( Origin gFrontEnd )
				)
				( attribute "CHIPS_PART_NAME" "CAP"
					( Origin gPackager )
				)
				( attribute "CDS_PART_NAME" "CAP_0402-1.0UF,16V,10%,X6S,D97A"
					( Origin gPackager )
				)
				( attribute "CDS_LOCATION" "C25W32"
					( Origin gPackager )
				)
				( attribute "CDS_SEC" "1"
					( Origin gPackager )
				)
				( attribute "SEC" "1"
					( Origin gPackager )
				)
				( objectStatus "C25W32" )
			)
			( gate "@baseboard_fab2_lib.baseboard_fab2(sch_1):page149_i100"
				( attribute "BOM_COST" "PROC"
					( Origin gFrontEnd )
				)
				( attribute "CDS_LIB" "mstr_discrete"
					( Origin gPackager )
				)
				( attribute "LOCATION" "C25W43"
					( Origin gFrontEnd )
				)
				( attribute "MATERIAL" "X6S"
					( Origin gFrontEnd )
				)
				( attribute "PACK_TYPE" "0402"
					( Origin gFrontEnd )
				)
				( attribute "PART_NUMBER" "D97712-011"
					( Origin gFrontEnd )
				)
				( attribute "PHYS_PAGE" "149"
					( Origin gFrontEnd )
				)
				( attribute "ROOM" "PROC_SIDEBAND"
					( Origin gFrontEnd )
				)
				( attribute "ROT" "0"
					( Origin gFrontEnd )
				)
				( attribute "TOLERANCE" "10%"
					( Origin gFrontEnd )
				)
				( attribute "VALUE" "1.0UF"
					( Origin gFrontEnd )
				)
				( attribute "VER" "1"
					( Origin gFrontEnd )
				)
				( attribute "VOLTAGE" "16V"
					( Units "uVoltage" "V" 1.000000)
					( Origin gFrontEnd )
				)
				( attribute "XY" "(-650,2900)"
					( Origin gFrontEnd )
				)
				( attribute "CHIPS_PART_NAME" "CAP"
					( Origin gPackager )
				)
				( attribute "CDS_PART_NAME" "CAP_0402-1.0UF,16V,10%,X6S,D97A"
					( Origin gPackager )
				)
				( attribute "CDS_LOCATION" "C25W43"
					( Origin gPackager )
				)
				( attribute "CDS_SEC" "1"
					( Origin gPackager )
				)
				( attribute "SEC" "1"
					( Origin gPackager )
				)
				( objectStatus "C25W43" )
			)
			( gate "@baseboard_fab2_lib.baseboard_fab2(sch_1):page149_i101"
				( attribute "BOM_COST" "PROC"
					( Origin gFrontEnd )
				)
				( attribute "CDS_LIB" "mstr_discrete"
					( Origin gPackager )
				)
				( attribute "LOCATION" "C25W44"
					( Origin gFrontEnd )
				)
				( attribute "MATERIAL" "X6S"
					( Origin gFrontEnd )
				)
				( attribute "PACK_TYPE" "0402"
					( Origin gFrontEnd )
				)
				( attribute "PART_NUMBER" "D97712-011"
					( Origin gFrontEnd )
				)
				( attribute "PHYS_PAGE" "149"
					( Origin gFrontEnd )
				)
				( attribute "ROOM" "PROC_SIDEBAND"
					( Origin gFrontEnd )
				)
				( attribute "ROT" "0"
					( Origin gFrontEnd )
				)
				( attribute "TOLERANCE" "10%"
					( Origin gFrontEnd )
				)
				( attribute "VALUE" "1.0UF"
					( Origin gFrontEnd )
				)
				( attribute "VER" "1"
					( Origin gFrontEnd )
				)
				( attribute "VOLTAGE" "16V"
					( Units "uVoltage" "V" 1.000000)
					( Origin gFrontEnd )
				)
				( attribute "XY" "(-350,2900)"
					( Origin gFrontEnd )
				)
				( attribute "CHIPS_PART_NAME" "CAP"
					( Origin gPackager )
				)
				( attribute "CDS_PART_NAME" "CAP_0402-1.0UF,16V,10%,X6S,D97A"
					( Origin gPackager )
				)
				( attribute "CDS_LOCATION" "C25W44"
					( Origin gPackager )
				)
				( attribute "CDS_SEC" "1"
					( Origin gPackager )
				)
				( attribute "SEC" "1"
					( Origin gPackager )
				)
				( objectStatus "C25W44" )
			)
			( gate "@baseboard_fab2_lib.baseboard_fab2(sch_1):page149_i102"
				( attribute "BOM_COST" "PROC"
					( Origin gFrontEnd )
				)
				( attribute "CDS_LIB" "mstr_discrete"
					( Origin gPackager )
				)
				( attribute "LOCATION" "C25W33"
					( Origin gFrontEnd )
				)
				( attribute "MATERIAL" "X6S"
					( Origin gFrontEnd )
				)
				( attribute "PACK_TYPE" "0402"
					( Origin gFrontEnd )
				)
				( attribute "PART_NUMBER" "D97712-011"
					( Origin gFrontEnd )
				)
				( attribute "PHYS_PAGE" "149"
					( Origin gFrontEnd )
				)
				( attribute "ROOM" "PROC_SIDEBAND"
					( Origin gFrontEnd )
				)
				( attribute "ROT" "0"
					( Origin gFrontEnd )
				)
				( attribute "TOLERANCE" "10%"
					( Origin gFrontEnd )
				)
				( attribute "VALUE" "1.0UF"
					( Origin gFrontEnd )
				)
				( attribute "VER" "1"
					( Origin gFrontEnd )
				)
				( attribute "VOLTAGE" "16V"
					( Units "uVoltage" "V" 1.000000)
					( Origin gFrontEnd )
				)
				( attribute "XY" "(-675,4100)"
					( Origin gFrontEnd )
				)
				( attribute "CHIPS_PART_NAME" "CAP"
					( Origin gPackager )
				)
				( attribute "CDS_PART_NAME" "CAP_0402-1.0UF,16V,10%,X6S,D97A"
					( Origin gPackager )
				)
				( attribute "CDS_LOCATION" "C25W33"
					( Origin gPackager )
				)
				( attribute "CDS_SEC" "1"
					( Origin gPackager )
				)
				( attribute "SEC" "1"
					( Origin gPackager )
				)
				( objectStatus "C25W33" )
			)
			( gate "@baseboard_fab2_lib.baseboard_fab2(sch_1):page149_i103"
				( attribute "BOM_COST" "PROC"
					( Origin gFrontEnd )
				)
				( attribute "CDS_LIB" "mstr_discrete"
					( Origin gPackager )
				)
				( attribute "LOCATION" "C25W23"
					( Origin gFrontEnd )
				)
				( attribute "MATERIAL" "X6S"
					( Origin gFrontEnd )
				)
				( attribute "PACK_TYPE" "0402"
					( Origin gFrontEnd )
				)
				( attribute "PART_NUMBER" "D97712-011"
					( Origin gFrontEnd )
				)
				( attribute "PHYS_PAGE" "149"
					( Origin gFrontEnd )
				)
				( attribute "ROOM" "PROC_SIDEBAND"
					( Origin gFrontEnd )
				)
				( attribute "ROT" "0"
					( Origin gFrontEnd )
				)
				( attribute "TOLERANCE" "10%"
					( Origin gFrontEnd )
				)
				( attribute "VALUE" "1.0UF"
					( Origin gFrontEnd )
				)
				( attribute "VER" "1"
					( Origin gFrontEnd )
				)
				( attribute "VOLTAGE" "16V"
					( Units "uVoltage" "V" 1.000000)
					( Origin gFrontEnd )
				)
				( attribute "XY" "(-2250,5400)"
					( Origin gFrontEnd )
				)
				( attribute "CHIPS_PART_NAME" "CAP"
					( Origin gPackager )
				)
				( attribute "CDS_PART_NAME" "CAP_0402-1.0UF,16V,10%,X6S,D97A"
					( Origin gPackager )
				)
				( attribute "CDS_LOCATION" "C25W23"
					( Origin gPackager )
				)
				( attribute "CDS_SEC" "1"
					( Origin gPackager )
				)
				( attribute "SEC" "1"
					( Origin gPackager )
				)
				( objectStatus "C25W23" )
			)
			( gate "@baseboard_fab2_lib.baseboard_fab2(sch_1):page149_i104"
				( attribute "BOM_COST" "PROC"
					( Origin gFrontEnd )
				)
				( attribute "CDS_LIB" "mstr_discrete"
					( Origin gPackager )
				)
				( attribute "LOCATION" "C25W24"
					( Origin gFrontEnd )
				)
				( attribute "MATERIAL" "X6S"
					( Origin gFrontEnd )
				)
				( attribute "PACK_TYPE" "0402"
					( Origin gFrontEnd )
				)
				( attribute "PART_NUMBER" "D97712-011"
					( Origin gFrontEnd )
				)
				( attribute "PHYS_PAGE" "149"
					( Origin gFrontEnd )
				)
				( attribute "ROOM" "PROC_SIDEBAND"
					( Origin gFrontEnd )
				)
				( attribute "ROT" "0"
					( Origin gFrontEnd )
				)
				( attribute "TOLERANCE" "10%"
					( Origin gFrontEnd )
				)
				( attribute "VALUE" "1.0UF"
					( Origin gFrontEnd )
				)
				( attribute "VER" "1"
					( Origin gFrontEnd )
				)
				( attribute "VOLTAGE" "16V"
					( Units "uVoltage" "V" 1.000000)
					( Origin gFrontEnd )
				)
				( attribute "XY" "(-1850,5400)"
					( Origin gFrontEnd )
				)
				( attribute "CHIPS_PART_NAME" "CAP"
					( Origin gPackager )
				)
				( attribute "CDS_PART_NAME" "CAP_0402-1.0UF,16V,10%,X6S,D97A"
					( Origin gPackager )
				)
				( attribute "CDS_LOCATION" "C25W24"
					( Origin gPackager )
				)
				( attribute "CDS_SEC" "1"
					( Origin gPackager )
				)
				( attribute "SEC" "1"
					( Origin gPackager )
				)
				( objectStatus "C25W24" )
			)
			( gate "@baseboard_fab2_lib.baseboard_fab2(sch_1):page149_i105"
				( attribute "BOM_COST" "PROC"
					( Origin gFrontEnd )
				)
				( attribute "CDS_LIB" "mstr_discrete"
					( Origin gPackager )
				)
				( attribute "LOCATION" "C25W25"
					( Origin gFrontEnd )
				)
				( attribute "MATERIAL" "X6S"
					( Origin gFrontEnd )
				)
				( attribute "PACK_TYPE" "0402"
					( Origin gFrontEnd )
				)
				( attribute "PART_NUMBER" "D97712-011"
					( Origin gFrontEnd )
				)
				( attribute "PHYS_PAGE" "149"
					( Origin gFrontEnd )
				)
				( attribute "ROOM" "PROC_SIDEBAND"
					( Origin gFrontEnd )
				)
				( attribute "ROT" "0"
					( Origin gFrontEnd )
				)
				( attribute "TOLERANCE" "10%"
					( Origin gFrontEnd )
				)
				( attribute "VALUE" "1.0UF"
					( Origin gFrontEnd )
				)
				( attribute "VER" "1"
					( Origin gFrontEnd )
				)
				( attribute "VOLTAGE" "16V"
					( Units "uVoltage" "V" 1.000000)
					( Origin gFrontEnd )
				)
				( attribute "XY" "(-1450,5400)"
					( Origin gFrontEnd )
				)
				( attribute "CHIPS_PART_NAME" "CAP"
					( Origin gPackager )
				)
				( attribute "CDS_PART_NAME" "CAP_0402-1.0UF,16V,10%,X6S,D97A"
					( Origin gPackager )
				)
				( attribute "CDS_LOCATION" "C25W25"
					( Origin gPackager )
				)
				( attribute "CDS_SEC" "1"
					( Origin gPackager )
				)
				( attribute "SEC" "1"
					( Origin gPackager )
				)
				( objectStatus "C25W25" )
			)
			( gate "@baseboard_fab2_lib.baseboard_fab2(sch_1):page149_i106"
				( attribute "BOM_COST" "PROC"
					( Origin gFrontEnd )
				)
				( attribute "CDS_LIB" "mstr_discrete"
					( Origin gPackager )
				)
				( attribute "LOCATION" "C25W26"
					( Origin gFrontEnd )
				)
				( attribute "MATERIAL" "X6S"
					( Origin gFrontEnd )
				)
				( attribute "PACK_TYPE" "0402"
					( Origin gFrontEnd )
				)
				( attribute "PART_NUMBER" "D97712-011"
					( Origin gFrontEnd )
				)
				( attribute "PHYS_PAGE" "149"
					( Origin gFrontEnd )
				)
				( attribute "ROOM" "PROC_SIDEBAND"
					( Origin gFrontEnd )
				)
				( attribute "ROT" "0"
					( Origin gFrontEnd )
				)
				( attribute "TOLERANCE" "10%"
					( Origin gFrontEnd )
				)
				( attribute "VALUE" "1.0UF"
					( Origin gFrontEnd )
				)
				( attribute "VER" "1"
					( Origin gFrontEnd )
				)
				( attribute "VOLTAGE" "16V"
					( Units "uVoltage" "V" 1.000000)
					( Origin gFrontEnd )
				)
				( attribute "XY" "(-1050,5400)"
					( Origin gFrontEnd )
				)
				( attribute "CHIPS_PART_NAME" "CAP"
					( Origin gPackager )
				)
				( attribute "CDS_PART_NAME" "CAP_0402-1.0UF,16V,10%,X6S,D97A"
					( Origin gPackager )
				)
				( attribute "CDS_LOCATION" "C25W26"
					( Origin gPackager )
				)
				( attribute "CDS_SEC" "1"
					( Origin gPackager )
				)
				( attribute "SEC" "1"
					( Origin gPackager )
				)
				( objectStatus "C25W26" )
			)
			( gate "@baseboard_fab2_lib.baseboard_fab2(sch_1):page149_i107"
				( attribute "BOM_COST" "PROC"
					( Origin gFrontEnd )
				)
				( attribute "CDS_LIB" "mstr_discrete"
					( Origin gPackager )
				)
				( attribute "LOCATION" "C25W27"
					( Origin gFrontEnd )
				)
				( attribute "MATERIAL" "X6S"
					( Origin gFrontEnd )
				)
				( attribute "PACK_TYPE" "0402"
					( Origin gFrontEnd )
				)
				( attribute "PART_NUMBER" "D97712-011"
					( Origin gFrontEnd )
				)
				( attribute "PHYS_PAGE" "149"
					( Origin gFrontEnd )
				)
				( attribute "ROOM" "PROC_SIDEBAND"
					( Origin gFrontEnd )
				)
				( attribute "ROT" "0"
					( Origin gFrontEnd )
				)
				( attribute "TOLERANCE" "10%"
					( Origin gFrontEnd )
				)
				( attribute "VALUE" "1.0UF"
					( Origin gFrontEnd )
				)
				( attribute "VER" "1"
					( Origin gFrontEnd )
				)
				( attribute "VOLTAGE" "16V"
					( Units "uVoltage" "V" 1.000000)
					( Origin gFrontEnd )
				)
				( attribute "XY" "(-650,5400)"
					( Origin gFrontEnd )
				)
				( attribute "CHIPS_PART_NAME" "CAP"
					( Origin gPackager )
				)
				( attribute "CDS_PART_NAME" "CAP_0402-1.0UF,16V,10%,X6S,D97A"
					( Origin gPackager )
				)
				( attribute "CDS_LOCATION" "C25W27"
					( Origin gPackager )
				)
				( attribute "CDS_SEC" "1"
					( Origin gPackager )
				)
				( attribute "SEC" "1"
					( Origin gPackager )
				)
				( objectStatus "C25W27" )
			)
			( gate "@baseboard_fab2_lib.baseboard_fab2(sch_1):page149_i108"
				( attribute "BOM_COST" "PROC"
					( Origin gFrontEnd )
				)
				( attribute "CDS_LIB" "mstr_discrete"
					( Origin gPackager )
				)
				( attribute "LOCATION" "C25W28"
					( Origin gFrontEnd )
				)
				( attribute "MATERIAL" "X6S"
					( Origin gFrontEnd )
				)
				( attribute "PACK_TYPE" "0402"
					( Origin gFrontEnd )
				)
				( attribute "PART_NUMBER" "D97712-011"
					( Origin gFrontEnd )
				)
				( attribute "PHYS_PAGE" "149"
					( Origin gFrontEnd )
				)
				( attribute "ROOM" "PROC_SIDEBAND"
					( Origin gFrontEnd )
				)
				( attribute "ROT" "0"
					( Origin gFrontEnd )
				)
				( attribute "TOLERANCE" "10%"
					( Origin gFrontEnd )
				)
				( attribute "VALUE" "1.0UF"
					( Origin gFrontEnd )
				)
				( attribute "VER" "1"
					( Origin gFrontEnd )
				)
				( attribute "VOLTAGE" "16V"
					( Units "uVoltage" "V" 1.000000)
					( Origin gFrontEnd )
				)
				( attribute "XY" "(-250,5400)"
					( Origin gFrontEnd )
				)
				( attribute "CHIPS_PART_NAME" "CAP"
					( Origin gPackager )
				)
				( attribute "CDS_PART_NAME" "CAP_0402-1.0UF,16V,10%,X6S,D97A"
					( Origin gPackager )
				)
				( attribute "CDS_LOCATION" "C25W28"
					( Origin gPackager )
				)
				( attribute "CDS_SEC" "1"
					( Origin gPackager )
				)
				( attribute "SEC" "1"
					( Origin gPackager )
				)
				( objectStatus "C25W28" )
			)
			( gate "@baseboard_fab2_lib.baseboard_fab2(sch_1):page149_i109"
				( attribute "BOM_COST" "PROC"
					( Origin gFrontEnd )
				)
				( attribute "CDS_LIB" "mstr_discrete"
					( Origin gPackager )
				)
				( attribute "LOCATION" "C25W60"
					( Origin gFrontEnd )
				)
				( attribute "MATERIAL" "X6S"
					( Origin gFrontEnd )
				)
				( attribute "PACK_TYPE" "0402"
					( Origin gFrontEnd )
				)
				( attribute "PART_NUMBER" "D97712-011"
					( Origin gFrontEnd )
				)
				( attribute "PHYS_PAGE" "149"
					( Origin gFrontEnd )
				)
				( attribute "ROOM" "PROC_SIDEBAND"
					( Origin gFrontEnd )
				)
				( attribute "ROT" "0"
					( Origin gFrontEnd )
				)
				( attribute "TOLERANCE" "10%"
					( Origin gFrontEnd )
				)
				( attribute "VALUE" "1.0UF"
					( Origin gFrontEnd )
				)
				( attribute "VER" "1"
					( Origin gFrontEnd )
				)
				( attribute "VOLTAGE" "16V"
					( Units "uVoltage" "V" 1.000000)
					( Origin gFrontEnd )
				)
				( attribute "XY" "(1475,1725)"
					( Origin gFrontEnd )
				)
				( attribute "CHIPS_PART_NAME" "CAP"
					( Origin gPackager )
				)
				( attribute "CDS_PART_NAME" "CAP_0402-1.0UF,16V,10%,X6S,D97A"
					( Origin gPackager )
				)
				( attribute "CDS_LOCATION" "C25W60"
					( Origin gPackager )
				)
				( attribute "CDS_SEC" "1"
					( Origin gPackager )
				)
				( attribute "SEC" "1"
					( Origin gPackager )
				)
				( objectStatus "C25W60" )
			)
			( gate "@baseboard_fab2_lib.baseboard_fab2(sch_1):page149_i110"
				( attribute "BOM_COST" "PROC"
					( Origin gFrontEnd )
				)
				( attribute "CDS_LIB" "mstr_discrete"
					( Origin gPackager )
				)
				( attribute "LOCATION" "C25W35"
					( Origin gFrontEnd )
				)
				( attribute "MATERIAL" "X6S"
					( Origin gFrontEnd )
				)
				( attribute "PACK_TYPE" "0402"
					( Origin gFrontEnd )
				)
				( attribute "PART_NUMBER" "D97712-011"
					( Origin gFrontEnd )
				)
				( attribute "PHYS_PAGE" "149"
					( Origin gFrontEnd )
				)
				( attribute "ROOM" "PROC_SIDEBAND"
					( Origin gFrontEnd )
				)
				( attribute "ROT" "0"
					( Origin gFrontEnd )
				)
				( attribute "TOLERANCE" "10%"
					( Origin gFrontEnd )
				)
				( attribute "VALUE" "1.0UF"
					( Origin gFrontEnd )
				)
				( attribute "VER" "1"
					( Origin gFrontEnd )
				)
				( attribute "VOLTAGE" "16V"
					( Units "uVoltage" "V" 1.000000)
					( Origin gFrontEnd )
				)
				( attribute "XY" "(775,4000)"
					( Origin gFrontEnd )
				)
				( attribute "CHIPS_PART_NAME" "CAP"
					( Origin gPackager )
				)
				( attribute "CDS_PART_NAME" "CAP_0402-1.0UF,16V,10%,X6S,D97A"
					( Origin gPackager )
				)
				( attribute "CDS_LOCATION" "C25W35"
					( Origin gPackager )
				)
				( attribute "CDS_SEC" "1"
					( Origin gPackager )
				)
				( attribute "SEC" "1"
					( Origin gPackager )
				)
				( objectStatus "C25W35" )
			)
			( gate "@baseboard_fab2_lib.baseboard_fab2(sch_1):page149_i112"
				( attribute "BOM_COST" "PROC"
					( Origin gFrontEnd )
				)
				( attribute "CDS_LIB" "mstr_discrete"
					( Origin gPackager )
				)
				( attribute "LOCATION" "C25W48"
					( Origin gFrontEnd )
				)
				( attribute "MATERIAL" "X6S"
					( Origin gFrontEnd )
				)
				( attribute "PACK_TYPE" "0402"
					( Origin gFrontEnd )
				)
				( attribute "PART_NUMBER" "D97712-011"
					( Origin gFrontEnd )
				)
				( attribute "PHYS_PAGE" "149"
					( Origin gFrontEnd )
				)
				( attribute "ROOM" "PROC_SIDEBAND"
					( Origin gFrontEnd )
				)
				( attribute "ROT" "0"
					( Origin gFrontEnd )
				)
				( attribute "TOLERANCE" "10%"
					( Origin gFrontEnd )
				)
				( attribute "VALUE" "1.0UF"
					( Origin gFrontEnd )
				)
				( attribute "VER" "1"
					( Origin gFrontEnd )
				)
				( attribute "VOLTAGE" "16V"
					( Units "uVoltage" "V" 1.000000)
					( Origin gFrontEnd )
				)
				( attribute "XY" "(2325,3000)"
					( Origin gFrontEnd )
				)
				( attribute "CHIPS_PART_NAME" "CAP"
					( Origin gPackager )
				)
				( attribute "CDS_PART_NAME" "CAP_0402-1.0UF,16V,10%,X6S,D97A"
					( Origin gPackager )
				)
				( attribute "CDS_LOCATION" "C25W48"
					( Origin gPackager )
				)
				( attribute "CDS_SEC" "1"
					( Origin gPackager )
				)
				( attribute "SEC" "1"
					( Origin gPackager )
				)
				( objectStatus "C25W48" )
			)
			( gate "@baseboard_fab2_lib.baseboard_fab2(sch_1):page149_i113"
				( attribute "BOM_COST" "PROC"
					( Origin gFrontEnd )
				)
				( attribute "CDS_LIB" "mstr_discrete"
					( Origin gPackager )
				)
				( attribute "LOCATION" "C25W37"
					( Origin gFrontEnd )
				)
				( attribute "MATERIAL" "X6S"
					( Origin gFrontEnd )
				)
				( attribute "PACK_TYPE" "0402"
					( Origin gFrontEnd )
				)
				( attribute "PART_NUMBER" "D97712-011"
					( Origin gFrontEnd )
				)
				( attribute "PHYS_PAGE" "149"
					( Origin gFrontEnd )
				)
				( attribute "ROOM" "PROC_SIDEBAND"
					( Origin gFrontEnd )
				)
				( attribute "ROT" "0"
					( Origin gFrontEnd )
				)
				( attribute "TOLERANCE" "10%"
					( Origin gFrontEnd )
				)
				( attribute "VALUE" "1.0UF"
					( Origin gFrontEnd )
				)
				( attribute "VER" "1"
					( Origin gFrontEnd )
				)
				( attribute "VOLTAGE" "16V"
					( Units "uVoltage" "V" 1.000000)
					( Origin gFrontEnd )
				)
				( attribute "XY" "(2775,3975)"
					( Origin gFrontEnd )
				)
				( attribute "CHIPS_PART_NAME" "CAP"
					( Origin gPackager )
				)
				( attribute "CDS_PART_NAME" "CAP_0402-1.0UF,16V,10%,X6S,D97A"
					( Origin gPackager )
				)
				( attribute "CDS_LOCATION" "C25W37"
					( Origin gPackager )
				)
				( attribute "CDS_SEC" "1"
					( Origin gPackager )
				)
				( attribute "SEC" "1"
					( Origin gPackager )
				)
				( objectStatus "C25W37" )
			)
			( gate "@baseboard_fab2_lib.baseboard_fab2(sch_1):page149_i114"
				( attribute "BOM_COST" "PROC"
					( Origin gFrontEnd )
				)
				( attribute "CDS_LIB" "mstr_discrete"
					( Origin gPackager )
				)
				( attribute "LOCATION" "C25W51"
					( Origin gFrontEnd )
				)
				( attribute "MATERIAL" "X6S"
					( Origin gFrontEnd )
				)
				( attribute "PACK_TYPE" "0402"
					( Origin gFrontEnd )
				)
				( attribute "PART_NUMBER" "D97712-011"
					( Origin gFrontEnd )
				)
				( attribute "PHYS_PAGE" "149"
					( Origin gFrontEnd )
				)
				( attribute "ROOM" "PROC_SIDEBAND"
					( Origin gFrontEnd )
				)
				( attribute "ROT" "0"
					( Origin gFrontEnd )
				)
				( attribute "TOLERANCE" "10%"
					( Origin gFrontEnd )
				)
				( attribute "VALUE" "1.0UF"
					( Origin gFrontEnd )
				)
				( attribute "VER" "1"
					( Origin gFrontEnd )
				)
				( attribute "VOLTAGE" "16V"
					( Units "uVoltage" "V" 1.000000)
					( Origin gFrontEnd )
				)
				( attribute "XY" "(3950,2900)"
					( Origin gFrontEnd )
				)
				( attribute "CHIPS_PART_NAME" "CAP"
					( Origin gPackager )
				)
				( attribute "CDS_PART_NAME" "CAP_0402-1.0UF,16V,10%,X6S,D97A"
					( Origin gPackager )
				)
				( attribute "CDS_LOCATION" "C25W51"
					( Origin gPackager )
				)
				( attribute "CDS_SEC" "1"
					( Origin gPackager )
				)
				( attribute "SEC" "1"
					( Origin gPackager )
				)
				( objectStatus "C25W51" )
			)
			( gate "@baseboard_fab2_lib.baseboard_fab2(sch_1):page149_i115"
				( attribute "BOM_COST" "PROC"
					( Origin gFrontEnd )
				)
				( attribute "CDS_LIB" "mstr_discrete"
					( Origin gPackager )
				)
				( attribute "LOCATION" "C25W71"
					( Origin gFrontEnd )
				)
				( attribute "MATERIAL" "X6S"
					( Origin gFrontEnd )
				)
				( attribute "PACK_TYPE" "0402"
					( Origin gFrontEnd )
				)
				( attribute "PART_NUMBER" "D97712-011"
					( Origin gFrontEnd )
				)
				( attribute "PHYS_PAGE" "149"
					( Origin gFrontEnd )
				)
				( attribute "ROOM" "PROC_SIDEBAND"
					( Origin gFrontEnd )
				)
				( attribute "ROT" "0"
					( Origin gFrontEnd )
				)
				( attribute "TOLERANCE" "10%"
					( Origin gFrontEnd )
				)
				( attribute "VALUE" "1.0UF"
					( Origin gFrontEnd )
				)
				( attribute "VER" "1"
					( Origin gFrontEnd )
				)
				( attribute "VOLTAGE" "16V"
					( Units "uVoltage" "V" 1.000000)
					( Origin gFrontEnd )
				)
				( attribute "XY" "(4800,5300)"
					( Origin gFrontEnd )
				)
				( attribute "CHIPS_PART_NAME" "CAP"
					( Origin gPackager )
				)
				( attribute "CDS_PART_NAME" "CAP_0402-1.0UF,16V,10%,X6S,D97A"
					( Origin gPackager )
				)
				( attribute "CDS_LOCATION" "C25W71"
					( Origin gPackager )
				)
				( attribute "CDS_SEC" "1"
					( Origin gPackager )
				)
				( attribute "SEC" "1"
					( Origin gPackager )
				)
				( objectStatus "C25W71" )
			)
			( gate "@baseboard_fab2_lib.baseboard_fab2(sch_1):page149_i116"
				( attribute "BOM_COST" "PROC"
					( Origin gFrontEnd )
				)
				( attribute "CDS_LIB" "mstr_discrete"
					( Origin gPackager )
				)
				( attribute "LOCATION" "C25W66"
					( Origin gFrontEnd )
				)
				( attribute "MATERIAL" "X6S"
					( Origin gFrontEnd )
				)
				( attribute "PACK_TYPE" "0402"
					( Origin gFrontEnd )
				)
				( attribute "PART_NUMBER" "D97712-011"
					( Origin gFrontEnd )
				)
				( attribute "PHYS_PAGE" "149"
					( Origin gFrontEnd )
				)
				( attribute "ROOM" "PROC_SIDEBAND"
					( Origin gFrontEnd )
				)
				( attribute "ROT" "0"
					( Origin gFrontEnd )
				)
				( attribute "TOLERANCE" "10%"
					( Origin gFrontEnd )
				)
				( attribute "VALUE" "1.0UF"
					( Origin gFrontEnd )
				)
				( attribute "VER" "1"
					( Origin gFrontEnd )
				)
				( attribute "VOLTAGE" "16V"
					( Units "uVoltage" "V" 1.000000)
					( Origin gFrontEnd )
				)
				( attribute "XY" "(2150,5175)"
					( Origin gFrontEnd )
				)
				( attribute "CHIPS_PART_NAME" "CAP"
					( Origin gPackager )
				)
				( attribute "CDS_PART_NAME" "CAP_0402-1.0UF,16V,10%,X6S,D97A"
					( Origin gPackager )
				)
				( attribute "CDS_LOCATION" "C25W66"
					( Origin gPackager )
				)
				( attribute "CDS_SEC" "1"
					( Origin gPackager )
				)
				( attribute "SEC" "1"
					( Origin gPackager )
				)
				( objectStatus "C25W66" )
			)
			( gate "@baseboard_fab2_lib.baseboard_fab2(sch_1):page149_i117"
				( attribute "BOM_COST" "PROC"
					( Origin gFrontEnd )
				)
				( attribute "CDS_LIB" "mstr_discrete"
					( Origin gPackager )
				)
				( attribute "LOCATION" "C25W67"
					( Origin gFrontEnd )
				)
				( attribute "MATERIAL" "X6S"
					( Origin gFrontEnd )
				)
				( attribute "PACK_TYPE" "0402"
					( Origin gFrontEnd )
				)
				( attribute "PART_NUMBER" "D97712-011"
					( Origin gFrontEnd )
				)
				( attribute "PHYS_PAGE" "149"
					( Origin gFrontEnd )
				)
				( attribute "ROOM" "PROC_SIDEBAND"
					( Origin gFrontEnd )
				)
				( attribute "ROT" "0"
					( Origin gFrontEnd )
				)
				( attribute "TOLERANCE" "10%"
					( Origin gFrontEnd )
				)
				( attribute "VALUE" "1.0UF"
					( Origin gFrontEnd )
				)
				( attribute "VER" "1"
					( Origin gFrontEnd )
				)
				( attribute "VOLTAGE" "16V"
					( Units "uVoltage" "V" 1.000000)
					( Origin gFrontEnd )
				)
				( attribute "XY" "(2400,5175)"
					( Origin gFrontEnd )
				)
				( attribute "CHIPS_PART_NAME" "CAP"
					( Origin gPackager )
				)
				( attribute "CDS_PART_NAME" "CAP_0402-1.0UF,16V,10%,X6S,D97A"
					( Origin gPackager )
				)
				( attribute "CDS_LOCATION" "C25W67"
					( Origin gPackager )
				)
				( attribute "CDS_SEC" "1"
					( Origin gPackager )
				)
				( attribute "SEC" "1"
					( Origin gPackager )
				)
				( objectStatus "C25W67" )
			)
			( gate "@baseboard_fab2_lib.baseboard_fab2(sch_1):page149_i118"
				( attribute "BOM_COST" "PROC"
					( Origin gFrontEnd )
				)
				( attribute "CDS_LIB" "mstr_discrete"
					( Origin gPackager )
				)
				( attribute "LOCATION" "C25W52"
					( Origin gFrontEnd )
				)
				( attribute "MATERIAL" "X6S"
					( Origin gFrontEnd )
				)
				( attribute "PACK_TYPE" "0402"
					( Origin gFrontEnd )
				)
				( attribute "PART_NUMBER" "D97712-011"
					( Origin gFrontEnd )
				)
				( attribute "PHYS_PAGE" "149"
					( Origin gFrontEnd )
				)
				( attribute "ROOM" "PROC_SIDEBAND"
					( Origin gFrontEnd )
				)
				( attribute "ROT" "0"
					( Origin gFrontEnd )
				)
				( attribute "TOLERANCE" "10%"
					( Origin gFrontEnd )
				)
				( attribute "VALUE" "1.0UF"
					( Origin gFrontEnd )
				)
				( attribute "VER" "1"
					( Origin gFrontEnd )
				)
				( attribute "VOLTAGE" "16V"
					( Units "uVoltage" "V" 1.000000)
					( Origin gFrontEnd )
				)
				( attribute "XY" "(4250,2900)"
					( Origin gFrontEnd )
				)
				( attribute "CHIPS_PART_NAME" "CAP"
					( Origin gPackager )
				)
				( attribute "CDS_PART_NAME" "CAP_0402-1.0UF,16V,10%,X6S,D97A"
					( Origin gPackager )
				)
				( attribute "CDS_LOCATION" "C25W52"
					( Origin gPackager )
				)
				( attribute "CDS_SEC" "1"
					( Origin gPackager )
				)
				( attribute "SEC" "1"
					( Origin gPackager )
				)
				( objectStatus "C25W52" )
			)
			( gate "@baseboard_fab2_lib.baseboard_fab2(sch_1):page176_i132"
				( attribute "CDS_LIB" "mstr_discrete"
					( Origin gPackager )
				)
				( attribute "LOCATION" "R1W10"
					( Origin gFrontEnd )
				)
				( attribute "MATERIAL" "CHIP"
					( Origin gFrontEnd )
				)
				( attribute "PACK_TYPE" "0805"
					( Origin gFrontEnd )
				)
				( attribute "PART_NUMBER" "G22179-004"
					( Origin gFrontEnd )
				)
				( attribute "PHYS_PAGE" "176"
					( Origin gFrontEnd )
				)
				( attribute "ROOM" "HOT_SWAP"
					( Origin gFrontEnd )
				)
				( attribute "ROT" "5"
					( Origin gFrontEnd )
				)
				( attribute "SEC" "1"
					( Origin gFrontEnd )
				)
				( attribute "SEC_TYPE" "0805"
					( Origin gFrontEnd )
				)
				( attribute "TOLERANCE" "5%"
					( Origin gFrontEnd )
				)
				( attribute "VALUE" "0.0"
					( Origin gFrontEnd )
				)
				( attribute "VER" "1"
					( Origin gFrontEnd )
				)
				( attribute "WATTAGE" "1/8W"
					( Origin gFrontEnd )
				)
				( attribute "XY" "(-5350,3950)"
					( Origin gFrontEnd )
				)
				( attribute "CHIPS_PART_NAME" "RES"
					( Origin gPackager )
				)
				( attribute "CDS_PART_NAME" "RES_0805-0.0,5%,1/8W,CHIP,G221A"
					( Origin gPackager )
				)
				( attribute "CDS_LOCATION" "R1W10"
					( Origin gPackager )
				)
				( attribute "CDS_SEC" "1"
					( Origin gPackager )
				)
				( objectStatus "R1W10" )
			)
			( gate "@baseboard_fab2_lib.baseboard_fab2(sch_1):page176_i133"
				( attribute "CDS_LIB" "mstr_discrete"
					( Origin gPackager )
				)
				( attribute "LOCATION" "R1W11"
					( Origin gFrontEnd )
				)
				( attribute "MATERIAL" "EMPTY"
					( Origin gFrontEnd )
				)
				( attribute "PACK_TYPE" "0805"
					( Origin gFrontEnd )
				)
				( attribute "PART_NUMBER" "G22179-004"
					( Origin gFrontEnd )
				)
				( attribute "PHYS_PAGE" "176"
					( Origin gFrontEnd )
				)
				( attribute "ROT" "5"
					( Origin gFrontEnd )
				)
				( attribute "SEC" "1"
					( Origin gFrontEnd )
				)
				( attribute "SEC_TYPE" "0805"
					( Origin gFrontEnd )
				)
				( attribute "TOLERANCE" "5%"
					( Origin gFrontEnd )
				)
				( attribute "VALUE" "0.0"
					( Origin gFrontEnd )
				)
				( attribute "VER" "1"
					( Origin gFrontEnd )
				)
				( attribute "WATTAGE" "1/8W"
					( Origin gFrontEnd )
				)
				( attribute "XY" "(-4950,3950)"
					( Origin gFrontEnd )
				)
				( attribute "CHIPS_PART_NAME" "RES"
					( Origin gPackager )
				)
				( attribute "CDS_PART_NAME" "RES_0805-0.0,5%,1/8W,EMPTY,G22A"
					( Origin gPackager )
				)
				( attribute "CDS_LOCATION" "R1W11"
					( Origin gPackager )
				)
				( attribute "CDS_SEC" "1"
					( Origin gPackager )
				)
				( objectStatus "R1W11" )
			)
			( gate "@baseboard_fab2_lib.baseboard_fab2(sch_1):page176_i137"
				( attribute "BOM_COST" "PROC_SIDEBAND"
					( Origin gFrontEnd )
				)
				( attribute "CDS_LIB" "mstr_discrete"
					( Origin gPackager )
				)
				( attribute "LOCATION" "R1W12"
					( Origin gFrontEnd )
				)
				( attribute "MATERIAL" "CHIP"
					( Origin gFrontEnd )
				)
				( attribute "PACK_TYPE" "0402"
					( Origin gFrontEnd )
				)
				( attribute "PART_NUMBER" "G21497-005"
					( Origin gFrontEnd )
				)
				( attribute "PHYS_PAGE" "176"
					( Origin gFrontEnd )
				)
				( attribute "ROOM" "CPU0"
					( Origin gFrontEnd )
				)
				( attribute "ROT" "0"
					( Origin gFrontEnd )
				)
				( attribute "SEC" "1"
					( Origin gFrontEnd )
				)
				( attribute "SEC_TYPE" "0402"
					( Origin gFrontEnd )
				)
				( attribute "TOLERANCE" "5%"
					( Origin gFrontEnd )
				)
				( attribute "VALUE" "0.0"
					( Origin gFrontEnd )
				)
				( attribute "VER" "1"
					( Origin gFrontEnd )
				)
				( attribute "WATTAGE" "1/16W"
					( Origin gFrontEnd )
				)
				( attribute "XY" "(-5650,3225)"
					( Origin gFrontEnd )
				)
				( attribute "CHIPS_PART_NAME" "RES"
					( Origin gPackager )
				)
				( attribute "CDS_PART_NAME" "RES_0402-0.0,5%,1/16W,CHIP,G21A"
					( Origin gPackager )
				)
				( attribute "CDS_LOCATION" "R1W12"
					( Origin gPackager )
				)
				( attribute "CDS_SEC" "1"
					( Origin gPackager )
				)
				( objectStatus "R1W12" )
			)
			( gate "@baseboard_fab2_lib.baseboard_fab2(sch_1):page176_i138"
				( attribute "BOM_COST" "PROC_SIDEBAND"
					( Origin gFrontEnd )
				)
				( attribute "CDS_LIB" "mstr_discrete"
					( Origin gPackager )
				)
				( attribute "LOCATION" "R1W13"
					( Origin gFrontEnd )
				)
				( attribute "MATERIAL" "CHIP"
					( Origin gFrontEnd )
				)
				( attribute "PACK_TYPE" "0402"
					( Origin gFrontEnd )
				)
				( attribute "PART_NUMBER" "G21497-005"
					( Origin gFrontEnd )
				)
				( attribute "PHYS_PAGE" "176"
					( Origin gFrontEnd )
				)
				( attribute "ROOM" "CPU0"
					( Origin gFrontEnd )
				)
				( attribute "ROT" "0"
					( Origin gFrontEnd )
				)
				( attribute "SEC" "1"
					( Origin gFrontEnd )
				)
				( attribute "SEC_TYPE" "0402"
					( Origin gFrontEnd )
				)
				( attribute "TOLERANCE" "5%"
					( Origin gFrontEnd )
				)
				( attribute "VALUE" "0.0"
					( Origin gFrontEnd )
				)
				( attribute "VER" "1"
					( Origin gFrontEnd )
				)
				( attribute "WATTAGE" "1/16W"
					( Origin gFrontEnd )
				)
				( attribute "XY" "(-5650,3000)"
					( Origin gFrontEnd )
				)
				( attribute "CHIPS_PART_NAME" "RES"
					( Origin gPackager )
				)
				( attribute "CDS_PART_NAME" "RES_0402-0.0,5%,1/16W,CHIP,G21A"
					( Origin gPackager )
				)
				( attribute "CDS_LOCATION" "R1W13"
					( Origin gPackager )
				)
				( attribute "CDS_SEC" "1"
					( Origin gPackager )
				)
				( attribute "POP" "NOPOP"
					( Origin gFrontEnd )
				)
				( objectStatus "R1W13" )
			)
			( gate "@baseboard_fab2_lib.baseboard_fab2(sch_1):page249_i36"
				( attribute "BOM_COST" "SYS_CLOCK"
					( Origin gFrontEnd )
				)
				( attribute "CDS_LIB" "mstr_discrete"
					( Origin gPackager )
				)
				( attribute "LOCATION" "R3W3"
					( Origin gFrontEnd )
				)
				( attribute "MATERIAL" "EMPTY"
					( Origin gFrontEnd )
				)
				( attribute "PACK_TYPE" "0402"
					( Origin gFrontEnd )
				)
				( attribute "PART_NUMBER" "G21796-016"
					( Origin gFrontEnd )
				)
				( attribute "PHYS_PAGE" "249"
					( Origin gFrontEnd )
				)
				( attribute "ROOM" "DB1200ZL"
					( Origin gFrontEnd )
				)
				( attribute "ROT" "0"
					( Origin gFrontEnd )
				)
				( attribute "SEC" "1"
					( Origin gFrontEnd )
				)
				( attribute "SEC_TYPE" "0402"
					( Origin gFrontEnd )
				)
				( attribute "TOLERANCE" "1%"
					( Origin gFrontEnd )
				)
				( attribute "VALUE" "10.0K"
					( Origin gFrontEnd )
				)
				( attribute "VER" "2"
					( Origin gFrontEnd )
				)
				( attribute "WATTAGE" "1/16W"
					( Origin gFrontEnd )
				)
				( attribute "XY" "(-4850,2850)"
					( Origin gFrontEnd )
				)
				( attribute "CHIPS_PART_NAME" "RES"
					( Origin gPackager )
				)
				( attribute "CDS_PART_NAME" "RES_0402-10.0K,1%,1/16W,EMPTY,A"
					( Origin gPackager )
				)
				( attribute "CDS_LOCATION" "R3W3"
					( Origin gPackager )
				)
				( attribute "CDS_SEC" "1"
					( Origin gPackager )
				)
				( objectStatus "R3W3" )
			)
			( gate "@baseboard_fab2_lib.baseboard_fab2(sch_1):page251_i19"
				( attribute "BOM_COST" "SM_THERM"
					( Origin gFrontEnd )
				)
				( attribute "CDS_LIB" "mstr_ttl"
					( Origin gPackager )
				)
				( attribute "CDS_LOCATION" "U10W1"
					( Origin gPackager )
				)
				( attribute "CDS_SEC" "1"
					( Origin gPackager )
				)
				( attribute "LOCATION" "U10W1"
					( Origin gFrontEnd )
				)
				( attribute "MATERIAL" "IC"
					( Origin gFrontEnd )
				)
				( attribute "PACK_TYPE" "SOP"
					( Origin gFrontEnd )
				)
				( attribute "PART_NUMBER" "C88419-001"
					( Origin gFrontEnd )
				)
				( attribute "PHYS_PAGE" "251"
					( Origin gFrontEnd )
				)
				( attribute "ROOM" "CPU_FANS"
					( Origin gFrontEnd )
				)
				( attribute "ROT" "0"
					( Origin gFrontEnd )
				)
				( attribute "SEC" "1"
					( Origin gFrontEnd )
				)
				( attribute "SEC_TYPE" "SOP"
					( Origin gFrontEnd )
				)
				( attribute "VALUE" "74LVC1G07"
					( Origin gFrontEnd )
				)
				( attribute "VER" "1"
					( Origin gFrontEnd )
				)
				( attribute "XY" "(-6325,4450)"
					( Origin gFrontEnd )
				)
				( attribute "CHIPS_PART_NAME" "TTL1G07_A"
					( Origin gPackager )
				)
				( attribute "CDS_PART_NAME" "TTL1G07_A_SOP-74LVC1G07,IC,C88B"
					( Origin gPackager )
				)
				( objectStatus "U10W1" )
			)
			( gate "@baseboard_fab2_lib.baseboard_fab2(sch_1):page251_i16"
				( attribute "BOM_COST" "SM_THERM"
					( Origin gFrontEnd )
				)
				( attribute "CDS_LIB" "dev_discrete"
					( Origin gPackager )
				)
				( attribute "CDS_LOCATION" "C10W3"
					( Origin gPackager )
				)
				( attribute "CDS_SEC" "1"
					( Origin gPackager )
				)
				( attribute "LOCATION" "C10W3"
					( Origin gFrontEnd )
				)
				( attribute "MATERIAL" "X7R"
					( Origin gFrontEnd )
				)
				( attribute "PACK_TYPE" "0402V"
					( Origin gFrontEnd )
				)
				( attribute "PART_NUMBER" "A36096-045"
					( Origin gFrontEnd )
				)
				( attribute "PHYS_PAGE" "251"
					( Origin gFrontEnd )
				)
				( attribute "ROOM" "CPU_FANS"
					( Origin gFrontEnd )
				)
				( attribute "ROT" "2"
					( Origin gFrontEnd )
				)
				( attribute "SEC" "1"
					( Origin gFrontEnd )
				)
				( attribute "SEC_TYPE" "0402V"
					( Origin gFrontEnd )
				)
				( attribute "TOLERANCE" "10%"
					( Origin gFrontEnd )
				)
				( attribute "VALUE" "0.01UF"
					( Origin gFrontEnd )
				)
				( attribute "VER" "1"
					( Origin gFrontEnd )
				)
				( attribute "VOLTAGE" "25V"
					( Units "uVoltage" "V" 1.000000)
					( Origin gFrontEnd )
				)
				( attribute "XY" "(-5175,5050)"
					( Origin gFrontEnd )
				)
				( attribute "CHIPS_PART_NAME" "CAP_A"
					( Origin gPackager )
				)
				( attribute "CDS_PART_NAME" "CAP_A_0402V-0.01UF,25V,10%,X7RA"
					( Origin gPackager )
				)
				( objectStatus "C10W3" )
			)
			( gate "@baseboard_fab2_lib.baseboard_fab2(sch_1):page251_i15"
				( attribute "BOM_COST" "SM_THERM"
					( Origin gFrontEnd )
				)
				( attribute "CDS_LIB" "mstr_discrete"
					( Origin gPackager )
				)
				( attribute "CDS_LOCATION" "R10W2"
					( Origin gPackager )
				)
				( attribute "CDS_SEC" "1"
					( Origin gPackager )
				)
				( attribute "LOCATION" "R10W2"
					( Origin gFrontEnd )
				)
				( attribute "MATERIAL" "CHIP"
					( Origin gFrontEnd )
				)
				( attribute "PACK_TYPE" "0402"
					( Origin gFrontEnd )
				)
				( attribute "PART_NUMBER" "G21796-072"
					( Origin gFrontEnd )
				)
				( attribute "PHYS_PAGE" "251"
					( Origin gFrontEnd )
				)
				( attribute "ROOM" "CPU_FANS"
					( Origin gFrontEnd )
				)
				( attribute "ROT" "0"
					( Origin gFrontEnd )
				)
				( attribute "SEC" "1"
					( Origin gFrontEnd )
				)
				( attribute "SEC_TYPE" "0402"
					( Origin gFrontEnd )
				)
				( attribute "TOLERANCE" "1%"
					( Origin gFrontEnd )
				)
				( attribute "VALUE" "4.75K"
					( Origin gFrontEnd )
				)
				( attribute "VER" "2"
					( Origin gFrontEnd )
				)
				( attribute "WATTAGE" "1/16W"
					( Origin gFrontEnd )
				)
				( attribute "XY" "(-5300,5450)"
					( Origin gFrontEnd )
				)
				( attribute "CHIPS_PART_NAME" "RES"
					( Origin gPackager )
				)
				( attribute "CDS_PART_NAME" "RES_0402-4.75K,1%,1/16W,CHIP,GA"
					( Origin gPackager )
				)
				( objectStatus "R10W2" )
			)
			( gate "@baseboard_fab2_lib.baseboard_fab2(sch_1):page251_i14"
				( attribute "BOM_COST" "SM_THERM"
					( Origin gFrontEnd )
				)
				( attribute "CDS_LIB" "mstr_discrete"
					( Origin gPackager )
				)
				( attribute "CDS_LOCATION" "R10W4"
					( Origin gPackager )
				)
				( attribute "CDS_SEC" "1"
					( Origin gPackager )
				)
				( attribute "LOCATION" "R10W4"
					( Origin gFrontEnd )
				)
				( attribute "MATERIAL" "CHIP"
					( Origin gFrontEnd )
				)
				( attribute "PACK_TYPE" "0402"
					( Origin gFrontEnd )
				)
				( attribute "PART_NUMBER" "G21796-271"
					( Origin gFrontEnd )
				)
				( attribute "PHYS_PAGE" "251"
					( Origin gFrontEnd )
				)
				( attribute "ROOM" "CPU_FANS"
					( Origin gFrontEnd )
				)
				( attribute "ROT" "0"
					( Origin gFrontEnd )
				)
				( attribute "SEC" "1"
					( Origin gFrontEnd )
				)
				( attribute "SEC_TYPE" "0402"
					( Origin gFrontEnd )
				)
				( attribute "TOLERANCE" "1.0%"
					( Origin gFrontEnd )
				)
				( attribute "VALUE" "221"
					( Origin gFrontEnd )
				)
				( attribute "VER" "1"
					( Origin gFrontEnd )
				)
				( attribute "WATTAGE" "1/16W"
					( Origin gFrontEnd )
				)
				( attribute "XY" "(-4650,4450)"
					( Origin gFrontEnd )
				)
				( attribute "CHIPS_PART_NAME" "RES"
					( Origin gPackager )
				)
				( attribute "CDS_PART_NAME" "RES_0402-221,1.0%,1/16W,CHIP,GA"
					( Origin gPackager )
				)
				( objectStatus "R10W4" )
			)
			( gate "@baseboard_fab2_lib.baseboard_fab2(sch_1):page251_i13"
				( attribute "BOM_COST" "SM_THERM"
					( Origin gFrontEnd )
				)
				( attribute "CDS_LIB" "mstr_discrete"
					( Origin gPackager )
				)
				( attribute "CDS_LOCATION" "R10W1"
					( Origin gPackager )
				)
				( attribute "CDS_SEC" "1"
					( Origin gPackager )
				)
				( attribute "LOCATION" "R10W1"
					( Origin gFrontEnd )
				)
				( attribute "MATERIAL" "CHIP"
					( Origin gFrontEnd )
				)
				( attribute "NO_XNET_CONNECTION" "1"
					( Origin gFrontEnd )
				)
				( attribute "PACK_TYPE" "0402"
					( Origin gFrontEnd )
				)
				( attribute "PART_NUMBER" "G21796-017"
					( Origin gFrontEnd )
				)
				( attribute "PHYS_PAGE" "251"
					( Origin gFrontEnd )
				)
				( attribute "ROOM" "CPU_FANS"
					( Origin gFrontEnd )
				)
				( attribute "ROT" "0"
					( Origin gFrontEnd )
				)
				( attribute "SEC" "1"
					( Origin gFrontEnd )
				)
				( attribute "SEC_TYPE" "0402"
					( Origin gFrontEnd )
				)
				( attribute "TOLERANCE" "1%"
					( Origin gFrontEnd )
				)
				( attribute "VALUE" "100.0"
					( Origin gFrontEnd )
				)
				( attribute "VER" "1"
					( Origin gFrontEnd )
				)
				( attribute "WATTAGE" "1/16W"
					( Origin gFrontEnd )
				)
				( attribute "XY" "(-4650,5250)"
					( Origin gFrontEnd )
				)
				( attribute "CHIPS_PART_NAME" "RES"
					( Origin gPackager )
				)
				( attribute "CDS_PART_NAME" "RES_0402-100.0,1%,1/16W,CHIP,GA"
					( Origin gPackager )
				)
				( objectStatus "R10W1" )
			)
			( gate "@baseboard_fab2_lib.baseboard_fab2(sch_1):page251_i12"
				( attribute "BOM_COST" "SM_THERM"
					( Origin gFrontEnd )
				)
				( attribute "CDS_LIB" "mstr_discrete"
					( Origin gPackager )
				)
				( attribute "CDS_LOCATION" "CR10W1"
					( Origin gPackager )
				)
				( attribute "CDS_SEC" "1"
					( Origin gPackager )
				)
				( attribute "LOCATION" "CR10W1"
					( Origin gFrontEnd )
				)
				( attribute "MATERIAL" "IC"
					( Origin gFrontEnd )
				)
				( attribute "PACK_TYPE" "SM"
					( Origin gFrontEnd )
				)
				( attribute "PART_NUMBER" "H71799-001"
					( Origin gFrontEnd )
				)
				( attribute "PHYS_PAGE" "251"
					( Origin gFrontEnd )
				)
				( attribute "ROOM" "CPU_FANS"
					( Origin gFrontEnd )
				)
				( attribute "ROT" "0"
					( Origin gFrontEnd )
				)
				( attribute "SEC" "1"
					( Origin gFrontEnd )
				)
				( attribute "SEC_TYPE" "SM"
					( Origin gFrontEnd )
				)
				( attribute "VALUE" "SDMK0340L"
					( Origin gFrontEnd )
				)
				( attribute "VER" "1"
					( Origin gFrontEnd )
				)
				( attribute "XY" "(-3200,5250)"
					( Origin gFrontEnd )
				)
				( attribute "CHIPS_PART_NAME" "DIODE"
					( Origin gPackager )
				)
				( attribute "CDS_PART_NAME" "DIODE_SM-SDMK0340L,IC,H71799-0A"
					( Origin gPackager )
				)
				( objectStatus "CR10W1" )
			)
			( gate "@baseboard_fab2_lib.baseboard_fab2(sch_1):page251_i11"
				( attribute "BOM_COST" "SM_THERM"
					( Origin gFrontEnd )
				)
				( attribute "CDS_LIB" "mstr_discrete"
					( Origin gPackager )
				)
				( attribute "CDS_LOCATION" "R10W3"
					( Origin gPackager )
				)
				( attribute "CDS_SEC" "1"
					( Origin gPackager )
				)
				( attribute "LOCATION" "R10W3"
					( Origin gFrontEnd )
				)
				( attribute "MATERIAL" "CHIP"
					( Origin gFrontEnd )
				)
				( attribute "PACK_TYPE" "0402"
					( Origin gFrontEnd )
				)
				( attribute "PART_NUMBER" "G21796-072"
					( Origin gFrontEnd )
				)
				( attribute "PHYS_PAGE" "251"
					( Origin gFrontEnd )
				)
				( attribute "ROOM" "CPU_FANS"
					( Origin gFrontEnd )
				)
				( attribute "ROT" "2"
					( Origin gFrontEnd )
				)
				( attribute "SEC" "1"
					( Origin gFrontEnd )
				)
				( attribute "SEC_TYPE" "0402"
					( Origin gFrontEnd )
				)
				( attribute "TOLERANCE" "1%"
					( Origin gFrontEnd )
				)
				( attribute "VALUE" "4.75K"
					( Origin gFrontEnd )
				)
				( attribute "VER" "2"
					( Origin gFrontEnd )
				)
				( attribute "WATTAGE" "1/16W"
					( Origin gFrontEnd )
				)
				( attribute "XY" "(-3250,4650)"
					( Origin gFrontEnd )
				)
				( attribute "CHIPS_PART_NAME" "RES"
					( Origin gPackager )
				)
				( attribute "CDS_PART_NAME" "RES_0402-4.75K,1%,1/16W,CHIP,GA"
					( Origin gPackager )
				)
				( objectStatus "R10W3" )
			)
			( gate "@baseboard_fab2_lib.baseboard_fab2(sch_1):page251_i5"
				( attribute "CDS_LIB" "mstr_discrete"
					( Origin gPackager )
				)
				( attribute "CDS_LOCATION" "R10W5"
					( Origin gPackager )
				)
				( attribute "CDS_SEC" "1"
					( Origin gPackager )
				)
				( attribute "LOCATION" "R10W5"
					( Origin gFrontEnd )
				)
				( attribute "MATERIAL" "CHIP"
					( Origin gFrontEnd )
				)
				( attribute "PACK_TYPE" "0805"
					( Origin gFrontEnd )
				)
				( attribute "PART_NUMBER" "G22179-004"
					( Origin gFrontEnd )
				)
				( attribute "PHYS_PAGE" "251"
					( Origin gFrontEnd )
				)
				( attribute "ROOM" "HOT_SWAP"
					( Origin gFrontEnd )
				)
				( attribute "ROT" "0"
					( Origin gFrontEnd )
				)
				( attribute "SEC" "1"
					( Origin gFrontEnd )
				)
				( attribute "SEC_TYPE" "0805"
					( Origin gFrontEnd )
				)
				( attribute "TOLERANCE" "5%"
					( Origin gFrontEnd )
				)
				( attribute "VALUE" "0.0"
					( Origin gFrontEnd )
				)
				( attribute "VER" "1"
					( Origin gFrontEnd )
				)
				( attribute "WATTAGE" "1/8W"
					( Origin gFrontEnd )
				)
				( attribute "XY" "(-3025,6025)"
					( Origin gFrontEnd )
				)
				( attribute "CHIPS_PART_NAME" "RES"
					( Origin gPackager )
				)
				( attribute "CDS_PART_NAME" "RES_0805-0.0,5%,1/8W,CHIP,G221A"
					( Origin gPackager )
				)
				( objectStatus "R10W5" )
			)
			( gate "@baseboard_fab2_lib.baseboard_fab2(sch_1):page251_i3"
				( attribute "BOM_COST" "SM_THERM"
					( Origin gFrontEnd )
				)
				( attribute "CDS_LIB" "mstr_discrete"
					( Origin gPackager )
				)
				( attribute "CDS_LOCATION" "C10W1"
					( Origin gPackager )
				)
				( attribute "CDS_SEC" "1"
					( Origin gPackager )
				)
				( attribute "LOCATION" "C10W1"
					( Origin gFrontEnd )
				)
				( attribute "MATERIAL" "X6S"
					( Origin gFrontEnd )
				)
				( attribute "PACK_TYPE" "0805"
					( Origin gFrontEnd )
				)
				( attribute "PART_NUMBER" "C95333-007"
					( Origin gFrontEnd )
				)
				( attribute "PHYS_PAGE" "251"
					( Origin gFrontEnd )
				)
				( attribute "ROOM" "CPU_FANS"
					( Origin gFrontEnd )
				)
				( attribute "ROT" "0"
					( Origin gFrontEnd )
				)
				( attribute "SEC" "1"
					( Origin gFrontEnd )
				)
				( attribute "SEC_TYPE" "0805"
					( Origin gFrontEnd )
				)
				( attribute "TOLERANCE" "10%"
					( Origin gFrontEnd )
				)
				( attribute "VALUE" "10UF"
					( Origin gFrontEnd )
				)
				( attribute "VER" "1"
					( Origin gFrontEnd )
				)
				( attribute "VOLTAGE" "16V"
					( Units "uVoltage" "V" 1.000000)
					( Origin gFrontEnd )
				)
				( attribute "XY" "(-2075,5825)"
					( Origin gFrontEnd )
				)
				( attribute "CHIPS_PART_NAME" "CAP"
					( Origin gPackager )
				)
				( attribute "CDS_PART_NAME" "CAP_0805-10UF,16V,10%,X6S,C953A"
					( Origin gPackager )
				)
				( objectStatus "C10W1" )
			)
			( gate "@baseboard_fab2_lib.baseboard_fab2(sch_1):page251_i1"
				( attribute "BOM_COST" "SM_THERM"
					( Origin gFrontEnd )
				)
				( attribute "CDS_LIB" "dev_discrete"
					( Origin gPackager )
				)
				( attribute "CDS_LOCATION" "C10W2"
					( Origin gPackager )
				)
				( attribute "CDS_SEC" "1"
					( Origin gPackager )
				)
				( attribute "LOCATION" "C10W2"
					( Origin gFrontEnd )
				)
				( attribute "MATERIAL" "X7R"
					( Origin gFrontEnd )
				)
				( attribute "PACK_TYPE" "0402V"
					( Origin gFrontEnd )
				)
				( attribute "PART_NUMBER" "A36096-030"
					( Origin gFrontEnd )
				)
				( attribute "PHYS_PAGE" "251"
					( Origin gFrontEnd )
				)
				( attribute "ROOM" "CPU_FANS"
					( Origin gFrontEnd )
				)
				( attribute "ROT" "0"
					( Origin gFrontEnd )
				)
				( attribute "SEC" "1"
					( Origin gFrontEnd )
				)
				( attribute "SEC_TYPE" "0402V"
					( Origin gFrontEnd )
				)
				( attribute "TOLERANCE" "10%"
					( Origin gFrontEnd )
				)
				( attribute "VALUE" "0.1UF"
					( Origin gFrontEnd )
				)
				( attribute "VER" "1"
					( Origin gFrontEnd )
				)
				( attribute "VOLTAGE" "16V"
					( Units "uVoltage" "V" 1.000000)
					( Origin gFrontEnd )
				)
				( attribute "XY" "(-1775,5825)"
					( Origin gFrontEnd )
				)
				( attribute "CHIPS_PART_NAME" "CAP_A"
					( Origin gPackager )
				)
				( attribute "CDS_PART_NAME" "CAP_A_0402V-0.1UF,16V,10%,X7R,A"
					( Origin gPackager )
				)
				( objectStatus "C10W2" )
			)
			( gate "@baseboard_fab2_lib.baseboard_fab2(sch_1):page250_i45"
				( attribute "CHIPS_PART_NAME" "TTL1G07_A"
					( Origin gPackager )
				)
			)
			( gate "@baseboard_fab2_lib.baseboard_fab2(sch_1):page157_i390"
				( attribute "CDS_LIB" "w_hdl"
					( Origin gPackager )
				)
				( attribute "CDS_LMAN_SYM_OUTLINE" "-200,150,200,-150"
					( Origin gPackager )
				)
				( attribute "LOCATION" "U2R1"
					( Origin gFrontEnd )
				)
				( attribute "PACK_TYPE" "DISCRET-GA1"
					( Origin gFrontEnd )
				)
				( attribute "PART_NUMBER" "073.7PZ14.0007"
					( Origin gFrontEnd )
				)
				( attribute "PHYS_PAGE" "157"
					( Origin gFrontEnd )
				)
				( attribute "ROT" "0"
					( Origin gFrontEnd )
				)
				( attribute "SEC" "1"
					( Origin gFrontEnd )
				)
				( attribute "SEC_TYPE" "DISCRET-GA1"
					( Origin gFrontEnd )
				)
				( attribute "VALUE" "TC7PZ14FU-GP"
					( Origin gFrontEnd )
				)
				( attribute "VER" "1"
					( Origin gFrontEnd )
				)
				( attribute "XY" "(-2425,2725)"
					( Origin gFrontEnd )
				)
				( attribute "CHIPS_PART_NAME" "TC7PZ14FU-GP"
					( Origin gPackager )
				)
				( attribute "CDS_PART_NAME" "TC7PZ14FU-GP_DISCRET-GA1-TC7PZA"
					( Origin gPackager )
				)
				( attribute "CDS_LOCATION" "U2R1"
					( Origin gPackager )
				)
				( attribute "CDS_SEC" "1"
					( Origin gPackager )
				)
				( objectStatus "U2R1" )
			)
			( gate "@baseboard_fab2_lib.baseboard_fab2(sch_1):page157_i391"
				( attribute "BOM_COST" "MIO_CHASSIS"
					( Origin gFrontEnd )
				)
				( attribute "CDS_LIB" "mstr_discrete"
					( Origin gPackager )
				)
				( attribute "CDS_LOCATION" "R2R10"
					( Origin gPackager )
				)
				( attribute "CDS_SEC" "1"
					( Origin gPackager )
				)
				( attribute "LOCATION" "R2R10"
					( Origin gFrontEnd )
				)
				( attribute "MATERIAL" "CHIP"
					( Origin gFrontEnd )
				)
				( attribute "PACK_TYPE" "0402"
					( Origin gFrontEnd )
				)
				( attribute "PART_NUMBER" "G21796-074"
					( Origin gFrontEnd )
				)
				( attribute "PHYS_PAGE" "157"
					( Origin gFrontEnd )
				)
				( attribute "ROOM" "MIO_CHASSIS"
					( Origin gFrontEnd )
				)
				( attribute "ROT" "0"
					( Origin gFrontEnd )
				)
				( attribute "SEC" "1"
					( Origin gFrontEnd )
				)
				( attribute "SEC_TYPE" "0402"
					( Origin gFrontEnd )
				)
				( attribute "TOLERANCE" "1%"
					( Origin gFrontEnd )
				)
				( attribute "VALUE" "33.2"
					( Origin gFrontEnd )
				)
				( attribute "VER" "1"
					( Origin gFrontEnd )
				)
				( attribute "WATTAGE" "1/16W"
					( Origin gFrontEnd )
				)
				( attribute "XY" "(-1250,2925)"
					( Origin gFrontEnd )
				)
				( attribute "CHIPS_PART_NAME" "RES"
					( Origin gPackager )
				)
				( attribute "CDS_PART_NAME" "RES_0402-33.2,1%,1/16W,CHIP,G2A"
					( Origin gPackager )
				)
				( objectStatus "R2R10" )
			)
			( gate "@baseboard_fab2_lib.baseboard_fab2(sch_1):page175_i95"
				( attribute "BOM_COST" "MIO_CHASSIS"
					( Origin gFrontEnd )
				)
				( attribute "CDS_LIB" "mstr_discrete"
					( Origin gPackager )
				)
				( attribute "CDS_LOCATION" "R9A9"
					( Origin gPackager )
				)
				( attribute "CDS_SEC" "1"
					( Origin gPackager )
				)
				( attribute "LOCATION" "R9A9"
					( Origin gFrontEnd )
				)
				( attribute "MATERIAL" "CHIP"
					( Origin gFrontEnd )
				)
				( attribute "PACK_TYPE" "0402"
					( Origin gFrontEnd )
				)
				( attribute "PART_NUMBER" "G21796-017"
					( Origin gFrontEnd )
				)
				( attribute "PHYS_PAGE" "175"
					( Origin gFrontEnd )
				)
				( attribute "ROOM" "MIO_CHASSIS"
					( Origin gFrontEnd )
				)
				( attribute "ROT" "0"
					( Origin gFrontEnd )
				)
				( attribute "SEC" "1"
					( Origin gFrontEnd )
				)
				( attribute "SEC_TYPE" "0402"
					( Origin gFrontEnd )
				)
				( attribute "TOLERANCE" "1%"
					( Origin gFrontEnd )
				)
				( attribute "VALUE" "100.0"
					( Origin gFrontEnd )
				)
				( attribute "VER" "1"
					( Origin gFrontEnd )
				)
				( attribute "WATTAGE" "1/16W"
					( Origin gFrontEnd )
				)
				( attribute "XY" "(-2225,2675)"
					( Origin gFrontEnd )
				)
				( attribute "CHIPS_PART_NAME" "RES"
					( Origin gPackager )
				)
				( attribute "CDS_PART_NAME" "RES_0402-100.0,1%,1/16W,CHIP,GA"
					( Origin gPackager )
				)
				( objectStatus "R9A9" )
			)
			( gate "@baseboard_fab2_lib.baseboard_fab2(sch_1):page175_i97"
				( attribute "CDS_LIB" "w_hdl"
					( Origin gPackager )
				)
				( attribute "CDS_LMAN_SYM_OUTLINE" "-200,150,200,-150"
					( Origin gPackager )
				)
				( attribute "LOCATION" "U9A4"
					( Origin gFrontEnd )
				)
				( attribute "PACK_TYPE" "DISCRET-GA1"
					( Origin gFrontEnd )
				)
				( attribute "PART_NUMBER" "073.7PZ14.0007"
					( Origin gFrontEnd )
				)
				( attribute "PHYS_PAGE" "175"
					( Origin gFrontEnd )
				)
				( attribute "ROT" "0"
					( Origin gFrontEnd )
				)
				( attribute "SEC" "1"
					( Origin gFrontEnd )
				)
				( attribute "SEC_TYPE" "DISCRET-GA1"
					( Origin gFrontEnd )
				)
				( attribute "VALUE" "TC7PZ14FU-GP"
					( Origin gFrontEnd )
				)
				( attribute "VER" "1"
					( Origin gFrontEnd )
				)
				( attribute "XY" "(-3675,4125)"
					( Origin gFrontEnd )
				)
				( attribute "CHIPS_PART_NAME" "TC7PZ14FU-GP"
					( Origin gPackager )
				)
				( attribute "CDS_PART_NAME" "TC7PZ14FU-GP_DISCRET-GA1-TC7PZA"
					( Origin gPackager )
				)
				( attribute "CDS_LOCATION" "U9A4"
					( Origin gPackager )
				)
				( attribute "CDS_SEC" "1"
					( Origin gPackager )
				)
				( objectStatus "U9A4" )
			)
			( gate "@baseboard_fab2_lib.baseboard_fab2(sch_1):page164_i40"
				( attribute "BOM_COST" "SM_CONTROLLER"
					( Origin gFrontEnd )
				)
				( attribute "CDS_LIB" "mstr_discrete"
					( Origin gPackager )
				)
				( attribute "CDS_LOCATION" "R1U18"
					( Origin gPackager )
				)
				( attribute "CDS_SEC" "1"
					( Origin gPackager )
				)
				( attribute "LOCATION" "R1U18"
					( Origin gFrontEnd )
				)
				( attribute "MATERIAL" "CHIP"
					( Origin gFrontEnd )
				)
				( attribute "PACK_TYPE" "0402"
					( Origin gFrontEnd )
				)
				( attribute "PART_NUMBER" "G21796-026"
					( Origin gFrontEnd )
				)
				( attribute "PHYS_PAGE" "164"
					( Origin gFrontEnd )
				)
				( attribute "ROOM" "BMC_MISC"
					( Origin gFrontEnd )
				)
				( attribute "ROT" "0"
					( Origin gFrontEnd )
				)
				( attribute "SEC" "1"
					( Origin gFrontEnd )
				)
				( attribute "SEC_TYPE" "0402"
					( Origin gFrontEnd )
				)
				( attribute "TOLERANCE" "1%"
					( Origin gFrontEnd )
				)
				( attribute "VALUE" "1.00K"
					( Origin gFrontEnd )
				)
				( attribute "VER" "2"
					( Origin gFrontEnd )
				)
				( attribute "WATTAGE" "1/16W"
					( Origin gFrontEnd )
				)
				( attribute "XY" "(-5425,3350)"
					( Origin gFrontEnd )
				)
				( attribute "CHIPS_PART_NAME" "RES"
					( Origin gPackager )
				)
				( attribute "CDS_PART_NAME" "RES_0402-1.00K,1%,1/16W,CHIP,GA"
					( Origin gPackager )
				)
				( attribute "GROUP" "PD_SKU_ID0"
					( Origin gFrontEnd )
				)
				( objectStatus "R1U18" )
			)
			( gate "@baseboard_fab2_lib.baseboard_fab2(sch_1):page156_i340"
				( attribute "CDS_LIB" "w_hdl"
					( Origin gPackager )
				)
				( attribute "CDS_LMAN_SYM_OUTLINE" "-175,150,175,-150"
					( Origin gPackager )
				)
				( attribute "LOCATION" "U8F3"
					( Origin gFrontEnd )
				)
				( attribute "PACK_TYPE" "DISCRET-G4"
					( Origin gFrontEnd )
				)
				( attribute "PART_NUMBER" "73.02G07.02J"
					( Origin gFrontEnd )
				)
				( attribute "PHYS_PAGE" "156"
					( Origin gFrontEnd )
				)
				( attribute "ROT" "0"
					( Origin gFrontEnd )
				)
				( attribute "SEC" "1"
					( Origin gFrontEnd )
				)
				( attribute "SEC_TYPE" "DISCRET-G4"
					( Origin gFrontEnd )
				)
				( attribute "VALUE" "SN74LVC2G07DCKR-GP"
					( Origin gFrontEnd )
				)
				( attribute "VER" "1"
					( Origin gFrontEnd )
				)
				( attribute "XY" "(-3225,4150)"
					( Origin gFrontEnd )
				)
				( attribute "CHIPS_PART_NAME" "SN74LVC2G07DCKR-GP"
					( Origin gPackager )
				)
				( attribute "CDS_PART_NAME" "SN74LVC2G07DCKR-GP_DISCRET-G4-A"
					( Origin gPackager )
				)
				( attribute "CDS_LOCATION" "U8F3"
					( Origin gPackager )
				)
				( attribute "CDS_SEC" "1"
					( Origin gPackager )
				)
				( objectStatus "U8F3" )
			)
			( gate "@baseboard_fab2_lib.baseboard_fab2(sch_1):page156_i342"
				( attribute "CDS_LIB" "w_hdl"
					( Origin gPackager )
				)
				( attribute "CDS_LMAN_SYM_OUTLINE" "-175,150,175,-150"
					( Origin gPackager )
				)
				( attribute "LOCATION" "U8G1"
					( Origin gFrontEnd )
				)
				( attribute "PACK_TYPE" "DISCRET-G4"
					( Origin gFrontEnd )
				)
				( attribute "PART_NUMBER" "73.02G07.02J"
					( Origin gFrontEnd )
				)
				( attribute "PHYS_PAGE" "156"
					( Origin gFrontEnd )
				)
				( attribute "ROT" "0"
					( Origin gFrontEnd )
				)
				( attribute "SEC" "1"
					( Origin gFrontEnd )
				)
				( attribute "SEC_TYPE" "DISCRET-G4"
					( Origin gFrontEnd )
				)
				( attribute "VALUE" "SN74LVC2G07DCKR-GP"
					( Origin gFrontEnd )
				)
				( attribute "VER" "1"
					( Origin gFrontEnd )
				)
				( attribute "XY" "(-3225,2950)"
					( Origin gFrontEnd )
				)
				( attribute "CHIPS_PART_NAME" "SN74LVC2G07DCKR-GP"
					( Origin gPackager )
				)
				( attribute "CDS_PART_NAME" "SN74LVC2G07DCKR-GP_DISCRET-G4-A"
					( Origin gPackager )
				)
				( attribute "CDS_LOCATION" "U8G1"
					( Origin gPackager )
				)
				( attribute "CDS_SEC" "1"
					( Origin gPackager )
				)
				( objectStatus "U8G1" )
			)
			( gate "@baseboard_fab2_lib.baseboard_fab2(sch_1):page149_i130"
				( attribute "BOM_COST" "SM_CONTROLLER"
					( Origin gFrontEnd )
				)
				( attribute "CDS_LIB" "mstr_discrete"
					( Origin gPackager )
				)
				( attribute "CDS_LOCATION" "C25W57"
					( Origin gPackager )
				)
				( attribute "LOCATION" "C25W57"
					( Origin gFrontEnd )
				)
				( attribute "MATERIAL" "COG"
					( Origin gFrontEnd )
				)
				( attribute "PACK_TYPE" "0402LF"
					( Origin gFrontEnd )
				)
				( attribute "PART_NUMBER" "A36095-026"
					( Origin gFrontEnd )
				)
				( attribute "PHYS_PAGE" "149"
					( Origin gFrontEnd )
				)
				( attribute "ROOM" "BMC"
					( Origin gFrontEnd )
				)
				( attribute "ROT" "0"
					( Origin gFrontEnd )
				)
				( attribute "SEC" "1"
					( Origin gFrontEnd )
				)
				( attribute "SEC_TYPE" "0402LF"
					( Origin gFrontEnd )
				)
				( attribute "TOLERANCE" "5%"
					( Origin gFrontEnd )
				)
				( attribute "VALUE" "100.0PF"
					( Origin gFrontEnd )
				)
				( attribute "VER" "1"
					( Origin gFrontEnd )
				)
				( attribute "VOLTAGE" "50V"
					( Units "uVoltage" "V" 1.000000)
					( Origin gFrontEnd )
				)
				( attribute "XY" "(-1450,1825)"
					( Origin gFrontEnd )
				)
				( attribute "CHIPS_PART_NAME" "CAP"
					( Origin gPackager )
				)
				( attribute "CDS_PART_NAME" "CAP_0402LF-100.0PF,50V,5%,COG,A"
					( Origin gPackager )
				)
				( attribute "CDS_SEC" "1"
					( Origin gPackager )
				)
				( objectStatus "C25W57" )
			)
			( gate "@baseboard_fab2_lib.baseboard_fab2(sch_1):page151_i209"
				( attribute "CDS_LIB" "mstr_discrete"
					( Origin gPackager )
				)
				( attribute "CDS_LOCATION" "R9F34"
					( Origin gPackager )
				)
				( attribute "CDS_SEC" "1"
					( Origin gPackager )
				)
				( attribute "LOCATION" "R9F34"
					( Origin gFrontEnd )
				)
				( attribute "MATERIAL" "EMPTY"
					( Origin gFrontEnd )
				)
				( attribute "PACK_TYPE" "0402"
					( Origin gFrontEnd )
				)
				( attribute "PART_NUMBER" "G21796-074"
					( Origin gFrontEnd )
				)
				( attribute "PHYS_PAGE" "151"
					( Origin gFrontEnd )
				)
				( attribute "ROOM" "DEBUG"
					( Origin gFrontEnd )
				)
				( attribute "ROT" "1"
					( Origin gFrontEnd )
				)
				( attribute "SEC" "1"
					( Origin gFrontEnd )
				)
				( attribute "SEC_TYPE" "0402"
					( Origin gFrontEnd )
				)
				( attribute "TOLERANCE" "1%"
					( Origin gFrontEnd )
				)
				( attribute "VALUE" "33.2"
					( Origin gFrontEnd )
				)
				( attribute "VER" "2"
					( Origin gFrontEnd )
				)
				( attribute "WATTAGE" "1/16W"
					( Origin gFrontEnd )
				)
				( attribute "XY" "(3125,1975)"
					( Origin gFrontEnd )
				)
				( attribute "CHIPS_PART_NAME" "RES"
					( Origin gPackager )
				)
				( attribute "CDS_PART_NAME" "RES_0402-33.2,1%,1/16W,EMPTY,GA"
					( Origin gPackager )
				)
				( objectStatus "R9F34" )
			)
			( gate "@baseboard_fab2_lib.baseboard_fab2(sch_1):page251_i21"
				( attribute "BOM_COST" "SM_THERM"
					( Origin gFrontEnd )
				)
				( attribute "CDS_LIB" "dev_discrete"
					( Origin gPackager )
				)
				( attribute "CDS_LOCATION" "C10W4"
					( Origin gPackager )
				)
				( attribute "CDS_SEC" "1"
					( Origin gPackager )
				)
				( attribute "LOCATION" "C10W4"
					( Origin gFrontEnd )
				)
				( attribute "MATERIAL" "X7R"
					( Origin gFrontEnd )
				)
				( attribute "PACK_TYPE" "0402V"
					( Origin gFrontEnd )
				)
				( attribute "PART_NUMBER" "A36096-030"
					( Origin gFrontEnd )
				)
				( attribute "PHYS_PAGE" "251"
					( Origin gFrontEnd )
				)
				( attribute "ROOM" "CPU_FANS"
					( Origin gFrontEnd )
				)
				( attribute "ROT" "0"
					( Origin gFrontEnd )
				)
				( attribute "SEC" "1"
					( Origin gFrontEnd )
				)
				( attribute "SEC_TYPE" "0402V"
					( Origin gFrontEnd )
				)
				( attribute "TOLERANCE" "10%"
					( Origin gFrontEnd )
				)
				( attribute "VALUE" "0.1UF"
					( Origin gFrontEnd )
				)
				( attribute "VER" "1"
					( Origin gFrontEnd )
				)
				( attribute "VOLTAGE" "16V"
					( Units "uVoltage" "V" 1.000000)
					( Origin gFrontEnd )
				)
				( attribute "XY" "(-6650,4900)"
					( Origin gFrontEnd )
				)
				( attribute "CHIPS_PART_NAME" "CAP_A"
					( Origin gPackager )
				)
				( attribute "CDS_PART_NAME" "CAP_A_0402V-0.1UF,16V,10%,X7R,A"
					( Origin gPackager )
				)
				( objectStatus "C10W4" )
			)
			( gate "@baseboard_fab2_lib.baseboard_fab2(sch_1):page115_i118"
				( attribute "BOM_COST" "SM_CONTROLLER"
					( Origin gFrontEnd )
				)
				( attribute "CDS_LIB" "mstr_discrete"
					( Origin gPackager )
				)
				( attribute "LOCATION" "R1W14"
					( Origin gFrontEnd )
				)
				( attribute "MATERIAL" "CHIP"
					( Origin gFrontEnd )
				)
				( attribute "PACK_TYPE" "0402"
					( Origin gFrontEnd )
				)
				( attribute "PART_NUMBER" "G21497-005"
					( Origin gFrontEnd )
				)
				( attribute "PHYS_PAGE" "115"
					( Origin gFrontEnd )
				)
				( attribute "ROOM" "BMC"
					( Origin gFrontEnd )
				)
				( attribute "ROT" "0"
					( Origin gFrontEnd )
				)
				( attribute "SEC" "1"
					( Origin gFrontEnd )
				)
				( attribute "SEC_TYPE" "0402"
					( Origin gFrontEnd )
				)
				( attribute "TOLERANCE" "5%"
					( Origin gFrontEnd )
				)
				( attribute "VALUE" "0.0"
					( Origin gFrontEnd )
				)
				( attribute "VER" "1"
					( Origin gFrontEnd )
				)
				( attribute "WATTAGE" "1/16W"
					( Origin gFrontEnd )
				)
				( attribute "XY" "(-2150,1950)"
					( Origin gFrontEnd )
				)
				( attribute "CHIPS_PART_NAME" "RES"
					( Origin gPackager )
				)
				( attribute "CDS_PART_NAME" "RES_0402-0.0,5%,1/16W,CHIP,G21A"
					( Origin gPackager )
				)
				( attribute "CDS_LOCATION" "R1W14"
					( Origin gPackager )
				)
				( attribute "CDS_SEC" "1"
					( Origin gPackager )
				)
				( objectStatus "R1W14" )
			)
			( gate "@baseboard_fab2_lib.baseboard_fab2(sch_1):page115_i119"
				( attribute "BOM_COST" "SM_CONTROLLER"
					( Origin gFrontEnd )
				)
				( attribute "CDS_LIB" "mstr_discrete"
					( Origin gPackager )
				)
				( attribute "LOCATION" "R1W15"
					( Origin gFrontEnd )
				)
				( attribute "MATERIAL" "CHIP"
					( Origin gFrontEnd )
				)
				( attribute "PACK_TYPE" "0402"
					( Origin gFrontEnd )
				)
				( attribute "PART_NUMBER" "G21497-005"
					( Origin gFrontEnd )
				)
				( attribute "PHYS_PAGE" "115"
					( Origin gFrontEnd )
				)
				( attribute "ROOM" "BMC"
					( Origin gFrontEnd )
				)
				( attribute "ROT" "0"
					( Origin gFrontEnd )
				)
				( attribute "SEC" "1"
					( Origin gFrontEnd )
				)
				( attribute "SEC_TYPE" "0402"
					( Origin gFrontEnd )
				)
				( attribute "TOLERANCE" "5%"
					( Origin gFrontEnd )
				)
				( attribute "VALUE" "0.0"
					( Origin gFrontEnd )
				)
				( attribute "VER" "1"
					( Origin gFrontEnd )
				)
				( attribute "WATTAGE" "1/16W"
					( Origin gFrontEnd )
				)
				( attribute "XY" "(-2150,1900)"
					( Origin gFrontEnd )
				)
				( attribute "CHIPS_PART_NAME" "RES"
					( Origin gPackager )
				)
				( attribute "CDS_PART_NAME" "RES_0402-0.0,5%,1/16W,CHIP,G21A"
					( Origin gPackager )
				)
				( attribute "CDS_LOCATION" "R1W15"
					( Origin gPackager )
				)
				( attribute "CDS_SEC" "1"
					( Origin gPackager )
				)
				( objectStatus "R1W15" )
			)
			( gate "@baseboard_fab2_lib.baseboard_fab2(sch_1):page115_i120"
				( attribute "BOM_COST" "SM_CONTROLLER"
					( Origin gFrontEnd )
				)
				( attribute "CDS_LIB" "mstr_discrete"
					( Origin gPackager )
				)
				( attribute "LOCATION" "R1W17"
					( Origin gFrontEnd )
				)
				( attribute "MATERIAL" "CHIP"
					( Origin gFrontEnd )
				)
				( attribute "PACK_TYPE" "0402"
					( Origin gFrontEnd )
				)
				( attribute "PART_NUMBER" "G21497-005"
					( Origin gFrontEnd )
				)
				( attribute "PHYS_PAGE" "115"
					( Origin gFrontEnd )
				)
				( attribute "ROOM" "BMC"
					( Origin gFrontEnd )
				)
				( attribute "ROT" "0"
					( Origin gFrontEnd )
				)
				( attribute "SEC" "1"
					( Origin gFrontEnd )
				)
				( attribute "SEC_TYPE" "0402"
					( Origin gFrontEnd )
				)
				( attribute "TOLERANCE" "5%"
					( Origin gFrontEnd )
				)
				( attribute "VALUE" "0.0"
					( Origin gFrontEnd )
				)
				( attribute "VER" "1"
					( Origin gFrontEnd )
				)
				( attribute "WATTAGE" "1/16W"
					( Origin gFrontEnd )
				)
				( attribute "XY" "(-2150,1800)"
					( Origin gFrontEnd )
				)
				( attribute "CHIPS_PART_NAME" "RES"
					( Origin gPackager )
				)
				( attribute "CDS_PART_NAME" "RES_0402-0.0,5%,1/16W,CHIP,G21A"
					( Origin gPackager )
				)
				( attribute "CDS_LOCATION" "R1W17"
					( Origin gPackager )
				)
				( attribute "CDS_SEC" "1"
					( Origin gPackager )
				)
				( objectStatus "R1W17" )
			)
			( gate "@baseboard_fab2_lib.baseboard_fab2(sch_1):page115_i121"
				( attribute "BOM_COST" "SM_CONTROLLER"
					( Origin gFrontEnd )
				)
				( attribute "CDS_LIB" "mstr_discrete"
					( Origin gPackager )
				)
				( attribute "LOCATION" "R1W16"
					( Origin gFrontEnd )
				)
				( attribute "MATERIAL" "CHIP"
					( Origin gFrontEnd )
				)
				( attribute "PACK_TYPE" "0402"
					( Origin gFrontEnd )
				)
				( attribute "PART_NUMBER" "G21497-005"
					( Origin gFrontEnd )
				)
				( attribute "PHYS_PAGE" "115"
					( Origin gFrontEnd )
				)
				( attribute "ROOM" "BMC"
					( Origin gFrontEnd )
				)
				( attribute "ROT" "0"
					( Origin gFrontEnd )
				)
				( attribute "SEC" "1"
					( Origin gFrontEnd )
				)
				( attribute "SEC_TYPE" "0402"
					( Origin gFrontEnd )
				)
				( attribute "TOLERANCE" "5%"
					( Origin gFrontEnd )
				)
				( attribute "VALUE" "0.0"
					( Origin gFrontEnd )
				)
				( attribute "VER" "1"
					( Origin gFrontEnd )
				)
				( attribute "WATTAGE" "1/16W"
					( Origin gFrontEnd )
				)
				( attribute "XY" "(-2150,1850)"
					( Origin gFrontEnd )
				)
				( attribute "CHIPS_PART_NAME" "RES"
					( Origin gPackager )
				)
				( attribute "CDS_PART_NAME" "RES_0402-0.0,5%,1/16W,CHIP,G21A"
					( Origin gPackager )
				)
				( attribute "CDS_LOCATION" "R1W16"
					( Origin gPackager )
				)
				( attribute "CDS_SEC" "1"
					( Origin gPackager )
				)
				( objectStatus "R1W16" )
			)
			( gate "@baseboard_fab2_lib.baseboard_fab2(sch_1):page115_i122"
				( attribute "BOM_COST" "SM_CONTROLLER"
					( Origin gFrontEnd )
				)
				( attribute "CDS_LIB" "mstr_discrete"
					( Origin gPackager )
				)
				( attribute "LOCATION" "R1W19"
					( Origin gFrontEnd )
				)
				( attribute "MATERIAL" "CHIP"
					( Origin gFrontEnd )
				)
				( attribute "PACK_TYPE" "0402"
					( Origin gFrontEnd )
				)
				( attribute "PART_NUMBER" "G21497-005"
					( Origin gFrontEnd )
				)
				( attribute "PHYS_PAGE" "115"
					( Origin gFrontEnd )
				)
				( attribute "ROOM" "BMC"
					( Origin gFrontEnd )
				)
				( attribute "ROT" "0"
					( Origin gFrontEnd )
				)
				( attribute "SEC" "1"
					( Origin gFrontEnd )
				)
				( attribute "SEC_TYPE" "0402"
					( Origin gFrontEnd )
				)
				( attribute "TOLERANCE" "5%"
					( Origin gFrontEnd )
				)
				( attribute "VALUE" "0.0"
					( Origin gFrontEnd )
				)
				( attribute "VER" "1"
					( Origin gFrontEnd )
				)
				( attribute "WATTAGE" "1/16W"
					( Origin gFrontEnd )
				)
				( attribute "XY" "(-2150,1600)"
					( Origin gFrontEnd )
				)
				( attribute "CHIPS_PART_NAME" "RES"
					( Origin gPackager )
				)
				( attribute "CDS_PART_NAME" "RES_0402-0.0,5%,1/16W,CHIP,G21A"
					( Origin gPackager )
				)
				( attribute "CDS_LOCATION" "R1W19"
					( Origin gPackager )
				)
				( attribute "CDS_SEC" "1"
					( Origin gPackager )
				)
				( objectStatus "R1W19" )
			)
			( gate "@baseboard_fab2_lib.baseboard_fab2(sch_1):page115_i123"
				( attribute "BOM_COST" "SM_CONTROLLER"
					( Origin gFrontEnd )
				)
				( attribute "CDS_LIB" "mstr_discrete"
					( Origin gPackager )
				)
				( attribute "LOCATION" "R1W18"
					( Origin gFrontEnd )
				)
				( attribute "MATERIAL" "CHIP"
					( Origin gFrontEnd )
				)
				( attribute "PACK_TYPE" "0402"
					( Origin gFrontEnd )
				)
				( attribute "PART_NUMBER" "G21497-005"
					( Origin gFrontEnd )
				)
				( attribute "PHYS_PAGE" "115"
					( Origin gFrontEnd )
				)
				( attribute "ROOM" "BMC"
					( Origin gFrontEnd )
				)
				( attribute "ROT" "0"
					( Origin gFrontEnd )
				)
				( attribute "SEC" "1"
					( Origin gFrontEnd )
				)
				( attribute "SEC_TYPE" "0402"
					( Origin gFrontEnd )
				)
				( attribute "TOLERANCE" "5%"
					( Origin gFrontEnd )
				)
				( attribute "VALUE" "0.0"
					( Origin gFrontEnd )
				)
				( attribute "VER" "1"
					( Origin gFrontEnd )
				)
				( attribute "WATTAGE" "1/16W"
					( Origin gFrontEnd )
				)
				( attribute "XY" "(-2150,1650)"
					( Origin gFrontEnd )
				)
				( attribute "CHIPS_PART_NAME" "RES"
					( Origin gPackager )
				)
				( attribute "CDS_PART_NAME" "RES_0402-0.0,5%,1/16W,CHIP,G21A"
					( Origin gPackager )
				)
				( attribute "CDS_LOCATION" "R1W18"
					( Origin gPackager )
				)
				( attribute "CDS_SEC" "1"
					( Origin gPackager )
				)
				( objectStatus "R1W18" )
			)
			( gate "@baseboard_fab2_lib.baseboard_fab2(sch_1):page144_i139"
				( attribute "BOM_COST" "PROC_SIDEBAND"
					( Origin gFrontEnd )
				)
				( attribute "CDS_LIB" "mstr_discrete"
					( Origin gPackager )
				)
				( attribute "CDS_LOCATION" "R25W123"
					( Origin gPackager )
				)
				( attribute "CDS_SEC" "1"
					( Origin gPackager )
				)
				( attribute "LOCATION" "R25W123"
					( Origin gFrontEnd )
				)
				( attribute "MATERIAL" "CHIP"
					( Origin gFrontEnd )
				)
				( attribute "PACK_TYPE" "0402"
					( Origin gFrontEnd )
				)
				( attribute "PART_NUMBER" "G21796-009"
					( Origin gFrontEnd )
				)
				( attribute "PHYS_PAGE" "144"
					( Origin gFrontEnd )
				)
				( attribute "ROOM" "PROC_SIDEBAND"
					( Origin gFrontEnd )
				)
				( attribute "ROT" "2"
					( Origin gFrontEnd )
				)
				( attribute "SEC" "1"
					( Origin gFrontEnd )
				)
				( attribute "SEC_TYPE" "0402"
					( Origin gFrontEnd )
				)
				( attribute "TOLERANCE" "1%"
					( Origin gFrontEnd )
				)
				( attribute "VALUE" "150.0"
					( Origin gFrontEnd )
				)
				( attribute "VER" "2"
					( Origin gFrontEnd )
				)
				( attribute "WATTAGE" "1/16W"
					( Origin gFrontEnd )
				)
				( attribute "XY" "(-2800,-4550)"
					( Origin gFrontEnd )
				)
				( attribute "CHIPS_PART_NAME" "RES"
					( Origin gPackager )
				)
				( attribute "CDS_PART_NAME" "RES_0402-150.0,1%,1/16W,CHIP,GA"
					( Origin gPackager )
				)
				( attribute "GROUP" "AST2500"
					( Origin gFrontEnd )
				)
				( objectStatus "R25W123" )
			)
			( gate "@baseboard_fab2_lib.baseboard_fab2(sch_1):page144_i140"
				( attribute "BOM_COST" "PROC_SIDEBAND"
					( Origin gFrontEnd )
				)
				( attribute "CDS_LIB" "mstr_discrete"
					( Origin gPackager )
				)
				( attribute "LOCATION" "R25W124"
					( Origin gFrontEnd )
				)
				( attribute "MATERIAL" "CHIP"
					( Origin gFrontEnd )
				)
				( attribute "PACK_TYPE" "0402"
					( Origin gFrontEnd )
				)
				( attribute "PART_NUMBER" "G21796-009"
					( Origin gFrontEnd )
				)
				( attribute "PHYS_PAGE" "144"
					( Origin gFrontEnd )
				)
				( attribute "ROOM" "PROC_SIDEBAND"
					( Origin gFrontEnd )
				)
				( attribute "ROT" "2"
					( Origin gFrontEnd )
				)
				( attribute "SEC" "1"
					( Origin gFrontEnd )
				)
				( attribute "SEC_TYPE" "0402"
					( Origin gFrontEnd )
				)
				( attribute "TOLERANCE" "1%"
					( Origin gFrontEnd )
				)
				( attribute "VALUE" "150.0"
					( Origin gFrontEnd )
				)
				( attribute "VER" "2"
					( Origin gFrontEnd )
				)
				( attribute "WATTAGE" "1/16W"
					( Origin gFrontEnd )
				)
				( attribute "XY" "(-2450,-4550)"
					( Origin gFrontEnd )
				)
				( attribute "CHIPS_PART_NAME" "RES"
					( Origin gPackager )
				)
				( attribute "CDS_PART_NAME" "RES_0402-150.0,1%,1/16W,CHIP,GA"
					( Origin gPackager )
				)
				( attribute "CDS_LOCATION" "R25W124"
					( Origin gPackager )
				)
				( attribute "CDS_SEC" "1"
					( Origin gPackager )
				)
				( attribute "GROUP" "AST2500"
					( Origin gFrontEnd )
				)
				( objectStatus "R25W124" )
			)
			( gate "@baseboard_fab2_lib.baseboard_fab2(sch_1):page144_i141"
				( attribute "BOM_COST" "PROC_SIDEBAND"
					( Origin gFrontEnd )
				)
				( attribute "CDS_LIB" "mstr_discrete"
					( Origin gPackager )
				)
				( attribute "LOCATION" "R25W125"
					( Origin gFrontEnd )
				)
				( attribute "MATERIAL" "CHIP"
					( Origin gFrontEnd )
				)
				( attribute "PACK_TYPE" "0402"
					( Origin gFrontEnd )
				)
				( attribute "PART_NUMBER" "G21796-009"
					( Origin gFrontEnd )
				)
				( attribute "PHYS_PAGE" "144"
					( Origin gFrontEnd )
				)
				( attribute "ROOM" "PROC_SIDEBAND"
					( Origin gFrontEnd )
				)
				( attribute "ROT" "2"
					( Origin gFrontEnd )
				)
				( attribute "SEC" "1"
					( Origin gFrontEnd )
				)
				( attribute "SEC_TYPE" "0402"
					( Origin gFrontEnd )
				)
				( attribute "TOLERANCE" "1%"
					( Origin gFrontEnd )
				)
				( attribute "VALUE" "150.0"
					( Origin gFrontEnd )
				)
				( attribute "VER" "2"
					( Origin gFrontEnd )
				)
				( attribute "WATTAGE" "1/16W"
					( Origin gFrontEnd )
				)
				( attribute "XY" "(-2100,-4550)"
					( Origin gFrontEnd )
				)
				( attribute "CHIPS_PART_NAME" "RES"
					( Origin gPackager )
				)
				( attribute "CDS_PART_NAME" "RES_0402-150.0,1%,1/16W,CHIP,GA"
					( Origin gPackager )
				)
				( attribute "CDS_LOCATION" "R25W125"
					( Origin gPackager )
				)
				( attribute "CDS_SEC" "1"
					( Origin gPackager )
				)
				( attribute "GROUP" "AST2500"
					( Origin gFrontEnd )
				)
				( objectStatus "R25W125" )
			)
			( gate "@baseboard_fab2_lib.baseboard_fab2(sch_1):page255_i7"
				( attribute "BOM_COST" "LBG_UART"
					( Origin gFrontEnd )
				)
				( attribute "CDS_LIB" "mstr_discrete"
					( Origin gPackager )
				)
				( attribute "CDS_LOCATION" "C25W72"
					( Origin gPackager )
				)
				( attribute "LOCATION" "C25W72"
					( Origin gFrontEnd )
				)
				( attribute "MATERIAL" "COG"
					( Origin gFrontEnd )
				)
				( attribute "PACK_TYPE" "0402LF"
					( Origin gFrontEnd )
				)
				( attribute "PART_NUMBER" "A36095-043"
					( Origin gFrontEnd )
				)
				( attribute "PHYS_PAGE" "252"
					( Origin gFrontEnd )
				)
				( attribute "ROOM" "LBG"
					( Origin gFrontEnd )
				)
				( attribute "ROT" "0"
					( Origin gFrontEnd )
				)
				( attribute "SEC" "1"
					( Origin gFrontEnd )
				)
				( attribute "SEC_TYPE" "0402LF"
					( Origin gFrontEnd )
				)
				( attribute "TOLERANCE" "5%"
					( Origin gFrontEnd )
				)
				( attribute "VALUE" "12.0PF"
					( Origin gFrontEnd )
				)
				( attribute "VER" "1"
					( Origin gFrontEnd )
				)
				( attribute "VOLTAGE" "50V"
					( Units "uVoltage" "V" 1.000000)
					( Origin gFrontEnd )
				)
				( attribute "XY" "(-4900,3450)"
					( Origin gFrontEnd )
				)
				( attribute "CHIPS_PART_NAME" "CAP"
					( Origin gPackager )
				)
				( attribute "CDS_PART_NAME" "CAP_0402LF-12.0PF,50V,5%,COG,AA"
					( Origin gPackager )
				)
				( attribute "CDS_SEC" "1"
					( Origin gPackager )
				)
				( attribute "GROUP" "AST2500"
					( Origin gFrontEnd )
				)
				( objectStatus "C25W72" )
			)
			( gate "@baseboard_fab2_lib.baseboard_fab2(sch_1):page255_i11"
				( attribute "BOM_COST" "LBG_UART"
					( Origin gFrontEnd )
				)
				( attribute "CDS_LIB" "mstr_discrete"
					( Origin gPackager )
				)
				( attribute "CDS_LOCATION" "C25W73"
					( Origin gPackager )
				)
				( attribute "LOCATION" "C25W73"
					( Origin gFrontEnd )
				)
				( attribute "MATERIAL" "COG"
					( Origin gFrontEnd )
				)
				( attribute "PACK_TYPE" "0402LF"
					( Origin gFrontEnd )
				)
				( attribute "PART_NUMBER" "A36095-043"
					( Origin gFrontEnd )
				)
				( attribute "PHYS_PAGE" "252"
					( Origin gFrontEnd )
				)
				( attribute "ROOM" "LBG"
					( Origin gFrontEnd )
				)
				( attribute "ROT" "0"
					( Origin gFrontEnd )
				)
				( attribute "SEC" "1"
					( Origin gFrontEnd )
				)
				( attribute "SEC_TYPE" "0402LF"
					( Origin gFrontEnd )
				)
				( attribute "TOLERANCE" "5%"
					( Origin gFrontEnd )
				)
				( attribute "VALUE" "12.0PF"
					( Origin gFrontEnd )
				)
				( attribute "VER" "1"
					( Origin gFrontEnd )
				)
				( attribute "VOLTAGE" "50V"
					( Units "uVoltage" "V" 1.000000)
					( Origin gFrontEnd )
				)
				( attribute "XY" "(-4500,3450)"
					( Origin gFrontEnd )
				)
				( attribute "CHIPS_PART_NAME" "CAP"
					( Origin gPackager )
				)
				( attribute "CDS_PART_NAME" "CAP_0402LF-12.0PF,50V,5%,COG,AA"
					( Origin gPackager )
				)
				( attribute "CDS_SEC" "1"
					( Origin gPackager )
				)
				( attribute "GROUP" "AST2500"
					( Origin gFrontEnd )
				)
				( objectStatus "C25W73" )
			)
			( gate "@baseboard_fab2_lib.baseboard_fab2(sch_1):page255_i12"
				( attribute "BOM_COST" "LBG_UART"
					( Origin gFrontEnd )
				)
				( attribute "CDS_LIB" "mstr_discrete"
					( Origin gPackager )
				)
				( attribute "CDS_LOCATION" "C25W74"
					( Origin gPackager )
				)
				( attribute "LOCATION" "C25W74"
					( Origin gFrontEnd )
				)
				( attribute "MATERIAL" "COG"
					( Origin gFrontEnd )
				)
				( attribute "PACK_TYPE" "0402LF"
					( Origin gFrontEnd )
				)
				( attribute "PART_NUMBER" "A36095-043"
					( Origin gFrontEnd )
				)
				( attribute "PHYS_PAGE" "252"
					( Origin gFrontEnd )
				)
				( attribute "ROOM" "LBG"
					( Origin gFrontEnd )
				)
				( attribute "ROT" "0"
					( Origin gFrontEnd )
				)
				( attribute "SEC" "1"
					( Origin gFrontEnd )
				)
				( attribute "SEC_TYPE" "0402LF"
					( Origin gFrontEnd )
				)
				( attribute "TOLERANCE" "5%"
					( Origin gFrontEnd )
				)
				( attribute "VALUE" "12.0PF"
					( Origin gFrontEnd )
				)
				( attribute "VER" "1"
					( Origin gFrontEnd )
				)
				( attribute "VOLTAGE" "50V"
					( Units "uVoltage" "V" 1.000000)
					( Origin gFrontEnd )
				)
				( attribute "XY" "(-4100,3450)"
					( Origin gFrontEnd )
				)
				( attribute "CHIPS_PART_NAME" "CAP"
					( Origin gPackager )
				)
				( attribute "CDS_PART_NAME" "CAP_0402LF-12.0PF,50V,5%,COG,AA"
					( Origin gPackager )
				)
				( attribute "CDS_SEC" "1"
					( Origin gPackager )
				)
				( attribute "GROUP" "AST2500"
					( Origin gFrontEnd )
				)
				( objectStatus "C25W74" )
			)
			( gate "@baseboard_fab2_lib.baseboard_fab2(sch_1):page255_i16"
				( attribute "BOM_COST" "LBG_UART"
					( Origin gFrontEnd )
				)
				( attribute "CDS_LIB" "mstr_discrete"
					( Origin gPackager )
				)
				( attribute "LOCATION" "C25W77"
					( Origin gFrontEnd )
				)
				( attribute "MATERIAL" "COG"
					( Origin gFrontEnd )
				)
				( attribute "PACK_TYPE" "0402LF"
					( Origin gFrontEnd )
				)
				( attribute "PART_NUMBER" "A36095-043"
					( Origin gFrontEnd )
				)
				( attribute "PHYS_PAGE" "252"
					( Origin gFrontEnd )
				)
				( attribute "ROOM" "LBG"
					( Origin gFrontEnd )
				)
				( attribute "ROT" "0"
					( Origin gFrontEnd )
				)
				( attribute "SEC" "1"
					( Origin gFrontEnd )
				)
				( attribute "SEC_TYPE" "0402LF"
					( Origin gFrontEnd )
				)
				( attribute "TOLERANCE" "5%"
					( Origin gFrontEnd )
				)
				( attribute "VALUE" "12.0PF"
					( Origin gFrontEnd )
				)
				( attribute "VER" "1"
					( Origin gFrontEnd )
				)
				( attribute "VOLTAGE" "50V"
					( Units "uVoltage" "V" 1.000000)
					( Origin gFrontEnd )
				)
				( attribute "XY" "(-2350,3450)"
					( Origin gFrontEnd )
				)
				( attribute "CHIPS_PART_NAME" "CAP"
					( Origin gPackager )
				)
				( attribute "CDS_PART_NAME" "CAP_0402LF-12.0PF,50V,5%,COG,AA"
					( Origin gPackager )
				)
				( attribute "CDS_LOCATION" "C25W77"
					( Origin gPackager )
				)
				( attribute "CDS_SEC" "1"
					( Origin gPackager )
				)
				( attribute "GROUP" "AST2500"
					( Origin gFrontEnd )
				)
				( objectStatus "C25W77" )
			)
			( gate "@baseboard_fab2_lib.baseboard_fab2(sch_1):page255_i18"
				( attribute "BOM_COST" "LBG_UART"
					( Origin gFrontEnd )
				)
				( attribute "CDS_LIB" "mstr_discrete"
					( Origin gPackager )
				)
				( attribute "LOCATION" "C25W76"
					( Origin gFrontEnd )
				)
				( attribute "MATERIAL" "COG"
					( Origin gFrontEnd )
				)
				( attribute "PACK_TYPE" "0402LF"
					( Origin gFrontEnd )
				)
				( attribute "PART_NUMBER" "A36095-043"
					( Origin gFrontEnd )
				)
				( attribute "PHYS_PAGE" "252"
					( Origin gFrontEnd )
				)
				( attribute "ROOM" "LBG"
					( Origin gFrontEnd )
				)
				( attribute "ROT" "0"
					( Origin gFrontEnd )
				)
				( attribute "SEC" "1"
					( Origin gFrontEnd )
				)
				( attribute "SEC_TYPE" "0402LF"
					( Origin gFrontEnd )
				)
				( attribute "TOLERANCE" "5%"
					( Origin gFrontEnd )
				)
				( attribute "VALUE" "12.0PF"
					( Origin gFrontEnd )
				)
				( attribute "VER" "1"
					( Origin gFrontEnd )
				)
				( attribute "VOLTAGE" "50V"
					( Units "uVoltage" "V" 1.000000)
					( Origin gFrontEnd )
				)
				( attribute "XY" "(-2700,3450)"
					( Origin gFrontEnd )
				)
				( attribute "CHIPS_PART_NAME" "CAP"
					( Origin gPackager )
				)
				( attribute "CDS_PART_NAME" "CAP_0402LF-12.0PF,50V,5%,COG,AA"
					( Origin gPackager )
				)
				( attribute "CDS_LOCATION" "C25W76"
					( Origin gPackager )
				)
				( attribute "CDS_SEC" "1"
					( Origin gPackager )
				)
				( attribute "GROUP" "AST2500"
					( Origin gFrontEnd )
				)
				( objectStatus "C25W76" )
			)
			( gate "@baseboard_fab2_lib.baseboard_fab2(sch_1):page255_i21"
				( attribute "BOM_COST" "LBG_UART"
					( Origin gFrontEnd )
				)
				( attribute "CDS_LIB" "mstr_discrete"
					( Origin gPackager )
				)
				( attribute "LOCATION" "C25W75"
					( Origin gFrontEnd )
				)
				( attribute "MATERIAL" "COG"
					( Origin gFrontEnd )
				)
				( attribute "PACK_TYPE" "0402LF"
					( Origin gFrontEnd )
				)
				( attribute "PART_NUMBER" "A36095-043"
					( Origin gFrontEnd )
				)
				( attribute "PHYS_PAGE" "252"
					( Origin gFrontEnd )
				)
				( attribute "ROOM" "LBG"
					( Origin gFrontEnd )
				)
				( attribute "ROT" "0"
					( Origin gFrontEnd )
				)
				( attribute "SEC" "1"
					( Origin gFrontEnd )
				)
				( attribute "SEC_TYPE" "0402LF"
					( Origin gFrontEnd )
				)
				( attribute "TOLERANCE" "5%"
					( Origin gFrontEnd )
				)
				( attribute "VALUE" "12.0PF"
					( Origin gFrontEnd )
				)
				( attribute "VER" "1"
					( Origin gFrontEnd )
				)
				( attribute "VOLTAGE" "50V"
					( Units "uVoltage" "V" 1.000000)
					( Origin gFrontEnd )
				)
				( attribute "XY" "(-3050,3450)"
					( Origin gFrontEnd )
				)
				( attribute "CHIPS_PART_NAME" "CAP"
					( Origin gPackager )
				)
				( attribute "CDS_PART_NAME" "CAP_0402LF-12.0PF,50V,5%,COG,AA"
					( Origin gPackager )
				)
				( attribute "CDS_LOCATION" "C25W75"
					( Origin gPackager )
				)
				( attribute "CDS_SEC" "1"
					( Origin gPackager )
				)
				( attribute "GROUP" "AST2500"
					( Origin gFrontEnd )
				)
				( objectStatus "C25W75" )
			)
			( gate "@baseboard_fab2_lib.baseboard_fab2(sch_1):page255_i22"
				( attribute "BOM_COST" "PROC_SIDEBAND"
					( Origin gFrontEnd )
				)
				( attribute "CDS_LIB" "mstr_discrete"
					( Origin gPackager )
				)
				( attribute "LOCATION" "R25W128"
					( Origin gFrontEnd )
				)
				( attribute "MATERIAL" "CHIP"
					( Origin gFrontEnd )
				)
				( attribute "PACK_TYPE" "0402"
					( Origin gFrontEnd )
				)
				( attribute "PART_NUMBER" "G21796-009"
					( Origin gFrontEnd )
				)
				( attribute "PHYS_PAGE" "252"
					( Origin gFrontEnd )
				)
				( attribute "ROOM" "PROC_SIDEBAND"
					( Origin gFrontEnd )
				)
				( attribute "ROT" "2"
					( Origin gFrontEnd )
				)
				( attribute "TOLERANCE" "1%"
					( Origin gFrontEnd )
				)
				( attribute "VALUE" "150.0"
					( Origin gFrontEnd )
				)
				( attribute "VER" "2"
					( Origin gFrontEnd )
				)
				( attribute "WATTAGE" "1/16W"
					( Origin gFrontEnd )
				)
				( attribute "XY" "(-6350,2550)"
					( Origin gFrontEnd )
				)
				( attribute "CHIPS_PART_NAME" "RES"
					( Origin gPackager )
				)
				( attribute "CDS_PART_NAME" "RES_0402-150.0,1%,1/16W,CHIP,GA"
					( Origin gPackager )
				)
				( attribute "CDS_LOCATION" "R25W128"
					( Origin gPackager )
				)
				( attribute "CDS_SEC" "1"
					( Origin gPackager )
				)
				( attribute "SEC" "1"
					( Origin gPackager )
				)
				( attribute "GROUP" "AST2500"
					( Origin gFrontEnd )
				)
				( objectStatus "R25W128" )
			)
			( gate "@baseboard_fab2_lib.baseboard_fab2(sch_1):page255_i24"
				( attribute "BOM_COST" "PROC_SIDEBAND"
					( Origin gFrontEnd )
				)
				( attribute "CDS_LIB" "mstr_discrete"
					( Origin gPackager )
				)
				( attribute "LOCATION" "R25W127"
					( Origin gFrontEnd )
				)
				( attribute "MATERIAL" "CHIP"
					( Origin gFrontEnd )
				)
				( attribute "PACK_TYPE" "0402"
					( Origin gFrontEnd )
				)
				( attribute "PART_NUMBER" "G21796-009"
					( Origin gFrontEnd )
				)
				( attribute "PHYS_PAGE" "252"
					( Origin gFrontEnd )
				)
				( attribute "ROOM" "PROC_SIDEBAND"
					( Origin gFrontEnd )
				)
				( attribute "ROT" "2"
					( Origin gFrontEnd )
				)
				( attribute "TOLERANCE" "1%"
					( Origin gFrontEnd )
				)
				( attribute "VALUE" "150.0"
					( Origin gFrontEnd )
				)
				( attribute "VER" "2"
					( Origin gFrontEnd )
				)
				( attribute "WATTAGE" "1/16W"
					( Origin gFrontEnd )
				)
				( attribute "XY" "(-6700,2550)"
					( Origin gFrontEnd )
				)
				( attribute "CHIPS_PART_NAME" "RES"
					( Origin gPackager )
				)
				( attribute "CDS_PART_NAME" "RES_0402-150.0,1%,1/16W,CHIP,GA"
					( Origin gPackager )
				)
				( attribute "CDS_LOCATION" "R25W127"
					( Origin gPackager )
				)
				( attribute "CDS_SEC" "1"
					( Origin gPackager )
				)
				( attribute "SEC" "1"
					( Origin gPackager )
				)
				( attribute "GROUP" "AST2500"
					( Origin gFrontEnd )
				)
				( objectStatus "R25W127" )
			)
			( gate "@baseboard_fab2_lib.baseboard_fab2(sch_1):page255_i26"
				( attribute "BOM_COST" "PROC_SIDEBAND"
					( Origin gFrontEnd )
				)
				( attribute "CDS_LIB" "mstr_discrete"
					( Origin gPackager )
				)
				( attribute "LOCATION" "R25W126"
					( Origin gFrontEnd )
				)
				( attribute "MATERIAL" "CHIP"
					( Origin gFrontEnd )
				)
				( attribute "PACK_TYPE" "0402"
					( Origin gFrontEnd )
				)
				( attribute "PART_NUMBER" "G21796-009"
					( Origin gFrontEnd )
				)
				( attribute "PHYS_PAGE" "252"
					( Origin gFrontEnd )
				)
				( attribute "ROOM" "PROC_SIDEBAND"
					( Origin gFrontEnd )
				)
				( attribute "ROT" "2"
					( Origin gFrontEnd )
				)
				( attribute "TOLERANCE" "1%"
					( Origin gFrontEnd )
				)
				( attribute "VALUE" "150.0"
					( Origin gFrontEnd )
				)
				( attribute "VER" "2"
					( Origin gFrontEnd )
				)
				( attribute "WATTAGE" "1/16W"
					( Origin gFrontEnd )
				)
				( attribute "XY" "(-7050,2550)"
					( Origin gFrontEnd )
				)
				( attribute "CHIPS_PART_NAME" "RES"
					( Origin gPackager )
				)
				( attribute "CDS_PART_NAME" "RES_0402-150.0,1%,1/16W,CHIP,GA"
					( Origin gPackager )
				)
				( attribute "CDS_LOCATION" "R25W126"
					( Origin gPackager )
				)
				( attribute "CDS_SEC" "1"
					( Origin gPackager )
				)
				( attribute "SEC" "1"
					( Origin gPackager )
				)
				( attribute "GROUP" "AST2500"
					( Origin gFrontEnd )
				)
				( objectStatus "R25W126" )
			)
			( gate "@baseboard_fab2_lib.baseboard_fab2(sch_1):page146_i152"
				( attribute "BOM_COST" "SM_THERM"
					( Origin gFrontEnd )
				)
				( attribute "CDS_LIB" "mstr_discrete"
					( Origin gPackager )
				)
				( attribute "CDS_LOCATION" "R25W129"
					( Origin gPackager )
				)
				( attribute "CDS_SEC" "1"
					( Origin gPackager )
				)
				( attribute "LOCATION" "R25W129"
					( Origin gFrontEnd )
				)
				( attribute "MATERIAL" "CHIP"
					( Origin gFrontEnd )
				)
				( attribute "PACK_TYPE" "0402"
					( Origin gFrontEnd )
				)
				( attribute "PART_NUMBER" "G21796-072"
					( Origin gFrontEnd )
				)
				( attribute "PHYS_PAGE" "146"
					( Origin gFrontEnd )
				)
				( attribute "ROOM" "CPU_FANS"
					( Origin gFrontEnd )
				)
				( attribute "ROT" "1"
					( Origin gFrontEnd )
				)
				( attribute "SEC" "1"
					( Origin gFrontEnd )
				)
				( attribute "SEC_TYPE" "0402"
					( Origin gFrontEnd )
				)
				( attribute "TOLERANCE" "1%"
					( Origin gFrontEnd )
				)
				( attribute "VALUE" "4.75K"
					( Origin gFrontEnd )
				)
				( attribute "VER" "2"
					( Origin gFrontEnd )
				)
				( attribute "WATTAGE" "1/16W"
					( Origin gFrontEnd )
				)
				( attribute "XY" "(-7300,400)"
					( Origin gFrontEnd )
				)
				( attribute "CHIPS_PART_NAME" "RES"
					( Origin gPackager )
				)
				( attribute "CDS_PART_NAME" "RES_0402-4.75K,1%,1/16W,CHIP,GA"
					( Origin gPackager )
				)
				( objectStatus "R25W129" )
			)
			( gate "@baseboard_fab2_lib.baseboard_fab2(sch_1):page146_i153"
				( attribute "BOM_COST" "SM_THERM"
					( Origin gFrontEnd )
				)
				( attribute "CDS_LIB" "mstr_discrete"
					( Origin gPackager )
				)
				( attribute "CDS_LOCATION" "R25W130"
					( Origin gPackager )
				)
				( attribute "CDS_SEC" "1"
					( Origin gPackager )
				)
				( attribute "LOCATION" "R25W130"
					( Origin gFrontEnd )
				)
				( attribute "MATERIAL" "CHIP"
					( Origin gFrontEnd )
				)
				( attribute "PACK_TYPE" "0402"
					( Origin gFrontEnd )
				)
				( attribute "PART_NUMBER" "G21796-072"
					( Origin gFrontEnd )
				)
				( attribute "PHYS_PAGE" "146"
					( Origin gFrontEnd )
				)
				( attribute "ROOM" "CPU_FANS"
					( Origin gFrontEnd )
				)
				( attribute "ROT" "1"
					( Origin gFrontEnd )
				)
				( attribute "SEC" "1"
					( Origin gFrontEnd )
				)
				( attribute "SEC_TYPE" "0402"
					( Origin gFrontEnd )
				)
				( attribute "TOLERANCE" "1%"
					( Origin gFrontEnd )
				)
				( attribute "VALUE" "4.75K"
					( Origin gFrontEnd )
				)
				( attribute "VER" "2"
					( Origin gFrontEnd )
				)
				( attribute "WATTAGE" "1/16W"
					( Origin gFrontEnd )
				)
				( attribute "XY" "(-7300,250)"
					( Origin gFrontEnd )
				)
				( attribute "CHIPS_PART_NAME" "RES"
					( Origin gPackager )
				)
				( attribute "CDS_PART_NAME" "RES_0402-4.75K,1%,1/16W,CHIP,GA"
					( Origin gPackager )
				)
				( objectStatus "R25W130" )
			)
			( gate "@baseboard_fab2_lib.baseboard_fab2(sch_1):page255_i30"
				( attribute "BOM_COST" "SM_THERM"
					( Origin gFrontEnd )
				)
				( attribute "CDS_LIB" "mstr_discrete"
					( Origin gPackager )
				)
				( attribute "CDS_LOCATION" "R25W131"
					( Origin gPackager )
				)
				( attribute "CDS_SEC" "1"
					( Origin gPackager )
				)
				( attribute "LOCATION" "R25W131"
					( Origin gFrontEnd )
				)
				( attribute "MATERIAL" "CHIP"
					( Origin gFrontEnd )
				)
				( attribute "PACK_TYPE" "0402"
					( Origin gFrontEnd )
				)
				( attribute "PART_NUMBER" "G21796-072"
					( Origin gFrontEnd )
				)
				( attribute "PHYS_PAGE" "252"
					( Origin gFrontEnd )
				)
				( attribute "ROOM" "CPU_FANS"
					( Origin gFrontEnd )
				)
				( attribute "ROT" "0"
					( Origin gFrontEnd )
				)
				( attribute "SEC" "1"
					( Origin gFrontEnd )
				)
				( attribute "SEC_TYPE" "0402"
					( Origin gFrontEnd )
				)
				( attribute "TOLERANCE" "1%"
					( Origin gFrontEnd )
				)
				( attribute "VALUE" "4.75K"
					( Origin gFrontEnd )
				)
				( attribute "VER" "2"
					( Origin gFrontEnd )
				)
				( attribute "WATTAGE" "1/16W"
					( Origin gFrontEnd )
				)
				( attribute "XY" "(-8200,5300)"
					( Origin gFrontEnd )
				)
				( attribute "CHIPS_PART_NAME" "RES"
					( Origin gPackager )
				)
				( attribute "CDS_PART_NAME" "RES_0402-4.75K,1%,1/16W,CHIP,GA"
					( Origin gPackager )
				)
				( attribute "GROUP" "AST2500"
					( Origin gFrontEnd )
				)
				( objectStatus "R25W131" )
			)
			( gate "@baseboard_fab2_lib.baseboard_fab2(sch_1):page255_i31"
				( attribute "BOM_COST" "SM_THERM"
					( Origin gFrontEnd )
				)
				( attribute "CDS_LIB" "mstr_discrete"
					( Origin gPackager )
				)
				( attribute "LOCATION" "R25W132"
					( Origin gFrontEnd )
				)
				( attribute "MATERIAL" "CHIP"
					( Origin gFrontEnd )
				)
				( attribute "PACK_TYPE" "0402"
					( Origin gFrontEnd )
				)
				( attribute "PART_NUMBER" "G21796-072"
					( Origin gFrontEnd )
				)
				( attribute "PHYS_PAGE" "252"
					( Origin gFrontEnd )
				)
				( attribute "ROOM" "CPU_FANS"
					( Origin gFrontEnd )
				)
				( attribute "ROT" "0"
					( Origin gFrontEnd )
				)
				( attribute "SEC" "1"
					( Origin gFrontEnd )
				)
				( attribute "SEC_TYPE" "0402"
					( Origin gFrontEnd )
				)
				( attribute "TOLERANCE" "1%"
					( Origin gFrontEnd )
				)
				( attribute "VALUE" "4.75K"
					( Origin gFrontEnd )
				)
				( attribute "VER" "2"
					( Origin gFrontEnd )
				)
				( attribute "WATTAGE" "1/16W"
					( Origin gFrontEnd )
				)
				( attribute "XY" "(-7750,4950)"
					( Origin gFrontEnd )
				)
				( attribute "CHIPS_PART_NAME" "RES"
					( Origin gPackager )
				)
				( attribute "CDS_PART_NAME" "RES_0402-4.75K,1%,1/16W,CHIP,GA"
					( Origin gPackager )
				)
				( attribute "CDS_LOCATION" "R25W132"
					( Origin gPackager )
				)
				( attribute "CDS_SEC" "1"
					( Origin gPackager )
				)
				( attribute "GROUP" "AST2500"
					( Origin gFrontEnd )
				)
				( objectStatus "R25W132" )
			)
			( gate "@baseboard_fab2_lib.baseboard_fab2(sch_1):page255_i34"
				( attribute "CDS_LIB" "mstr_discrete"
					( Origin gPackager )
				)
				( attribute "CDS_LOCATION" "R25W133"
					( Origin gPackager )
				)
				( attribute "CDS_SEC" "1"
					( Origin gPackager )
				)
				( attribute "LOCATION" "R25W133"
					( Origin gFrontEnd )
				)
				( attribute "MATERIAL" "CHIP"
					( Origin gFrontEnd )
				)
				( attribute "PACK_TYPE" "0402"
					( Origin gFrontEnd )
				)
				( attribute "PART_NUMBER" "G21796-074"
					( Origin gFrontEnd )
				)
				( attribute "PHYS_PAGE" "252"
					( Origin gFrontEnd )
				)
				( attribute "ROT" "0"
					( Origin gFrontEnd )
				)
				( attribute "SEC" "1"
					( Origin gFrontEnd )
				)
				( attribute "SEC_TYPE" "0402"
					( Origin gFrontEnd )
				)
				( attribute "TOLERANCE" "1%"
					( Origin gFrontEnd )
				)
				( attribute "VALUE" "33.2"
					( Origin gFrontEnd )
				)
				( attribute "VER" "1"
					( Origin gFrontEnd )
				)
				( attribute "WATTAGE" "1/16W"
					( Origin gFrontEnd )
				)
				( attribute "XY" "(-6800,4750)"
					( Origin gFrontEnd )
				)
				( attribute "CHIPS_PART_NAME" "RES"
					( Origin gPackager )
				)
				( attribute "CDS_PART_NAME" "RES_0402-33.2,1%,1/16W,CHIP,G2A"
					( Origin gPackager )
				)
				( attribute "GROUP" "AST2500"
					( Origin gFrontEnd )
				)
				( objectStatus "R25W133" )
			)
			( gate "@baseboard_fab2_lib.baseboard_fab2(sch_1):page255_i35"
				( attribute "BOM_COST" "PVPP_KLM_VR"
					( Origin gFrontEnd )
				)
				( attribute "CDS_LIB" "mstr_discrete"
					( Origin gPackager )
				)
				( attribute "LOCATION" "C25W78"
					( Origin gFrontEnd )
				)
				( attribute "MATERIAL" "COG"
					( Origin gFrontEnd )
				)
				( attribute "PACK_TYPE" "0402LF"
					( Origin gFrontEnd )
				)
				( attribute "PART_NUMBER" "A36095-026"
					( Origin gFrontEnd )
				)
				( attribute "PHYS_PAGE" "252"
					( Origin gFrontEnd )
				)
				( attribute "REUSE_ID" "27"
					( Origin gFrontEnd )
				)
				( attribute "ROOM" "PVPP_KLM_VR"
					( Origin gFrontEnd )
				)
				( attribute "ROT" "3"
					( Origin gFrontEnd )
				)
				( attribute "SEC" "1"
					( Origin gFrontEnd )
				)
				( attribute "SEC_TYPE" "0402LF"
					( Origin gFrontEnd )
				)
				( attribute "TOLERANCE" "5%"
					( Origin gFrontEnd )
				)
				( attribute "VALUE" "100.0PF"
					( Origin gFrontEnd )
				)
				( attribute "VER" "2"
					( Origin gFrontEnd )
				)
				( attribute "VOLTAGE" "50V"
					( Units "uVoltage" "V" 1.000000)
					( Origin gFrontEnd )
				)
				( attribute "XY" "(-6550,4550)"
					( Origin gFrontEnd )
				)
				( attribute "CHIPS_PART_NAME" "CAP"
					( Origin gPackager )
				)
				( attribute "CDS_PART_NAME" "CAP_0402LF-100.0PF,50V,5%,COG,A"
					( Origin gPackager )
				)
				( attribute "CDS_LOCATION" "C25W78"
					( Origin gPackager )
				)
				( attribute "CDS_SEC" "1"
					( Origin gPackager )
				)
				( attribute "GROUP" "AST2500"
					( Origin gFrontEnd )
				)
				( objectStatus "C25W78" )
			)
			( gate "@baseboard_fab2_lib.baseboard_fab2(sch_1):page255_i38"
				( attribute "CDS_LIB" "mstr_discrete"
					( Origin gPackager )
				)
				( attribute "CDS_LOCATION" "R25W136"
					( Origin gPackager )
				)
				( attribute "CDS_SEC" "1"
					( Origin gPackager )
				)
				( attribute "LOCATION" "R25W136"
					( Origin gFrontEnd )
				)
				( attribute "MATERIAL" "CHIP"
					( Origin gFrontEnd )
				)
				( attribute "PACK_TYPE" "0402"
					( Origin gFrontEnd )
				)
				( attribute "PART_NUMBER" "G21796-074"
					( Origin gFrontEnd )
				)
				( attribute "PHYS_PAGE" "252"
					( Origin gFrontEnd )
				)
				( attribute "ROT" "0"
					( Origin gFrontEnd )
				)
				( attribute "SEC" "1"
					( Origin gFrontEnd )
				)
				( attribute "SEC_TYPE" "0402"
					( Origin gFrontEnd )
				)
				( attribute "TOLERANCE" "1%"
					( Origin gFrontEnd )
				)
				( attribute "VALUE" "33.2"
					( Origin gFrontEnd )
				)
				( attribute "VER" "1"
					( Origin gFrontEnd )
				)
				( attribute "WATTAGE" "1/16W"
					( Origin gFrontEnd )
				)
				( attribute "XY" "(-6800,3500)"
					( Origin gFrontEnd )
				)
				( attribute "CHIPS_PART_NAME" "RES"
					( Origin gPackager )
				)
				( attribute "CDS_PART_NAME" "RES_0402-33.2,1%,1/16W,CHIP,G2A"
					( Origin gPackager )
				)
				( attribute "GROUP" "AST2500"
					( Origin gFrontEnd )
				)
				( objectStatus "R25W136" )
			)
			( gate "@baseboard_fab2_lib.baseboard_fab2(sch_1):page255_i39"
				( attribute "BOM_COST" "PVPP_KLM_VR"
					( Origin gFrontEnd )
				)
				( attribute "CDS_LIB" "mstr_discrete"
					( Origin gPackager )
				)
				( attribute "LOCATION" "C25W79"
					( Origin gFrontEnd )
				)
				( attribute "MATERIAL" "COG"
					( Origin gFrontEnd )
				)
				( attribute "PACK_TYPE" "0402LF"
					( Origin gFrontEnd )
				)
				( attribute "PART_NUMBER" "A36095-026"
					( Origin gFrontEnd )
				)
				( attribute "PHYS_PAGE" "252"
					( Origin gFrontEnd )
				)
				( attribute "REUSE_ID" "27"
					( Origin gFrontEnd )
				)
				( attribute "ROOM" "PVPP_KLM_VR"
					( Origin gFrontEnd )
				)
				( attribute "ROT" "3"
					( Origin gFrontEnd )
				)
				( attribute "SEC" "1"
					( Origin gFrontEnd )
				)
				( attribute "SEC_TYPE" "0402LF"
					( Origin gFrontEnd )
				)
				( attribute "TOLERANCE" "5%"
					( Origin gFrontEnd )
				)
				( attribute "VALUE" "100.0PF"
					( Origin gFrontEnd )
				)
				( attribute "VER" "2"
					( Origin gFrontEnd )
				)
				( attribute "VOLTAGE" "50V"
					( Units "uVoltage" "V" 1.000000)
					( Origin gFrontEnd )
				)
				( attribute "XY" "(-6550,3300)"
					( Origin gFrontEnd )
				)
				( attribute "CHIPS_PART_NAME" "CAP"
					( Origin gPackager )
				)
				( attribute "CDS_PART_NAME" "CAP_0402LF-100.0PF,50V,5%,COG,A"
					( Origin gPackager )
				)
				( attribute "CDS_LOCATION" "C25W79"
					( Origin gPackager )
				)
				( attribute "CDS_SEC" "1"
					( Origin gPackager )
				)
				( attribute "GROUP" "AST2500"
					( Origin gFrontEnd )
				)
				( objectStatus "C25W79" )
			)
			( gate "@baseboard_fab2_lib.baseboard_fab2(sch_1):page255_i43"
				( attribute "BOM_COST" "SM_THERM"
					( Origin gFrontEnd )
				)
				( attribute "CDS_LIB" "mstr_discrete"
					( Origin gPackager )
				)
				( attribute "CDS_LOCATION" "R25W134"
					( Origin gPackager )
				)
				( attribute "CDS_SEC" "1"
					( Origin gPackager )
				)
				( attribute "LOCATION" "R25W134"
					( Origin gFrontEnd )
				)
				( attribute "MATERIAL" "CHIP"
					( Origin gFrontEnd )
				)
				( attribute "PACK_TYPE" "0402"
					( Origin gFrontEnd )
				)
				( attribute "PART_NUMBER" "G21796-072"
					( Origin gFrontEnd )
				)
				( attribute "PHYS_PAGE" "252"
					( Origin gFrontEnd )
				)
				( attribute "ROOM" "CPU_FANS"
					( Origin gFrontEnd )
				)
				( attribute "ROT" "0"
					( Origin gFrontEnd )
				)
				( attribute "SEC" "1"
					( Origin gFrontEnd )
				)
				( attribute "SEC_TYPE" "0402"
					( Origin gFrontEnd )
				)
				( attribute "TOLERANCE" "1%"
					( Origin gFrontEnd )
				)
				( attribute "VALUE" "4.75K"
					( Origin gFrontEnd )
				)
				( attribute "VER" "2"
					( Origin gFrontEnd )
				)
				( attribute "WATTAGE" "1/16W"
					( Origin gFrontEnd )
				)
				( attribute "XY" "(-8200,4050)"
					( Origin gFrontEnd )
				)
				( attribute "CHIPS_PART_NAME" "RES"
					( Origin gPackager )
				)
				( attribute "CDS_PART_NAME" "RES_0402-4.75K,1%,1/16W,CHIP,GA"
					( Origin gPackager )
				)
				( attribute "GROUP" "AST2500"
					( Origin gFrontEnd )
				)
				( objectStatus "R25W134" )
			)
			( gate "@baseboard_fab2_lib.baseboard_fab2(sch_1):page255_i44"
				( attribute "BOM_COST" "SM_THERM"
					( Origin gFrontEnd )
				)
				( attribute "CDS_LIB" "mstr_discrete"
					( Origin gPackager )
				)
				( attribute "LOCATION" "R25W135"
					( Origin gFrontEnd )
				)
				( attribute "MATERIAL" "CHIP"
					( Origin gFrontEnd )
				)
				( attribute "PACK_TYPE" "0402"
					( Origin gFrontEnd )
				)
				( attribute "PART_NUMBER" "G21796-072"
					( Origin gFrontEnd )
				)
				( attribute "PHYS_PAGE" "252"
					( Origin gFrontEnd )
				)
				( attribute "ROOM" "CPU_FANS"
					( Origin gFrontEnd )
				)
				( attribute "ROT" "0"
					( Origin gFrontEnd )
				)
				( attribute "TOLERANCE" "1%"
					( Origin gFrontEnd )
				)
				( attribute "VALUE" "4.75K"
					( Origin gFrontEnd )
				)
				( attribute "VER" "2"
					( Origin gFrontEnd )
				)
				( attribute "WATTAGE" "1/16W"
					( Origin gFrontEnd )
				)
				( attribute "XY" "(-7750,3700)"
					( Origin gFrontEnd )
				)
				( attribute "CHIPS_PART_NAME" "RES"
					( Origin gPackager )
				)
				( attribute "CDS_PART_NAME" "RES_0402-4.75K,1%,1/16W,CHIP,GA"
					( Origin gPackager )
				)
				( attribute "CDS_LOCATION" "R25W135"
					( Origin gPackager )
				)
				( attribute "CDS_SEC" "1"
					( Origin gPackager )
				)
				( attribute "SEC" "1"
					( Origin gPackager )
				)
				( attribute "GROUP" "AST2500"
					( Origin gFrontEnd )
				)
				( objectStatus "R25W135" )
			)
			( gate "@baseboard_fab2_lib.baseboard_fab2(sch_1):page168_i48"
				( attribute "CDS_LIB" "mstr_discrete"
					( Origin gPackager )
				)
				( attribute "CDS_LOCATION" "R6W49"
					( Origin gPackager )
				)
				( attribute "CDS_SEC" "1"
					( Origin gPackager )
				)
				( attribute "LOCATION" "R6W49"
					( Origin gFrontEnd )
				)
				( attribute "MATERIAL" "CHIP"
					( Origin gFrontEnd )
				)
				( attribute "PACK_TYPE" "0402"
					( Origin gFrontEnd )
				)
				( attribute "PART_NUMBER" "G21796-133"
					( Origin gFrontEnd )
				)
				( attribute "PHYS_PAGE" "168"
					( Origin gFrontEnd )
				)
				( attribute "ROOM" "HOT_SWAP"
					( Origin gFrontEnd )
				)
				( attribute "ROT" "1"
					( Origin gFrontEnd )
				)
				( attribute "SEC" "1"
					( Origin gFrontEnd )
				)
				( attribute "SEC_TYPE" "0402"
					( Origin gFrontEnd )
				)
				( attribute "TOLERANCE" "1%"
					( Origin gFrontEnd )
				)
				( attribute "VALUE" "40.2K"
					( Origin gFrontEnd )
				)
				( attribute "VER" "2"
					( Origin gFrontEnd )
				)
				( attribute "WATTAGE" "1/16W"
					( Origin gFrontEnd )
				)
				( attribute "XY" "(-5950,1450)"
					( Origin gFrontEnd )
				)
				( attribute "CHIPS_PART_NAME" "RES"
					( Origin gPackager )
				)
				( attribute "CDS_PART_NAME" "RES_0402-40.2K,1%,1/16W,CHIP,GA"
					( Origin gPackager )
				)
				( objectStatus "R6W49" )
			)
			( gate "@baseboard_fab2_lib.baseboard_fab2(sch_1):page200_i243"
				( attribute "CDS_LIB" "mstr_discrete"
					( Origin gPackager )
				)
				( attribute "LOCATION" "R9P15"
					( Origin gFrontEnd )
				)
				( attribute "MATERIAL" "CHIP"
					( Origin gFrontEnd )
				)
				( attribute "PACK_TYPE" "0402"
					( Origin gFrontEnd )
				)
				( attribute "PART_NUMBER" "G21497-005"
					( Origin gFrontEnd )
				)
				( attribute "PHYS_PAGE" "200"
					( Origin gFrontEnd )
				)
				( attribute "ROT" "0"
					( Origin gFrontEnd )
				)
				( attribute "SEC" "1"
					( Origin gFrontEnd )
				)
				( attribute "SEC_TYPE" "0402"
					( Origin gFrontEnd )
				)
				( attribute "TOLERANCE" "5%"
					( Origin gFrontEnd )
				)
				( attribute "VALUE" "0.0"
					( Origin gFrontEnd )
				)
				( attribute "VER" "1"
					( Origin gFrontEnd )
				)
				( attribute "WATTAGE" "1/16W"
					( Origin gFrontEnd )
				)
				( attribute "XY" "(-1750,3800)"
					( Origin gFrontEnd )
				)
				( attribute "CHIPS_PART_NAME" "RES"
					( Origin gPackager )
				)
				( attribute "CDS_PART_NAME" "RES_0402-0.0,5%,1/16W,CHIP,G21A"
					( Origin gPackager )
				)
				( attribute "CDS_LOCATION" "R9P15"
					( Origin gPackager )
				)
				( attribute "CDS_SEC" "1"
					( Origin gPackager )
				)
				( objectStatus "R9P15" )
			)
			( gate "@baseboard_fab2_lib.baseboard_fab2(sch_1):page200_i244"
				( attribute "CDS_LIB" "mstr_discrete"
					( Origin gPackager )
				)
				( attribute "CDS_LOCATION" "R1D10"
					( Origin gPackager )
				)
				( attribute "CDS_SEC" "1"
					( Origin gPackager )
				)
				( attribute "LOCATION" "R1D10"
					( Origin gFrontEnd )
				)
				( attribute "MATERIAL" "CHIP"
					( Origin gFrontEnd )
				)
				( attribute "PACK_TYPE" "0402"
					( Origin gFrontEnd )
				)
				( attribute "PART_NUMBER" "G21796-016"
					( Origin gFrontEnd )
				)
				( attribute "PHYS_PAGE" "200"
					( Origin gFrontEnd )
				)
				( attribute "ROOM" "HOT_SWAP"
					( Origin gFrontEnd )
				)
				( attribute "ROT" "0"
					( Origin gFrontEnd )
				)
				( attribute "SEC" "1"
					( Origin gFrontEnd )
				)
				( attribute "SEC_TYPE" "0402"
					( Origin gFrontEnd )
				)
				( attribute "TOLERANCE" "1%"
					( Origin gFrontEnd )
				)
				( attribute "VALUE" "10.0K"
					( Origin gFrontEnd )
				)
				( attribute "VER" "2"
					( Origin gFrontEnd )
				)
				( attribute "WATTAGE" "1/16W"
					( Origin gFrontEnd )
				)
				( attribute "XY" "(-2600,3550)"
					( Origin gFrontEnd )
				)
				( attribute "CHIPS_PART_NAME" "RES"
					( Origin gPackager )
				)
				( attribute "CDS_PART_NAME" "RES_0402-10.0K,1%,1/16W,CHIP,GA"
					( Origin gPackager )
				)
				( objectStatus "R1D10" )
			)
			( gate "@baseboard_fab2_lib.baseboard_fab2(sch_1):page141_i129"
				( attribute "CDS_LIB" "w_hdl"
					( Origin gPackager )
				)
				( attribute "CDS_LMAN_SYM_OUTLINE" "-250,625,250,-625"
					( Origin gPackager )
				)
				( attribute "LOCATION" "JA9G1"
					( Origin gFrontEnd )
				)
				( attribute "PACK_TYPE" "SOCKET-G2"
					( Origin gFrontEnd )
				)
				( attribute "PART_NUMBER" "022.10001.0S51"
					( Origin gFrontEnd )
				)
				( attribute "PHYS_PAGE" "141"
					( Origin gFrontEnd )
				)
				( attribute "ROT" "0"
					( Origin gFrontEnd )
				)
				( attribute "SEC" "1"
					( Origin gFrontEnd )
				)
				( attribute "SEC_TYPE" "SOCKET-G2"
					( Origin gFrontEnd )
				)
				( attribute "VALUE" "SKT-RJ45-LED-XFOR-1-GP"
					( Origin gFrontEnd )
				)
				( attribute "VER" "1"
					( Origin gFrontEnd )
				)
				( attribute "XY" "(-1650,1825)"
					( Origin gFrontEnd )
				)
				( attribute "CHIPS_PART_NAME" "SKT-RJ45-LED-XFOR-1-GP"
					( Origin gPackager )
				)
				( attribute "CDS_PART_NAME" "SKT-RJ45-LED-XFOR-1-GP_SOCKET-A"
					( Origin gPackager )
				)
				( attribute "CDS_LOCATION" "JA9G1"
					( Origin gPackager )
				)
				( attribute "CDS_SEC" "1"
					( Origin gPackager )
				)
				( attribute "GROUP" "NI_I210&RJ45"
					( Origin gFrontEnd )
				)
				( objectStatus "JA9G1" )
			)
			( gate "@baseboard_fab2_lib.baseboard_fab2(sch_1):page172_i66"
				( attribute "CDS_LIB" "mstr_discrete"
					( Origin gPackager )
				)
				( attribute "CDS_LOCATION" "F9B1"
					( Origin gPackager )
				)
				( attribute "CDS_SEC" "1"
					( Origin gPackager )
				)
				( attribute "LOCATION" "F9B1"
					( Origin gFrontEnd )
				)
				( attribute "MATERIAL" "IC"
					( Origin gFrontEnd )
				)
				( attribute "PACK_TYPE" "SM"
					( Origin gFrontEnd )
				)
				( attribute "PART_NUMBER" "C94311-016"
					( Origin gFrontEnd )
				)
				( attribute "PHYS_PAGE" "172"
					( Origin gFrontEnd )
				)
				( attribute "ROOM" "ST_SATA"
					( Origin gFrontEnd )
				)
				( attribute "ROT" "4"
					( Origin gFrontEnd )
				)
				( attribute "SEC" "1"
					( Origin gFrontEnd )
				)
				( attribute "SEC_TYPE" "SM"
					( Origin gFrontEnd )
				)
				( attribute "VER" "1"
					( Origin gFrontEnd )
				)
				( attribute "XY" "(975,450)"
					( Origin gFrontEnd )
				)
				( attribute "CHIPS_PART_NAME" "FUSE"
					( Origin gPackager )
				)
				( attribute "CDS_PART_NAME" "FUSE_SM-IC,C94311-016"
					( Origin gPackager )
				)
				( objectStatus "F9B1" )
			)
			( gate "@baseboard_fab2_lib.baseboard_fab2(sch_1):page255_i49"
				( attribute "BOM_COST" "PROC_SIDEBAND"
					( Origin gFrontEnd )
				)
				( attribute "CDS_LIB" "mstr_discrete"
					( Origin gPackager )
				)
				( attribute "CDS_LOCATION" "R25W138"
					( Origin gPackager )
				)
				( attribute "LOCATION" "R25W138"
					( Origin gFrontEnd )
				)
				( attribute "MATERIAL" "CHIP"
					( Origin gFrontEnd )
				)
				( attribute "PACK_TYPE" "0402"
					( Origin gFrontEnd )
				)
				( attribute "PART_NUMBER" "G21796-074"
					( Origin gFrontEnd )
				)
				( attribute "PHYS_PAGE" "252"
					( Origin gFrontEnd )
				)
				( attribute "ROOM" "PROC_TRANSLATORS"
					( Origin gFrontEnd )
				)
				( attribute "ROT" "0"
					( Origin gFrontEnd )
				)
				( attribute "SEC" "1"
					( Origin gFrontEnd )
				)
				( attribute "SEC_TYPE" "0402"
					( Origin gFrontEnd )
				)
				( attribute "TOLERANCE" "1%"
					( Origin gFrontEnd )
				)
				( attribute "VALUE" "33.2"
					( Origin gFrontEnd )
				)
				( attribute "VER" "1"
					( Origin gFrontEnd )
				)
				( attribute "WATTAGE" "1/16W"
					( Origin gFrontEnd )
				)
				( attribute "XY" "(-3250,5000)"
					( Origin gFrontEnd )
				)
				( attribute "CHIPS_PART_NAME" "RES"
					( Origin gPackager )
				)
				( attribute "CDS_PART_NAME" "RES_0402-33.2,1%,1/16W,CHIP,G2A"
					( Origin gPackager )
				)
				( attribute "CDS_SEC" "1"
					( Origin gPackager )
				)
				( attribute "GROUP" "AST2500"
					( Origin gFrontEnd )
				)
				( objectStatus "R25W138" )
			)
			( gate "@baseboard_fab2_lib.baseboard_fab2(sch_1):page255_i60"
				( attribute "BOM_COST" "SM_HM"
					( Origin gFrontEnd )
				)
				( attribute "CDS_LIB" "mstr_discrete"
					( Origin gPackager )
				)
				( attribute "CDS_LOCATION" "C25W81"
					( Origin gPackager )
				)
				( attribute "CDS_SEC" "1"
					( Origin gPackager )
				)
				( attribute "LOCATION" "C25W81"
					( Origin gFrontEnd )
				)
				( attribute "MATERIAL" "COG"
					( Origin gFrontEnd )
				)
				( attribute "PACK_TYPE" "0402LF"
					( Origin gFrontEnd )
				)
				( attribute "PART_NUMBER" "A36094-025"
					( Origin gFrontEnd )
				)
				( attribute "PHYS_PAGE" "252"
					( Origin gFrontEnd )
				)
				( attribute "ROOM" "BMC_VOLT_MONITOR"
					( Origin gFrontEnd )
				)
				( attribute "ROT" "0"
					( Origin gFrontEnd )
				)
				( attribute "SEC" "1"
					( Origin gFrontEnd )
				)
				( attribute "SEC_TYPE" "0402LF"
					( Origin gFrontEnd )
				)
				( attribute "TOLERANCE" "5%"
					( Origin gFrontEnd )
				)
				( attribute "VALUE" "10.0PF"
					( Origin gFrontEnd )
				)
				( attribute "VER" "1"
					( Origin gFrontEnd )
				)
				( attribute "VOLTAGE" "50V"
					( Units "uVoltage" "V" 1.000000)
					( Origin gFrontEnd )
				)
				( attribute "XY" "(-2750,4850)"
					( Origin gFrontEnd )
				)
				( attribute "CHIPS_PART_NAME" "CAP"
					( Origin gPackager )
				)
				( attribute "CDS_PART_NAME" "CAP_0402LF-10.0PF,50V,5%,COG,AA"
					( Origin gPackager )
				)
				( attribute "GROUP" "AST2500"
					( Origin gFrontEnd )
				)
				( objectStatus "C25W81" )
			)
			( gate "@baseboard_fab2_lib.baseboard_fab2(sch_1):page255_i59"
				( attribute "BOM_COST" "PROC_SIDEBAND"
					( Origin gFrontEnd )
				)
				( attribute "CDS_LIB" "mstr_discrete"
					( Origin gPackager )
				)
				( attribute "CDS_LOCATION" "R25W139"
					( Origin gPackager )
				)
				( attribute "CDS_SEC" "1"
					( Origin gPackager )
				)
				( attribute "LOCATION" "R25W139"
					( Origin gFrontEnd )
				)
				( attribute "MATERIAL" "CHIP"
					( Origin gFrontEnd )
				)
				( attribute "PACK_TYPE" "0402"
					( Origin gFrontEnd )
				)
				( attribute "PART_NUMBER" "G21796-074"
					( Origin gFrontEnd )
				)
				( attribute "PHYS_PAGE" "252"
					( Origin gFrontEnd )
				)
				( attribute "ROOM" "PROC_TRANSLATORS"
					( Origin gFrontEnd )
				)
				( attribute "ROT" "0"
					( Origin gFrontEnd )
				)
				( attribute "SEC" "1"
					( Origin gFrontEnd )
				)
				( attribute "SEC_TYPE" "0402"
					( Origin gFrontEnd )
				)
				( attribute "TOLERANCE" "1%"
					( Origin gFrontEnd )
				)
				( attribute "VALUE" "33.2"
					( Origin gFrontEnd )
				)
				( attribute "VER" "1"
					( Origin gFrontEnd )
				)
				( attribute "WATTAGE" "1/16W"
					( Origin gFrontEnd )
				)
				( attribute "XY" "(-3250,4450)"
					( Origin gFrontEnd )
				)
				( attribute "CHIPS_PART_NAME" "RES"
					( Origin gPackager )
				)
				( attribute "CDS_PART_NAME" "RES_0402-33.2,1%,1/16W,CHIP,G2A"
					( Origin gPackager )
				)
				( attribute "GROUP" "AST2500"
					( Origin gFrontEnd )
				)
				( objectStatus "R25W139" )
			)
			( gate "@baseboard_fab2_lib.baseboard_fab2(sch_1):page255_i62"
				( attribute "BOM_COST" "SM_HM"
					( Origin gFrontEnd )
				)
				( attribute "CDS_LIB" "mstr_discrete"
					( Origin gPackager )
				)
				( attribute "CDS_LOCATION" "C25W82"
					( Origin gPackager )
				)
				( attribute "CDS_SEC" "1"
					( Origin gPackager )
				)
				( attribute "LOCATION" "C25W82"
					( Origin gFrontEnd )
				)
				( attribute "MATERIAL" "COG"
					( Origin gFrontEnd )
				)
				( attribute "PACK_TYPE" "0402LF"
					( Origin gFrontEnd )
				)
				( attribute "PART_NUMBER" "A36094-025"
					( Origin gFrontEnd )
				)
				( attribute "PHYS_PAGE" "252"
					( Origin gFrontEnd )
				)
				( attribute "ROOM" "BMC_VOLT_MONITOR"
					( Origin gFrontEnd )
				)
				( attribute "ROT" "0"
					( Origin gFrontEnd )
				)
				( attribute "SEC" "1"
					( Origin gFrontEnd )
				)
				( attribute "SEC_TYPE" "0402LF"
					( Origin gFrontEnd )
				)
				( attribute "TOLERANCE" "5%"
					( Origin gFrontEnd )
				)
				( attribute "VALUE" "10.0PF"
					( Origin gFrontEnd )
				)
				( attribute "VER" "1"
					( Origin gFrontEnd )
				)
				( attribute "VOLTAGE" "50V"
					( Units "uVoltage" "V" 1.000000)
					( Origin gFrontEnd )
				)
				( attribute "XY" "(-2750,4300)"
					( Origin gFrontEnd )
				)
				( attribute "CHIPS_PART_NAME" "CAP"
					( Origin gPackager )
				)
				( attribute "CDS_PART_NAME" "CAP_0402LF-10.0PF,50V,5%,COG,AA"
					( Origin gPackager )
				)
				( attribute "GROUP" "AST2500"
					( Origin gFrontEnd )
				)
				( objectStatus "C25W82" )
			)
			( gate "@baseboard_fab2_lib.baseboard_fab2(sch_1):page255_i74"
				( attribute "BOM_COST" "PROC_SIDEBAND"
					( Origin gFrontEnd )
				)
				( attribute "CDS_LIB" "dev_discrete"
					( Origin gPackager )
				)
				( attribute "CDS_LOCATION" "C25P83"
					( Origin gPackager )
				)
				( attribute "CDS_SEC" "1"
					( Origin gPackager )
				)
				( attribute "LOCATION" "C25P83"
					( Origin gFrontEnd )
				)
				( attribute "MATERIAL" "X7R"
					( Origin gFrontEnd )
				)
				( attribute "PACK_TYPE" "0402V"
					( Origin gFrontEnd )
				)
				( attribute "PART_NUMBER" "A36096-030"
					( Origin gFrontEnd )
				)
				( attribute "PHYS_PAGE" "252"
					( Origin gFrontEnd )
				)
				( attribute "ROOM" "PROC_SIDEBAND"
					( Origin gFrontEnd )
				)
				( attribute "ROT" "0"
					( Origin gFrontEnd )
				)
				( attribute "SEC" "1"
					( Origin gFrontEnd )
				)
				( attribute "SEC_TYPE" "0402V"
					( Origin gFrontEnd )
				)
				( attribute "TOLERANCE" "10%"
					( Origin gFrontEnd )
				)
				( attribute "VALUE" "0.1UF"
					( Origin gFrontEnd )
				)
				( attribute "VER" "1"
					( Origin gFrontEnd )
				)
				( attribute "VOLTAGE" "16V"
					( Units "uVoltage" "V" 1.000000)
					( Origin gFrontEnd )
				)
				( attribute "XY" "(-3200,2350)"
					( Origin gFrontEnd )
				)
				( attribute "CHIPS_PART_NAME" "CAP_A"
					( Origin gPackager )
				)
				( attribute "CDS_PART_NAME" "CAP_A_0402V-0.1UF,16V,10%,X7R,A"
					( Origin gPackager )
				)
				( attribute "GROUP" "AST2500"
					( Origin gFrontEnd )
				)
				( objectStatus "C25P83" )
			)
			( gate "@baseboard_fab2_lib.baseboard_fab2(sch_1):page255_i76"
				( attribute "CDS_LIB" "w_hdl"
					( Origin gPackager )
				)
				( attribute "CDS_LMAN_SYM_OUTLINE" "-50,100,50,-100"
					( Origin gPackager )
				)
				( attribute "LOCATION" "L25W1"
					( Origin gFrontEnd )
				)
				( attribute "PACK_TYPE" "DISCRET-GC1"
					( Origin gFrontEnd )
				)
				( attribute "PART_NUMBER" "68.6803N.10D"
					( Origin gFrontEnd )
				)
				( attribute "PHYS_PAGE" "252"
					( Origin gFrontEnd )
				)
				( attribute "ROT" "1"
					( Origin gFrontEnd )
				)
				( attribute "SEC" "1"
					( Origin gFrontEnd )
				)
				( attribute "SEC_TYPE" "DISCRET-GC1"
					( Origin gFrontEnd )
				)
				( attribute "VALUE" "IND-68NH-15-GP"
					( Origin gFrontEnd )
				)
				( attribute "VER" "1"
					( Origin gFrontEnd )
				)
				( attribute "XY" "(-3650,3600)"
					( Origin gFrontEnd )
				)
				( attribute "CHIPS_PART_NAME" "IND-68NH-15-GP"
					( Origin gPackager )
				)
				( attribute "CDS_PART_NAME" "IND-68NH-15-GP_DISCRET-GC1-INDA"
					( Origin gPackager )
				)
				( attribute "CDS_LOCATION" "L25W1"
					( Origin gPackager )
				)
				( attribute "CDS_SEC" "1"
					( Origin gPackager )
				)
				( attribute "ATTRIBUTE" "68NH"
					( Origin gFrontEnd )
				)
				( attribute "PACK_SIZE" "DCR=800MOHM"
					( Origin gFrontEnd )
				)
				( attribute "RATED" "300MA"
					( Origin gFrontEnd )
				)
				( attribute "GROUP" "AST2500"
					( Origin gFrontEnd )
				)
				( objectStatus "L25W1" )
			)
			( gate "@baseboard_fab2_lib.baseboard_fab2(sch_1):page255_i77"
				( attribute "CDS_LIB" "w_hdl"
					( Origin gPackager )
				)
				( attribute "CDS_LMAN_SYM_OUTLINE" "-50,100,50,-100"
					( Origin gPackager )
				)
				( attribute "LOCATION" "L25W2"
					( Origin gFrontEnd )
				)
				( attribute "PACK_TYPE" "DISCRET-GC1"
					( Origin gFrontEnd )
				)
				( attribute "PART_NUMBER" "68.6803N.10D"
					( Origin gFrontEnd )
				)
				( attribute "PHYS_PAGE" "252"
					( Origin gFrontEnd )
				)
				( attribute "ROT" "1"
					( Origin gFrontEnd )
				)
				( attribute "SEC" "1"
					( Origin gFrontEnd )
				)
				( attribute "SEC_TYPE" "DISCRET-GC1"
					( Origin gFrontEnd )
				)
				( attribute "VALUE" "IND-68NH-15-GP"
					( Origin gFrontEnd )
				)
				( attribute "VER" "1"
					( Origin gFrontEnd )
				)
				( attribute "XY" "(-3650,3750)"
					( Origin gFrontEnd )
				)
				( attribute "CHIPS_PART_NAME" "IND-68NH-15-GP"
					( Origin gPackager )
				)
				( attribute "CDS_PART_NAME" "IND-68NH-15-GP_DISCRET-GC1-INDA"
					( Origin gPackager )
				)
				( attribute "CDS_LOCATION" "L25W2"
					( Origin gPackager )
				)
				( attribute "CDS_SEC" "1"
					( Origin gPackager )
				)
				( attribute "ATTRIBUTE" "68NH"
					( Origin gFrontEnd )
				)
				( attribute "PACK_SIZE" "DCR=800MOHM"
					( Origin gFrontEnd )
				)
				( attribute "RATED" "300MA"
					( Origin gFrontEnd )
				)
				( attribute "GROUP" "AST2500"
					( Origin gFrontEnd )
				)
				( objectStatus "L25W2" )
			)
			( gate "@baseboard_fab2_lib.baseboard_fab2(sch_1):page255_i78"
				( attribute "CDS_LIB" "w_hdl"
					( Origin gPackager )
				)
				( attribute "CDS_LMAN_SYM_OUTLINE" "-50,100,50,-100"
					( Origin gPackager )
				)
				( attribute "LOCATION" "L25W3"
					( Origin gFrontEnd )
				)
				( attribute "PACK_TYPE" "DISCRET-GC1"
					( Origin gFrontEnd )
				)
				( attribute "PART_NUMBER" "68.6803N.10D"
					( Origin gFrontEnd )
				)
				( attribute "PHYS_PAGE" "252"
					( Origin gFrontEnd )
				)
				( attribute "ROT" "1"
					( Origin gFrontEnd )
				)
				( attribute "SEC" "1"
					( Origin gFrontEnd )
				)
				( attribute "SEC_TYPE" "DISCRET-GC1"
					( Origin gFrontEnd )
				)
				( attribute "VALUE" "IND-68NH-15-GP"
					( Origin gFrontEnd )
				)
				( attribute "VER" "1"
					( Origin gFrontEnd )
				)
				( attribute "XY" "(-3600,3900)"
					( Origin gFrontEnd )
				)
				( attribute "CHIPS_PART_NAME" "IND-68NH-15-GP"
					( Origin gPackager )
				)
				( attribute "CDS_PART_NAME" "IND-68NH-15-GP_DISCRET-GC1-INDA"
					( Origin gPackager )
				)
				( attribute "CDS_LOCATION" "L25W3"
					( Origin gPackager )
				)
				( attribute "CDS_SEC" "1"
					( Origin gPackager )
				)
				( attribute "ATTRIBUTE" "68NH"
					( Origin gFrontEnd )
				)
				( attribute "PACK_SIZE" "DCR=800MOHM"
					( Origin gFrontEnd )
				)
				( attribute "RATED" "300MA"
					( Origin gFrontEnd )
				)
				( attribute "GROUP" "AST2500"
					( Origin gFrontEnd )
				)
				( objectStatus "L25W3" )
			)
			( gate "@baseboard_fab2_lib.baseboard_fab2(sch_1):page163_i28"
				( attribute "CDS_LIB" "w_hdl"
					( Origin gPackager )
				)
				( attribute "CDS_LMAN_SYM_OUTLINE" "-175,175,175,-175"
					( Origin gPackager )
				)
				( attribute "PACK_TYPE" "DISCRET-G8"
					( Origin gFrontEnd )
				)
				( attribute "PART_NUMBER" "071.09517.0009"
					( Origin gFrontEnd )
				)
				( attribute "PHYS_PAGE" "163"
					( Origin gFrontEnd )
				)
				( attribute "ROT" "0"
					( Origin gFrontEnd )
				)
				( attribute "VALUE" "TCA9517DGKR-GP"
					( Origin gFrontEnd )
				)
				( attribute "VER" "1"
					( Origin gFrontEnd )
				)
				( attribute "XY" "(-1475,3275)"
					( Origin gFrontEnd )
				)
				( attribute "CHIPS_PART_NAME" "TCA9517DGKR-GP"
					( Origin gPackager )
				)
				( attribute "CDS_PART_NAME" "TCA9517DGKR-GP_DISCRET-G8-TCA9A"
					( Origin gPackager )
				)
				( attribute "LOCATION" "U1B2"
					( Origin gFrontEnd )
				)
				( attribute "SEC" "1"
					( Origin gFrontEnd )
				)
				( attribute "SEC_TYPE" "DISCRET-G8"
					( Origin gFrontEnd )
				)
				( attribute "CDS_LOCATION" "U1B2"
					( Origin gPackager )
				)
				( attribute "CDS_SEC" "1"
					( Origin gPackager )
				)
				( objectStatus "U1B2" )
			)
			( gate "@baseboard_fab2_lib.baseboard_fab2(sch_1):page247_i118"
				( attribute "CDS_LIB" "w_hdl"
					( Origin gPackager )
				)
				( attribute "CDS_LMAN_SYM_OUTLINE" "-175,175,175,-175"
					( Origin gPackager )
				)
				( attribute "LOCATION" "U6W2"
					( Origin gFrontEnd )
				)
				( attribute "PACK_TYPE" "DISCRET-G8"
					( Origin gFrontEnd )
				)
				( attribute "PART_NUMBER" "071.09517.0009"
					( Origin gFrontEnd )
				)
				( attribute "PHYS_PAGE" "247"
					( Origin gFrontEnd )
				)
				( attribute "ROT" "0"
					( Origin gFrontEnd )
				)
				( attribute "SEC" "1"
					( Origin gFrontEnd )
				)
				( attribute "SEC_TYPE" "DISCRET-G8"
					( Origin gFrontEnd )
				)
				( attribute "VALUE" "TCA9517DGKR-GP"
					( Origin gFrontEnd )
				)
				( attribute "VER" "1"
					( Origin gFrontEnd )
				)
				( attribute "XY" "(-6375,925)"
					( Origin gFrontEnd )
				)
				( attribute "CHIPS_PART_NAME" "TCA9517DGKR-GP"
					( Origin gPackager )
				)
				( attribute "CDS_PART_NAME" "TCA9517DGKR-GP_DISCRET-G8-TCA9A"
					( Origin gPackager )
				)
				( attribute "CDS_LOCATION" "U6W2"
					( Origin gPackager )
				)
				( attribute "CDS_SEC" "1"
					( Origin gPackager )
				)
				( objectStatus "U6W2" )
			)
			( gate "@baseboard_fab2_lib.baseboard_fab2(sch_1):page248_i49"
				( attribute "CDS_LIB" "w_hdl"
					( Origin gPackager )
				)
				( attribute "CDS_LMAN_SYM_OUTLINE" "-175,175,175,-175"
					( Origin gPackager )
				)
				( attribute "LOCATION" "U1W2"
					( Origin gFrontEnd )
				)
				( attribute "PACK_TYPE" "DISCRET-G8"
					( Origin gFrontEnd )
				)
				( attribute "PART_NUMBER" "071.09517.0009"
					( Origin gFrontEnd )
				)
				( attribute "PHYS_PAGE" "248"
					( Origin gFrontEnd )
				)
				( attribute "ROT" "0"
					( Origin gFrontEnd )
				)
				( attribute "SEC" "1"
					( Origin gFrontEnd )
				)
				( attribute "SEC_TYPE" "DISCRET-G8"
					( Origin gFrontEnd )
				)
				( attribute "VALUE" "TCA9517DGKR-GP"
					( Origin gFrontEnd )
				)
				( attribute "VER" "1"
					( Origin gFrontEnd )
				)
				( attribute "XY" "(-3925,3500)"
					( Origin gFrontEnd )
				)
				( attribute "CHIPS_PART_NAME" "TCA9517DGKR-GP"
					( Origin gPackager )
				)
				( attribute "CDS_PART_NAME" "TCA9517DGKR-GP_DISCRET-G8-TCA9A"
					( Origin gPackager )
				)
				( attribute "CDS_LOCATION" "U1W2"
					( Origin gPackager )
				)
				( attribute "CDS_SEC" "1"
					( Origin gPackager )
				)
				( objectStatus "U1W2" )
			)
			( gate "@baseboard_fab2_lib.baseboard_fab2(sch_1):page116_i238"
				( attribute "BOM_COST" "PROC_SIDEBAND"
					( Origin gFrontEnd )
				)
				( attribute "CDS_LIB" "dev_discrete"
					( Origin gPackager )
				)
				( attribute "CDS_LOCATION" "C2M4"
					( Origin gPackager )
				)
				( attribute "CDS_SEC" "1"
					( Origin gPackager )
				)
				( attribute "LOCATION" "C2M4"
					( Origin gFrontEnd )
				)
				( attribute "MATERIAL" "X7R"
					( Origin gFrontEnd )
				)
				( attribute "PACK_TYPE" "0402V"
					( Origin gFrontEnd )
				)
				( attribute "PART_NUMBER" "A36096-030"
					( Origin gFrontEnd )
				)
				( attribute "PHYS_PAGE" "116"
					( Origin gFrontEnd )
				)
				( attribute "ROOM" "PROC_SIDEBAND"
					( Origin gFrontEnd )
				)
				( attribute "ROT" "1"
					( Origin gFrontEnd )
				)
				( attribute "SEC" "1"
					( Origin gFrontEnd )
				)
				( attribute "SEC_TYPE" "0402V"
					( Origin gFrontEnd )
				)
				( attribute "TOLERANCE" "10%"
					( Origin gFrontEnd )
				)
				( attribute "VALUE" "0.1UF"
					( Origin gFrontEnd )
				)
				( attribute "VER" "1"
					( Origin gFrontEnd )
				)
				( attribute "VOLTAGE" "16V"
					( Units "uVoltage" "V" 1.000000)
					( Origin gFrontEnd )
				)
				( attribute "XY" "(-1725,2650)"
					( Origin gFrontEnd )
				)
				( attribute "CHIPS_PART_NAME" "CAP_A"
					( Origin gPackager )
				)
				( attribute "CDS_PART_NAME" "CAP_A_0402V-0.1UF,16V,10%,X7R,A"
					( Origin gPackager )
				)
				( attribute "GROUP" "AST2500"
					( Origin gFrontEnd )
				)
				( objectStatus "C2M4" )
			)
			( gate "@baseboard_fab2_lib.baseboard_fab2(sch_1):page116_i239"
				( attribute "BOM_COST" "PROC_SIDEBAND"
					( Origin gFrontEnd )
				)
				( attribute "CDS_LIB" "dev_discrete"
					( Origin gPackager )
				)
				( attribute "CDS_LOCATION" "C2M3"
					( Origin gPackager )
				)
				( attribute "CDS_SEC" "1"
					( Origin gPackager )
				)
				( attribute "LOCATION" "C2M3"
					( Origin gFrontEnd )
				)
				( attribute "MATERIAL" "X7R"
					( Origin gFrontEnd )
				)
				( attribute "PACK_TYPE" "0402V"
					( Origin gFrontEnd )
				)
				( attribute "PART_NUMBER" "A36096-030"
					( Origin gFrontEnd )
				)
				( attribute "PHYS_PAGE" "116"
					( Origin gFrontEnd )
				)
				( attribute "ROOM" "PROC_SIDEBAND"
					( Origin gFrontEnd )
				)
				( attribute "ROT" "1"
					( Origin gFrontEnd )
				)
				( attribute "SEC" "1"
					( Origin gFrontEnd )
				)
				( attribute "SEC_TYPE" "0402V"
					( Origin gFrontEnd )
				)
				( attribute "TOLERANCE" "10%"
					( Origin gFrontEnd )
				)
				( attribute "VALUE" "0.1UF"
					( Origin gFrontEnd )
				)
				( attribute "VER" "1"
					( Origin gFrontEnd )
				)
				( attribute "VOLTAGE" "16V"
					( Units "uVoltage" "V" 1.000000)
					( Origin gFrontEnd )
				)
				( attribute "XY" "(-1325,2600)"
					( Origin gFrontEnd )
				)
				( attribute "CHIPS_PART_NAME" "CAP_A"
					( Origin gPackager )
				)
				( attribute "CDS_PART_NAME" "CAP_A_0402V-0.1UF,16V,10%,X7R,A"
					( Origin gPackager )
				)
				( attribute "GROUP" "AST2500"
					( Origin gFrontEnd )
				)
				( objectStatus "C2M3" )
			)
			( gate "@baseboard_fab2_lib.baseboard_fab2(sch_1):page114_i191"
				( attribute "BOM_COST" "PROC_SIDEBAND"
					( Origin gFrontEnd )
				)
				( attribute "CDS_LIB" "mstr_discrete"
					( Origin gPackager )
				)
				( attribute "CDS_LOCATION" "R7C4"
					( Origin gPackager )
				)
				( attribute "CDS_SEC" "1"
					( Origin gPackager )
				)
				( attribute "LOCATION" "R7C4"
					( Origin gFrontEnd )
				)
				( attribute "MATERIAL" "CHIP"
					( Origin gFrontEnd )
				)
				( attribute "PACK_TYPE" "0402"
					( Origin gFrontEnd )
				)
				( attribute "PART_NUMBER" "G21497-005"
					( Origin gFrontEnd )
				)
				( attribute "PHYS_PAGE" "114"
					( Origin gFrontEnd )
				)
				( attribute "ROOM" "CPU0"
					( Origin gFrontEnd )
				)
				( attribute "ROT" "0"
					( Origin gFrontEnd )
				)
				( attribute "SEC" "1"
					( Origin gFrontEnd )
				)
				( attribute "SEC_TYPE" "0402"
					( Origin gFrontEnd )
				)
				( attribute "TOLERANCE" "5%"
					( Origin gFrontEnd )
				)
				( attribute "VALUE" "0.0"
					( Origin gFrontEnd )
				)
				( attribute "VER" "1"
					( Origin gFrontEnd )
				)
				( attribute "WATTAGE" "1/16W"
					( Origin gFrontEnd )
				)
				( attribute "XY" "(-1625,2850)"
					( Origin gFrontEnd )
				)
				( attribute "CHIPS_PART_NAME" "RES"
					( Origin gPackager )
				)
				( attribute "CDS_PART_NAME" "RES_0402-0.0,5%,1/16W,CHIP,G21A"
					( Origin gPackager )
				)
				( attribute "GROUP" "AST2500"
					( Origin gFrontEnd )
				)
				( objectStatus "R7C4" )
			)
			( gate "@baseboard_fab2_lib.baseboard_fab2(sch_1):page114_i192"
				( attribute "BOM_COST" "PROC_SIDEBAND"
					( Origin gFrontEnd )
				)
				( attribute "CDS_LIB" "mstr_discrete"
					( Origin gPackager )
				)
				( attribute "CDS_LOCATION" "R7C2"
					( Origin gPackager )
				)
				( attribute "CDS_SEC" "1"
					( Origin gPackager )
				)
				( attribute "LOCATION" "R7C2"
					( Origin gFrontEnd )
				)
				( attribute "MATERIAL" "CHIP"
					( Origin gFrontEnd )
				)
				( attribute "PACK_TYPE" "0402"
					( Origin gFrontEnd )
				)
				( attribute "PART_NUMBER" "G21497-005"
					( Origin gFrontEnd )
				)
				( attribute "PHYS_PAGE" "114"
					( Origin gFrontEnd )
				)
				( attribute "ROOM" "CPU0"
					( Origin gFrontEnd )
				)
				( attribute "ROT" "0"
					( Origin gFrontEnd )
				)
				( attribute "SEC" "1"
					( Origin gFrontEnd )
				)
				( attribute "SEC_TYPE" "0402"
					( Origin gFrontEnd )
				)
				( attribute "TOLERANCE" "5%"
					( Origin gFrontEnd )
				)
				( attribute "VALUE" "0.0"
					( Origin gFrontEnd )
				)
				( attribute "VER" "1"
					( Origin gFrontEnd )
				)
				( attribute "WATTAGE" "1/16W"
					( Origin gFrontEnd )
				)
				( attribute "XY" "(-1275,2800)"
					( Origin gFrontEnd )
				)
				( attribute "CHIPS_PART_NAME" "RES"
					( Origin gPackager )
				)
				( attribute "CDS_PART_NAME" "RES_0402-0.0,5%,1/16W,CHIP,G21A"
					( Origin gPackager )
				)
				( attribute "GROUP" "AST2500"
					( Origin gFrontEnd )
				)
				( objectStatus "R7C2" )
			)
			( gate "@baseboard_fab2_lib.baseboard_fab2(sch_1):page125_i85"
				( attribute "BOM_COST" "SB"
					( Origin gFrontEnd )
				)
				( attribute "CDS_LIB" "mstr_discrete"
					( Origin gPackager )
				)
				( attribute "CDS_LOCATION" "R8D16"
					( Origin gPackager )
				)
				( attribute "CDS_SEC" "1"
					( Origin gPackager )
				)
				( attribute "LOCATION" "R8D16"
					( Origin gFrontEnd )
				)
				( attribute "MATERIAL" "CHIP"
					( Origin gFrontEnd )
				)
				( attribute "PACK_TYPE" "0402"
					( Origin gFrontEnd )
				)
				( attribute "PART_NUMBER" "G21796-016"
					( Origin gFrontEnd )
				)
				( attribute "PHYS_PAGE" "125"
					( Origin gFrontEnd )
				)
				( attribute "ROOM" "SB_HEADERS"
					( Origin gFrontEnd )
				)
				( attribute "ROT" "0"
					( Origin gFrontEnd )
				)
				( attribute "SEC" "1"
					( Origin gPackager )
				)
				( attribute "TOLERANCE" "1%"
					( Origin gFrontEnd )
				)
				( attribute "VALUE" "10.0K"
					( Origin gFrontEnd )
				)
				( attribute "VER" "2"
					( Origin gFrontEnd )
				)
				( attribute "WATTAGE" "1/16W"
					( Origin gFrontEnd )
				)
				( attribute "XY" "(-5050,3775)"
					( Origin gFrontEnd )
				)
				( attribute "CHIPS_PART_NAME" "RES"
					( Origin gPackager )
				)
				( attribute "CDS_PART_NAME" "RES_0402-10.0K,1%,1/16W,CHIP,GA"
					( Origin gPackager )
				)
				( objectStatus "R8D16" )
			)
			( gate "@baseboard_fab2_lib.baseboard_fab2(sch_1):page125_i86"
				( attribute "BOM_COST" "SB"
					( Origin gFrontEnd )
				)
				( attribute "CDS_LIB" "mstr_discrete"
					( Origin gPackager )
				)
				( attribute "CDS_LOCATION" "R7D1"
					( Origin gPackager )
				)
				( attribute "CDS_SEC" "1"
					( Origin gPackager )
				)
				( attribute "LOCATION" "R7D1"
					( Origin gFrontEnd )
				)
				( attribute "MATERIAL" "EMPTY"
					( Origin gFrontEnd )
				)
				( attribute "PACK_TYPE" "0402"
					( Origin gFrontEnd )
				)
				( attribute "PART_NUMBER" "G21796-026"
					( Origin gFrontEnd )
				)
				( attribute "PHYS_PAGE" "125"
					( Origin gFrontEnd )
				)
				( attribute "ROOM" "SB"
					( Origin gFrontEnd )
				)
				( attribute "ROT" "0"
					( Origin gFrontEnd )
				)
				( attribute "SEC" "1"
					( Origin gPackager )
				)
				( attribute "TOLERANCE" "1%"
					( Origin gFrontEnd )
				)
				( attribute "VALUE" "1.00K"
					( Origin gFrontEnd )
				)
				( attribute "VER" "2"
					( Origin gFrontEnd )
				)
				( attribute "WATTAGE" "1/16W"
					( Origin gFrontEnd )
				)
				( attribute "XY" "(-5050,3375)"
					( Origin gFrontEnd )
				)
				( attribute "CHIPS_PART_NAME" "RES"
					( Origin gPackager )
				)
				( attribute "CDS_PART_NAME" "RES_0402-1.00K,1%,1/16W,EMPTY,A"
					( Origin gPackager )
				)
				( objectStatus "R7D1" )
			)
			( gate "@baseboard_fab2_lib.baseboard_fab2(sch_1):page203_i135"
				( attribute "ATTRIBUTE" "1 OHM"
					( Origin gFrontEnd )
				)
				( attribute "CDS_LIB" "w_hdl"
					( Origin gPackager )
				)
				( attribute "CDS_LMAN_SYM_OUTLINE" "-50,75,50,-75"
					( Origin gPackager )
				)
				( attribute "LOCATION" "RT27"
					( Origin gFrontEnd )
				)
				( attribute "PACK_TYPE" "RCL_GP"
					( Origin gFrontEnd )
				)
				( attribute "PART_NUMBER" "64.1R005.55L"
					( Origin gFrontEnd )
				)
				( attribute "PHYS_PAGE" "203"
					( Origin gFrontEnd )
				)
				( attribute "POP" "NOPOP"
					( Origin gFrontEnd )
				)
				( attribute "RATED" "1/10W"
					( Origin gFrontEnd )
				)
				( attribute "ROT" "0"
					( Origin gFrontEnd )
				)
				( attribute "SEC" "1"
					( Origin gFrontEnd )
				)
				( attribute "SEC_TYPE" "RCL_GP"
					( Origin gFrontEnd )
				)
				( attribute "TOLERANCE" "1%"
					( Origin gFrontEnd )
				)
				( attribute "VALUE" "1R3F-GP"
					( Origin gFrontEnd )
				)
				( attribute "VER" "1"
					( Origin gFrontEnd )
				)
				( attribute "XY" "(-1975,550)"
					( Origin gFrontEnd )
				)
				( attribute "CHIPS_PART_NAME" "1R3F-GP"
					( Origin gPackager )
				)
				( attribute "CDS_PART_NAME" "1R3F-GP_RCL_GP-1R3F-GP,64.1R00A"
					( Origin gPackager )
				)
				( attribute "PACK_SIZE" "0603"
					( Origin gFrontEnd )
				)
				( attribute "CDS_LOCATION" "RT27"
					( Origin gPackager )
				)
				( attribute "CDS_SEC" "1"
					( Origin gPackager )
				)
				( objectStatus "RT27" )
			)
			( gate "@baseboard_fab2_lib.baseboard_fab2(sch_1):page203_i134"
				( attribute "ATTRIBUTE" "1 OHM"
					( Origin gFrontEnd )
				)
				( attribute "CDS_LIB" "w_hdl"
					( Origin gPackager )
				)
				( attribute "CDS_LMAN_SYM_OUTLINE" "-50,75,50,-75"
					( Origin gPackager )
				)
				( attribute "LOCATION" "RT26"
					( Origin gFrontEnd )
				)
				( attribute "PACK_TYPE" "RCL_GP"
					( Origin gFrontEnd )
				)
				( attribute "PART_NUMBER" "64.1R005.55L"
					( Origin gFrontEnd )
				)
				( attribute "PHYS_PAGE" "203"
					( Origin gFrontEnd )
				)
				( attribute "POP" "NOPOP"
					( Origin gFrontEnd )
				)
				( attribute "RATED" "1/10W"
					( Origin gFrontEnd )
				)
				( attribute "ROT" "0"
					( Origin gFrontEnd )
				)
				( attribute "SEC" "1"
					( Origin gFrontEnd )
				)
				( attribute "SEC_TYPE" "RCL_GP"
					( Origin gFrontEnd )
				)
				( attribute "TOLERANCE" "1%"
					( Origin gFrontEnd )
				)
				( attribute "VALUE" "1R3F-GP"
					( Origin gFrontEnd )
				)
				( attribute "VER" "1"
					( Origin gFrontEnd )
				)
				( attribute "XY" "(-1950,3200)"
					( Origin gFrontEnd )
				)
				( attribute "CHIPS_PART_NAME" "1R3F-GP"
					( Origin gPackager )
				)
				( attribute "CDS_PART_NAME" "1R3F-GP_RCL_GP-1R3F-GP,64.1R00A"
					( Origin gPackager )
				)
				( attribute "PACK_SIZE" "0603"
					( Origin gFrontEnd )
				)
				( attribute "CDS_LOCATION" "RT26"
					( Origin gPackager )
				)
				( attribute "CDS_SEC" "1"
					( Origin gPackager )
				)
				( objectStatus "RT26" )
			)
			( gate "@baseboard_fab2_lib.baseboard_fab2(sch_1):page225_i247"
				( attribute "CDS_LIB" "w_hdl"
					( Origin gPackager )
				)
				( attribute "CDS_LMAN_SYM_OUTLINE" "-50,25,50,-25"
					( Origin gPackager )
				)
				( attribute "LOCATION" "C22W2"
					( Origin gFrontEnd )
				)
				( attribute "PACK_TYPE" "SMD-BCG5"
					( Origin gFrontEnd )
				)
				( attribute "PART_NUMBER" "078.22611.0811"
					( Origin gFrontEnd )
				)
				( attribute "PHYS_PAGE" "225"
					( Origin gFrontEnd )
				)
				( attribute "ROT" "0"
					( Origin gFrontEnd )
				)
				( attribute "SEC" "1"
					( Origin gFrontEnd )
				)
				( attribute "SEC_TYPE" "SMD-BCG5"
					( Origin gFrontEnd )
				)
				( attribute "VALUE" "SC22U16V5MX-4-GP"
					( Origin gFrontEnd )
				)
				( attribute "VER" "1"
					( Origin gFrontEnd )
				)
				( attribute "XY" "(-950,1150)"
					( Origin gFrontEnd )
				)
				( attribute "CHIPS_PART_NAME" "SC22U16V5MX-4-GP"
					( Origin gPackager )
				)
				( attribute "CDS_PART_NAME" "SC22U16V5MX-4-GP_SMD-BCG5-SC22A"
					( Origin gPackager )
				)
				( attribute "CDS_LOCATION" "C22W2"
					( Origin gPackager )
				)
				( attribute "CDS_SEC" "1"
					( Origin gPackager )
				)
				( attribute "ATTRIBUTE" "22UF"
					( Origin gFrontEnd )
				)
				( attribute "PACK_SIZE" "0805"
					( Origin gFrontEnd )
				)
				( attribute "RATED" "16V"
					( Origin gFrontEnd )
				)
				( attribute "TOLERANCE" "20%"
					( Origin gFrontEnd )
				)
				( attribute "TYPE" "X6S"
					( Origin gFrontEnd )
				)
				( objectStatus "C22W2" )
			)
			( gate "@baseboard_fab2_lib.baseboard_fab2(sch_1):page225_i251"
				( attribute "CDS_LIB" "w_hdl"
					( Origin gPackager )
				)
				( attribute "CDS_LMAN_SYM_OUTLINE" "-50,25,50,-25"
					( Origin gPackager )
				)
				( attribute "LOCATION" "C22W4"
					( Origin gFrontEnd )
				)
				( attribute "PACK_TYPE" "SMD-BCG5"
					( Origin gFrontEnd )
				)
				( attribute "PART_NUMBER" "078.22611.0811"
					( Origin gFrontEnd )
				)
				( attribute "PHYS_PAGE" "225"
					( Origin gFrontEnd )
				)
				( attribute "ROT" "0"
					( Origin gFrontEnd )
				)
				( attribute "SEC" "1"
					( Origin gFrontEnd )
				)
				( attribute "SEC_TYPE" "SMD-BCG5"
					( Origin gFrontEnd )
				)
				( attribute "VALUE" "SC22U16V5MX-4-GP"
					( Origin gFrontEnd )
				)
				( attribute "VER" "1"
					( Origin gFrontEnd )
				)
				( attribute "XY" "(1150,1150)"
					( Origin gFrontEnd )
				)
				( attribute "CHIPS_PART_NAME" "SC22U16V5MX-4-GP"
					( Origin gPackager )
				)
				( attribute "CDS_PART_NAME" "SC22U16V5MX-4-GP_SMD-BCG5-SC22A"
					( Origin gPackager )
				)
				( attribute "CDS_LOCATION" "C22W4"
					( Origin gPackager )
				)
				( attribute "CDS_SEC" "1"
					( Origin gPackager )
				)
				( attribute "ATTRIBUTE" "22UF"
					( Origin gFrontEnd )
				)
				( attribute "PACK_SIZE" "0805"
					( Origin gFrontEnd )
				)
				( attribute "RATED" "16V"
					( Origin gFrontEnd )
				)
				( attribute "TOLERANCE" "20%"
					( Origin gFrontEnd )
				)
				( attribute "TYPE" "X6S"
					( Origin gFrontEnd )
				)
				( objectStatus "C22W4" )
			)
			( gate "@baseboard_fab2_lib.baseboard_fab2(sch_1):page176_i178"
				( attribute "CDS_LIB" "mstr_discrete"
					( Origin gPackager )
				)
				( attribute "CDS_LOCATION" "R6W50"
					( Origin gPackager )
				)
				( attribute "CDS_SEC" "1"
					( Origin gPackager )
				)
				( attribute "LOCATION" "R6W50"
					( Origin gFrontEnd )
				)
				( attribute "MATERIAL" "CHIP"
					( Origin gFrontEnd )
				)
				( attribute "PACK_TYPE" "0402"
					( Origin gFrontEnd )
				)
				( attribute "PART_NUMBER" "G21796-072"
					( Origin gFrontEnd )
				)
				( attribute "PHYS_PAGE" "176"
					( Origin gFrontEnd )
				)
				( attribute "ROT" "5"
					( Origin gFrontEnd )
				)
				( attribute "SEC" "1"
					( Origin gFrontEnd )
				)
				( attribute "SEC_TYPE" "0402"
					( Origin gFrontEnd )
				)
				( attribute "TOLERANCE" "1%"
					( Origin gFrontEnd )
				)
				( attribute "VALUE" "4.75K"
					( Origin gFrontEnd )
				)
				( attribute "VER" "1"
					( Origin gFrontEnd )
				)
				( attribute "WATTAGE" "1/16W"
					( Origin gFrontEnd )
				)
				( attribute "XY" "(-2150,4950)"
					( Origin gFrontEnd )
				)
				( attribute "CHIPS_PART_NAME" "RES"
					( Origin gPackager )
				)
				( attribute "CDS_PART_NAME" "RES_0402-4.75K,1%,1/16W,CHIP,GA"
					( Origin gPackager )
				)
				( attribute "POP" "NOPOP"
					( Origin gFrontEnd )
				)
				( objectStatus "R6W50" )
			)
			( gate "@baseboard_fab2_lib.baseboard_fab2(sch_1):page233_i280"
				( attribute "CDS_LIB" "w_hdl"
					( Origin gPackager )
				)
				( attribute "CDS_LMAN_SYM_OUTLINE" "-50,25,50,-25"
					( Origin gPackager )
				)
				( attribute "LOCATION" "C4G5"
					( Origin gFrontEnd )
				)
				( attribute "PACK_TYPE" "SMD-BCG5"
					( Origin gFrontEnd )
				)
				( attribute "PART_NUMBER" "078.22611.0811"
					( Origin gFrontEnd )
				)
				( attribute "PHYS_PAGE" "233"
					( Origin gFrontEnd )
				)
				( attribute "ROT" "0"
					( Origin gFrontEnd )
				)
				( attribute "SEC" "1"
					( Origin gFrontEnd )
				)
				( attribute "SEC_TYPE" "SMD-BCG5"
					( Origin gFrontEnd )
				)
				( attribute "VALUE" "SC22U16V5MX-4-GP"
					( Origin gFrontEnd )
				)
				( attribute "VER" "1"
					( Origin gFrontEnd )
				)
				( attribute "XY" "(-7300,3950)"
					( Origin gFrontEnd )
				)
				( attribute "CHIPS_PART_NAME" "SC22U16V5MX-4-GP"
					( Origin gPackager )
				)
				( attribute "CDS_PART_NAME" "SC22U16V5MX-4-GP_SMD-BCG5-SC22A"
					( Origin gPackager )
				)
				( attribute "CDS_LOCATION" "C4G5"
					( Origin gPackager )
				)
				( attribute "CDS_SEC" "1"
					( Origin gPackager )
				)
				( attribute "ATTRIBUTE" "22UF"
					( Origin gFrontEnd )
				)
				( attribute "PACK_SIZE" "0805"
					( Origin gFrontEnd )
				)
				( attribute "RATED" "16V"
					( Origin gFrontEnd )
				)
				( attribute "TOLERANCE" "20%"
					( Origin gFrontEnd )
				)
				( attribute "TYPE" "X6S"
					( Origin gFrontEnd )
				)
				( objectStatus "C4G5" )
			)
			( gate "@baseboard_fab2_lib.baseboard_fab2(sch_1):page232_i311"
				( attribute "CDS_LIB" "w_hdl"
					( Origin gPackager )
				)
				( attribute "CDS_LMAN_SYM_OUTLINE" "-50,25,50,-25"
					( Origin gPackager )
				)
				( attribute "LOCATION" "C22W7"
					( Origin gFrontEnd )
				)
				( attribute "PACK_TYPE" "SMD-BCG5"
					( Origin gFrontEnd )
				)
				( attribute "PART_NUMBER" "078.22611.0811"
					( Origin gFrontEnd )
				)
				( attribute "PHYS_PAGE" "232"
					( Origin gFrontEnd )
				)
				( attribute "ROT" "0"
					( Origin gFrontEnd )
				)
				( attribute "SEC" "1"
					( Origin gFrontEnd )
				)
				( attribute "SEC_TYPE" "SMD-BCG5"
					( Origin gFrontEnd )
				)
				( attribute "VALUE" "SC22U16V5MX-4-GP"
					( Origin gFrontEnd )
				)
				( attribute "VER" "1"
					( Origin gFrontEnd )
				)
				( attribute "XY" "(-7300,4100)"
					( Origin gFrontEnd )
				)
				( attribute "CHIPS_PART_NAME" "SC22U16V5MX-4-GP"
					( Origin gPackager )
				)
				( attribute "CDS_PART_NAME" "SC22U16V5MX-4-GP_SMD-BCG5-SC22A"
					( Origin gPackager )
				)
				( attribute "CDS_LOCATION" "C22W7"
					( Origin gPackager )
				)
				( attribute "CDS_SEC" "1"
					( Origin gPackager )
				)
				( attribute "ATTRIBUTE" "22UF"
					( Origin gFrontEnd )
				)
				( attribute "PACK_SIZE" "0805"
					( Origin gFrontEnd )
				)
				( attribute "RATED" "16V"
					( Origin gFrontEnd )
				)
				( attribute "TOLERANCE" "20%"
					( Origin gFrontEnd )
				)
				( attribute "TYPE" "X6S"
					( Origin gFrontEnd )
				)
				( objectStatus "C22W7" )
			)
			( gate "@baseboard_fab2_lib.baseboard_fab2(sch_1):page241_i95"
				( attribute "CDS_LIB" "w_hdl"
					( Origin gPackager )
				)
				( attribute "CDS_LMAN_SYM_OUTLINE" "-50,25,50,-25"
					( Origin gPackager )
				)
				( attribute "LOCATION" "C22W9"
					( Origin gFrontEnd )
				)
				( attribute "PACK_TYPE" "SMD-BCG5"
					( Origin gFrontEnd )
				)
				( attribute "PART_NUMBER" "078.22611.0811"
					( Origin gFrontEnd )
				)
				( attribute "PHYS_PAGE" "241"
					( Origin gFrontEnd )
				)
				( attribute "ROT" "0"
					( Origin gFrontEnd )
				)
				( attribute "SEC" "1"
					( Origin gFrontEnd )
				)
				( attribute "SEC_TYPE" "SMD-BCG5"
					( Origin gFrontEnd )
				)
				( attribute "VALUE" "SC22U16V5MX-4-GP"
					( Origin gFrontEnd )
				)
				( attribute "VER" "1"
					( Origin gFrontEnd )
				)
				( attribute "XY" "(-2100,4325)"
					( Origin gFrontEnd )
				)
				( attribute "CHIPS_PART_NAME" "SC22U16V5MX-4-GP"
					( Origin gPackager )
				)
				( attribute "CDS_PART_NAME" "SC22U16V5MX-4-GP_SMD-BCG5-SC22A"
					( Origin gPackager )
				)
				( attribute "CDS_LOCATION" "C22W9"
					( Origin gPackager )
				)
				( attribute "CDS_SEC" "1"
					( Origin gPackager )
				)
				( attribute "ATTRIBUTE" "22UF"
					( Origin gFrontEnd )
				)
				( attribute "PACK_SIZE" "0805"
					( Origin gFrontEnd )
				)
				( attribute "RATED" "16V"
					( Origin gFrontEnd )
				)
				( attribute "TOLERANCE" "20%"
					( Origin gFrontEnd )
				)
				( attribute "TYPE" "X6S"
					( Origin gFrontEnd )
				)
				( objectStatus "C22W9" )
			)
			( gate "@baseboard_fab2_lib.baseboard_fab2(sch_1):page241_i96"
				( attribute "CDS_LIB" "w_hdl"
					( Origin gPackager )
				)
				( attribute "CDS_LMAN_SYM_OUTLINE" "-50,25,50,-25"
					( Origin gPackager )
				)
				( attribute "LOCATION" "C22W8"
					( Origin gFrontEnd )
				)
				( attribute "PACK_TYPE" "SMD-BCG5"
					( Origin gFrontEnd )
				)
				( attribute "PART_NUMBER" "078.22611.0811"
					( Origin gFrontEnd )
				)
				( attribute "PHYS_PAGE" "241"
					( Origin gFrontEnd )
				)
				( attribute "ROT" "0"
					( Origin gFrontEnd )
				)
				( attribute "SEC" "1"
					( Origin gFrontEnd )
				)
				( attribute "SEC_TYPE" "SMD-BCG5"
					( Origin gFrontEnd )
				)
				( attribute "VALUE" "SC22U16V5MX-4-GP"
					( Origin gFrontEnd )
				)
				( attribute "VER" "1"
					( Origin gFrontEnd )
				)
				( attribute "XY" "(-2750,4325)"
					( Origin gFrontEnd )
				)
				( attribute "CHIPS_PART_NAME" "SC22U16V5MX-4-GP"
					( Origin gPackager )
				)
				( attribute "CDS_PART_NAME" "SC22U16V5MX-4-GP_SMD-BCG5-SC22A"
					( Origin gPackager )
				)
				( attribute "CDS_LOCATION" "C22W8"
					( Origin gPackager )
				)
				( attribute "CDS_SEC" "1"
					( Origin gPackager )
				)
				( attribute "ATTRIBUTE" "22UF"
					( Origin gFrontEnd )
				)
				( attribute "PACK_SIZE" "0805"
					( Origin gFrontEnd )
				)
				( attribute "RATED" "16V"
					( Origin gFrontEnd )
				)
				( attribute "TOLERANCE" "20%"
					( Origin gFrontEnd )
				)
				( attribute "TYPE" "X6S"
					( Origin gFrontEnd )
				)
				( objectStatus "C22W8" )
			)
			( gate "@baseboard_fab2_lib.baseboard_fab2(sch_1):page241_i98"
				( attribute "CDS_LIB" "w_hdl"
					( Origin gPackager )
				)
				( attribute "CDS_LMAN_SYM_OUTLINE" "-50,25,50,-25"
					( Origin gPackager )
				)
				( attribute "LOCATION" "C7E12"
					( Origin gFrontEnd )
				)
				( attribute "PACK_TYPE" "SMD-BCG5"
					( Origin gFrontEnd )
				)
				( attribute "PART_NUMBER" "078.22611.0811"
					( Origin gFrontEnd )
				)
				( attribute "PHYS_PAGE" "241"
					( Origin gFrontEnd )
				)
				( attribute "ROT" "0"
					( Origin gFrontEnd )
				)
				( attribute "SEC" "1"
					( Origin gFrontEnd )
				)
				( attribute "SEC_TYPE" "SMD-BCG5"
					( Origin gFrontEnd )
				)
				( attribute "VALUE" "SC22U16V5MX-4-GP"
					( Origin gFrontEnd )
				)
				( attribute "VER" "1"
					( Origin gFrontEnd )
				)
				( attribute "XY" "(-3050,4325)"
					( Origin gFrontEnd )
				)
				( attribute "CHIPS_PART_NAME" "SC22U16V5MX-4-GP"
					( Origin gPackager )
				)
				( attribute "CDS_PART_NAME" "SC22U16V5MX-4-GP_SMD-BCG5-SC22A"
					( Origin gPackager )
				)
				( attribute "CDS_LOCATION" "C7E12"
					( Origin gPackager )
				)
				( attribute "CDS_SEC" "1"
					( Origin gPackager )
				)
				( attribute "ATTRIBUTE" "22UF"
					( Origin gFrontEnd )
				)
				( attribute "PACK_SIZE" "0805"
					( Origin gFrontEnd )
				)
				( attribute "RATED" "16V"
					( Origin gFrontEnd )
				)
				( attribute "TOLERANCE" "20%"
					( Origin gFrontEnd )
				)
				( attribute "TYPE" "X6S"
					( Origin gFrontEnd )
				)
				( objectStatus "C7E12" )
			)
			( gate "@baseboard_fab2_lib.baseboard_fab2(sch_1):page240_i181"
				( attribute "CDS_LIB" "w_hdl"
					( Origin gPackager )
				)
				( attribute "CDS_LMAN_SYM_OUTLINE" "-50,25,50,-25"
					( Origin gPackager )
				)
				( attribute "LOCATION" "C9F1"
					( Origin gFrontEnd )
				)
				( attribute "PACK_TYPE" "SMD-BCG5"
					( Origin gFrontEnd )
				)
				( attribute "PART_NUMBER" "078.22611.0811"
					( Origin gFrontEnd )
				)
				( attribute "PHYS_PAGE" "240"
					( Origin gFrontEnd )
				)
				( attribute "ROT" "0"
					( Origin gFrontEnd )
				)
				( attribute "SEC" "1"
					( Origin gFrontEnd )
				)
				( attribute "SEC_TYPE" "SMD-BCG5"
					( Origin gFrontEnd )
				)
				( attribute "VALUE" "SC22U16V5MX-4-GP"
					( Origin gFrontEnd )
				)
				( attribute "VER" "1"
					( Origin gFrontEnd )
				)
				( attribute "XY" "(6700,4275)"
					( Origin gFrontEnd )
				)
				( attribute "CHIPS_PART_NAME" "SC22U16V5MX-4-GP"
					( Origin gPackager )
				)
				( attribute "CDS_PART_NAME" "SC22U16V5MX-4-GP_SMD-BCG5-SC22A"
					( Origin gPackager )
				)
				( attribute "CDS_LOCATION" "C9F1"
					( Origin gPackager )
				)
				( attribute "CDS_SEC" "1"
					( Origin gPackager )
				)
				( attribute "ATTRIBUTE" "22UF"
					( Origin gFrontEnd )
				)
				( attribute "PACK_SIZE" "0805"
					( Origin gFrontEnd )
				)
				( attribute "RATED" "16V"
					( Origin gFrontEnd )
				)
				( attribute "TOLERANCE" "20%"
					( Origin gFrontEnd )
				)
				( attribute "TYPE" "X6S"
					( Origin gFrontEnd )
				)
				( objectStatus "C9F1" )
			)
			( gate "@baseboard_fab2_lib.baseboard_fab2(sch_1):page231_i225"
				( attribute "CDS_LIB" "w_hdl"
					( Origin gPackager )
				)
				( attribute "CDS_LMAN_SYM_OUTLINE" "-50,25,50,-25"
					( Origin gPackager )
				)
				( attribute "LOCATION" "C22W10"
					( Origin gFrontEnd )
				)
				( attribute "PACK_TYPE" "SMD-BCG5"
					( Origin gFrontEnd )
				)
				( attribute "PART_NUMBER" "078.22611.0811"
					( Origin gFrontEnd )
				)
				( attribute "PHYS_PAGE" "231"
					( Origin gFrontEnd )
				)
				( attribute "ROT" "0"
					( Origin gFrontEnd )
				)
				( attribute "SEC" "1"
					( Origin gFrontEnd )
				)
				( attribute "SEC_TYPE" "SMD-BCG5"
					( Origin gFrontEnd )
				)
				( attribute "VALUE" "SC22U16V5MX-4-GP"
					( Origin gFrontEnd )
				)
				( attribute "VER" "1"
					( Origin gFrontEnd )
				)
				( attribute "XY" "(-6650,4325)"
					( Origin gFrontEnd )
				)
				( attribute "CHIPS_PART_NAME" "SC22U16V5MX-4-GP"
					( Origin gPackager )
				)
				( attribute "CDS_PART_NAME" "SC22U16V5MX-4-GP_SMD-BCG5-SC22A"
					( Origin gPackager )
				)
				( attribute "CDS_LOCATION" "C22W10"
					( Origin gPackager )
				)
				( attribute "CDS_SEC" "1"
					( Origin gPackager )
				)
				( attribute "ATTRIBUTE" "22UF"
					( Origin gFrontEnd )
				)
				( attribute "PACK_SIZE" "0805"
					( Origin gFrontEnd )
				)
				( attribute "RATED" "16V"
					( Origin gFrontEnd )
				)
				( attribute "TOLERANCE" "20%"
					( Origin gFrontEnd )
				)
				( attribute "TYPE" "X6S"
					( Origin gFrontEnd )
				)
				( objectStatus "C22W10" )
			)
			( gate "@baseboard_fab2_lib.baseboard_fab2(sch_1):page231_i226"
				( attribute "CDS_LIB" "w_hdl"
					( Origin gPackager )
				)
				( attribute "CDS_LMAN_SYM_OUTLINE" "-50,25,50,-25"
					( Origin gPackager )
				)
				( attribute "LOCATION" "C7F7"
					( Origin gFrontEnd )
				)
				( attribute "PACK_TYPE" "SMD-BCG5"
					( Origin gFrontEnd )
				)
				( attribute "PART_NUMBER" "078.22611.0811"
					( Origin gFrontEnd )
				)
				( attribute "PHYS_PAGE" "231"
					( Origin gFrontEnd )
				)
				( attribute "ROT" "0"
					( Origin gFrontEnd )
				)
				( attribute "SEC" "1"
					( Origin gFrontEnd )
				)
				( attribute "SEC_TYPE" "SMD-BCG5"
					( Origin gFrontEnd )
				)
				( attribute "VALUE" "SC22U16V5MX-4-GP"
					( Origin gFrontEnd )
				)
				( attribute "VER" "1"
					( Origin gFrontEnd )
				)
				( attribute "XY" "(-6950,4325)"
					( Origin gFrontEnd )
				)
				( attribute "CHIPS_PART_NAME" "SC22U16V5MX-4-GP"
					( Origin gPackager )
				)
				( attribute "CDS_PART_NAME" "SC22U16V5MX-4-GP_SMD-BCG5-SC22A"
					( Origin gPackager )
				)
				( attribute "CDS_LOCATION" "C7F7"
					( Origin gPackager )
				)
				( attribute "CDS_SEC" "1"
					( Origin gPackager )
				)
				( attribute "ATTRIBUTE" "22UF"
					( Origin gFrontEnd )
				)
				( attribute "PACK_SIZE" "0805"
					( Origin gFrontEnd )
				)
				( attribute "RATED" "16V"
					( Origin gFrontEnd )
				)
				( attribute "TOLERANCE" "20%"
					( Origin gFrontEnd )
				)
				( attribute "TYPE" "X6S"
					( Origin gFrontEnd )
				)
				( objectStatus "C7F7" )
			)
			( gate "@baseboard_fab2_lib.baseboard_fab2(sch_1):page240_i186"
				( attribute "CDS_LIB" "w_hdl"
					( Origin gPackager )
				)
				( attribute "CDS_LMAN_SYM_OUTLINE" "-50,25,50,-25"
					( Origin gPackager )
				)
				( attribute "LOCATION" "C22W12"
					( Origin gFrontEnd )
				)
				( attribute "PACK_TYPE" "SMD-BCG5"
					( Origin gFrontEnd )
				)
				( attribute "PART_NUMBER" "078.22611.0811"
					( Origin gFrontEnd )
				)
				( attribute "PHYS_PAGE" "240"
					( Origin gFrontEnd )
				)
				( attribute "ROT" "0"
					( Origin gFrontEnd )
				)
				( attribute "SEC" "1"
					( Origin gFrontEnd )
				)
				( attribute "SEC_TYPE" "SMD-BCG5"
					( Origin gFrontEnd )
				)
				( attribute "VALUE" "SC22U16V5MX-4-GP"
					( Origin gFrontEnd )
				)
				( attribute "VER" "1"
					( Origin gFrontEnd )
				)
				( attribute "XY" "(7800,4275)"
					( Origin gFrontEnd )
				)
				( attribute "CHIPS_PART_NAME" "SC22U16V5MX-4-GP"
					( Origin gPackager )
				)
				( attribute "CDS_PART_NAME" "SC22U16V5MX-4-GP_SMD-BCG5-SC22A"
					( Origin gPackager )
				)
				( attribute "CDS_LOCATION" "C22W12"
					( Origin gPackager )
				)
				( attribute "CDS_SEC" "1"
					( Origin gPackager )
				)
				( attribute "ATTRIBUTE" "22UF"
					( Origin gFrontEnd )
				)
				( attribute "PACK_SIZE" "0805"
					( Origin gFrontEnd )
				)
				( attribute "RATED" "16V"
					( Origin gFrontEnd )
				)
				( attribute "TOLERANCE" "20%"
					( Origin gFrontEnd )
				)
				( attribute "TYPE" "X6S"
					( Origin gFrontEnd )
				)
				( objectStatus "C22W12" )
			)
			( gate "@baseboard_fab2_lib.baseboard_fab2(sch_1):page214_i152"
				( attribute "CDS_LIB" "w_hdl"
					( Origin gPackager )
				)
				( attribute "CDS_LMAN_SYM_OUTLINE" "-50,25,50,-25"
					( Origin gPackager )
				)
				( attribute "LOCATION" "C22W14"
					( Origin gFrontEnd )
				)
				( attribute "PACK_TYPE" "SMD-BCG5"
					( Origin gFrontEnd )
				)
				( attribute "PART_NUMBER" "078.22611.0811"
					( Origin gFrontEnd )
				)
				( attribute "PHYS_PAGE" "214"
					( Origin gFrontEnd )
				)
				( attribute "ROT" "0"
					( Origin gFrontEnd )
				)
				( attribute "SEC" "1"
					( Origin gFrontEnd )
				)
				( attribute "SEC_TYPE" "SMD-BCG5"
					( Origin gFrontEnd )
				)
				( attribute "VALUE" "SC22U16V5MX-4-GP"
					( Origin gFrontEnd )
				)
				( attribute "VER" "1"
					( Origin gFrontEnd )
				)
				( attribute "XY" "(850,1200)"
					( Origin gFrontEnd )
				)
				( attribute "CHIPS_PART_NAME" "SC22U16V5MX-4-GP"
					( Origin gPackager )
				)
				( attribute "CDS_PART_NAME" "SC22U16V5MX-4-GP_SMD-BCG5-SC22A"
					( Origin gPackager )
				)
				( attribute "CDS_LOCATION" "C22W14"
					( Origin gPackager )
				)
				( attribute "CDS_SEC" "1"
					( Origin gPackager )
				)
				( attribute "ATTRIBUTE" "22UF"
					( Origin gFrontEnd )
				)
				( attribute "PACK_SIZE" "0805"
					( Origin gFrontEnd )
				)
				( attribute "RATED" "16V"
					( Origin gFrontEnd )
				)
				( attribute "TOLERANCE" "20%"
					( Origin gFrontEnd )
				)
				( attribute "TYPE" "X6S"
					( Origin gFrontEnd )
				)
				( objectStatus "C22W14" )
			)
			( gate "@baseboard_fab2_lib.baseboard_fab2(sch_1):page214_i154"
				( attribute "CDS_LIB" "w_hdl"
					( Origin gPackager )
				)
				( attribute "CDS_LMAN_SYM_OUTLINE" "-50,25,50,-25"
					( Origin gPackager )
				)
				( attribute "LOCATION" "C22W15"
					( Origin gFrontEnd )
				)
				( attribute "PACK_TYPE" "SMD-BCG5"
					( Origin gFrontEnd )
				)
				( attribute "PART_NUMBER" "078.22611.0811"
					( Origin gFrontEnd )
				)
				( attribute "PHYS_PAGE" "214"
					( Origin gFrontEnd )
				)
				( attribute "ROT" "0"
					( Origin gFrontEnd )
				)
				( attribute "SEC" "1"
					( Origin gFrontEnd )
				)
				( attribute "SEC_TYPE" "SMD-BCG5"
					( Origin gFrontEnd )
				)
				( attribute "VALUE" "SC22U16V5MX-4-GP"
					( Origin gFrontEnd )
				)
				( attribute "VER" "1"
					( Origin gFrontEnd )
				)
				( attribute "XY" "(1150,1200)"
					( Origin gFrontEnd )
				)
				( attribute "CHIPS_PART_NAME" "SC22U16V5MX-4-GP"
					( Origin gPackager )
				)
				( attribute "CDS_PART_NAME" "SC22U16V5MX-4-GP_SMD-BCG5-SC22A"
					( Origin gPackager )
				)
				( attribute "CDS_LOCATION" "C22W15"
					( Origin gPackager )
				)
				( attribute "CDS_SEC" "1"
					( Origin gPackager )
				)
				( attribute "ATTRIBUTE" "22UF"
					( Origin gFrontEnd )
				)
				( attribute "PACK_SIZE" "0805"
					( Origin gFrontEnd )
				)
				( attribute "RATED" "16V"
					( Origin gFrontEnd )
				)
				( attribute "TOLERANCE" "20%"
					( Origin gFrontEnd )
				)
				( attribute "TYPE" "X6S"
					( Origin gFrontEnd )
				)
				( objectStatus "C22W15" )
			)
			( gate "@baseboard_fab2_lib.baseboard_fab2(sch_1):page214_i156"
				( attribute "CDS_LIB" "w_hdl"
					( Origin gPackager )
				)
				( attribute "CDS_LMAN_SYM_OUTLINE" "-50,25,50,-25"
					( Origin gPackager )
				)
				( attribute "LOCATION" "C22W18"
					( Origin gFrontEnd )
				)
				( attribute "PACK_TYPE" "SMD-BCG5"
					( Origin gFrontEnd )
				)
				( attribute "PART_NUMBER" "078.22611.0811"
					( Origin gFrontEnd )
				)
				( attribute "PHYS_PAGE" "214"
					( Origin gFrontEnd )
				)
				( attribute "ROT" "0"
					( Origin gFrontEnd )
				)
				( attribute "SEC" "1"
					( Origin gFrontEnd )
				)
				( attribute "SEC_TYPE" "SMD-BCG5"
					( Origin gFrontEnd )
				)
				( attribute "VALUE" "SC22U16V5MX-4-GP"
					( Origin gFrontEnd )
				)
				( attribute "VER" "1"
					( Origin gFrontEnd )
				)
				( attribute "XY" "(2500,1200)"
					( Origin gFrontEnd )
				)
				( attribute "CHIPS_PART_NAME" "SC22U16V5MX-4-GP"
					( Origin gPackager )
				)
				( attribute "CDS_PART_NAME" "SC22U16V5MX-4-GP_SMD-BCG5-SC22A"
					( Origin gPackager )
				)
				( attribute "CDS_LOCATION" "C22W18"
					( Origin gPackager )
				)
				( attribute "CDS_SEC" "1"
					( Origin gPackager )
				)
				( attribute "ATTRIBUTE" "22UF"
					( Origin gFrontEnd )
				)
				( attribute "PACK_SIZE" "0805"
					( Origin gFrontEnd )
				)
				( attribute "RATED" "16V"
					( Origin gFrontEnd )
				)
				( attribute "TOLERANCE" "20%"
					( Origin gFrontEnd )
				)
				( attribute "TYPE" "X6S"
					( Origin gFrontEnd )
				)
				( objectStatus "C22W18" )
			)
			( gate "@baseboard_fab2_lib.baseboard_fab2(sch_1):page214_i158"
				( attribute "CDS_LIB" "w_hdl"
					( Origin gPackager )
				)
				( attribute "CDS_LMAN_SYM_OUTLINE" "-50,25,50,-25"
					( Origin gPackager )
				)
				( attribute "LOCATION" "C22W17"
					( Origin gFrontEnd )
				)
				( attribute "PACK_TYPE" "SMD-BCG5"
					( Origin gFrontEnd )
				)
				( attribute "PART_NUMBER" "078.22611.0811"
					( Origin gFrontEnd )
				)
				( attribute "PHYS_PAGE" "214"
					( Origin gFrontEnd )
				)
				( attribute "ROT" "0"
					( Origin gFrontEnd )
				)
				( attribute "SEC" "1"
					( Origin gFrontEnd )
				)
				( attribute "SEC_TYPE" "SMD-BCG5"
					( Origin gFrontEnd )
				)
				( attribute "VALUE" "SC22U16V5MX-4-GP"
					( Origin gFrontEnd )
				)
				( attribute "VER" "1"
					( Origin gFrontEnd )
				)
				( attribute "XY" "(2200,1200)"
					( Origin gFrontEnd )
				)
				( attribute "CHIPS_PART_NAME" "SC22U16V5MX-4-GP"
					( Origin gPackager )
				)
				( attribute "CDS_PART_NAME" "SC22U16V5MX-4-GP_SMD-BCG5-SC22A"
					( Origin gPackager )
				)
				( attribute "CDS_LOCATION" "C22W17"
					( Origin gPackager )
				)
				( attribute "CDS_SEC" "1"
					( Origin gPackager )
				)
				( attribute "ATTRIBUTE" "22UF"
					( Origin gFrontEnd )
				)
				( attribute "PACK_SIZE" "0805"
					( Origin gFrontEnd )
				)
				( attribute "RATED" "16V"
					( Origin gFrontEnd )
				)
				( attribute "TOLERANCE" "20%"
					( Origin gFrontEnd )
				)
				( attribute "TYPE" "X6S"
					( Origin gFrontEnd )
				)
				( objectStatus "C22W17" )
			)
			( gate "@baseboard_fab2_lib.baseboard_fab2(sch_1):page214_i160"
				( attribute "CDS_LIB" "w_hdl"
					( Origin gPackager )
				)
				( attribute "CDS_LMAN_SYM_OUTLINE" "-50,25,50,-25"
					( Origin gPackager )
				)
				( attribute "LOCATION" "C22W16"
					( Origin gFrontEnd )
				)
				( attribute "PACK_TYPE" "SMD-BCG5"
					( Origin gFrontEnd )
				)
				( attribute "PART_NUMBER" "078.22611.0811"
					( Origin gFrontEnd )
				)
				( attribute "PHYS_PAGE" "214"
					( Origin gFrontEnd )
				)
				( attribute "ROT" "0"
					( Origin gFrontEnd )
				)
				( attribute "SEC" "1"
					( Origin gFrontEnd )
				)
				( attribute "SEC_TYPE" "SMD-BCG5"
					( Origin gFrontEnd )
				)
				( attribute "VALUE" "SC22U16V5MX-4-GP"
					( Origin gFrontEnd )
				)
				( attribute "VER" "1"
					( Origin gFrontEnd )
				)
				( attribute "XY" "(1900,1200)"
					( Origin gFrontEnd )
				)
				( attribute "CHIPS_PART_NAME" "SC22U16V5MX-4-GP"
					( Origin gPackager )
				)
				( attribute "CDS_PART_NAME" "SC22U16V5MX-4-GP_SMD-BCG5-SC22A"
					( Origin gPackager )
				)
				( attribute "CDS_LOCATION" "C22W16"
					( Origin gPackager )
				)
				( attribute "CDS_SEC" "1"
					( Origin gPackager )
				)
				( attribute "ATTRIBUTE" "22UF"
					( Origin gFrontEnd )
				)
				( attribute "PACK_SIZE" "0805"
					( Origin gFrontEnd )
				)
				( attribute "RATED" "16V"
					( Origin gFrontEnd )
				)
				( attribute "TOLERANCE" "20%"
					( Origin gFrontEnd )
				)
				( attribute "TYPE" "X6S"
					( Origin gFrontEnd )
				)
				( objectStatus "C22W16" )
			)
			( gate "@baseboard_fab2_lib.baseboard_fab2(sch_1):page214_i161"
				( attribute "CDS_LIB" "w_hdl"
					( Origin gPackager )
				)
				( attribute "CDS_LMAN_SYM_OUTLINE" "-50,25,50,-25"
					( Origin gPackager )
				)
				( attribute "LOCATION" "C4E8"
					( Origin gFrontEnd )
				)
				( attribute "PACK_TYPE" "SMD-BCG5"
					( Origin gFrontEnd )
				)
				( attribute "PART_NUMBER" "078.22611.0811"
					( Origin gFrontEnd )
				)
				( attribute "PHYS_PAGE" "214"
					( Origin gFrontEnd )
				)
				( attribute "ROT" "0"
					( Origin gFrontEnd )
				)
				( attribute "SEC" "1"
					( Origin gFrontEnd )
				)
				( attribute "SEC_TYPE" "SMD-BCG5"
					( Origin gFrontEnd )
				)
				( attribute "VALUE" "SC22U16V5MX-4-GP"
					( Origin gFrontEnd )
				)
				( attribute "VER" "1"
					( Origin gFrontEnd )
				)
				( attribute "XY" "(1600,1200)"
					( Origin gFrontEnd )
				)
				( attribute "CHIPS_PART_NAME" "SC22U16V5MX-4-GP"
					( Origin gPackager )
				)
				( attribute "CDS_PART_NAME" "SC22U16V5MX-4-GP_SMD-BCG5-SC22A"
					( Origin gPackager )
				)
				( attribute "CDS_LOCATION" "C4E8"
					( Origin gPackager )
				)
				( attribute "CDS_SEC" "1"
					( Origin gPackager )
				)
				( attribute "ATTRIBUTE" "22UF"
					( Origin gFrontEnd )
				)
				( attribute "PACK_SIZE" "0805"
					( Origin gFrontEnd )
				)
				( attribute "RATED" "16V"
					( Origin gFrontEnd )
				)
				( attribute "TOLERANCE" "20%"
					( Origin gFrontEnd )
				)
				( attribute "TYPE" "X6S"
					( Origin gFrontEnd )
				)
				( objectStatus "C4E8" )
			)
			( gate "@baseboard_fab2_lib.baseboard_fab2(sch_1):page214_i164"
				( attribute "CDS_LIB" "w_hdl"
					( Origin gPackager )
				)
				( attribute "CDS_LMAN_SYM_OUTLINE" "-50,25,50,-25"
					( Origin gPackager )
				)
				( attribute "LOCATION" "C4E9"
					( Origin gFrontEnd )
				)
				( attribute "PACK_TYPE" "SMD-BCG5"
					( Origin gFrontEnd )
				)
				( attribute "PART_NUMBER" "078.22611.0811"
					( Origin gFrontEnd )
				)
				( attribute "PHYS_PAGE" "214"
					( Origin gFrontEnd )
				)
				( attribute "ROT" "0"
					( Origin gFrontEnd )
				)
				( attribute "SEC" "1"
					( Origin gFrontEnd )
				)
				( attribute "SEC_TYPE" "SMD-BCG5"
					( Origin gFrontEnd )
				)
				( attribute "VALUE" "SC22U16V5MX-4-GP"
					( Origin gFrontEnd )
				)
				( attribute "VER" "1"
					( Origin gFrontEnd )
				)
				( attribute "XY" "(2950,1200)"
					( Origin gFrontEnd )
				)
				( attribute "CHIPS_PART_NAME" "SC22U16V5MX-4-GP"
					( Origin gPackager )
				)
				( attribute "CDS_PART_NAME" "SC22U16V5MX-4-GP_SMD-BCG5-SC22A"
					( Origin gPackager )
				)
				( attribute "CDS_LOCATION" "C4E9"
					( Origin gPackager )
				)
				( attribute "CDS_SEC" "1"
					( Origin gPackager )
				)
				( attribute "ATTRIBUTE" "22UF"
					( Origin gFrontEnd )
				)
				( attribute "PACK_SIZE" "0805"
					( Origin gFrontEnd )
				)
				( attribute "RATED" "16V"
					( Origin gFrontEnd )
				)
				( attribute "TOLERANCE" "20%"
					( Origin gFrontEnd )
				)
				( attribute "TYPE" "X6S"
					( Origin gFrontEnd )
				)
				( objectStatus "C4E9" )
			)
			( gate "@baseboard_fab2_lib.baseboard_fab2(sch_1):page214_i166"
				( attribute "CDS_LIB" "w_hdl"
					( Origin gPackager )
				)
				( attribute "CDS_LMAN_SYM_OUTLINE" "-50,25,50,-25"
					( Origin gPackager )
				)
				( attribute "LOCATION" "C22W21"
					( Origin gFrontEnd )
				)
				( attribute "PACK_TYPE" "SMD-BCG5"
					( Origin gFrontEnd )
				)
				( attribute "PART_NUMBER" "078.22611.0811"
					( Origin gFrontEnd )
				)
				( attribute "PHYS_PAGE" "214"
					( Origin gFrontEnd )
				)
				( attribute "ROT" "0"
					( Origin gFrontEnd )
				)
				( attribute "SEC" "1"
					( Origin gFrontEnd )
				)
				( attribute "SEC_TYPE" "SMD-BCG5"
					( Origin gFrontEnd )
				)
				( attribute "VALUE" "SC22U16V5MX-4-GP"
					( Origin gFrontEnd )
				)
				( attribute "VER" "1"
					( Origin gFrontEnd )
				)
				( attribute "XY" "(3850,1200)"
					( Origin gFrontEnd )
				)
				( attribute "CHIPS_PART_NAME" "SC22U16V5MX-4-GP"
					( Origin gPackager )
				)
				( attribute "CDS_PART_NAME" "SC22U16V5MX-4-GP_SMD-BCG5-SC22A"
					( Origin gPackager )
				)
				( attribute "ATTRIBUTE" "22UF"
					( Origin gFrontEnd )
				)
				( attribute "PACK_SIZE" "0805"
					( Origin gFrontEnd )
				)
				( attribute "RATED" "16V"
					( Origin gFrontEnd )
				)
				( attribute "TOLERANCE" "20%"
					( Origin gFrontEnd )
				)
				( attribute "TYPE" "X6S"
					( Origin gFrontEnd )
				)
				( attribute "CDS_LOCATION" "C22W21"
					( Origin gPackager )
				)
				( attribute "CDS_SEC" "1"
					( Origin gPackager )
				)
				( objectStatus "C22W21" )
			)
			( gate "@baseboard_fab2_lib.baseboard_fab2(sch_1):page214_i168"
				( attribute "CDS_LIB" "w_hdl"
					( Origin gPackager )
				)
				( attribute "CDS_LMAN_SYM_OUTLINE" "-50,25,50,-25"
					( Origin gPackager )
				)
				( attribute "LOCATION" "C22W20"
					( Origin gFrontEnd )
				)
				( attribute "PACK_TYPE" "SMD-BCG5"
					( Origin gFrontEnd )
				)
				( attribute "PART_NUMBER" "078.22611.0811"
					( Origin gFrontEnd )
				)
				( attribute "PHYS_PAGE" "214"
					( Origin gFrontEnd )
				)
				( attribute "ROT" "0"
					( Origin gFrontEnd )
				)
				( attribute "SEC" "1"
					( Origin gFrontEnd )
				)
				( attribute "SEC_TYPE" "SMD-BCG5"
					( Origin gFrontEnd )
				)
				( attribute "VALUE" "SC22U16V5MX-4-GP"
					( Origin gFrontEnd )
				)
				( attribute "VER" "1"
					( Origin gFrontEnd )
				)
				( attribute "XY" "(3550,1200)"
					( Origin gFrontEnd )
				)
				( attribute "CHIPS_PART_NAME" "SC22U16V5MX-4-GP"
					( Origin gPackager )
				)
				( attribute "CDS_PART_NAME" "SC22U16V5MX-4-GP_SMD-BCG5-SC22A"
					( Origin gPackager )
				)
				( attribute "CDS_LOCATION" "C22W20"
					( Origin gPackager )
				)
				( attribute "CDS_SEC" "1"
					( Origin gPackager )
				)
				( attribute "ATTRIBUTE" "22UF"
					( Origin gFrontEnd )
				)
				( attribute "PACK_SIZE" "0805"
					( Origin gFrontEnd )
				)
				( attribute "RATED" "16V"
					( Origin gFrontEnd )
				)
				( attribute "TOLERANCE" "20%"
					( Origin gFrontEnd )
				)
				( attribute "TYPE" "X6S"
					( Origin gFrontEnd )
				)
				( objectStatus "C22W20" )
			)
			( gate "@baseboard_fab2_lib.baseboard_fab2(sch_1):page214_i169"
				( attribute "CDS_LIB" "w_hdl"
					( Origin gPackager )
				)
				( attribute "CDS_LMAN_SYM_OUTLINE" "-50,25,50,-25"
					( Origin gPackager )
				)
				( attribute "LOCATION" "C22W19"
					( Origin gFrontEnd )
				)
				( attribute "PACK_TYPE" "SMD-BCG5"
					( Origin gFrontEnd )
				)
				( attribute "PART_NUMBER" "078.22611.0811"
					( Origin gFrontEnd )
				)
				( attribute "PHYS_PAGE" "214"
					( Origin gFrontEnd )
				)
				( attribute "ROT" "0"
					( Origin gFrontEnd )
				)
				( attribute "SEC" "1"
					( Origin gFrontEnd )
				)
				( attribute "SEC_TYPE" "SMD-BCG5"
					( Origin gFrontEnd )
				)
				( attribute "VALUE" "SC22U16V5MX-4-GP"
					( Origin gFrontEnd )
				)
				( attribute "VER" "1"
					( Origin gFrontEnd )
				)
				( attribute "XY" "(3250,1200)"
					( Origin gFrontEnd )
				)
				( attribute "CHIPS_PART_NAME" "SC22U16V5MX-4-GP"
					( Origin gPackager )
				)
				( attribute "CDS_PART_NAME" "SC22U16V5MX-4-GP_SMD-BCG5-SC22A"
					( Origin gPackager )
				)
				( attribute "CDS_LOCATION" "C22W19"
					( Origin gPackager )
				)
				( attribute "CDS_SEC" "1"
					( Origin gPackager )
				)
				( attribute "ATTRIBUTE" "22UF"
					( Origin gFrontEnd )
				)
				( attribute "PACK_SIZE" "0805"
					( Origin gFrontEnd )
				)
				( attribute "RATED" "16V"
					( Origin gFrontEnd )
				)
				( attribute "TOLERANCE" "20%"
					( Origin gFrontEnd )
				)
				( attribute "TYPE" "X6S"
					( Origin gFrontEnd )
				)
				( objectStatus "C22W19" )
			)
			( gate "@baseboard_fab2_lib.baseboard_fab2(sch_1):page236_i162"
				( attribute "CDS_LIB" "w_hdl"
					( Origin gPackager )
				)
				( attribute "CDS_LMAN_SYM_OUTLINE" "-50,25,50,-25"
					( Origin gPackager )
				)
				( attribute "LOCATION" "C22W25"
					( Origin gFrontEnd )
				)
				( attribute "PACK_TYPE" "SMD-BCG5"
					( Origin gFrontEnd )
				)
				( attribute "PART_NUMBER" "078.22611.0811"
					( Origin gFrontEnd )
				)
				( attribute "PHYS_PAGE" "236"
					( Origin gFrontEnd )
				)
				( attribute "ROT" "0"
					( Origin gFrontEnd )
				)
				( attribute "SEC" "1"
					( Origin gFrontEnd )
				)
				( attribute "SEC_TYPE" "SMD-BCG5"
					( Origin gFrontEnd )
				)
				( attribute "VALUE" "SC22U16V5MX-4-GP"
					( Origin gFrontEnd )
				)
				( attribute "VER" "1"
					( Origin gFrontEnd )
				)
				( attribute "XY" "(12100,975)"
					( Origin gFrontEnd )
				)
				( attribute "CHIPS_PART_NAME" "SC22U16V5MX-4-GP"
					( Origin gPackager )
				)
				( attribute "CDS_PART_NAME" "SC22U16V5MX-4-GP_SMD-BCG5-SC22A"
					( Origin gPackager )
				)
				( attribute "ATTRIBUTE" "22UF"
					( Origin gFrontEnd )
				)
				( attribute "PACK_SIZE" "0805"
					( Origin gFrontEnd )
				)
				( attribute "RATED" "16V"
					( Origin gFrontEnd )
				)
				( attribute "TOLERANCE" "20%"
					( Origin gFrontEnd )
				)
				( attribute "TYPE" "X6S"
					( Origin gFrontEnd )
				)
				( attribute "CDS_LOCATION" "C22W25"
					( Origin gPackager )
				)
				( attribute "CDS_SEC" "1"
					( Origin gPackager )
				)
				( objectStatus "C22W25" )
			)
			( gate "@baseboard_fab2_lib.baseboard_fab2(sch_1):page236_i163"
				( attribute "CDS_LIB" "w_hdl"
					( Origin gPackager )
				)
				( attribute "CDS_LMAN_SYM_OUTLINE" "-50,25,50,-25"
					( Origin gPackager )
				)
				( attribute "LOCATION" "C22W27"
					( Origin gFrontEnd )
				)
				( attribute "PACK_TYPE" "SMD-BCG5"
					( Origin gFrontEnd )
				)
				( attribute "PART_NUMBER" "078.22611.0811"
					( Origin gFrontEnd )
				)
				( attribute "PHYS_PAGE" "236"
					( Origin gFrontEnd )
				)
				( attribute "ROT" "0"
					( Origin gFrontEnd )
				)
				( attribute "SEC" "1"
					( Origin gFrontEnd )
				)
				( attribute "SEC_TYPE" "SMD-BCG5"
					( Origin gFrontEnd )
				)
				( attribute "VALUE" "SC22U16V5MX-4-GP"
					( Origin gFrontEnd )
				)
				( attribute "VER" "1"
					( Origin gFrontEnd )
				)
				( attribute "XY" "(12700,975)"
					( Origin gFrontEnd )
				)
				( attribute "CHIPS_PART_NAME" "SC22U16V5MX-4-GP"
					( Origin gPackager )
				)
				( attribute "CDS_PART_NAME" "SC22U16V5MX-4-GP_SMD-BCG5-SC22A"
					( Origin gPackager )
				)
				( attribute "CDS_LOCATION" "C22W27"
					( Origin gPackager )
				)
				( attribute "CDS_SEC" "1"
					( Origin gPackager )
				)
				( attribute "ATTRIBUTE" "22UF"
					( Origin gFrontEnd )
				)
				( attribute "PACK_SIZE" "0805"
					( Origin gFrontEnd )
				)
				( attribute "RATED" "16V"
					( Origin gFrontEnd )
				)
				( attribute "TOLERANCE" "20%"
					( Origin gFrontEnd )
				)
				( attribute "TYPE" "X6S"
					( Origin gFrontEnd )
				)
				( objectStatus "C22W27" )
			)
			( gate "@baseboard_fab2_lib.baseboard_fab2(sch_1):page236_i165"
				( attribute "CDS_LIB" "w_hdl"
					( Origin gPackager )
				)
				( attribute "CDS_LMAN_SYM_OUTLINE" "-50,25,50,-25"
					( Origin gPackager )
				)
				( attribute "LOCATION" "C22W26"
					( Origin gFrontEnd )
				)
				( attribute "PACK_TYPE" "SMD-BCG5"
					( Origin gFrontEnd )
				)
				( attribute "PART_NUMBER" "078.22611.0811"
					( Origin gFrontEnd )
				)
				( attribute "PHYS_PAGE" "236"
					( Origin gFrontEnd )
				)
				( attribute "ROT" "0"
					( Origin gFrontEnd )
				)
				( attribute "SEC" "1"
					( Origin gFrontEnd )
				)
				( attribute "SEC_TYPE" "SMD-BCG5"
					( Origin gFrontEnd )
				)
				( attribute "VALUE" "SC22U16V5MX-4-GP"
					( Origin gFrontEnd )
				)
				( attribute "VER" "1"
					( Origin gFrontEnd )
				)
				( attribute "XY" "(12400,975)"
					( Origin gFrontEnd )
				)
				( attribute "CHIPS_PART_NAME" "SC22U16V5MX-4-GP"
					( Origin gPackager )
				)
				( attribute "CDS_PART_NAME" "SC22U16V5MX-4-GP_SMD-BCG5-SC22A"
					( Origin gPackager )
				)
				( attribute "CDS_LOCATION" "C22W26"
					( Origin gPackager )
				)
				( attribute "CDS_SEC" "1"
					( Origin gPackager )
				)
				( attribute "ATTRIBUTE" "22UF"
					( Origin gFrontEnd )
				)
				( attribute "PACK_SIZE" "0805"
					( Origin gFrontEnd )
				)
				( attribute "RATED" "16V"
					( Origin gFrontEnd )
				)
				( attribute "TOLERANCE" "20%"
					( Origin gFrontEnd )
				)
				( attribute "TYPE" "X6S"
					( Origin gFrontEnd )
				)
				( objectStatus "C22W26" )
			)
			( gate "@baseboard_fab2_lib.baseboard_fab2(sch_1):page236_i171"
				( attribute "CDS_LIB" "w_hdl"
					( Origin gPackager )
				)
				( attribute "CDS_LMAN_SYM_OUTLINE" "-50,25,50,-25"
					( Origin gPackager )
				)
				( attribute "LOCATION" "C22W22"
					( Origin gFrontEnd )
				)
				( attribute "PACK_TYPE" "SMD-BCG5"
					( Origin gFrontEnd )
				)
				( attribute "PART_NUMBER" "078.22611.0811"
					( Origin gFrontEnd )
				)
				( attribute "PHYS_PAGE" "236"
					( Origin gFrontEnd )
				)
				( attribute "ROT" "0"
					( Origin gFrontEnd )
				)
				( attribute "SEC" "1"
					( Origin gFrontEnd )
				)
				( attribute "SEC_TYPE" "SMD-BCG5"
					( Origin gFrontEnd )
				)
				( attribute "VALUE" "SC22U16V5MX-4-GP"
					( Origin gFrontEnd )
				)
				( attribute "VER" "1"
					( Origin gFrontEnd )
				)
				( attribute "XY" "(10850,975)"
					( Origin gFrontEnd )
				)
				( attribute "CHIPS_PART_NAME" "SC22U16V5MX-4-GP"
					( Origin gPackager )
				)
				( attribute "CDS_PART_NAME" "SC22U16V5MX-4-GP_SMD-BCG5-SC22A"
					( Origin gPackager )
				)
				( attribute "CDS_LOCATION" "C22W22"
					( Origin gPackager )
				)
				( attribute "CDS_SEC" "1"
					( Origin gPackager )
				)
				( attribute "ATTRIBUTE" "22UF"
					( Origin gFrontEnd )
				)
				( attribute "PACK_SIZE" "0805"
					( Origin gFrontEnd )
				)
				( attribute "RATED" "16V"
					( Origin gFrontEnd )
				)
				( attribute "TOLERANCE" "20%"
					( Origin gFrontEnd )
				)
				( attribute "TYPE" "X6S"
					( Origin gFrontEnd )
				)
				( objectStatus "C22W22" )
			)
			( gate "@baseboard_fab2_lib.baseboard_fab2(sch_1):page236_i172"
				( attribute "CDS_LIB" "w_hdl"
					( Origin gPackager )
				)
				( attribute "CDS_LMAN_SYM_OUTLINE" "-50,25,50,-25"
					( Origin gPackager )
				)
				( attribute "LOCATION" "C7A14"
					( Origin gFrontEnd )
				)
				( attribute "PACK_TYPE" "SMD-BCG5"
					( Origin gFrontEnd )
				)
				( attribute "PART_NUMBER" "078.22611.0811"
					( Origin gFrontEnd )
				)
				( attribute "PHYS_PAGE" "236"
					( Origin gFrontEnd )
				)
				( attribute "ROT" "0"
					( Origin gFrontEnd )
				)
				( attribute "SEC" "1"
					( Origin gFrontEnd )
				)
				( attribute "SEC_TYPE" "SMD-BCG5"
					( Origin gFrontEnd )
				)
				( attribute "VALUE" "SC22U16V5MX-4-GP"
					( Origin gFrontEnd )
				)
				( attribute "VER" "1"
					( Origin gFrontEnd )
				)
				( attribute "XY" "(10550,975)"
					( Origin gFrontEnd )
				)
				( attribute "CHIPS_PART_NAME" "SC22U16V5MX-4-GP"
					( Origin gPackager )
				)
				( attribute "CDS_PART_NAME" "SC22U16V5MX-4-GP_SMD-BCG5-SC22A"
					( Origin gPackager )
				)
				( attribute "CDS_LOCATION" "C7A14"
					( Origin gPackager )
				)
				( attribute "CDS_SEC" "1"
					( Origin gPackager )
				)
				( attribute "ATTRIBUTE" "22UF"
					( Origin gFrontEnd )
				)
				( attribute "PACK_SIZE" "0805"
					( Origin gFrontEnd )
				)
				( attribute "RATED" "16V"
					( Origin gFrontEnd )
				)
				( attribute "TOLERANCE" "20%"
					( Origin gFrontEnd )
				)
				( attribute "TYPE" "X6S"
					( Origin gFrontEnd )
				)
				( objectStatus "C7A14" )
			)
			( gate "@baseboard_fab2_lib.baseboard_fab2(sch_1):page212_i129"
				( attribute "CDS_LIB" "w_hdl"
					( Origin gPackager )
				)
				( attribute "CDS_LMAN_SYM_OUTLINE" "-50,25,50,-25"
					( Origin gPackager )
				)
				( attribute "LOCATION" "C22W31"
					( Origin gFrontEnd )
				)
				( attribute "PACK_TYPE" "SMD-BCG5"
					( Origin gFrontEnd )
				)
				( attribute "PART_NUMBER" "078.22611.0811"
					( Origin gFrontEnd )
				)
				( attribute "PHYS_PAGE" "212"
					( Origin gFrontEnd )
				)
				( attribute "ROT" "0"
					( Origin gFrontEnd )
				)
				( attribute "SEC" "1"
					( Origin gFrontEnd )
				)
				( attribute "SEC_TYPE" "SMD-BCG5"
					( Origin gFrontEnd )
				)
				( attribute "VALUE" "SC22U16V5MX-4-GP"
					( Origin gFrontEnd )
				)
				( attribute "VER" "1"
					( Origin gFrontEnd )
				)
				( attribute "XY" "(2300,2175)"
					( Origin gFrontEnd )
				)
				( attribute "CHIPS_PART_NAME" "SC22U16V5MX-4-GP"
					( Origin gPackager )
				)
				( attribute "CDS_PART_NAME" "SC22U16V5MX-4-GP_SMD-BCG5-SC22A"
					( Origin gPackager )
				)
				( attribute "CDS_LOCATION" "C22W31"
					( Origin gPackager )
				)
				( attribute "CDS_SEC" "1"
					( Origin gPackager )
				)
				( attribute "ATTRIBUTE" "22UF"
					( Origin gFrontEnd )
				)
				( attribute "PACK_SIZE" "0805"
					( Origin gFrontEnd )
				)
				( attribute "RATED" "16V"
					( Origin gFrontEnd )
				)
				( attribute "TOLERANCE" "20%"
					( Origin gFrontEnd )
				)
				( attribute "TYPE" "X6S"
					( Origin gFrontEnd )
				)
				( objectStatus "C22W31" )
			)
			( gate "@baseboard_fab2_lib.baseboard_fab2(sch_1):page212_i130"
				( attribute "CDS_LIB" "w_hdl"
					( Origin gPackager )
				)
				( attribute "CDS_LMAN_SYM_OUTLINE" "-50,25,50,-25"
					( Origin gPackager )
				)
				( attribute "LOCATION" "C7C8"
					( Origin gFrontEnd )
				)
				( attribute "PACK_TYPE" "SMD-BCG5"
					( Origin gFrontEnd )
				)
				( attribute "PART_NUMBER" "078.22611.0811"
					( Origin gFrontEnd )
				)
				( attribute "PHYS_PAGE" "212"
					( Origin gFrontEnd )
				)
				( attribute "ROT" "0"
					( Origin gFrontEnd )
				)
				( attribute "SEC" "1"
					( Origin gFrontEnd )
				)
				( attribute "SEC_TYPE" "SMD-BCG5"
					( Origin gFrontEnd )
				)
				( attribute "VALUE" "SC22U16V5MX-4-GP"
					( Origin gFrontEnd )
				)
				( attribute "VER" "1"
					( Origin gFrontEnd )
				)
				( attribute "XY" "(2000,2175)"
					( Origin gFrontEnd )
				)
				( attribute "CHIPS_PART_NAME" "SC22U16V5MX-4-GP"
					( Origin gPackager )
				)
				( attribute "CDS_PART_NAME" "SC22U16V5MX-4-GP_SMD-BCG5-SC22A"
					( Origin gPackager )
				)
				( attribute "CDS_LOCATION" "C7C8"
					( Origin gPackager )
				)
				( attribute "CDS_SEC" "1"
					( Origin gPackager )
				)
				( attribute "ATTRIBUTE" "22UF"
					( Origin gFrontEnd )
				)
				( attribute "PACK_SIZE" "0805"
					( Origin gFrontEnd )
				)
				( attribute "RATED" "16V"
					( Origin gFrontEnd )
				)
				( attribute "TOLERANCE" "20%"
					( Origin gFrontEnd )
				)
				( attribute "TYPE" "X6S"
					( Origin gFrontEnd )
				)
				( objectStatus "C7C8" )
			)
			( gate "@baseboard_fab2_lib.baseboard_fab2(sch_1):page212_i132"
				( attribute "CDS_LIB" "w_hdl"
					( Origin gPackager )
				)
				( attribute "CDS_LMAN_SYM_OUTLINE" "-50,25,50,-25"
					( Origin gPackager )
				)
				( attribute "LOCATION" "C22W30"
					( Origin gFrontEnd )
				)
				( attribute "PACK_TYPE" "SMD-BCG5"
					( Origin gFrontEnd )
				)
				( attribute "PART_NUMBER" "078.22611.0811"
					( Origin gFrontEnd )
				)
				( attribute "PHYS_PAGE" "212"
					( Origin gFrontEnd )
				)
				( attribute "ROT" "0"
					( Origin gFrontEnd )
				)
				( attribute "SEC" "1"
					( Origin gFrontEnd )
				)
				( attribute "SEC_TYPE" "SMD-BCG5"
					( Origin gFrontEnd )
				)
				( attribute "VALUE" "SC22U16V5MX-4-GP"
					( Origin gFrontEnd )
				)
				( attribute "VER" "1"
					( Origin gFrontEnd )
				)
				( attribute "XY" "(1550,2175)"
					( Origin gFrontEnd )
				)
				( attribute "CHIPS_PART_NAME" "SC22U16V5MX-4-GP"
					( Origin gPackager )
				)
				( attribute "CDS_PART_NAME" "SC22U16V5MX-4-GP_SMD-BCG5-SC22A"
					( Origin gPackager )
				)
				( attribute "CDS_LOCATION" "C22W30"
					( Origin gPackager )
				)
				( attribute "CDS_SEC" "1"
					( Origin gPackager )
				)
				( attribute "ATTRIBUTE" "22UF"
					( Origin gFrontEnd )
				)
				( attribute "PACK_SIZE" "0805"
					( Origin gFrontEnd )
				)
				( attribute "RATED" "16V"
					( Origin gFrontEnd )
				)
				( attribute "TOLERANCE" "20%"
					( Origin gFrontEnd )
				)
				( attribute "TYPE" "X6S"
					( Origin gFrontEnd )
				)
				( objectStatus "C22W30" )
			)
			( gate "@baseboard_fab2_lib.baseboard_fab2(sch_1):page212_i134"
				( attribute "CDS_LIB" "w_hdl"
					( Origin gPackager )
				)
				( attribute "CDS_LMAN_SYM_OUTLINE" "-50,25,50,-25"
					( Origin gPackager )
				)
				( attribute "LOCATION" "C22W29"
					( Origin gFrontEnd )
				)
				( attribute "PACK_TYPE" "SMD-BCG5"
					( Origin gFrontEnd )
				)
				( attribute "PART_NUMBER" "078.22611.0811"
					( Origin gFrontEnd )
				)
				( attribute "PHYS_PAGE" "212"
					( Origin gFrontEnd )
				)
				( attribute "ROT" "0"
					( Origin gFrontEnd )
				)
				( attribute "SEC" "1"
					( Origin gFrontEnd )
				)
				( attribute "SEC_TYPE" "SMD-BCG5"
					( Origin gFrontEnd )
				)
				( attribute "VALUE" "SC22U16V5MX-4-GP"
					( Origin gFrontEnd )
				)
				( attribute "VER" "1"
					( Origin gFrontEnd )
				)
				( attribute "XY" "(1250,2175)"
					( Origin gFrontEnd )
				)
				( attribute "CHIPS_PART_NAME" "SC22U16V5MX-4-GP"
					( Origin gPackager )
				)
				( attribute "CDS_PART_NAME" "SC22U16V5MX-4-GP_SMD-BCG5-SC22A"
					( Origin gPackager )
				)
				( attribute "CDS_LOCATION" "C22W29"
					( Origin gPackager )
				)
				( attribute "CDS_SEC" "1"
					( Origin gPackager )
				)
				( attribute "ATTRIBUTE" "22UF"
					( Origin gFrontEnd )
				)
				( attribute "PACK_SIZE" "0805"
					( Origin gFrontEnd )
				)
				( attribute "RATED" "16V"
					( Origin gFrontEnd )
				)
				( attribute "TOLERANCE" "20%"
					( Origin gFrontEnd )
				)
				( attribute "TYPE" "X6S"
					( Origin gFrontEnd )
				)
				( objectStatus "C22W29" )
			)
			( gate "@baseboard_fab2_lib.baseboard_fab2(sch_1):page212_i136"
				( attribute "CDS_LIB" "w_hdl"
					( Origin gPackager )
				)
				( attribute "CDS_LMAN_SYM_OUTLINE" "-50,25,50,-25"
					( Origin gPackager )
				)
				( attribute "LOCATION" "C22W28"
					( Origin gFrontEnd )
				)
				( attribute "PACK_TYPE" "SMD-BCG5"
					( Origin gFrontEnd )
				)
				( attribute "PART_NUMBER" "078.22611.0811"
					( Origin gFrontEnd )
				)
				( attribute "PHYS_PAGE" "212"
					( Origin gFrontEnd )
				)
				( attribute "ROT" "0"
					( Origin gFrontEnd )
				)
				( attribute "SEC" "1"
					( Origin gFrontEnd )
				)
				( attribute "SEC_TYPE" "SMD-BCG5"
					( Origin gFrontEnd )
				)
				( attribute "VALUE" "SC22U16V5MX-4-GP"
					( Origin gFrontEnd )
				)
				( attribute "VER" "1"
					( Origin gFrontEnd )
				)
				( attribute "XY" "(950,2175)"
					( Origin gFrontEnd )
				)
				( attribute "CHIPS_PART_NAME" "SC22U16V5MX-4-GP"
					( Origin gPackager )
				)
				( attribute "CDS_PART_NAME" "SC22U16V5MX-4-GP_SMD-BCG5-SC22A"
					( Origin gPackager )
				)
				( attribute "CDS_LOCATION" "C22W28"
					( Origin gPackager )
				)
				( attribute "CDS_SEC" "1"
					( Origin gPackager )
				)
				( attribute "ATTRIBUTE" "22UF"
					( Origin gFrontEnd )
				)
				( attribute "PACK_SIZE" "0805"
					( Origin gFrontEnd )
				)
				( attribute "RATED" "16V"
					( Origin gFrontEnd )
				)
				( attribute "TOLERANCE" "20%"
					( Origin gFrontEnd )
				)
				( attribute "TYPE" "X6S"
					( Origin gFrontEnd )
				)
				( objectStatus "C22W28" )
			)
			( gate "@baseboard_fab2_lib.baseboard_fab2(sch_1):page212_i138"
				( attribute "CDS_LIB" "w_hdl"
					( Origin gPackager )
				)
				( attribute "CDS_LMAN_SYM_OUTLINE" "-50,25,50,-25"
					( Origin gPackager )
				)
				( attribute "LOCATION" "C7C7"
					( Origin gFrontEnd )
				)
				( attribute "PACK_TYPE" "SMD-BCG5"
					( Origin gFrontEnd )
				)
				( attribute "PART_NUMBER" "078.22611.0811"
					( Origin gFrontEnd )
				)
				( attribute "PHYS_PAGE" "212"
					( Origin gFrontEnd )
				)
				( attribute "ROT" "0"
					( Origin gFrontEnd )
				)
				( attribute "SEC" "1"
					( Origin gFrontEnd )
				)
				( attribute "SEC_TYPE" "SMD-BCG5"
					( Origin gFrontEnd )
				)
				( attribute "VALUE" "SC22U16V5MX-4-GP"
					( Origin gFrontEnd )
				)
				( attribute "VER" "1"
					( Origin gFrontEnd )
				)
				( attribute "XY" "(650,2175)"
					( Origin gFrontEnd )
				)
				( attribute "CHIPS_PART_NAME" "SC22U16V5MX-4-GP"
					( Origin gPackager )
				)
				( attribute "CDS_PART_NAME" "SC22U16V5MX-4-GP_SMD-BCG5-SC22A"
					( Origin gPackager )
				)
				( attribute "CDS_LOCATION" "C7C7"
					( Origin gPackager )
				)
				( attribute "CDS_SEC" "1"
					( Origin gPackager )
				)
				( attribute "ATTRIBUTE" "22UF"
					( Origin gFrontEnd )
				)
				( attribute "PACK_SIZE" "0805"
					( Origin gFrontEnd )
				)
				( attribute "RATED" "16V"
					( Origin gFrontEnd )
				)
				( attribute "TOLERANCE" "20%"
					( Origin gFrontEnd )
				)
				( attribute "TYPE" "X6S"
					( Origin gFrontEnd )
				)
				( objectStatus "C7C7" )
			)
			( gate "@baseboard_fab2_lib.baseboard_fab2(sch_1):page125_i87"
				( attribute "BOM_COST" "SYS_CLOCK"
					( Origin gFrontEnd )
				)
				( attribute "CDS_LIB" "mstr_discrete"
					( Origin gPackager )
				)
				( attribute "CDS_LOCATION" "R8D13"
					( Origin gPackager )
				)
				( attribute "CDS_SEC" "1"
					( Origin gPackager )
				)
				( attribute "LOCATION" "R8D13"
					( Origin gFrontEnd )
				)
				( attribute "MATERIAL" "EMPTY"
					( Origin gFrontEnd )
				)
				( attribute "PACK_TYPE" "0402"
					( Origin gFrontEnd )
				)
				( attribute "PART_NUMBER" "G21796-016"
					( Origin gFrontEnd )
				)
				( attribute "PHYS_PAGE" "125"
					( Origin gFrontEnd )
				)
				( attribute "ROOM" "DB1200ZL"
					( Origin gFrontEnd )
				)
				( attribute "ROT" "0"
					( Origin gFrontEnd )
				)
				( attribute "SEC" "1"
					( Origin gFrontEnd )
				)
				( attribute "SEC_TYPE" "0402"
					( Origin gFrontEnd )
				)
				( attribute "TOLERANCE" "1%"
					( Origin gFrontEnd )
				)
				( attribute "VALUE" "10.0K"
					( Origin gFrontEnd )
				)
				( attribute "VER" "2"
					( Origin gFrontEnd )
				)
				( attribute "WATTAGE" "1/16W"
					( Origin gFrontEnd )
				)
				( attribute "XY" "(-925,4925)"
					( Origin gFrontEnd )
				)
				( attribute "CHIPS_PART_NAME" "RES"
					( Origin gPackager )
				)
				( attribute "CDS_PART_NAME" "RES_0402-10.0K,1%,1/16W,EMPTY,A"
					( Origin gPackager )
				)
				( objectStatus "R8D13" )
			)
			( gate "@baseboard_fab2_lib.baseboard_fab2(sch_1):page139_i244"
				( attribute "CDS_LIB" "w_hdl"
					( Origin gPackager )
				)
				( attribute "CDS_LMAN_SYM_OUTLINE" "-50,25,50,-25"
					( Origin gPackager )
				)
				( attribute "CDS_LOCATION" "C22W34"
					( Origin gPackager )
				)
				( attribute "CDS_SEC" "1"
					( Origin gPackager )
				)
				( attribute "LOCATION" "C22W34"
					( Origin gFrontEnd )
				)
				( attribute "PACK_TYPE" "SMD-BCG5"
					( Origin gFrontEnd )
				)
				( attribute "PART_NUMBER" "078.22611.0811"
					( Origin gFrontEnd )
				)
				( attribute "PHYS_PAGE" "139"
					( Origin gFrontEnd )
				)
				( attribute "POP" "NOPOP"
					( Origin gFrontEnd )
				)
				( attribute "ROT" "0"
					( Origin gFrontEnd )
				)
				( attribute "SEC" "1"
					( Origin gFrontEnd )
				)
				( attribute "SEC_TYPE" "SMD-BCG5"
					( Origin gFrontEnd )
				)
				( attribute "VALUE" "SC22U16V5MX-4-GP"
					( Origin gFrontEnd )
				)
				( attribute "VER" "1"
					( Origin gFrontEnd )
				)
				( attribute "XY" "(-5800,825)"
					( Origin gFrontEnd )
				)
				( attribute "CHIPS_PART_NAME" "SC22U16V5MX-4-GP"
					( Origin gPackager )
				)
				( attribute "CDS_PART_NAME" "SC22U16V5MX-4-GP_SMD-BCG5-SC22A"
					( Origin gPackager )
				)
				( attribute "ATTRIBUTE" "22UF"
					( Origin gFrontEnd )
				)
				( attribute "PACK_SIZE" "0805"
					( Origin gFrontEnd )
				)
				( attribute "RATED" "16V"
					( Origin gFrontEnd )
				)
				( attribute "TOLERANCE" "20%"
					( Origin gFrontEnd )
				)
				( attribute "TYPE" "X6S"
					( Origin gFrontEnd )
				)
				( attribute "GROUP" "NI_I210&RJ45"
					( Origin gFrontEnd )
				)
				( objectStatus "C22W34" )
			)
			( gate "@baseboard_fab2_lib.baseboard_fab2(sch_1):page139_i245"
				( attribute "CDS_LIB" "w_hdl"
					( Origin gPackager )
				)
				( attribute "CDS_LMAN_SYM_OUTLINE" "-50,25,50,-25"
					( Origin gPackager )
				)
				( attribute "CDS_LOCATION" "C9F2"
					( Origin gPackager )
				)
				( attribute "CDS_SEC" "1"
					( Origin gPackager )
				)
				( attribute "LOCATION" "C9F2"
					( Origin gFrontEnd )
				)
				( attribute "PACK_TYPE" "SMD-BCG5"
					( Origin gFrontEnd )
				)
				( attribute "PART_NUMBER" "078.22611.0811"
					( Origin gFrontEnd )
				)
				( attribute "PHYS_PAGE" "139"
					( Origin gFrontEnd )
				)
				( attribute "POP" "NOPOP"
					( Origin gFrontEnd )
				)
				( attribute "ROT" "0"
					( Origin gFrontEnd )
				)
				( attribute "SEC" "1"
					( Origin gFrontEnd )
				)
				( attribute "SEC_TYPE" "SMD-BCG5"
					( Origin gFrontEnd )
				)
				( attribute "VALUE" "SC22U16V5MX-4-GP"
					( Origin gFrontEnd )
				)
				( attribute "VER" "1"
					( Origin gFrontEnd )
				)
				( attribute "XY" "(-6100,825)"
					( Origin gFrontEnd )
				)
				( attribute "CHIPS_PART_NAME" "SC22U16V5MX-4-GP"
					( Origin gPackager )
				)
				( attribute "CDS_PART_NAME" "SC22U16V5MX-4-GP_SMD-BCG5-SC22A"
					( Origin gPackager )
				)
				( attribute "ATTRIBUTE" "22UF"
					( Origin gFrontEnd )
				)
				( attribute "PACK_SIZE" "0805"
					( Origin gFrontEnd )
				)
				( attribute "RATED" "16V"
					( Origin gFrontEnd )
				)
				( attribute "TOLERANCE" "20%"
					( Origin gFrontEnd )
				)
				( attribute "TYPE" "X6S"
					( Origin gFrontEnd )
				)
				( attribute "GROUP" "NI_I210&RJ45"
					( Origin gFrontEnd )
				)
				( objectStatus "C9F2" )
			)
			( gate "@baseboard_fab2_lib.baseboard_fab2(sch_1):page139_i246"
				( attribute "CDS_LIB" "w_hdl"
					( Origin gPackager )
				)
				( attribute "CDS_LMAN_SYM_OUTLINE" "-50,25,50,-25"
					( Origin gPackager )
				)
				( attribute "LOCATION" "C22W35"
					( Origin gFrontEnd )
				)
				( attribute "PACK_TYPE" "SMD-BCG5"
					( Origin gFrontEnd )
				)
				( attribute "PART_NUMBER" "078.22611.0811"
					( Origin gFrontEnd )
				)
				( attribute "PHYS_PAGE" "139"
					( Origin gFrontEnd )
				)
				( attribute "POP" "NOPOP"
					( Origin gFrontEnd )
				)
				( attribute "ROT" "0"
					( Origin gFrontEnd )
				)
				( attribute "SEC" "1"
					( Origin gFrontEnd )
				)
				( attribute "SEC_TYPE" "SMD-BCG5"
					( Origin gFrontEnd )
				)
				( attribute "VALUE" "SC22U16V5MX-4-GP"
					( Origin gFrontEnd )
				)
				( attribute "VER" "1"
					( Origin gFrontEnd )
				)
				( attribute "XY" "(-3700,800)"
					( Origin gFrontEnd )
				)
				( attribute "CHIPS_PART_NAME" "SC22U16V5MX-4-GP"
					( Origin gPackager )
				)
				( attribute "CDS_PART_NAME" "SC22U16V5MX-4-GP_SMD-BCG5-SC22A"
					( Origin gPackager )
				)
				( attribute "ATTRIBUTE" "22UF"
					( Origin gFrontEnd )
				)
				( attribute "PACK_SIZE" "0805"
					( Origin gFrontEnd )
				)
				( attribute "RATED" "16V"
					( Origin gFrontEnd )
				)
				( attribute "TOLERANCE" "20%"
					( Origin gFrontEnd )
				)
				( attribute "TYPE" "X6S"
					( Origin gFrontEnd )
				)
				( attribute "CDS_LOCATION" "C22W35"
					( Origin gPackager )
				)
				( attribute "CDS_SEC" "1"
					( Origin gPackager )
				)
				( attribute "GROUP" "NI_I210&RJ45"
					( Origin gFrontEnd )
				)
				( objectStatus "C22W35" )
			)
			( gate "@baseboard_fab2_lib.baseboard_fab2(sch_1):page139_i248"
				( attribute "CDS_LIB" "w_hdl"
					( Origin gPackager )
				)
				( attribute "CDS_LMAN_SYM_OUTLINE" "-50,25,50,-25"
					( Origin gPackager )
				)
				( attribute "LOCATION" "C9E6"
					( Origin gFrontEnd )
				)
				( attribute "PACK_TYPE" "SMD-BCG5"
					( Origin gFrontEnd )
				)
				( attribute "PART_NUMBER" "078.22611.0811"
					( Origin gFrontEnd )
				)
				( attribute "PHYS_PAGE" "139"
					( Origin gFrontEnd )
				)
				( attribute "POP" "NOPOP"
					( Origin gFrontEnd )
				)
				( attribute "ROT" "0"
					( Origin gFrontEnd )
				)
				( attribute "SEC" "1"
					( Origin gFrontEnd )
				)
				( attribute "SEC_TYPE" "SMD-BCG5"
					( Origin gFrontEnd )
				)
				( attribute "VALUE" "SC22U16V5MX-4-GP"
					( Origin gFrontEnd )
				)
				( attribute "VER" "1"
					( Origin gFrontEnd )
				)
				( attribute "XY" "(-4000,800)"
					( Origin gFrontEnd )
				)
				( attribute "CHIPS_PART_NAME" "SC22U16V5MX-4-GP"
					( Origin gPackager )
				)
				( attribute "CDS_PART_NAME" "SC22U16V5MX-4-GP_SMD-BCG5-SC22A"
					( Origin gPackager )
				)
				( attribute "ATTRIBUTE" "22UF"
					( Origin gFrontEnd )
				)
				( attribute "PACK_SIZE" "0805"
					( Origin gFrontEnd )
				)
				( attribute "RATED" "16V"
					( Origin gFrontEnd )
				)
				( attribute "TOLERANCE" "20%"
					( Origin gFrontEnd )
				)
				( attribute "TYPE" "X6S"
					( Origin gFrontEnd )
				)
				( attribute "CDS_LOCATION" "C9E6"
					( Origin gPackager )
				)
				( attribute "CDS_SEC" "1"
					( Origin gPackager )
				)
				( attribute "GROUP" "NI_I210&RJ45"
					( Origin gFrontEnd )
				)
				( objectStatus "C9E6" )
			)
			( gate "@baseboard_fab2_lib.baseboard_fab2(sch_1):page126_i27"
				( attribute "BOM_COST" "SYS_CLOCK"
					( Origin gFrontEnd )
				)
				( attribute "CDS_LIB" "mstr_discrete"
					( Origin gPackager )
				)
				( attribute "CDS_LOCATION" "R2N10"
					( Origin gPackager )
				)
				( attribute "CDS_SEC" "1"
					( Origin gPackager )
				)
				( attribute "LOCATION" "R2N10"
					( Origin gFrontEnd )
				)
				( attribute "MATERIAL" "EMPTY"
					( Origin gFrontEnd )
				)
				( attribute "PACK_TYPE" "0402"
					( Origin gFrontEnd )
				)
				( attribute "PART_NUMBER" "G21796-072"
					( Origin gFrontEnd )
				)
				( attribute "PHYS_PAGE" "126"
					( Origin gFrontEnd )
				)
				( attribute "ROOM" "DB1200ZL"
					( Origin gFrontEnd )
				)
				( attribute "ROT" "2"
					( Origin gFrontEnd )
				)
				( attribute "SEC" "1"
					( Origin gFrontEnd )
				)
				( attribute "SEC_TYPE" "0402"
					( Origin gFrontEnd )
				)
				( attribute "TOLERANCE" "1%"
					( Origin gFrontEnd )
				)
				( attribute "VALUE" "4.75K"
					( Origin gFrontEnd )
				)
				( attribute "VER" "2"
					( Origin gFrontEnd )
				)
				( attribute "WATTAGE" "1/16W"
					( Origin gFrontEnd )
				)
				( attribute "XY" "(-6325,4300)"
					( Origin gFrontEnd )
				)
				( attribute "CHIPS_PART_NAME" "RES"
					( Origin gPackager )
				)
				( attribute "CDS_PART_NAME" "RES_0402-4.75K,1%,1/16W,EMPTY,A"
					( Origin gPackager )
				)
				( objectStatus "R2N10" )
			)
			( gate "@baseboard_fab2_lib.baseboard_fab2(sch_1):page250_i29"
				( attribute "CDS_LIB" "mstr_discrete"
					( Origin gPackager )
				)
				( attribute "CDS_LOCATION" "Q1W1"
					( Origin gPackager )
				)
				( attribute "CDS_SEC" "1"
					( Origin gPackager )
				)
				( attribute "LOCATION" "Q1W1"
					( Origin gFrontEnd )
				)
				( attribute "MATERIAL" "FET"
					( Origin gFrontEnd )
				)
				( attribute "PACK_TYPE" "SOT23LF"
					( Origin gFrontEnd )
				)
				( attribute "PART_NUMBER" "C79254-001"
					( Origin gFrontEnd )
				)
				( attribute "PHYS_PAGE" "250"
					( Origin gFrontEnd )
				)
				( attribute "ROOM" "HOT_SWAP"
					( Origin gFrontEnd )
				)
				( attribute "ROT" "0"
					( Origin gFrontEnd )
				)
				( attribute "SEC" "1"
					( Origin gFrontEnd )
				)
				( attribute "SEC_TYPE" "SOT23LF"
					( Origin gFrontEnd )
				)
				( attribute "VALUE" "2N7002"
					( Origin gFrontEnd )
				)
				( attribute "VER" "8"
					( Origin gFrontEnd )
				)
				( attribute "XY" "(-7350,5375)"
					( Origin gFrontEnd )
				)
				( attribute "CHIPS_PART_NAME" "FET_N"
					( Origin gPackager )
				)
				( attribute "CDS_PART_NAME" "FET_N_SOT23LF-2N7002,FET,C7925A"
					( Origin gPackager )
				)
				( objectStatus "Q1W1" )
			)
			( gate "@baseboard_fab2_lib.baseboard_fab2(sch_1):page197_i109"
				( attribute "ATTRIBUTE" "665KOHM"
					( Origin gFrontEnd )
				)
				( attribute "CDS_LIB" "w_hdl"
					( Origin gPackager )
				)
				( attribute "CDS_LMAN_SYM_OUTLINE" "-50,75,50,-75"
					( Origin gPackager )
				)
				( attribute "LOCATION" "R12W10"
					( Origin gFrontEnd )
				)
				( attribute "PACK_TYPE" "SMD-RG2"
					( Origin gFrontEnd )
				)
				( attribute "PART_NUMBER" "064.6653D.06DD"
					( Origin gFrontEnd )
				)
				( attribute "PHYS_PAGE" "197"
					( Origin gFrontEnd )
				)
				( attribute "POP" "NOPOP"
					( Origin gFrontEnd )
				)
				( attribute "RATED" "1/16W"
					( Origin gFrontEnd )
				)
				( attribute "ROT" "1"
					( Origin gFrontEnd )
				)
				( attribute "SEC" "1"
					( Origin gFrontEnd )
				)
				( attribute "SEC_TYPE" "SMD-RG2"
					( Origin gFrontEnd )
				)
				( attribute "TOLERANCE" "0.1%"
					( Origin gFrontEnd )
				)
				( attribute "VALUE" "665KR2B-GP"
					( Origin gFrontEnd )
				)
				( attribute "VER" "1"
					( Origin gFrontEnd )
				)
				( attribute "XY" "(-4250,1700)"
					( Origin gFrontEnd )
				)
				( attribute "CHIPS_PART_NAME" "665KR2B-GP"
					( Origin gPackager )
				)
				( attribute "CDS_PART_NAME" "665KR2B-GP_SMD-RG2-665KR2B-GP,A"
					( Origin gPackager )
				)
				( attribute "PACK_SIZE" "0402"
					( Origin gFrontEnd )
				)
				( attribute "CDS_LOCATION" "R12W10"
					( Origin gPackager )
				)
				( attribute "CDS_SEC" "1"
					( Origin gPackager )
				)
				( objectStatus "R12W10" )
			)
			( gate "@baseboard_fab2_lib.baseboard_fab2(sch_1):page247_i120"
				( attribute "CDS_LIB" "w_hdl"
					( Origin gPackager )
				)
				( attribute "CDS_LMAN_SYM_OUTLINE" "-200,475,200,-475"
					( Origin gPackager )
				)
				( attribute "LOCATION" "U6W1"
					( Origin gFrontEnd )
				)
				( attribute "PACK_TYPE" "DISCRET-GC1"
					( Origin gFrontEnd )
				)
				( attribute "PART_NUMBER" "071.09555.000W"
					( Origin gFrontEnd )
				)
				( attribute "PHYS_PAGE" "247"
					( Origin gFrontEnd )
				)
				( attribute "ROT" "0"
					( Origin gFrontEnd )
				)
				( attribute "SEC" "1"
					( Origin gFrontEnd )
				)
				( attribute "SEC_TYPE" "DISCRET-GC1"
					( Origin gFrontEnd )
				)
				( attribute "VALUE" "TCA9555PWR-GP"
					( Origin gFrontEnd )
				)
				( attribute "VER" "1"
					( Origin gFrontEnd )
				)
				( attribute "XY" "(-3950,3675)"
					( Origin gFrontEnd )
				)
				( attribute "CHIPS_PART_NAME" "TCA9555PWR-GP"
					( Origin gPackager )
				)
				( attribute "CDS_PART_NAME" "TCA9555PWR-GP_DISCRET-GC1-TCA9A"
					( Origin gPackager )
				)
				( attribute "CDS_LOCATION" "U6W1"
					( Origin gPackager )
				)
				( attribute "CDS_SEC" "1"
					( Origin gPackager )
				)
				( objectStatus "U6W1" )
			)
			( gate "@baseboard_fab2_lib.baseboard_fab2(sch_1):page176_i139"
				( attribute "CDS_LIB" "dev_discrete"
					( Origin gPackager )
				)
				( attribute "CDS_LOCATION" "C6W10"
					( Origin gPackager )
				)
				( attribute "CDS_SEC" "1"
					( Origin gPackager )
				)
				( attribute "LOCATION" "C6W10"
					( Origin gFrontEnd )
				)
				( attribute "MATERIAL" "X7R"
					( Origin gFrontEnd )
				)
				( attribute "PACK_TYPE" "0402V"
					( Origin gFrontEnd )
				)
				( attribute "PART_NUMBER" "A36096-030"
					( Origin gFrontEnd )
				)
				( attribute "PHYS_PAGE" "176"
					( Origin gFrontEnd )
				)
				( attribute "ROOM" "VDDQ_KLM_PWR_VR"
					( Origin gFrontEnd )
				)
				( attribute "ROT" "0"
					( Origin gFrontEnd )
				)
				( attribute "SEC" "1"
					( Origin gFrontEnd )
				)
				( attribute "SEC_TYPE" "0402V"
					( Origin gFrontEnd )
				)
				( attribute "TOLERANCE" "10%"
					( Origin gFrontEnd )
				)
				( attribute "VALUE" "0.1UF"
					( Origin gFrontEnd )
				)
				( attribute "VER" "1"
					( Origin gFrontEnd )
				)
				( attribute "VOLTAGE" "16V"
					( Units "uVoltage" "V" 1.000000)
					( Origin gFrontEnd )
				)
				( attribute "XY" "(-200,1500)"
					( Origin gFrontEnd )
				)
				( attribute "CHIPS_PART_NAME" "CAP_A"
					( Origin gPackager )
				)
				( attribute "CDS_PART_NAME" "CAP_A_0402V-0.1UF,16V,10%,X7R,A"
					( Origin gPackager )
				)
				( objectStatus "C6W10" )
			)
			( gate "@baseboard_fab2_lib.baseboard_fab2(sch_1):page90_i100"
				( attribute "BOM_COST" "PROC"
					( Origin gFrontEnd )
				)
				( attribute "CDS_LIB" "mstr_discrete"
					( Origin gPackager )
				)
				( attribute "CDS_LOCATION" "R7P14"
					( Origin gPackager )
				)
				( attribute "CDS_SEC" "1"
					( Origin gPackager )
				)
				( attribute "LOCATION" "R7P14"
					( Origin gFrontEnd )
				)
				( attribute "MATERIAL" "CHIP"
					( Origin gFrontEnd )
				)
				( attribute "PACK_TYPE" "0402"
					( Origin gFrontEnd )
				)
				( attribute "PART_NUMBER" "G21796-294"
					( Origin gFrontEnd )
				)
				( attribute "PHYS_PAGE" "90"
					( Origin gFrontEnd )
				)
				( attribute "ROOM" "PROC_SIDEBAND"
					( Origin gFrontEnd )
				)
				( attribute "ROT" "0"
					( Origin gFrontEnd )
				)
				( attribute "SEC" "1"
					( Origin gFrontEnd )
				)
				( attribute "SEC_TYPE" "0402"
					( Origin gFrontEnd )
				)
				( attribute "TOLERANCE" "1.0%"
					( Origin gFrontEnd )
				)
				( attribute "VALUE" "240"
					( Origin gFrontEnd )
				)
				( attribute "VER" "1"
					( Origin gFrontEnd )
				)
				( attribute "WATTAGE" "1/16W"
					( Origin gFrontEnd )
				)
				( attribute "XY" "(-425,850)"
					( Origin gFrontEnd )
				)
				( attribute "CHIPS_PART_NAME" "RES"
					( Origin gPackager )
				)
				( attribute "CDS_PART_NAME" "RES_0402-240,1.0%,1/16W,CHIP,GA"
					( Origin gPackager )
				)
				( objectStatus "R7P14" )
			)
			( gate "@baseboard_fab2_lib.baseboard_fab2(sch_1):page90_i96"
				( attribute "BOM_COST" "PROC"
					( Origin gFrontEnd )
				)
				( attribute "CDS_LIB" "mstr_discrete"
					( Origin gPackager )
				)
				( attribute "CDS_LOCATION" "R5D4"
					( Origin gPackager )
				)
				( attribute "CDS_SEC" "1"
					( Origin gPackager )
				)
				( attribute "LOCATION" "R5D4"
					( Origin gFrontEnd )
				)
				( attribute "MATERIAL" "CHIP"
					( Origin gFrontEnd )
				)
				( attribute "PACK_TYPE" "0402"
					( Origin gFrontEnd )
				)
				( attribute "PART_NUMBER" "G21796-294"
					( Origin gFrontEnd )
				)
				( attribute "PHYS_PAGE" "90"
					( Origin gFrontEnd )
				)
				( attribute "ROOM" "PROC_SIDEBAND"
					( Origin gFrontEnd )
				)
				( attribute "ROT" "0"
					( Origin gFrontEnd )
				)
				( attribute "SEC" "1"
					( Origin gFrontEnd )
				)
				( attribute "SEC_TYPE" "0402"
					( Origin gFrontEnd )
				)
				( attribute "TOLERANCE" "1.0%"
					( Origin gFrontEnd )
				)
				( attribute "VALUE" "240"
					( Origin gFrontEnd )
				)
				( attribute "VER" "1"
					( Origin gFrontEnd )
				)
				( attribute "WATTAGE" "1/16W"
					( Origin gFrontEnd )
				)
				( attribute "XY" "(-2475,4000)"
					( Origin gFrontEnd )
				)
				( attribute "CHIPS_PART_NAME" "RES"
					( Origin gPackager )
				)
				( attribute "CDS_PART_NAME" "RES_0402-240,1.0%,1/16W,CHIP,GA"
					( Origin gPackager )
				)
				( objectStatus "R5D4" )
			)
			( gate "@baseboard_fab2_lib.baseboard_fab2(sch_1):page200_i246"
				( attribute "CDS_LIB" "mstr_discrete"
					( Origin gPackager )
				)
				( attribute "CDS_LOCATION" "R1D14"
					( Origin gPackager )
				)
				( attribute "CDS_SEC" "1"
					( Origin gPackager )
				)
				( attribute "LOCATION" "R1D14"
					( Origin gFrontEnd )
				)
				( attribute "MATERIAL" "CHIP"
					( Origin gFrontEnd )
				)
				( attribute "PACK_TYPE" "0402"
					( Origin gFrontEnd )
				)
				( attribute "PART_NUMBER" "G21796-099"
					( Origin gFrontEnd )
				)
				( attribute "PHYS_PAGE" "200"
					( Origin gFrontEnd )
				)
				( attribute "ROT" "0"
					( Origin gFrontEnd )
				)
				( attribute "SEC" "1"
					( Origin gFrontEnd )
				)
				( attribute "SEC_TYPE" "0402"
					( Origin gFrontEnd )
				)
				( attribute "TOLERANCE" "1%"
					( Origin gFrontEnd )
				)
				( attribute "VALUE" "105.0K"
					( Origin gFrontEnd )
				)
				( attribute "VER" "2"
					( Origin gFrontEnd )
				)
				( attribute "WATTAGE" "1/16W"
					( Origin gFrontEnd )
				)
				( attribute "XY" "(-4575,3450)"
					( Origin gFrontEnd )
				)
				( attribute "CHIPS_PART_NAME" "RES"
					( Origin gPackager )
				)
				( attribute "CDS_PART_NAME" "RES_0402-105.0K,1%,1/16W,CHIP,A"
					( Origin gPackager )
				)
				( attribute "BOM_DS" "64.15435.6DL"
					( Origin gFrontEnd )
				)
				( attribute "BOM_SS" "64.16535.6DL"
					( Origin gFrontEnd )
				)
				( objectStatus "R1D14" )
			)
			( gate "@baseboard_fab2_lib.baseboard_fab2(sch_1):page255_i95"
				( attribute "BOM_COST" "DEBUG"
					( Origin gFrontEnd )
				)
				( attribute "CDS_LIB" "mstr_discrete"
					( Origin gPackager )
				)
				( attribute "CDS_LOCATION" "Q25W4"
					( Origin gPackager )
				)
				( attribute "CDS_SEC" "1"
					( Origin gPackager )
				)
				( attribute "LOCATION" "Q25W4"
					( Origin gFrontEnd )
				)
				( attribute "MATERIAL" "FET"
					( Origin gFrontEnd )
				)
				( attribute "PACK_TYPE" "SMLF"
					( Origin gFrontEnd )
				)
				( attribute "PART_NUMBER" "D24280-001"
					( Origin gFrontEnd )
				)
				( attribute "PHYS_PAGE" "252"
					( Origin gFrontEnd )
				)
				( attribute "ROOM" "UART_MUX"
					( Origin gFrontEnd )
				)
				( attribute "ROT" "5"
					( Origin gFrontEnd )
				)
				( attribute "SEC" "1"
					( Origin gFrontEnd )
				)
				( attribute "SEC_TYPE" "SMLF"
					( Origin gFrontEnd )
				)
				( attribute "VALUE" "2N7002DW"
					( Origin gFrontEnd )
				)
				( attribute "VER" "5"
					( Origin gFrontEnd )
				)
				( attribute "XY" "(-8100,4750)"
					( Origin gFrontEnd )
				)
				( attribute "CHIPS_PART_NAME" "FET_N_DUAL"
					( Origin gPackager )
				)
				( attribute "CDS_PART_NAME" "FET_N_DUAL_SMLF-2N7002DW,FET,DA"
					( Origin gPackager )
				)
				( attribute "GROUP" "AST2500"
					( Origin gFrontEnd )
				)
				( objectStatus "Q25W4" )
			)
			( gate "@baseboard_fab2_lib.baseboard_fab2(sch_1):page255_i96"
				( attribute "BOM_COST" "DEBUG"
					( Origin gFrontEnd )
				)
				( attribute "CDS_LIB" "mstr_discrete"
					( Origin gPackager )
				)
				( attribute "CDS_LOCATION" "Q25W4"
					( Origin gPackager )
				)
				( attribute "LOCATION" "Q25W4"
					( Origin gFrontEnd )
				)
				( attribute "MATERIAL" "FET"
					( Origin gFrontEnd )
				)
				( attribute "PACK_TYPE" "SMLF"
					( Origin gFrontEnd )
				)
				( attribute "PART_NUMBER" "D24280-001"
					( Origin gFrontEnd )
				)
				( attribute "PHYS_PAGE" "252"
					( Origin gFrontEnd )
				)
				( attribute "ROOM" "UART_MUX"
					( Origin gFrontEnd )
				)
				( attribute "ROT" "5"
					( Origin gFrontEnd )
				)
				( attribute "SEC" "2"
					( Origin gFrontEnd )
				)
				( attribute "SEC_TYPE" "SMLF"
					( Origin gFrontEnd )
				)
				( attribute "VALUE" "2N7002DW"
					( Origin gFrontEnd )
				)
				( attribute "VER" "5"
					( Origin gFrontEnd )
				)
				( attribute "XY" "(-8100,3500)"
					( Origin gFrontEnd )
				)
				( attribute "CHIPS_PART_NAME" "FET_N_DUAL"
					( Origin gPackager )
				)
				( attribute "CDS_PART_NAME" "FET_N_DUAL_SMLF-2N7002DW,FET,DA"
					( Origin gPackager )
				)
				( attribute "CDS_SEC" "2"
					( Origin gPackager )
				)
				( attribute "GROUP" "AST2500"
					( Origin gFrontEnd )
				)
				( objectStatus "Q25W4" )
			)
			( gate "@baseboard_fab2_lib.baseboard_fab2(sch_1):page113_i273"
				( attribute "CDS_LIB" "mstr_discrete"
					( Origin gPackager )
				)
				( attribute "LOCATION" "R5W2"
					( Origin gFrontEnd )
				)
				( attribute "MATERIAL" "CHIP"
					( Origin gFrontEnd )
				)
				( attribute "PACK_TYPE" "0402"
					( Origin gFrontEnd )
				)
				( attribute "PART_NUMBER" "G21497-005"
					( Origin gFrontEnd )
				)
				( attribute "PHYS_PAGE" "113"
					( Origin gFrontEnd )
				)
				( attribute "ROT" "0"
					( Origin gFrontEnd )
				)
				( attribute "TOLERANCE" "5%"
					( Origin gFrontEnd )
				)
				( attribute "VALUE" "0.0"
					( Origin gFrontEnd )
				)
				( attribute "VER" "1"
					( Origin gFrontEnd )
				)
				( attribute "WATTAGE" "1/16W"
					( Origin gFrontEnd )
				)
				( attribute "XY" "(1600,2375)"
					( Origin gFrontEnd )
				)
				( attribute "CHIPS_PART_NAME" "RES"
					( Origin gPackager )
				)
				( attribute "CDS_PART_NAME" "RES_0402-0.0,5%,1/16W,CHIP,G21A"
					( Origin gPackager )
				)
				( attribute "CDS_LOCATION" "R5W2"
					( Origin gPackager )
				)
				( attribute "CDS_SEC" "1"
					( Origin gPackager )
				)
				( attribute "SEC" "1"
					( Origin gPackager )
				)
				( attribute "GROUP" "MCP"
					( Origin gFrontEnd )
				)
				( objectStatus "R5W2" )
			)
			( gate "@baseboard_fab2_lib.baseboard_fab2(sch_1):page113_i272"
				( attribute "CDS_LIB" "mstr_discrete"
					( Origin gPackager )
				)
				( attribute "CDS_LOCATION" "R5W1"
					( Origin gPackager )
				)
				( attribute "CDS_SEC" "1"
					( Origin gPackager )
				)
				( attribute "LOCATION" "R5W1"
					( Origin gFrontEnd )
				)
				( attribute "MATERIAL" "CHIP"
					( Origin gFrontEnd )
				)
				( attribute "PACK_TYPE" "0402"
					( Origin gFrontEnd )
				)
				( attribute "PART_NUMBER" "G21497-005"
					( Origin gFrontEnd )
				)
				( attribute "PHYS_PAGE" "113"
					( Origin gFrontEnd )
				)
				( attribute "ROT" "0"
					( Origin gFrontEnd )
				)
				( attribute "SEC" "1"
					( Origin gFrontEnd )
				)
				( attribute "SEC_TYPE" "0402"
					( Origin gFrontEnd )
				)
				( attribute "TOLERANCE" "5%"
					( Origin gFrontEnd )
				)
				( attribute "VALUE" "0.0"
					( Origin gFrontEnd )
				)
				( attribute "VER" "1"
					( Origin gFrontEnd )
				)
				( attribute "WATTAGE" "1/16W"
					( Origin gFrontEnd )
				)
				( attribute "XY" "(1600,3750)"
					( Origin gFrontEnd )
				)
				( attribute "CHIPS_PART_NAME" "RES"
					( Origin gPackager )
				)
				( attribute "CDS_PART_NAME" "RES_0402-0.0,5%,1/16W,CHIP,G21A"
					( Origin gPackager )
				)
				( attribute "GROUP" "MCP"
					( Origin gFrontEnd )
				)
				( objectStatus "R5W1" )
			)
			( gate "@baseboard_fab2_lib.baseboard_fab2(sch_1):page113_i271"
				( attribute "CDS_LIB" "mstr_discrete"
					( Origin gPackager )
				)
				( attribute "LOCATION" "R6M8"
					( Origin gFrontEnd )
				)
				( attribute "MATERIAL" "CHIP"
					( Origin gFrontEnd )
				)
				( attribute "PACK_TYPE" "0402"
					( Origin gFrontEnd )
				)
				( attribute "PART_NUMBER" "G21796-026"
					( Origin gFrontEnd )
				)
				( attribute "PHYS_PAGE" "113"
					( Origin gFrontEnd )
				)
				( attribute "ROOM" "PROC_SIDEBAND"
					( Origin gFrontEnd )
				)
				( attribute "ROT" "0"
					( Origin gFrontEnd )
				)
				( attribute "SEC" "1"
					( Origin gFrontEnd )
				)
				( attribute "SEC_TYPE" "0402"
					( Origin gFrontEnd )
				)
				( attribute "TOLERANCE" "1%"
					( Origin gFrontEnd )
				)
				( attribute "VALUE" "1.00K"
					( Origin gFrontEnd )
				)
				( attribute "VER" "2"
					( Origin gFrontEnd )
				)
				( attribute "WATTAGE" "1/16W"
					( Origin gFrontEnd )
				)
				( attribute "XY" "(2450,1825)"
					( Origin gFrontEnd )
				)
				( attribute "CHIPS_PART_NAME" "RES"
					( Origin gPackager )
				)
				( attribute "CDS_PART_NAME" "RES_0402-1.00K,1%,1/16W,CHIP,GA"
					( Origin gPackager )
				)
				( attribute "CDS_LOCATION" "R6M8"
					( Origin gPackager )
				)
				( attribute "CDS_SEC" "1"
					( Origin gPackager )
				)
				( attribute "GROUP" "MCP"
					( Origin gFrontEnd )
				)
				( objectStatus "R6M8" )
			)
			( gate "@baseboard_fab2_lib.baseboard_fab2(sch_1):page113_i270"
				( attribute "CDS_LIB" "mstr_discrete"
					( Origin gPackager )
				)
				( attribute "LOCATION" "R4R6"
					( Origin gFrontEnd )
				)
				( attribute "MATERIAL" "CHIP"
					( Origin gFrontEnd )
				)
				( attribute "PACK_TYPE" "0402"
					( Origin gFrontEnd )
				)
				( attribute "PART_NUMBER" "G21796-026"
					( Origin gFrontEnd )
				)
				( attribute "PHYS_PAGE" "113"
					( Origin gFrontEnd )
				)
				( attribute "ROOM" "PROC_SIDEBAND"
					( Origin gFrontEnd )
				)
				( attribute "ROT" "0"
					( Origin gFrontEnd )
				)
				( attribute "SEC" "1"
					( Origin gFrontEnd )
				)
				( attribute "SEC_TYPE" "0402"
					( Origin gFrontEnd )
				)
				( attribute "TOLERANCE" "1%"
					( Origin gFrontEnd )
				)
				( attribute "VALUE" "1.00K"
					( Origin gFrontEnd )
				)
				( attribute "VER" "2"
					( Origin gFrontEnd )
				)
				( attribute "WATTAGE" "1/16W"
					( Origin gFrontEnd )
				)
				( attribute "XY" "(2450,3200)"
					( Origin gFrontEnd )
				)
				( attribute "CHIPS_PART_NAME" "RES"
					( Origin gPackager )
				)
				( attribute "CDS_PART_NAME" "RES_0402-1.00K,1%,1/16W,CHIP,GA"
					( Origin gPackager )
				)
				( attribute "CDS_LOCATION" "R4R6"
					( Origin gPackager )
				)
				( attribute "CDS_SEC" "1"
					( Origin gPackager )
				)
				( attribute "GROUP" "MCP"
					( Origin gFrontEnd )
				)
				( objectStatus "R4R6" )
			)
			( gate "@baseboard_fab2_lib.baseboard_fab2(sch_1):page118_i167"
				( attribute "BOM_COST" "SB"
					( Origin gFrontEnd )
				)
				( attribute "CDS_LIB" "mstr_discrete"
					( Origin gPackager )
				)
				( attribute "CDS_LOCATION" "R7W1"
					( Origin gPackager )
				)
				( attribute "CDS_SEC" "1"
					( Origin gPackager )
				)
				( attribute "LOCATION" "R7W1"
					( Origin gFrontEnd )
				)
				( attribute "MATERIAL" "CHIP"
					( Origin gFrontEnd )
				)
				( attribute "PACK_TYPE" "0402"
					( Origin gFrontEnd )
				)
				( attribute "PART_NUMBER" "G21497-005"
					( Origin gFrontEnd )
				)
				( attribute "PHYS_PAGE" "118"
					( Origin gFrontEnd )
				)
				( attribute "ROOM" "SB"
					( Origin gFrontEnd )
				)
				( attribute "ROT" "0"
					( Origin gFrontEnd )
				)
				( attribute "SEC" "1"
					( Origin gFrontEnd )
				)
				( attribute "SEC_TYPE" "0402"
					( Origin gFrontEnd )
				)
				( attribute "TOLERANCE" "5%"
					( Origin gFrontEnd )
				)
				( attribute "VALUE" "0.0"
					( Origin gFrontEnd )
				)
				( attribute "VER" "1"
					( Origin gFrontEnd )
				)
				( attribute "WATTAGE" "1/16W"
					( Origin gFrontEnd )
				)
				( attribute "XY" "(-6650,4075)"
					( Origin gFrontEnd )
				)
				( attribute "CHIPS_PART_NAME" "RES"
					( Origin gPackager )
				)
				( attribute "CDS_PART_NAME" "RES_0402-0.0,5%,1/16W,CHIP,G21A"
					( Origin gPackager )
				)
				( objectStatus "R7W1" )
			)
			( gate "@baseboard_fab2_lib.baseboard_fab2(sch_1):page199_i131"
				( attribute "CDS_LIB" "w_hdl"
					( Origin gPackager )
				)
				( attribute "CDS_LMAN_SYM_OUTLINE" "-50,125,50,-125"
					( Origin gPackager )
				)
				( attribute "LOCATION" "J1B4"
					( Origin gFrontEnd )
				)
				( attribute "PACK_TYPE" "CONN-G3"
					( Origin gFrontEnd )
				)
				( attribute "PART_NUMBER" "021.D0139.0103"
					( Origin gFrontEnd )
				)
				( attribute "PHYS_PAGE" "199"
					( Origin gFrontEnd )
				)
				( attribute "ROT" "0"
					( Origin gFrontEnd )
				)
				( attribute "SEC" "1"
					( Origin gFrontEnd )
				)
				( attribute "SEC_TYPE" "CONN-G3"
					( Origin gFrontEnd )
				)
				( attribute "VALUE" "CLX-CONN3A-1-GP"
					( Origin gFrontEnd )
				)
				( attribute "VER" "1"
					( Origin gFrontEnd )
				)
				( attribute "XY" "(-7750,725)"
					( Origin gFrontEnd )
				)
				( attribute "CHIPS_PART_NAME" "CLX-CONN3A-1-GP"
					( Origin gPackager )
				)
				( attribute "CDS_PART_NAME" "CLX-CONN3A-1-GP_CONN-G3-CLX-COA"
					( Origin gPackager )
				)
				( attribute "CDS_LOCATION" "J1B4"
					( Origin gPackager )
				)
				( attribute "CDS_SEC" "1"
					( Origin gPackager )
				)
				( objectStatus "J1B4" )
			)
			( gate "@baseboard_fab2_lib.baseboard_fab2(sch_1):page253_i5"
				( attribute "BOM_COST" "MIO_USB"
					( Origin gFrontEnd )
				)
				( attribute "CDS_LIB" "mstr_discrete"
					( Origin gPackager )
				)
				( attribute "CDS_LOCATION" "CR30W1"
					( Origin gPackager )
				)
				( attribute "CDS_SEC" "1"
					( Origin gPackager )
				)
				( attribute "LOCATION" "CR30W1"
					( Origin gFrontEnd )
				)
				( attribute "MATERIAL" "IC"
					( Origin gFrontEnd )
				)
				( attribute "PACK_TYPE" "SM9"
					( Origin gFrontEnd )
				)
				( attribute "PART_NUMBER" "G18435-001"
					( Origin gFrontEnd )
				)
				( attribute "PHYS_PAGE" "253"
					( Origin gFrontEnd )
				)
				( attribute "ROOM" "USB_REAR"
					( Origin gFrontEnd )
				)
				( attribute "ROT" "0"
					( Origin gFrontEnd )
				)
				( attribute "SEC" "1"
					( Origin gFrontEnd )
				)
				( attribute "SEC_TYPE" "SM9"
					( Origin gFrontEnd )
				)
				( attribute "VALUE" "ESD3V3U4ULC"
					( Origin gFrontEnd )
				)
				( attribute "VER" "7"
					( Origin gFrontEnd )
				)
				( attribute "XY" "(-3300,2300)"
					( Origin gFrontEnd )
				)
				( attribute "CHIPS_PART_NAME" "DIODEAC_DUAL_ARRAY"
					( Origin gPackager )
				)
				( attribute "CDS_PART_NAME" "DIODEAC_DUAL_ARRAY_SM9-ESD3V3UA"
					( Origin gPackager )
				)
				( objectStatus "CR30W1" )
			)
			( gate "@baseboard_fab2_lib.baseboard_fab2(sch_1):page253_i11"
				( attribute "CDS_LIB" "mstr_discrete"
					( Origin gPackager )
				)
				( attribute "CDS_LMAN_SYM_OUTLINE" "-200,150,150,-150"
					( Origin gPackager )
				)
				( attribute "LOCATION" "L30W2"
					( Origin gFrontEnd )
				)
				( attribute "MATERIAL" "EMPTY"
					( Origin gFrontEnd )
				)
				( attribute "PACK_TYPE" "SM_B"
					( Origin gFrontEnd )
				)
				( attribute "PART_NUMBER" "752402-028"
					( Origin gFrontEnd )
				)
				( attribute "PHYS_PAGE" "253"
					( Origin gFrontEnd )
				)
				( attribute "ROT" "0"
					( Origin gFrontEnd )
				)
				( attribute "SEC" "1"
					( Origin gFrontEnd )
				)
				( attribute "SEC_TYPE" "SM_B"
					( Origin gFrontEnd )
				)
				( attribute "VALUE" "67 OHM"
					( Origin gFrontEnd )
				)
				( attribute "VER" "2"
					( Origin gFrontEnd )
				)
				( attribute "XY" "(-5300,2150)"
					( Origin gFrontEnd )
				)
				( attribute "CHIPS_PART_NAME" "CHOKE_4PIN"
					( Origin gPackager )
				)
				( attribute "CDS_PART_NAME" "CHOKE_4PIN_SM_B-67 OHM,EMPTY,7A"
					( Origin gPackager )
				)
				( attribute "CDS_LOCATION" "L30W2"
					( Origin gPackager )
				)
				( attribute "CDS_SEC" "1"
					( Origin gPackager )
				)
				( objectStatus "L30W2" )
			)
			( gate "@baseboard_fab2_lib.baseboard_fab2(sch_1):page253_i12"
				( attribute "BOM_COST" "PROC"
					( Origin gFrontEnd )
				)
				( attribute "CDS_LIB" "mstr_discrete"
					( Origin gPackager )
				)
				( attribute "CDS_LOCATION" "R30W2"
					( Origin gPackager )
				)
				( attribute "CDS_SEC" "1"
					( Origin gPackager )
				)
				( attribute "LOCATION" "R30W2"
					( Origin gFrontEnd )
				)
				( attribute "MATERIAL" "CHIP"
					( Origin gFrontEnd )
				)
				( attribute "PACK_TYPE" "0402"
					( Origin gFrontEnd )
				)
				( attribute "PART_NUMBER" "G21497-005"
					( Origin gFrontEnd )
				)
				( attribute "PHYS_PAGE" "253"
					( Origin gFrontEnd )
				)
				( attribute "ROOM" "PROC_SIDEBAND"
					( Origin gFrontEnd )
				)
				( attribute "ROT" "0"
					( Origin gFrontEnd )
				)
				( attribute "SEC" "1"
					( Origin gFrontEnd )
				)
				( attribute "SEC_TYPE" "0402"
					( Origin gFrontEnd )
				)
				( attribute "TOLERANCE" "5%"
					( Origin gFrontEnd )
				)
				( attribute "VALUE" "0.0"
					( Origin gFrontEnd )
				)
				( attribute "VER" "1"
					( Origin gFrontEnd )
				)
				( attribute "WATTAGE" "1/16W"
					( Origin gFrontEnd )
				)
				( attribute "XY" "(-5350,3950)"
					( Origin gFrontEnd )
				)
				( attribute "CHIPS_PART_NAME" "RES"
					( Origin gPackager )
				)
				( attribute "CDS_PART_NAME" "RES_0402-0.0,5%,1/16W,CHIP,G21A"
					( Origin gPackager )
				)
				( objectStatus "R30W2" )
			)
			( gate "@baseboard_fab2_lib.baseboard_fab2(sch_1):page253_i13"
				( attribute "BOM_COST" "PROC"
					( Origin gFrontEnd )
				)
				( attribute "CDS_LIB" "mstr_discrete"
					( Origin gPackager )
				)
				( attribute "CDS_LOCATION" "R30W1"
					( Origin gPackager )
				)
				( attribute "CDS_SEC" "1"
					( Origin gPackager )
				)
				( attribute "LOCATION" "R30W1"
					( Origin gFrontEnd )
				)
				( attribute "MATERIAL" "CHIP"
					( Origin gFrontEnd )
				)
				( attribute "PACK_TYPE" "0402"
					( Origin gFrontEnd )
				)
				( attribute "PART_NUMBER" "G21497-005"
					( Origin gFrontEnd )
				)
				( attribute "PHYS_PAGE" "253"
					( Origin gFrontEnd )
				)
				( attribute "ROOM" "PROC_SIDEBAND"
					( Origin gFrontEnd )
				)
				( attribute "ROT" "0"
					( Origin gFrontEnd )
				)
				( attribute "SEC" "1"
					( Origin gFrontEnd )
				)
				( attribute "SEC_TYPE" "0402"
					( Origin gFrontEnd )
				)
				( attribute "TOLERANCE" "5%"
					( Origin gFrontEnd )
				)
				( attribute "VALUE" "0.0"
					( Origin gFrontEnd )
				)
				( attribute "VER" "1"
					( Origin gFrontEnd )
				)
				( attribute "WATTAGE" "1/16W"
					( Origin gFrontEnd )
				)
				( attribute "XY" "(-5350,3000)"
					( Origin gFrontEnd )
				)
				( attribute "CHIPS_PART_NAME" "RES"
					( Origin gPackager )
				)
				( attribute "CDS_PART_NAME" "RES_0402-0.0,5%,1/16W,CHIP,G21A"
					( Origin gPackager )
				)
				( objectStatus "R30W1" )
			)
			( gate "@baseboard_fab2_lib.baseboard_fab2(sch_1):page253_i14"
				( attribute "BOM_COST" "PROC"
					( Origin gFrontEnd )
				)
				( attribute "CDS_LIB" "mstr_discrete"
					( Origin gPackager )
				)
				( attribute "CDS_LOCATION" "R30W4"
					( Origin gPackager )
				)
				( attribute "CDS_SEC" "1"
					( Origin gPackager )
				)
				( attribute "LOCATION" "R30W4"
					( Origin gFrontEnd )
				)
				( attribute "MATERIAL" "CHIP"
					( Origin gFrontEnd )
				)
				( attribute "PACK_TYPE" "0402"
					( Origin gFrontEnd )
				)
				( attribute "PART_NUMBER" "G21497-005"
					( Origin gFrontEnd )
				)
				( attribute "PHYS_PAGE" "253"
					( Origin gFrontEnd )
				)
				( attribute "ROOM" "PROC_SIDEBAND"
					( Origin gFrontEnd )
				)
				( attribute "ROT" "0"
					( Origin gFrontEnd )
				)
				( attribute "SEC" "1"
					( Origin gFrontEnd )
				)
				( attribute "SEC_TYPE" "0402"
					( Origin gFrontEnd )
				)
				( attribute "TOLERANCE" "5%"
					( Origin gFrontEnd )
				)
				( attribute "VALUE" "0.0"
					( Origin gFrontEnd )
				)
				( attribute "VER" "1"
					( Origin gFrontEnd )
				)
				( attribute "WATTAGE" "1/16W"
					( Origin gFrontEnd )
				)
				( attribute "XY" "(-5350,2700)"
					( Origin gFrontEnd )
				)
				( attribute "CHIPS_PART_NAME" "RES"
					( Origin gPackager )
				)
				( attribute "CDS_PART_NAME" "RES_0402-0.0,5%,1/16W,CHIP,G21A"
					( Origin gPackager )
				)
				( objectStatus "R30W4" )
			)
			( gate "@baseboard_fab2_lib.baseboard_fab2(sch_1):page253_i15"
				( attribute "BOM_COST" "PROC"
					( Origin gFrontEnd )
				)
				( attribute "CDS_LIB" "mstr_discrete"
					( Origin gPackager )
				)
				( attribute "CDS_LOCATION" "R30W3"
					( Origin gPackager )
				)
				( attribute "CDS_SEC" "1"
					( Origin gPackager )
				)
				( attribute "LOCATION" "R30W3"
					( Origin gFrontEnd )
				)
				( attribute "MATERIAL" "CHIP"
					( Origin gFrontEnd )
				)
				( attribute "PACK_TYPE" "0402"
					( Origin gFrontEnd )
				)
				( attribute "PART_NUMBER" "G21497-005"
					( Origin gFrontEnd )
				)
				( attribute "PHYS_PAGE" "253"
					( Origin gFrontEnd )
				)
				( attribute "ROOM" "PROC_SIDEBAND"
					( Origin gFrontEnd )
				)
				( attribute "ROT" "0"
					( Origin gFrontEnd )
				)
				( attribute "SEC" "1"
					( Origin gFrontEnd )
				)
				( attribute "SEC_TYPE" "0402"
					( Origin gFrontEnd )
				)
				( attribute "TOLERANCE" "5%"
					( Origin gFrontEnd )
				)
				( attribute "VALUE" "0.0"
					( Origin gFrontEnd )
				)
				( attribute "VER" "1"
					( Origin gFrontEnd )
				)
				( attribute "WATTAGE" "1/16W"
					( Origin gFrontEnd )
				)
				( attribute "XY" "(-5350,1750)"
					( Origin gFrontEnd )
				)
				( attribute "CHIPS_PART_NAME" "RES"
					( Origin gPackager )
				)
				( attribute "CDS_PART_NAME" "RES_0402-0.0,5%,1/16W,CHIP,G21A"
					( Origin gPackager )
				)
				( objectStatus "R30W3" )
			)
			( gate "@baseboard_fab2_lib.baseboard_fab2(sch_1):page253_i16"
				( attribute "CDS_LIB" "mstr_discrete"
					( Origin gPackager )
				)
				( attribute "CDS_LMAN_SYM_OUTLINE" "-200,150,150,-150"
					( Origin gPackager )
				)
				( attribute "LOCATION" "L30W1"
					( Origin gFrontEnd )
				)
				( attribute "MATERIAL" "EMPTY"
					( Origin gFrontEnd )
				)
				( attribute "PACK_TYPE" "SM_B"
					( Origin gFrontEnd )
				)
				( attribute "PART_NUMBER" "752402-028"
					( Origin gFrontEnd )
				)
				( attribute "PHYS_PAGE" "253"
					( Origin gFrontEnd )
				)
				( attribute "ROT" "0"
					( Origin gFrontEnd )
				)
				( attribute "SEC" "1"
					( Origin gFrontEnd )
				)
				( attribute "SEC_TYPE" "SM_B"
					( Origin gFrontEnd )
				)
				( attribute "VALUE" "67 OHM"
					( Origin gFrontEnd )
				)
				( attribute "VER" "2"
					( Origin gFrontEnd )
				)
				( attribute "XY" "(-5300,3400)"
					( Origin gFrontEnd )
				)
				( attribute "CHIPS_PART_NAME" "CHOKE_4PIN"
					( Origin gPackager )
				)
				( attribute "CDS_PART_NAME" "CHOKE_4PIN_SM_B-67 OHM,EMPTY,7A"
					( Origin gPackager )
				)
				( attribute "CDS_LOCATION" "L30W1"
					( Origin gPackager )
				)
				( attribute "CDS_SEC" "1"
					( Origin gPackager )
				)
				( objectStatus "L30W1" )
			)
			( gate "@baseboard_fab2_lib.baseboard_fab2(sch_1):page253_i19"
				( attribute "BOM_COST" "PROC_SIDEBAND"
					( Origin gFrontEnd )
				)
				( attribute "CDS_LIB" "dev_discrete"
					( Origin gPackager )
				)
				( attribute "CDS_LOCATION" "C30W2"
					( Origin gPackager )
				)
				( attribute "CDS_SEC" "1"
					( Origin gPackager )
				)
				( attribute "LOCATION" "C30W2"
					( Origin gFrontEnd )
				)
				( attribute "MATERIAL" "X7R"
					( Origin gFrontEnd )
				)
				( attribute "PACK_TYPE" "0402V"
					( Origin gFrontEnd )
				)
				( attribute "PART_NUMBER" "A36096-030"
					( Origin gFrontEnd )
				)
				( attribute "PHYS_PAGE" "253"
					( Origin gFrontEnd )
				)
				( attribute "ROOM" "PROC_SIDEBAND"
					( Origin gFrontEnd )
				)
				( attribute "ROT" "1"
					( Origin gFrontEnd )
				)
				( attribute "SEC" "1"
					( Origin gFrontEnd )
				)
				( attribute "SEC_TYPE" "0402V"
					( Origin gFrontEnd )
				)
				( attribute "TOLERANCE" "10%"
					( Origin gFrontEnd )
				)
				( attribute "VALUE" "0.1UF"
					( Origin gFrontEnd )
				)
				( attribute "VER" "1"
					( Origin gFrontEnd )
				)
				( attribute "VOLTAGE" "16V"
					( Units "uVoltage" "V" 1.000000)
					( Origin gFrontEnd )
				)
				( attribute "XY" "(-6275,2250)"
					( Origin gFrontEnd )
				)
				( attribute "CHIPS_PART_NAME" "CAP_A"
					( Origin gPackager )
				)
				( attribute "CDS_PART_NAME" "CAP_A_0402V-0.1UF,16V,10%,X7R,A"
					( Origin gPackager )
				)
				( objectStatus "C30W2" )
			)
			( gate "@baseboard_fab2_lib.baseboard_fab2(sch_1):page253_i20"
				( attribute "BOM_COST" "PROC_SIDEBAND"
					( Origin gFrontEnd )
				)
				( attribute "CDS_LIB" "dev_discrete"
					( Origin gPackager )
				)
				( attribute "CDS_LOCATION" "C30W1"
					( Origin gPackager )
				)
				( attribute "CDS_SEC" "1"
					( Origin gPackager )
				)
				( attribute "LOCATION" "C30W1"
					( Origin gFrontEnd )
				)
				( attribute "MATERIAL" "X7R"
					( Origin gFrontEnd )
				)
				( attribute "PACK_TYPE" "0402V"
					( Origin gFrontEnd )
				)
				( attribute "PART_NUMBER" "A36096-030"
					( Origin gFrontEnd )
				)
				( attribute "PHYS_PAGE" "253"
					( Origin gFrontEnd )
				)
				( attribute "ROOM" "PROC_SIDEBAND"
					( Origin gFrontEnd )
				)
				( attribute "ROT" "1"
					( Origin gFrontEnd )
				)
				( attribute "SEC" "1"
					( Origin gFrontEnd )
				)
				( attribute "SEC_TYPE" "0402V"
					( Origin gFrontEnd )
				)
				( attribute "TOLERANCE" "10%"
					( Origin gFrontEnd )
				)
				( attribute "VALUE" "0.1UF"
					( Origin gFrontEnd )
				)
				( attribute "VER" "1"
					( Origin gFrontEnd )
				)
				( attribute "VOLTAGE" "16V"
					( Units "uVoltage" "V" 1.000000)
					( Origin gFrontEnd )
				)
				( attribute "XY" "(-6275,2050)"
					( Origin gFrontEnd )
				)
				( attribute "CHIPS_PART_NAME" "CAP_A"
					( Origin gPackager )
				)
				( attribute "CDS_PART_NAME" "CAP_A_0402V-0.1UF,16V,10%,X7R,A"
					( Origin gPackager )
				)
				( objectStatus "C30W1" )
			)
			( gate "@baseboard_fab2_lib.baseboard_fab2(sch_1):page255_i111"
				( attribute "CDS_LIB" "w_hdl"
					( Origin gPackager )
				)
				( attribute "CDS_LMAN_SYM_OUTLINE" "-150,150,150,-150"
					( Origin gPackager )
				)
				( attribute "LOCATION" "U25W7"
					( Origin gFrontEnd )
				)
				( attribute "PACK_TYPE" "TTL-G4"
					( Origin gFrontEnd )
				)
				( attribute "PART_NUMBER" "73.1G125.D0G"
					( Origin gFrontEnd )
				)
				( attribute "PHYS_PAGE" "252"
					( Origin gFrontEnd )
				)
				( attribute "ROT" "0"
					( Origin gFrontEnd )
				)
				( attribute "SEC" "1"
					( Origin gFrontEnd )
				)
				( attribute "SEC_TYPE" "TTL-G4"
					( Origin gFrontEnd )
				)
				( attribute "VALUE" "U74AHCT1G125G-AL5-R-GP-U"
					( Origin gFrontEnd )
				)
				( attribute "VER" "1"
					( Origin gFrontEnd )
				)
				( attribute "XY" "(-4350,5100)"
					( Origin gFrontEnd )
				)
				( attribute "CHIPS_PART_NAME" "U74AHCT1G125G-AL5-R-GP-U"
					( Origin gPackager )
				)
				( attribute "CDS_PART_NAME" "U74AHCT1G125G-AL5-R-GP-U_TTL-GA"
					( Origin gPackager )
				)
				( attribute "CDS_LOCATION" "U25W7"
					( Origin gPackager )
				)
				( attribute "CDS_SEC" "1"
					( Origin gPackager )
				)
				( attribute "GROUP" "AST2500"
					( Origin gFrontEnd )
				)
				( objectStatus "U25W7" )
			)
			( gate "@baseboard_fab2_lib.baseboard_fab2(sch_1):page255_i112"
				( attribute "CDS_LIB" "w_hdl"
					( Origin gPackager )
				)
				( attribute "CDS_LMAN_SYM_OUTLINE" "-150,150,150,-150"
					( Origin gPackager )
				)
				( attribute "LOCATION" "U25W8"
					( Origin gFrontEnd )
				)
				( attribute "PACK_TYPE" "TTL-G4"
					( Origin gFrontEnd )
				)
				( attribute "PART_NUMBER" "73.1G125.D0G"
					( Origin gFrontEnd )
				)
				( attribute "PHYS_PAGE" "252"
					( Origin gFrontEnd )
				)
				( attribute "ROT" "0"
					( Origin gFrontEnd )
				)
				( attribute "SEC" "1"
					( Origin gFrontEnd )
				)
				( attribute "SEC_TYPE" "TTL-G4"
					( Origin gFrontEnd )
				)
				( attribute "VALUE" "U74AHCT1G125G-AL5-R-GP-U"
					( Origin gFrontEnd )
				)
				( attribute "VER" "1"
					( Origin gFrontEnd )
				)
				( attribute "XY" "(-4350,4550)"
					( Origin gFrontEnd )
				)
				( attribute "CHIPS_PART_NAME" "U74AHCT1G125G-AL5-R-GP-U"
					( Origin gPackager )
				)
				( attribute "CDS_PART_NAME" "U74AHCT1G125G-AL5-R-GP-U_TTL-GA"
					( Origin gPackager )
				)
				( attribute "CDS_LOCATION" "U25W8"
					( Origin gPackager )
				)
				( attribute "CDS_SEC" "1"
					( Origin gPackager )
				)
				( attribute "GROUP" "AST2500"
					( Origin gFrontEnd )
				)
				( objectStatus "U25W8" )
			)
			( gate "@baseboard_fab2_lib.baseboard_fab2(sch_1):page255_i118"
				( attribute "BOM_COST" "PROC_SIDEBAND"
					( Origin gFrontEnd )
				)
				( attribute "CDS_LIB" "dev_discrete"
					( Origin gPackager )
				)
				( attribute "CDS_LOCATION" "C25W90"
					( Origin gPackager )
				)
				( attribute "CDS_SEC" "1"
					( Origin gPackager )
				)
				( attribute "LOCATION" "C25W90"
					( Origin gFrontEnd )
				)
				( attribute "MATERIAL" "X7R"
					( Origin gFrontEnd )
				)
				( attribute "PACK_TYPE" "0402V"
					( Origin gFrontEnd )
				)
				( attribute "PART_NUMBER" "A36096-030"
					( Origin gFrontEnd )
				)
				( attribute "PHYS_PAGE" "252"
					( Origin gFrontEnd )
				)
				( attribute "ROOM" "PROC_SIDEBAND"
					( Origin gFrontEnd )
				)
				( attribute "ROT" "1"
					( Origin gFrontEnd )
				)
				( attribute "SEC" "1"
					( Origin gFrontEnd )
				)
				( attribute "SEC_TYPE" "0402V"
					( Origin gFrontEnd )
				)
				( attribute "TOLERANCE" "10%"
					( Origin gFrontEnd )
				)
				( attribute "VALUE" "0.1UF"
					( Origin gFrontEnd )
				)
				( attribute "VER" "1"
					( Origin gFrontEnd )
				)
				( attribute "VOLTAGE" "16V"
					( Units "uVoltage" "V" 1.000000)
					( Origin gFrontEnd )
				)
				( attribute "XY" "(-3500,4650)"
					( Origin gFrontEnd )
				)
				( attribute "CHIPS_PART_NAME" "CAP_A"
					( Origin gPackager )
				)
				( attribute "CDS_PART_NAME" "CAP_A_0402V-0.1UF,16V,10%,X7R,A"
					( Origin gPackager )
				)
				( attribute "GROUP" "AST2500"
					( Origin gFrontEnd )
				)
				( objectStatus "C25W90" )
			)
			( gate "@baseboard_fab2_lib.baseboard_fab2(sch_1):page255_i128"
				( attribute "CDS_LIB" "w_hdl"
					( Origin gPackager )
				)
				( attribute "CDS_LMAN_SYM_OUTLINE" "-75,50,75,-50"
					( Origin gPackager )
				)
				( attribute "LOCATION" "D25W8"
					( Origin gFrontEnd )
				)
				( attribute "PACK_TYPE" "DISCRET-G"
					( Origin gFrontEnd )
				)
				( attribute "PART_NUMBER" "83.R5003.H8H"
					( Origin gFrontEnd )
				)
				( attribute "PHYS_PAGE" "252"
					( Origin gFrontEnd )
				)
				( attribute "ROT" "0"
					( Origin gFrontEnd )
				)
				( attribute "SEC" "1"
					( Origin gFrontEnd )
				)
				( attribute "SEC_TYPE" "DISCRET-G"
					( Origin gFrontEnd )
				)
				( attribute "VALUE" "RB551V30-GP"
					( Origin gFrontEnd )
				)
				( attribute "VER" "1"
					( Origin gFrontEnd )
				)
				( attribute "XY" "(-4775,2750)"
					( Origin gFrontEnd )
				)
				( attribute "CHIPS_PART_NAME" "RB551V30-GP"
					( Origin gPackager )
				)
				( attribute "CDS_PART_NAME" "RB551V30-GP_DISCRET-G-RB551V30A"
					( Origin gPackager )
				)
				( attribute "CDS_LOCATION" "D25W8"
					( Origin gPackager )
				)
				( attribute "CDS_SEC" "1"
					( Origin gPackager )
				)
				( attribute "GROUP" "AST2500"
					( Origin gFrontEnd )
				)
				( objectStatus "D25W8" )
			)
			( gate "@baseboard_fab2_lib.baseboard_fab2(sch_1):page255_i129"
				( attribute "BOM_COST" "MIO_USB"
					( Origin gFrontEnd )
				)
				( attribute "CDS_LIB" "mstr_discrete"
					( Origin gPackager )
				)
				( attribute "CDS_LOCATION" "CR25W1"
					( Origin gPackager )
				)
				( attribute "CDS_SEC" "1"
					( Origin gPackager )
				)
				( attribute "LOCATION" "CR25W1"
					( Origin gFrontEnd )
				)
				( attribute "MATERIAL" "IC"
					( Origin gFrontEnd )
				)
				( attribute "PACK_TYPE" "SM9"
					( Origin gFrontEnd )
				)
				( attribute "PART_NUMBER" "G18435-001"
					( Origin gFrontEnd )
				)
				( attribute "PHYS_PAGE" "252"
					( Origin gFrontEnd )
				)
				( attribute "ROOM" "USB_REAR"
					( Origin gFrontEnd )
				)
				( attribute "ROT" "0"
					( Origin gFrontEnd )
				)
				( attribute "SEC" "1"
					( Origin gFrontEnd )
				)
				( attribute "SEC_TYPE" "SM9"
					( Origin gFrontEnd )
				)
				( attribute "VALUE" "ESD3V3U4ULC"
					( Origin gFrontEnd )
				)
				( attribute "VER" "7"
					( Origin gFrontEnd )
				)
				( attribute "XY" "(-7000,5750)"
					( Origin gFrontEnd )
				)
				( attribute "CHIPS_PART_NAME" "DIODEAC_DUAL_ARRAY"
					( Origin gPackager )
				)
				( attribute "CDS_PART_NAME" "DIODEAC_DUAL_ARRAY_SM9-ESD3V3UA"
					( Origin gPackager )
				)
				( attribute "GROUP" "AST2500"
					( Origin gFrontEnd )
				)
				( objectStatus "CR25W1" )
			)
			( gate "@baseboard_fab2_lib.baseboard_fab2(sch_1):page255_i131"
				( attribute "BOM_COST" "MIO_USB"
					( Origin gFrontEnd )
				)
				( attribute "CDS_LIB" "mstr_discrete"
					( Origin gPackager )
				)
				( attribute "CDS_LOCATION" "CR25W2"
					( Origin gPackager )
				)
				( attribute "CDS_SEC" "1"
					( Origin gPackager )
				)
				( attribute "LOCATION" "CR25W2"
					( Origin gFrontEnd )
				)
				( attribute "MATERIAL" "IC"
					( Origin gFrontEnd )
				)
				( attribute "PACK_TYPE" "SM9"
					( Origin gFrontEnd )
				)
				( attribute "PART_NUMBER" "G18435-001"
					( Origin gFrontEnd )
				)
				( attribute "PHYS_PAGE" "252"
					( Origin gFrontEnd )
				)
				( attribute "ROOM" "USB_REAR"
					( Origin gFrontEnd )
				)
				( attribute "ROT" "0"
					( Origin gFrontEnd )
				)
				( attribute "SEC" "1"
					( Origin gFrontEnd )
				)
				( attribute "SEC_TYPE" "SM9"
					( Origin gFrontEnd )
				)
				( attribute "VALUE" "ESD3V3U4ULC"
					( Origin gFrontEnd )
				)
				( attribute "VER" "7"
					( Origin gFrontEnd )
				)
				( attribute "XY" "(-4350,5750)"
					( Origin gFrontEnd )
				)
				( attribute "CHIPS_PART_NAME" "DIODEAC_DUAL_ARRAY"
					( Origin gPackager )
				)
				( attribute "CDS_PART_NAME" "DIODEAC_DUAL_ARRAY_SM9-ESD3V3UA"
					( Origin gPackager )
				)
				( attribute "GROUP" "AST2500"
					( Origin gFrontEnd )
				)
				( objectStatus "CR25W2" )
			)
			( gate "@baseboard_fab2_lib.baseboard_fab2(sch_1):page255_i134"
				( attribute "BOM_COST" "PROC_SIDEBAND"
					( Origin gFrontEnd )
				)
				( attribute "CDS_LIB" "dev_discrete"
					( Origin gPackager )
				)
				( attribute "CDS_LOCATION" "C25P80"
					( Origin gPackager )
				)
				( attribute "CDS_SEC" "1"
					( Origin gPackager )
				)
				( attribute "LOCATION" "C25P80"
					( Origin gFrontEnd )
				)
				( attribute "MATERIAL" "X7R"
					( Origin gFrontEnd )
				)
				( attribute "PACK_TYPE" "0402V"
					( Origin gFrontEnd )
				)
				( attribute "PART_NUMBER" "A36096-030"
					( Origin gFrontEnd )
				)
				( attribute "PHYS_PAGE" "252"
					( Origin gFrontEnd )
				)
				( attribute "ROOM" "PROC_SIDEBAND"
					( Origin gFrontEnd )
				)
				( attribute "ROT" "1"
					( Origin gFrontEnd )
				)
				( attribute "SEC" "1"
					( Origin gFrontEnd )
				)
				( attribute "SEC_TYPE" "0402V"
					( Origin gFrontEnd )
				)
				( attribute "TOLERANCE" "10%"
					( Origin gFrontEnd )
				)
				( attribute "VALUE" "0.1UF"
					( Origin gFrontEnd )
				)
				( attribute "VER" "1"
					( Origin gFrontEnd )
				)
				( attribute "VOLTAGE" "16V"
					( Units "uVoltage" "V" 1.000000)
					( Origin gFrontEnd )
				)
				( attribute "XY" "(-3500,5200)"
					( Origin gFrontEnd )
				)
				( attribute "CHIPS_PART_NAME" "CAP_A"
					( Origin gPackager )
				)
				( attribute "CDS_PART_NAME" "CAP_A_0402V-0.1UF,16V,10%,X7R,A"
					( Origin gPackager )
				)
				( attribute "GROUP" "AST2500"
					( Origin gFrontEnd )
				)
				( objectStatus "C25P80" )
			)
			( gate "@baseboard_fab2_lib.baseboard_fab2(sch_1):page199_i132"
				( attribute "CDS_LIB" "mstr_discrete"
					( Origin gPackager )
				)
				( attribute "CDS_LOCATION" "C1W16"
					( Origin gPackager )
				)
				( attribute "CDS_SEC" "1"
					( Origin gPackager )
				)
				( attribute "LOCATION" "C1W16"
					( Origin gFrontEnd )
				)
				( attribute "MATERIAL" "X7R"
					( Origin gFrontEnd )
				)
				( attribute "PACK_TYPE" "0402LF"
					( Origin gFrontEnd )
				)
				( attribute "PART_NUMBER" "A36096-046"
					( Origin gFrontEnd )
				)
				( attribute "PHYS_PAGE" "199"
					( Origin gFrontEnd )
				)
				( attribute "ROOM" "PVCCIN_CPU0_VR"
					( Origin gFrontEnd )
				)
				( attribute "ROT" "2"
					( Origin gFrontEnd )
				)
				( attribute "SEC" "1"
					( Origin gFrontEnd )
				)
				( attribute "SEC_TYPE" "0402LF"
					( Origin gFrontEnd )
				)
				( attribute "TOLERANCE" "10%"
					( Origin gFrontEnd )
				)
				( attribute "VALUE" "1000PF"
					( Origin gFrontEnd )
				)
				( attribute "VER" "1"
					( Origin gFrontEnd )
				)
				( attribute "VOLTAGE" "50V"
					( Units "uVoltage" "V" 1.000000)
					( Origin gFrontEnd )
				)
				( attribute "XY" "(-1500,1700)"
					( Origin gFrontEnd )
				)
				( attribute "CHIPS_PART_NAME" "CAP"
					( Origin gPackager )
				)
				( attribute "CDS_PART_NAME" "CAP_0402LF-1000PF,50V,10%,X7R,A"
					( Origin gPackager )
				)
				( objectStatus "C1W16" )
			)
			( gate "@baseboard_fab2_lib.baseboard_fab2(sch_1):page199_i134"
				( attribute "BOM_COST" "PROC_SIDEBAND"
					( Origin gFrontEnd )
				)
				( attribute "CDS_LIB" "mstr_discrete"
					( Origin gPackager )
				)
				( attribute "CDS_LOCATION" "R1W20"
					( Origin gPackager )
				)
				( attribute "CDS_SEC" "1"
					( Origin gPackager )
				)
				( attribute "LOCATION" "R1W20"
					( Origin gFrontEnd )
				)
				( attribute "MATERIAL" "CHIP"
					( Origin gFrontEnd )
				)
				( attribute "PACK_TYPE" "0402"
					( Origin gFrontEnd )
				)
				( attribute "PART_NUMBER" "G21497-005"
					( Origin gFrontEnd )
				)
				( attribute "PHYS_PAGE" "199"
					( Origin gFrontEnd )
				)
				( attribute "ROOM" "CPU0"
					( Origin gFrontEnd )
				)
				( attribute "ROT" "0"
					( Origin gFrontEnd )
				)
				( attribute "SEC" "1"
					( Origin gFrontEnd )
				)
				( attribute "SEC_TYPE" "0402"
					( Origin gFrontEnd )
				)
				( attribute "TOLERANCE" "5%"
					( Origin gFrontEnd )
				)
				( attribute "VALUE" "0.0"
					( Origin gFrontEnd )
				)
				( attribute "VER" "1"
					( Origin gFrontEnd )
				)
				( attribute "WATTAGE" "1/16W"
					( Origin gFrontEnd )
				)
				( attribute "XY" "(-1250,1850)"
					( Origin gFrontEnd )
				)
				( attribute "CHIPS_PART_NAME" "RES"
					( Origin gPackager )
				)
				( attribute "CDS_PART_NAME" "RES_0402-0.0,5%,1/16W,CHIP,G21A"
					( Origin gPackager )
				)
				( objectStatus "R1W20" )
			)
			( gate "@baseboard_fab2_lib.baseboard_fab2(sch_1):page199_i135"
				( attribute "BOM_COST" "PROC_SIDEBAND"
					( Origin gFrontEnd )
				)
				( attribute "CDS_LIB" "mstr_discrete"
					( Origin gPackager )
				)
				( attribute "CDS_LOCATION" "R1W21"
					( Origin gPackager )
				)
				( attribute "CDS_SEC" "1"
					( Origin gPackager )
				)
				( attribute "LOCATION" "R1W21"
					( Origin gFrontEnd )
				)
				( attribute "MATERIAL" "CHIP"
					( Origin gFrontEnd )
				)
				( attribute "PACK_TYPE" "0402"
					( Origin gFrontEnd )
				)
				( attribute "PART_NUMBER" "G21497-005"
					( Origin gFrontEnd )
				)
				( attribute "PHYS_PAGE" "199"
					( Origin gFrontEnd )
				)
				( attribute "ROOM" "CPU0"
					( Origin gFrontEnd )
				)
				( attribute "ROT" "0"
					( Origin gFrontEnd )
				)
				( attribute "SEC" "1"
					( Origin gFrontEnd )
				)
				( attribute "SEC_TYPE" "0402"
					( Origin gFrontEnd )
				)
				( attribute "TOLERANCE" "5%"
					( Origin gFrontEnd )
				)
				( attribute "VALUE" "0.0"
					( Origin gFrontEnd )
				)
				( attribute "VER" "1"
					( Origin gFrontEnd )
				)
				( attribute "WATTAGE" "1/16W"
					( Origin gFrontEnd )
				)
				( attribute "XY" "(-1250,1550)"
					( Origin gFrontEnd )
				)
				( attribute "CHIPS_PART_NAME" "RES"
					( Origin gPackager )
				)
				( attribute "CDS_PART_NAME" "RES_0402-0.0,5%,1/16W,CHIP,G21A"
					( Origin gPackager )
				)
				( objectStatus "R1W21" )
			)
			( gate "@baseboard_fab2_lib.baseboard_fab2(sch_1):page183_i3"
				( attribute "BOM_COST" "LBG_UART"
					( Origin gFrontEnd )
				)
				( attribute "CDS_LIB" "mstr_discrete"
					( Origin gPackager )
				)
				( attribute "CDS_LOCATION" "R9F55"
					( Origin gPackager )
				)
				( attribute "CDS_SEC" "1"
					( Origin gPackager )
				)
				( attribute "LOCATION" "R9F55"
					( Origin gFrontEnd )
				)
				( attribute "MATERIAL" "CHIP"
					( Origin gFrontEnd )
				)
				( attribute "PACK_TYPE" "0402"
					( Origin gFrontEnd )
				)
				( attribute "PART_NUMBER" "G21796-072"
					( Origin gFrontEnd )
				)
				( attribute "PHYS_PAGE" "183"
					( Origin gFrontEnd )
				)
				( attribute "ROOM" "LBG"
					( Origin gFrontEnd )
				)
				( attribute "ROT" "0"
					( Origin gFrontEnd )
				)
				( attribute "SEC" "1"
					( Origin gFrontEnd )
				)
				( attribute "SEC_TYPE" "0402"
					( Origin gFrontEnd )
				)
				( attribute "TOLERANCE" "1%"
					( Origin gFrontEnd )
				)
				( attribute "VALUE" "4.75K"
					( Origin gFrontEnd )
				)
				( attribute "VER" "2"
					( Origin gFrontEnd )
				)
				( attribute "WATTAGE" "1/16W"
					( Origin gFrontEnd )
				)
				( attribute "XY" "(3150,-400)"
					( Origin gFrontEnd )
				)
				( attribute "CHIPS_PART_NAME" "RES"
					( Origin gPackager )
				)
				( attribute "CDS_PART_NAME" "RES_0402-4.75K,1%,1/16W,CHIP,GA"
					( Origin gPackager )
				)
				( objectStatus "R9F55" )
			)
			( gate "@baseboard_fab2_lib.baseboard_fab2(sch_1):page145_i163"
				( attribute "CDS_LIB" "mstr_discrete"
					( Origin gPackager )
				)
				( attribute "LOCATION" "R25W121"
					( Origin gFrontEnd )
				)
				( attribute "MATERIAL" "CHIP"
					( Origin gFrontEnd )
				)
				( attribute "PACK_TYPE" "0402"
					( Origin gFrontEnd )
				)
				( attribute "PART_NUMBER" "G21796-173"
					( Origin gFrontEnd )
				)
				( attribute "PHYS_PAGE" "145"
					( Origin gFrontEnd )
				)
				( attribute "ROOM" "SMB_PE_HP_CPU1"
					( Origin gFrontEnd )
				)
				( attribute "ROT" "0"
					( Origin gFrontEnd )
				)
				( attribute "SEC" "1"
					( Origin gFrontEnd )
				)
				( attribute "SEC_TYPE" "0402"
					( Origin gFrontEnd )
				)
				( attribute "TOLERANCE" "1%"
					( Origin gFrontEnd )
				)
				( attribute "VALUE" "20.0"
					( Origin gFrontEnd )
				)
				( attribute "VER" "1"
					( Origin gFrontEnd )
				)
				( attribute "WATTAGE" "1/16W"
					( Origin gFrontEnd )
				)
				( attribute "XY" "(-6450,-1850)"
					( Origin gFrontEnd )
				)
				( attribute "CHIPS_PART_NAME" "RES"
					( Origin gPackager )
				)
				( attribute "CDS_PART_NAME" "RES_0402-20.0,1%,1/16W,CHIP,G2A"
					( Origin gPackager )
				)
				( attribute "CDS_LOCATION" "R25W121"
					( Origin gPackager )
				)
				( attribute "CDS_SEC" "1"
					( Origin gPackager )
				)
				( objectStatus "R25W121" )
			)
			( gate "@baseboard_fab2_lib.baseboard_fab2(sch_1):page145_i164"
				( attribute "CDS_LIB" "mstr_discrete"
					( Origin gPackager )
				)
				( attribute "LOCATION" "R25W122"
					( Origin gFrontEnd )
				)
				( attribute "MATERIAL" "CHIP"
					( Origin gFrontEnd )
				)
				( attribute "PACK_TYPE" "0402"
					( Origin gFrontEnd )
				)
				( attribute "PART_NUMBER" "G21796-173"
					( Origin gFrontEnd )
				)
				( attribute "PHYS_PAGE" "145"
					( Origin gFrontEnd )
				)
				( attribute "ROOM" "SMB_PE_HP_CPU1"
					( Origin gFrontEnd )
				)
				( attribute "ROT" "0"
					( Origin gFrontEnd )
				)
				( attribute "SEC" "1"
					( Origin gFrontEnd )
				)
				( attribute "SEC_TYPE" "0402"
					( Origin gFrontEnd )
				)
				( attribute "TOLERANCE" "1%"
					( Origin gFrontEnd )
				)
				( attribute "VALUE" "20.0"
					( Origin gFrontEnd )
				)
				( attribute "VER" "1"
					( Origin gFrontEnd )
				)
				( attribute "WATTAGE" "1/16W"
					( Origin gFrontEnd )
				)
				( attribute "XY" "(-6450,-1900)"
					( Origin gFrontEnd )
				)
				( attribute "CHIPS_PART_NAME" "RES"
					( Origin gPackager )
				)
				( attribute "CDS_PART_NAME" "RES_0402-20.0,1%,1/16W,CHIP,G2A"
					( Origin gPackager )
				)
				( attribute "CDS_LOCATION" "R25W122"
					( Origin gPackager )
				)
				( attribute "CDS_SEC" "1"
					( Origin gPackager )
				)
				( objectStatus "R25W122" )
			)
			( gate "@baseboard_fab2_lib.baseboard_fab2(sch_1):page172_i67"
				( attribute "CDS_LIB" "w_hdl"
					( Origin gPackager )
				)
				( attribute "CDS_LMAN_SYM_OUTLINE" "-100,500,100,-500"
					( Origin gPackager )
				)
				( attribute "LOCATION" "J2W1"
					( Origin gFrontEnd )
				)
				( attribute "PACK_TYPE" "SOCKET-G6"
					( Origin gFrontEnd )
				)
				( attribute "PART_NUMBER" "022.10014.0121"
					( Origin gFrontEnd )
				)
				( attribute "PHYS_PAGE" "172"
					( Origin gFrontEnd )
				)
				( attribute "ROT" "0"
					( Origin gFrontEnd )
				)
				( attribute "SEC" "1"
					( Origin gFrontEnd )
				)
				( attribute "SEC_TYPE" "SOCKET-G6"
					( Origin gFrontEnd )
				)
				( attribute "VALUE" "SKT-SATA7P-6P-165-GP-U1"
					( Origin gFrontEnd )
				)
				( attribute "VER" "1"
					( Origin gFrontEnd )
				)
				( attribute "XY" "(-2300,800)"
					( Origin gFrontEnd )
				)
				( attribute "CHIPS_PART_NAME" "SKT-SATA7P-6P-165-GP-U1"
					( Origin gPackager )
				)
				( attribute "CDS_PART_NAME" "SKT-SATA7P-6P-165-GP-U1_SOCKETA"
					( Origin gPackager )
				)
				( attribute "CDS_LOCATION" "J2W1"
					( Origin gPackager )
				)
				( attribute "CDS_SEC" "1"
					( Origin gPackager )
				)
				( attribute "BOM_SS" "NOPOP"
					( Origin gFrontEnd )
				)
				( objectStatus "J2W1" )
			)
			( gate "@baseboard_fab2_lib.baseboard_fab2(sch_1):page172_i68"
				( attribute "CDS_LIB" "w_hdl"
					( Origin gPackager )
				)
				( attribute "CDS_LMAN_SYM_OUTLINE" "-100,500,100,-500"
					( Origin gPackager )
				)
				( attribute "LOCATION" "J2W2"
					( Origin gFrontEnd )
				)
				( attribute "PACK_TYPE" "SOCKET-G6"
					( Origin gFrontEnd )
				)
				( attribute "PART_NUMBER" "022.10014.0121"
					( Origin gFrontEnd )
				)
				( attribute "PHYS_PAGE" "172"
					( Origin gFrontEnd )
				)
				( attribute "ROT" "0"
					( Origin gFrontEnd )
				)
				( attribute "SEC" "1"
					( Origin gFrontEnd )
				)
				( attribute "SEC_TYPE" "SOCKET-G6"
					( Origin gFrontEnd )
				)
				( attribute "VALUE" "SKT-SATA7P-6P-165-GP-U1"
					( Origin gFrontEnd )
				)
				( attribute "VER" "1"
					( Origin gFrontEnd )
				)
				( attribute "XY" "(-2300,2050)"
					( Origin gFrontEnd )
				)
				( attribute "CHIPS_PART_NAME" "SKT-SATA7P-6P-165-GP-U1"
					( Origin gPackager )
				)
				( attribute "CDS_PART_NAME" "SKT-SATA7P-6P-165-GP-U1_SOCKETA"
					( Origin gPackager )
				)
				( attribute "CDS_LOCATION" "J2W2"
					( Origin gPackager )
				)
				( attribute "CDS_SEC" "1"
					( Origin gPackager )
				)
				( attribute "BOM_DS" "NOPOP"
					( Origin gFrontEnd )
				)
				( objectStatus "J2W2" )
			)
			( gate "@baseboard_fab2_lib.baseboard_fab2(sch_1):page141_i134"
				( attribute "BOM_COST" "PROC"
					( Origin gFrontEnd )
				)
				( attribute "CDS_LIB" "mstr_discrete"
					( Origin gPackager )
				)
				( attribute "CDS_LOCATION" "R9G2"
					( Origin gPackager )
				)
				( attribute "CDS_SEC" "1"
					( Origin gPackager )
				)
				( attribute "LOCATION" "R9G2"
					( Origin gFrontEnd )
				)
				( attribute "MATERIAL" "CHIP"
					( Origin gFrontEnd )
				)
				( attribute "PACK_TYPE" "0402"
					( Origin gFrontEnd )
				)
				( attribute "PART_NUMBER" "G21796-267"
					( Origin gFrontEnd )
				)
				( attribute "PHYS_PAGE" "141"
					( Origin gFrontEnd )
				)
				( attribute "ROOM" "PROC_SIDEBAND"
					( Origin gFrontEnd )
				)
				( attribute "ROT" "4"
					( Origin gFrontEnd )
				)
				( attribute "SEC" "1"
					( Origin gPackager )
				)
				( attribute "TOLERANCE" "1.0%"
					( Origin gFrontEnd )
				)
				( attribute "VALUE" "75"
					( Origin gFrontEnd )
				)
				( attribute "VER" "1"
					( Origin gFrontEnd )
				)
				( attribute "WATTAGE" "1/16W"
					( Origin gFrontEnd )
				)
				( attribute "XY" "(-2800,2725)"
					( Origin gFrontEnd )
				)
				( attribute "CHIPS_PART_NAME" "RES"
					( Origin gPackager )
				)
				( attribute "CDS_PART_NAME" "RES_0402-75,1.0%,1/16W,CHIP,G2A"
					( Origin gPackager )
				)
				( attribute "GROUP" "NI_I210&RJ45"
					( Origin gFrontEnd )
				)
				( objectStatus "R9G2" )
			)
			( gate "@baseboard_fab2_lib.baseboard_fab2(sch_1):page141_i135"
				( attribute "BOM_COST" "PROC"
					( Origin gFrontEnd )
				)
				( attribute "CDS_LIB" "mstr_discrete"
					( Origin gPackager )
				)
				( attribute "CDS_LOCATION" "R9G3"
					( Origin gPackager )
				)
				( attribute "CDS_SEC" "1"
					( Origin gPackager )
				)
				( attribute "LOCATION" "R9G3"
					( Origin gFrontEnd )
				)
				( attribute "MATERIAL" "CHIP"
					( Origin gFrontEnd )
				)
				( attribute "PACK_TYPE" "0402"
					( Origin gFrontEnd )
				)
				( attribute "PART_NUMBER" "G21796-267"
					( Origin gFrontEnd )
				)
				( attribute "PHYS_PAGE" "141"
					( Origin gFrontEnd )
				)
				( attribute "ROOM" "PROC_SIDEBAND"
					( Origin gFrontEnd )
				)
				( attribute "ROT" "4"
					( Origin gFrontEnd )
				)
				( attribute "SEC" "1"
					( Origin gPackager )
				)
				( attribute "TOLERANCE" "1.0%"
					( Origin gFrontEnd )
				)
				( attribute "VALUE" "75"
					( Origin gFrontEnd )
				)
				( attribute "VER" "1"
					( Origin gFrontEnd )
				)
				( attribute "WATTAGE" "1/16W"
					( Origin gFrontEnd )
				)
				( attribute "XY" "(-2800,2525)"
					( Origin gFrontEnd )
				)
				( attribute "CHIPS_PART_NAME" "RES"
					( Origin gPackager )
				)
				( attribute "CDS_PART_NAME" "RES_0402-75,1.0%,1/16W,CHIP,G2A"
					( Origin gPackager )
				)
				( attribute "GROUP" "NI_I210&RJ45"
					( Origin gFrontEnd )
				)
				( objectStatus "R9G3" )
			)
			( gate "@baseboard_fab2_lib.baseboard_fab2(sch_1):page141_i138"
				( attribute "BOM_COST" "NT_GBE_BASE"
					( Origin gFrontEnd )
				)
				( attribute "CDS_LIB" "mstr_discrete"
					( Origin gPackager )
				)
				( attribute "CDS_LOCATION" "C9G3"
					( Origin gPackager )
				)
				( attribute "CDS_SEC" "1"
					( Origin gPackager )
				)
				( attribute "LOCATION" "C9G3"
					( Origin gFrontEnd )
				)
				( attribute "MATERIAL" "X7R"
					( Origin gFrontEnd )
				)
				( attribute "PACK_TYPE" "0402LF"
					( Origin gFrontEnd )
				)
				( attribute "PART_NUMBER" "A36096-049"
					( Origin gFrontEnd )
				)
				( attribute "PHYS_PAGE" "141"
					( Origin gFrontEnd )
				)
				( attribute "ROOM" "NIC_SPRV"
					( Origin gFrontEnd )
				)
				( attribute "ROT" "0"
					( Origin gFrontEnd )
				)
				( attribute "SEC" "1"
					( Origin gFrontEnd )
				)
				( attribute "SEC_TYPE" "0402LF"
					( Origin gFrontEnd )
				)
				( attribute "TOLERANCE" "10%"
					( Origin gFrontEnd )
				)
				( attribute "VALUE" "470PF"
					( Origin gFrontEnd )
				)
				( attribute "VER" "1"
					( Origin gFrontEnd )
				)
				( attribute "VOLTAGE" "50V"
					( Units "uVoltage" "V" 1.000000)
					( Origin gFrontEnd )
				)
				( attribute "XY" "(-3350,2375)"
					( Origin gFrontEnd )
				)
				( attribute "CHIPS_PART_NAME" "CAP"
					( Origin gPackager )
				)
				( attribute "CDS_PART_NAME" "CAP_0402LF-470PF,50V,10%,X7R,AA"
					( Origin gPackager )
				)
				( attribute "GROUP" "NI_I210&RJ45"
					( Origin gFrontEnd )
				)
				( objectStatus "C9G3" )
			)
			( gate "@baseboard_fab2_lib.baseboard_fab2(sch_1):page141_i140"
				( attribute "BOM_COST" "NT_GBE_BASE"
					( Origin gFrontEnd )
				)
				( attribute "CDS_LIB" "mstr_discrete"
					( Origin gPackager )
				)
				( attribute "CDS_LOCATION" "C9G1"
					( Origin gPackager )
				)
				( attribute "CDS_SEC" "1"
					( Origin gPackager )
				)
				( attribute "LOCATION" "C9G1"
					( Origin gFrontEnd )
				)
				( attribute "MATERIAL" "X7R"
					( Origin gFrontEnd )
				)
				( attribute "PACK_TYPE" "0402LF"
					( Origin gFrontEnd )
				)
				( attribute "PART_NUMBER" "A36096-049"
					( Origin gFrontEnd )
				)
				( attribute "PHYS_PAGE" "141"
					( Origin gFrontEnd )
				)
				( attribute "ROOM" "NIC_SPRV"
					( Origin gFrontEnd )
				)
				( attribute "ROT" "0"
					( Origin gFrontEnd )
				)
				( attribute "SEC" "1"
					( Origin gFrontEnd )
				)
				( attribute "SEC_TYPE" "0402LF"
					( Origin gFrontEnd )
				)
				( attribute "TOLERANCE" "10%"
					( Origin gFrontEnd )
				)
				( attribute "VALUE" "470PF"
					( Origin gFrontEnd )
				)
				( attribute "VER" "1"
					( Origin gFrontEnd )
				)
				( attribute "VOLTAGE" "50V"
					( Units "uVoltage" "V" 1.000000)
					( Origin gFrontEnd )
				)
				( attribute "XY" "(-3650,2375)"
					( Origin gFrontEnd )
				)
				( attribute "CHIPS_PART_NAME" "CAP"
					( Origin gPackager )
				)
				( attribute "CDS_PART_NAME" "CAP_0402LF-470PF,50V,10%,X7R,AA"
					( Origin gPackager )
				)
				( attribute "GROUP" "NI_I210&RJ45"
					( Origin gFrontEnd )
				)
				( objectStatus "C9G1" )
			)
			( gate "@baseboard_fab2_lib.baseboard_fab2(sch_1):page141_i152"
				( attribute "BOM_COST" "NT_GBE_BASE"
					( Origin gFrontEnd )
				)
				( attribute "CDS_LIB" "mstr_discrete"
					( Origin gPackager )
				)
				( attribute "CDS_LOCATION" "C9G2"
					( Origin gPackager )
				)
				( attribute "CDS_SEC" "1"
					( Origin gPackager )
				)
				( attribute "LOCATION" "C9G2"
					( Origin gFrontEnd )
				)
				( attribute "MATERIAL" "X7R"
					( Origin gFrontEnd )
				)
				( attribute "PACK_TYPE" "0402LF"
					( Origin gFrontEnd )
				)
				( attribute "PART_NUMBER" "A36096-049"
					( Origin gFrontEnd )
				)
				( attribute "PHYS_PAGE" "141"
					( Origin gFrontEnd )
				)
				( attribute "ROOM" "NIC_SPRV"
					( Origin gFrontEnd )
				)
				( attribute "ROT" "0"
					( Origin gFrontEnd )
				)
				( attribute "SEC" "1"
					( Origin gFrontEnd )
				)
				( attribute "SEC_TYPE" "0402LF"
					( Origin gFrontEnd )
				)
				( attribute "TOLERANCE" "10%"
					( Origin gFrontEnd )
				)
				( attribute "VALUE" "470PF"
					( Origin gFrontEnd )
				)
				( attribute "VER" "1"
					( Origin gFrontEnd )
				)
				( attribute "VOLTAGE" "50V"
					( Units "uVoltage" "V" 1.000000)
					( Origin gFrontEnd )
				)
				( attribute "XY" "(-3200,1050)"
					( Origin gFrontEnd )
				)
				( attribute "CHIPS_PART_NAME" "CAP"
					( Origin gPackager )
				)
				( attribute "CDS_PART_NAME" "CAP_0402LF-470PF,50V,10%,X7R,AA"
					( Origin gPackager )
				)
				( attribute "GROUP" "NI_I210&RJ45"
					( Origin gFrontEnd )
				)
				( objectStatus "C9G2" )
			)
			( gate "@baseboard_fab2_lib.baseboard_fab2(sch_1):page141_i156"
				( attribute "BOM_COST" "NT_GBE_BASE"
					( Origin gFrontEnd )
				)
				( attribute "CDS_LIB" "mstr_discrete"
					( Origin gPackager )
				)
				( attribute "CDS_LOCATION" "R9G4"
					( Origin gPackager )
				)
				( attribute "CDS_SEC" "1"
					( Origin gPackager )
				)
				( attribute "LOCATION" "R9G4"
					( Origin gFrontEnd )
				)
				( attribute "MATERIAL" "CHIP"
					( Origin gFrontEnd )
				)
				( attribute "PACK_TYPE" "0402"
					( Origin gFrontEnd )
				)
				( attribute "PART_NUMBER" "G21497-005"
					( Origin gFrontEnd )
				)
				( attribute "PHYS_PAGE" "141"
					( Origin gFrontEnd )
				)
				( attribute "ROOM" "NIC_SPRV"
					( Origin gFrontEnd )
				)
				( attribute "ROT" "4"
					( Origin gFrontEnd )
				)
				( attribute "SEC" "1"
					( Origin gFrontEnd )
				)
				( attribute "SEC_TYPE" "0402"
					( Origin gFrontEnd )
				)
				( attribute "TOLERANCE" "5%"
					( Origin gFrontEnd )
				)
				( attribute "VALUE" "0.0"
					( Origin gFrontEnd )
				)
				( attribute "VER" "1"
					( Origin gFrontEnd )
				)
				( attribute "WATTAGE" "1/16W"
					( Origin gFrontEnd )
				)
				( attribute "XY" "(-2875,1200)"
					( Origin gFrontEnd )
				)
				( attribute "CHIPS_PART_NAME" "RES"
					( Origin gPackager )
				)
				( attribute "CDS_PART_NAME" "RES_0402-0.0,5%,1/16W,CHIP,G21A"
					( Origin gPackager )
				)
				( attribute "GROUP" "NI_I210&RJ45"
					( Origin gFrontEnd )
				)
				( objectStatus "R9G4" )
			)
			( gate "@baseboard_fab2_lib.baseboard_fab2(sch_1):page141_i157"
				( attribute "BOM_COST" "NT_GBE_BASE"
					( Origin gFrontEnd )
				)
				( attribute "CDS_LIB" "mstr_discrete"
					( Origin gPackager )
				)
				( attribute "CDS_LOCATION" "R9G1"
					( Origin gPackager )
				)
				( attribute "CDS_SEC" "1"
					( Origin gPackager )
				)
				( attribute "LOCATION" "R9G1"
					( Origin gFrontEnd )
				)
				( attribute "MATERIAL" "CHIP"
					( Origin gFrontEnd )
				)
				( attribute "PACK_TYPE" "0402"
					( Origin gFrontEnd )
				)
				( attribute "PART_NUMBER" "G21796-009"
					( Origin gFrontEnd )
				)
				( attribute "PHYS_PAGE" "141"
					( Origin gFrontEnd )
				)
				( attribute "ROOM" "NIC_SPRV"
					( Origin gFrontEnd )
				)
				( attribute "ROT" "0"
					( Origin gFrontEnd )
				)
				( attribute "SEC" "1"
					( Origin gFrontEnd )
				)
				( attribute "SEC_TYPE" "0402"
					( Origin gFrontEnd )
				)
				( attribute "TOLERANCE" "1%"
					( Origin gFrontEnd )
				)
				( attribute "VALUE" "150.0"
					( Origin gFrontEnd )
				)
				( attribute "VER" "1"
					( Origin gFrontEnd )
				)
				( attribute "WATTAGE" "1/16W"
					( Origin gFrontEnd )
				)
				( attribute "XY" "(-2800,1450)"
					( Origin gFrontEnd )
				)
				( attribute "CHIPS_PART_NAME" "RES"
					( Origin gPackager )
				)
				( attribute "CDS_PART_NAME" "RES_0402-150.0,1%,1/16W,CHIP,GA"
					( Origin gPackager )
				)
				( attribute "GROUP" "NI_I210&RJ45"
					( Origin gFrontEnd )
				)
				( objectStatus "R9G1" )
			)
			( gate "@baseboard_fab2_lib.baseboard_fab2(sch_1):page141_i159"
				( attribute "BOM_COST" "NT_GBE_BASE"
					( Origin gFrontEnd )
				)
				( attribute "CDS_LIB" "mstr_discrete"
					( Origin gPackager )
				)
				( attribute "CDS_LOCATION" "C9F22"
					( Origin gPackager )
				)
				( attribute "CDS_SEC" "1"
					( Origin gPackager )
				)
				( attribute "LOCATION" "C9F22"
					( Origin gFrontEnd )
				)
				( attribute "MATERIAL" "X7R"
					( Origin gFrontEnd )
				)
				( attribute "PACK_TYPE" "0402LF"
					( Origin gFrontEnd )
				)
				( attribute "PART_NUMBER" "A36096-049"
					( Origin gFrontEnd )
				)
				( attribute "PHYS_PAGE" "141"
					( Origin gFrontEnd )
				)
				( attribute "ROOM" "NIC_SPRV"
					( Origin gFrontEnd )
				)
				( attribute "ROT" "0"
					( Origin gFrontEnd )
				)
				( attribute "SEC" "1"
					( Origin gFrontEnd )
				)
				( attribute "SEC_TYPE" "0402LF"
					( Origin gFrontEnd )
				)
				( attribute "TOLERANCE" "10%"
					( Origin gFrontEnd )
				)
				( attribute "VALUE" "470PF"
					( Origin gFrontEnd )
				)
				( attribute "VER" "1"
					( Origin gFrontEnd )
				)
				( attribute "VOLTAGE" "50V"
					( Units "uVoltage" "V" 1.000000)
					( Origin gFrontEnd )
				)
				( attribute "XY" "(-3650,1300)"
					( Origin gFrontEnd )
				)
				( attribute "CHIPS_PART_NAME" "CAP"
					( Origin gPackager )
				)
				( attribute "CDS_PART_NAME" "CAP_0402LF-470PF,50V,10%,X7R,AA"
					( Origin gPackager )
				)
				( attribute "GROUP" "NI_I210&RJ45"
					( Origin gFrontEnd )
				)
				( objectStatus "C9F22" )
			)
			( gate "@baseboard_fab2_lib.baseboard_fab2(sch_1):page202_i109"
				( attribute "CDS_LIB" "w_hdl"
					( Origin gPackager )
				)
				( attribute "CDS_LMAN_SYM_OUTLINE" "-75,100,75,-100"
					( Origin gPackager )
				)
				( attribute "LOCATION" "L4E1"
					( Origin gFrontEnd )
				)
				( attribute "PACK_TYPE" "DISCRET-GB2"
					( Origin gFrontEnd )
				)
				( attribute "PART_NUMBER" "068.1202N.M001"
					( Origin gFrontEnd )
				)
				( attribute "PHYS_PAGE" "202"
					( Origin gFrontEnd )
				)
				( attribute "ROT" "1"
					( Origin gFrontEnd )
				)
				( attribute "SEC" "1"
					( Origin gFrontEnd )
				)
				( attribute "SEC_TYPE" "DISCRET-GB2"
					( Origin gFrontEnd )
				)
				( attribute "VALUE" "IND-120NH-30-GP"
					( Origin gFrontEnd )
				)
				( attribute "VER" "1"
					( Origin gFrontEnd )
				)
				( attribute "XY" "(-1700,3525)"
					( Origin gFrontEnd )
				)
				( attribute "CHIPS_PART_NAME" "IND-120NH-30-GP"
					( Origin gPackager )
				)
				( attribute "CDS_PART_NAME" "IND-120NH-30-GP_DISCRET-GB2-INA"
					( Origin gPackager )
				)
				( attribute "CDS_LOCATION" "L4E1"
					( Origin gPackager )
				)
				( attribute "CDS_SEC" "1"
					( Origin gPackager )
				)
				( attribute "ATTRIBUTE" "120NH"
					( Origin gFrontEnd )
				)
				( attribute "PACK_SIZE" "DCR=0.17MOHM"
					( Origin gFrontEnd )
				)
				( attribute "RATED" "ISAT=94A@25C"
					( Origin gFrontEnd )
				)
				( attribute "TYPE" "IRMS=66A@DELTA_T<40C"
					( Origin gFrontEnd )
				)
				( objectStatus "L4E1" )
			)
			( gate "@baseboard_fab2_lib.baseboard_fab2(sch_1):page203_i131"
				( attribute "CDS_LIB" "w_hdl"
					( Origin gPackager )
				)
				( attribute "CDS_LMAN_SYM_OUTLINE" "-75,100,75,-100"
					( Origin gPackager )
				)
				( attribute "LOCATION" "L4D1"
					( Origin gFrontEnd )
				)
				( attribute "PACK_TYPE" "DISCRET-GB2"
					( Origin gFrontEnd )
				)
				( attribute "PART_NUMBER" "068.1202N.M001"
					( Origin gFrontEnd )
				)
				( attribute "PHYS_PAGE" "203"
					( Origin gFrontEnd )
				)
				( attribute "ROT" "1"
					( Origin gFrontEnd )
				)
				( attribute "SEC" "1"
					( Origin gFrontEnd )
				)
				( attribute "SEC_TYPE" "DISCRET-GB2"
					( Origin gFrontEnd )
				)
				( attribute "VALUE" "IND-120NH-30-GP"
					( Origin gFrontEnd )
				)
				( attribute "VER" "1"
					( Origin gFrontEnd )
				)
				( attribute "XY" "(-1075,950)"
					( Origin gFrontEnd )
				)
				( attribute "CHIPS_PART_NAME" "IND-120NH-30-GP"
					( Origin gPackager )
				)
				( attribute "CDS_PART_NAME" "IND-120NH-30-GP_DISCRET-GB2-INA"
					( Origin gPackager )
				)
				( attribute "CDS_LOCATION" "L4D1"
					( Origin gPackager )
				)
				( attribute "CDS_SEC" "1"
					( Origin gPackager )
				)
				( attribute "ATTRIBUTE" "120NH"
					( Origin gFrontEnd )
				)
				( attribute "PACK_SIZE" "DCR=0.17MOHM"
					( Origin gFrontEnd )
				)
				( attribute "RATED" "ISAT=94A@25C"
					( Origin gFrontEnd )
				)
				( attribute "TYPE" "IRMS=66A@DELTA_T<40C"
					( Origin gFrontEnd )
				)
				( objectStatus "L4D1" )
			)
			( gate "@baseboard_fab2_lib.baseboard_fab2(sch_1):page208_i116"
				( attribute "CDS_LIB" "w_hdl"
					( Origin gPackager )
				)
				( attribute "CDS_LMAN_SYM_OUTLINE" "-75,100,75,-100"
					( Origin gPackager )
				)
				( attribute "LOCATION" "L1D2"
					( Origin gFrontEnd )
				)
				( attribute "PACK_TYPE" "DISCRET-GB2"
					( Origin gFrontEnd )
				)
				( attribute "PART_NUMBER" "068.1202N.M001"
					( Origin gFrontEnd )
				)
				( attribute "PHYS_PAGE" "208"
					( Origin gFrontEnd )
				)
				( attribute "ROT" "1"
					( Origin gFrontEnd )
				)
				( attribute "SEC" "1"
					( Origin gFrontEnd )
				)
				( attribute "SEC_TYPE" "DISCRET-GB2"
					( Origin gFrontEnd )
				)
				( attribute "VALUE" "IND-120NH-30-GP"
					( Origin gFrontEnd )
				)
				( attribute "VER" "1"
					( Origin gFrontEnd )
				)
				( attribute "XY" "(-1425,3650)"
					( Origin gFrontEnd )
				)
				( attribute "CHIPS_PART_NAME" "IND-120NH-30-GP"
					( Origin gPackager )
				)
				( attribute "CDS_PART_NAME" "IND-120NH-30-GP_DISCRET-GB2-INA"
					( Origin gPackager )
				)
				( attribute "CDS_LOCATION" "L1D2"
					( Origin gPackager )
				)
				( attribute "CDS_SEC" "1"
					( Origin gPackager )
				)
				( attribute "ATTRIBUTE" "120NH"
					( Origin gFrontEnd )
				)
				( attribute "PACK_SIZE" "DCR=0.17MOHM"
					( Origin gFrontEnd )
				)
				( attribute "RATED" "ISAT=94A@25C"
					( Origin gFrontEnd )
				)
				( attribute "TYPE" "IRMS=66A@DELTA_T<40C"
					( Origin gFrontEnd )
				)
				( objectStatus "L1D2" )
			)
			( gate "@baseboard_fab2_lib.baseboard_fab2(sch_1):page208_i117"
				( attribute "CDS_LIB" "w_hdl"
					( Origin gPackager )
				)
				( attribute "CDS_LMAN_SYM_OUTLINE" "-75,100,75,-100"
					( Origin gPackager )
				)
				( attribute "LOCATION" "L1D1"
					( Origin gFrontEnd )
				)
				( attribute "PACK_TYPE" "DISCRET-GB2"
					( Origin gFrontEnd )
				)
				( attribute "PART_NUMBER" "068.1202N.M001"
					( Origin gFrontEnd )
				)
				( attribute "PHYS_PAGE" "208"
					( Origin gFrontEnd )
				)
				( attribute "ROT" "1"
					( Origin gFrontEnd )
				)
				( attribute "SEC" "1"
					( Origin gFrontEnd )
				)
				( attribute "SEC_TYPE" "DISCRET-GB2"
					( Origin gFrontEnd )
				)
				( attribute "VALUE" "IND-120NH-30-GP"
					( Origin gFrontEnd )
				)
				( attribute "VER" "1"
					( Origin gFrontEnd )
				)
				( attribute "XY" "(-1275,1050)"
					( Origin gFrontEnd )
				)
				( attribute "CHIPS_PART_NAME" "IND-120NH-30-GP"
					( Origin gPackager )
				)
				( attribute "CDS_PART_NAME" "IND-120NH-30-GP_DISCRET-GB2-INA"
					( Origin gPackager )
				)
				( attribute "CDS_LOCATION" "L1D1"
					( Origin gPackager )
				)
				( attribute "CDS_SEC" "1"
					( Origin gPackager )
				)
				( attribute "ATTRIBUTE" "120NH"
					( Origin gFrontEnd )
				)
				( attribute "PACK_SIZE" "DCR=0.17MOHM"
					( Origin gFrontEnd )
				)
				( attribute "RATED" "ISAT=94A@25C"
					( Origin gFrontEnd )
				)
				( attribute "TYPE" "IRMS=66A@DELTA_T<40C"
					( Origin gFrontEnd )
				)
				( objectStatus "L1D1" )
			)
			( gate "@baseboard_fab2_lib.baseboard_fab2(sch_1):page230_i36"
				( attribute "BOM_COST" "MEM_VRD_VTT_KLM"
					( Origin gFrontEnd )
				)
				( attribute "CDS_LIB" "mstr_discrete"
					( Origin gPackager )
				)
				( attribute "CDS_LOCATION" "C4A14"
					( Origin gPackager )
				)
				( attribute "CDS_SEC" "1"
					( Origin gPackager )
				)
				( attribute "LOCATION" "C4A14"
					( Origin gFrontEnd )
				)
				( attribute "MATERIAL" "X6S"
					( Origin gFrontEnd )
				)
				( attribute "PACK_TYPE" "0402"
					( Origin gFrontEnd )
				)
				( attribute "PART_NUMBER" "D97712-011"
					( Origin gFrontEnd )
				)
				( attribute "PHYS_PAGE" "230"
					( Origin gFrontEnd )
				)
				( attribute "ROOM" "VTT_KLM_PWR_VR"
					( Origin gFrontEnd )
				)
				( attribute "ROT" "0"
					( Origin gFrontEnd )
				)
				( attribute "SEC" "1"
					( Origin gFrontEnd )
				)
				( attribute "SEC_TYPE" "0402"
					( Origin gFrontEnd )
				)
				( attribute "TOLERANCE" "10%"
					( Origin gFrontEnd )
				)
				( attribute "VALUE" "1.0UF"
					( Origin gFrontEnd )
				)
				( attribute "VER" "1"
					( Origin gFrontEnd )
				)
				( attribute "VOLTAGE" "16V"
					( Units "uVoltage" "V" 1.000000)
					( Origin gFrontEnd )
				)
				( attribute "XY" "(675,125)"
					( Origin gFrontEnd )
				)
				( attribute "CHIPS_PART_NAME" "CAP"
					( Origin gPackager )
				)
				( attribute "CDS_PART_NAME" "CAP_0402-1.0UF,16V,10%,X6S,D97A"
					( Origin gPackager )
				)
				( objectStatus "C4A14" )
			)
			( gate "@baseboard_fab2_lib.baseboard_fab2(sch_1):page230_i35"
				( attribute "BOM_COST" "MEM_VRD_VTT_KLM"
					( Origin gFrontEnd )
				)
				( attribute "CDS_LIB" "mstr_discrete"
					( Origin gPackager )
				)
				( attribute "CDS_LOCATION" "C6L5"
					( Origin gPackager )
				)
				( attribute "CDS_SEC" "1"
					( Origin gPackager )
				)
				( attribute "LOCATION" "C6L5"
					( Origin gFrontEnd )
				)
				( attribute "MATERIAL" "X6S"
					( Origin gFrontEnd )
				)
				( attribute "PACK_TYPE" "0603LF"
					( Origin gFrontEnd )
				)
				( attribute "PART_NUMBER" "E15431-001"
					( Origin gFrontEnd )
				)
				( attribute "PHYS_PAGE" "230"
					( Origin gFrontEnd )
				)
				( attribute "ROOM" "VTT_KLM_PWR_VR"
					( Origin gFrontEnd )
				)
				( attribute "ROT" "0"
					( Origin gFrontEnd )
				)
				( attribute "SEC" "1"
					( Origin gFrontEnd )
				)
				( attribute "SEC_TYPE" "0603LF"
					( Origin gFrontEnd )
				)
				( attribute "TOLERANCE" "20%"
					( Origin gFrontEnd )
				)
				( attribute "VALUE" "10UF"
					( Origin gFrontEnd )
				)
				( attribute "VER" "1"
					( Origin gFrontEnd )
				)
				( attribute "VOLTAGE" "4V"
					( Units "uVoltage" "V" 1.000000)
					( Origin gFrontEnd )
				)
				( attribute "XY" "(-1625,1625)"
					( Origin gFrontEnd )
				)
				( attribute "CHIPS_PART_NAME" "CAP"
					( Origin gPackager )
				)
				( attribute "CDS_PART_NAME" "CAP_0603LF-10UF,4V,20%,X6S,E15A"
					( Origin gPackager )
				)
				( objectStatus "C6L5" )
			)
			( gate "@baseboard_fab2_lib.baseboard_fab2(sch_1):page230_i32"
				( attribute "CDS_LIB" "mstr_discrete"
					( Origin gPackager )
				)
				( attribute "CDS_LOCATION" "R4A4"
					( Origin gPackager )
				)
				( attribute "CDS_SEC" "1"
					( Origin gPackager )
				)
				( attribute "LOCATION" "R4A4"
					( Origin gFrontEnd )
				)
				( attribute "MATERIAL" "CHIP"
					( Origin gFrontEnd )
				)
				( attribute "PACK_TYPE" "0402"
					( Origin gFrontEnd )
				)
				( attribute "PART_NUMBER" "G21796-074"
					( Origin gFrontEnd )
				)
				( attribute "PHYS_PAGE" "230"
					( Origin gFrontEnd )
				)
				( attribute "ROT" "0"
					( Origin gFrontEnd )
				)
				( attribute "SEC" "1"
					( Origin gFrontEnd )
				)
				( attribute "SEC_TYPE" "0402"
					( Origin gFrontEnd )
				)
				( attribute "TOLERANCE" "1%"
					( Origin gFrontEnd )
				)
				( attribute "VALUE" "33.2"
					( Origin gFrontEnd )
				)
				( attribute "VER" "1"
					( Origin gFrontEnd )
				)
				( attribute "WATTAGE" "1/16W"
					( Origin gFrontEnd )
				)
				( attribute "XY" "(2575,1100)"
					( Origin gFrontEnd )
				)
				( attribute "CHIPS_PART_NAME" "RES"
					( Origin gPackager )
				)
				( attribute "CDS_PART_NAME" "RES_0402-33.2,1%,1/16W,CHIP,G2A"
					( Origin gPackager )
				)
				( objectStatus "R4A4" )
			)
			( gate "@baseboard_fab2_lib.baseboard_fab2(sch_1):page230_i24"
				( attribute "CDS_LIB" "dev_discrete"
					( Origin gPackager )
				)
				( attribute "CDS_LOCATION" "C8M12"
					( Origin gPackager )
				)
				( attribute "CDS_SEC" "1"
					( Origin gPackager )
				)
				( attribute "LOCATION" "C8M12"
					( Origin gFrontEnd )
				)
				( attribute "MATERIAL" "X5R"
					( Origin gFrontEnd )
				)
				( attribute "PACK_TYPE" "0603V"
					( Origin gFrontEnd )
				)
				( attribute "PART_NUMBER" "602433-106"
					( Origin gFrontEnd )
				)
				( attribute "PHYS_PAGE" "230"
					( Origin gFrontEnd )
				)
				( attribute "ROT" "0"
					( Origin gFrontEnd )
				)
				( attribute "SEC" "1"
					( Origin gFrontEnd )
				)
				( attribute "SEC_TYPE" "0603V"
					( Origin gFrontEnd )
				)
				( attribute "TOLERANCE" "20%"
					( Origin gFrontEnd )
				)
				( attribute "VALUE" "47UF"
					( Origin gFrontEnd )
				)
				( attribute "VER" "1"
					( Origin gFrontEnd )
				)
				( attribute "VOLTAGE" "4V"
					( Units "uVoltage" "V" 1.000000)
					( Origin gFrontEnd )
				)
				( attribute "XY" "(1350,2675)"
					( Origin gFrontEnd )
				)
				( attribute "CHIPS_PART_NAME" "CAP_A"
					( Origin gPackager )
				)
				( attribute "CDS_PART_NAME" "CAP_A_0603V-47UF,4V,20%,X5R,60A"
					( Origin gPackager )
				)
				( attribute "GROUP" "PWR_MLCC_CAP"
					( Origin gFrontEnd )
				)
				( objectStatus "C8M12" )
			)
			( gate "@baseboard_fab2_lib.baseboard_fab2(sch_1):page230_i23"
				( attribute "BOM_COST" "MEM_VRD_VTT_KLM"
					( Origin gFrontEnd )
				)
				( attribute "CDS_LIB" "mstr_discrete"
					( Origin gPackager )
				)
				( attribute "CDS_LOCATION" "C4A3"
					( Origin gPackager )
				)
				( attribute "CDS_SEC" "1"
					( Origin gPackager )
				)
				( attribute "LOCATION" "C4A3"
					( Origin gFrontEnd )
				)
				( attribute "MATERIAL" "X7R"
					( Origin gFrontEnd )
				)
				( attribute "PACK_TYPE" "0402LF"
					( Origin gFrontEnd )
				)
				( attribute "PART_NUMBER" "A36096-046"
					( Origin gFrontEnd )
				)
				( attribute "PHYS_PAGE" "230"
					( Origin gFrontEnd )
				)
				( attribute "ROOM" "VTT_KLM_PWR_VR"
					( Origin gFrontEnd )
				)
				( attribute "ROT" "2"
					( Origin gFrontEnd )
				)
				( attribute "SEC" "1"
					( Origin gFrontEnd )
				)
				( attribute "SEC_TYPE" "0402LF"
					( Origin gFrontEnd )
				)
				( attribute "TOLERANCE" "10%"
					( Origin gFrontEnd )
				)
				( attribute "VALUE" "1000PF"
					( Origin gFrontEnd )
				)
				( attribute "VER" "1"
					( Origin gFrontEnd )
				)
				( attribute "VOLTAGE" "50V"
					( Units "uVoltage" "V" 1.000000)
					( Origin gFrontEnd )
				)
				( attribute "XY" "(2200,900)"
					( Origin gFrontEnd )
				)
				( attribute "CHIPS_PART_NAME" "CAP"
					( Origin gPackager )
				)
				( attribute "CDS_PART_NAME" "CAP_0402LF-1000PF,50V,10%,X7R,A"
					( Origin gPackager )
				)
				( objectStatus "C4A3" )
			)
			( gate "@baseboard_fab2_lib.baseboard_fab2(sch_1):page255_i136"
				( attribute "CDS_LIB" "w_hdl"
					( Origin gPackager )
				)
				( attribute "CDS_LMAN_SYM_OUTLINE" "-75,425,75,-425"
					( Origin gPackager )
				)
				( attribute "LOCATION" "J25W1"
					( Origin gFrontEnd )
				)
				( attribute "PACK_TYPE" "CONN-GC2"
					( Origin gFrontEnd )
				)
				( attribute "PART_NUMBER" "021.D0181.0113"
					( Origin gFrontEnd )
				)
				( attribute "PHYS_PAGE" "252"
					( Origin gFrontEnd )
				)
				( attribute "ROT" "0"
					( Origin gFrontEnd )
				)
				( attribute "SEC" "1"
					( Origin gFrontEnd )
				)
				( attribute "SEC_TYPE" "CONN-GC2"
					( Origin gFrontEnd )
				)
				( attribute "VALUE" "SMC-CON13-GP"
					( Origin gFrontEnd )
				)
				( attribute "VER" "1"
					( Origin gFrontEnd )
				)
				( attribute "XY" "(-9225,2725)"
					( Origin gFrontEnd )
				)
				( attribute "CHIPS_PART_NAME" "SMC-CON13-GP"
					( Origin gPackager )
				)
				( attribute "CDS_PART_NAME" "SMC-CON13-GP_CONN-GC2-SMC-CON1A"
					( Origin gPackager )
				)
				( attribute "CDS_LOCATION" "J25W1"
					( Origin gPackager )
				)
				( attribute "CDS_SEC" "1"
					( Origin gPackager )
				)
				( attribute "GROUP" "AST2500"
					( Origin gFrontEnd )
				)
				( objectStatus "J25W1" )
			)
			( gate "@baseboard_fab2_lib.baseboard_fab2(sch_1):page172_i71"
				( attribute "CDS_LIB" "w_hdl"
					( Origin gPackager )
				)
				( attribute "CDS_LMAN_SYM_OUTLINE" "-75,50,75,-50"
					( Origin gPackager )
				)
				( attribute "LOCATION" "F8B1"
					( Origin gFrontEnd )
				)
				( attribute "PACK_TYPE" "DISCRET-G5"
					( Origin gFrontEnd )
				)
				( attribute "PART_NUMBER" "69.43001.511"
					( Origin gFrontEnd )
				)
				( attribute "PHYS_PAGE" "172"
					( Origin gFrontEnd )
				)
				( attribute "ROT" "0"
					( Origin gFrontEnd )
				)
				( attribute "VALUE" "FUSE-3A75V-GP"
					( Origin gFrontEnd )
				)
				( attribute "VER" "1"
					( Origin gFrontEnd )
				)
				( attribute "XY" "(175,650)"
					( Origin gFrontEnd )
				)
				( attribute "CHIPS_PART_NAME" "FUSE-3A75V-GP"
					( Origin gPackager )
				)
				( attribute "CDS_PART_NAME" "FUSE-3A75V-GP_DISCRET-G5-FUSE-A"
					( Origin gPackager )
				)
				( attribute "SEC" "1"
					( Origin gFrontEnd )
				)
				( attribute "SEC_TYPE" "DISCRET-G5"
					( Origin gFrontEnd )
				)
				( attribute "CDS_LOCATION" "F8B1"
					( Origin gPackager )
				)
				( attribute "CDS_SEC" "1"
					( Origin gPackager )
				)
				( objectStatus "F8B1" )
			)
			( gate "@baseboard_fab2_lib.baseboard_fab2(sch_1):page240_i189"
				( attribute "CDS_LIB" "w_hdl"
					( Origin gPackager )
				)
				( attribute "CDS_LMAN_SYM_OUTLINE" "-50,25,50,-25"
					( Origin gPackager )
				)
				( attribute "LOCATION" "C8F14"
					( Origin gFrontEnd )
				)
				( attribute "PACK_TYPE" "SMD-TCG4"
					( Origin gFrontEnd )
				)
				( attribute "PART_NUMBER" "077.C4771.0061"
					( Origin gFrontEnd )
				)
				( attribute "PHYS_PAGE" "240"
					( Origin gFrontEnd )
				)
				( attribute "ROT" "0"
					( Origin gFrontEnd )
				)
				( attribute "SEC" "1"
					( Origin gFrontEnd )
				)
				( attribute "SEC_TYPE" "SMD-TCG4"
					( Origin gFrontEnd )
				)
				( attribute "VALUE" "ST470U6D3VDM-7-GP"
					( Origin gFrontEnd )
				)
				( attribute "VER" "1"
					( Origin gFrontEnd )
				)
				( attribute "XY" "(11100,3825)"
					( Origin gFrontEnd )
				)
				( attribute "CHIPS_PART_NAME" "ST470U6D3VDM-7-GP"
					( Origin gPackager )
				)
				( attribute "CDS_PART_NAME" "ST470U6D3VDM-7-GP_SMD-TCG4-ST4A"
					( Origin gPackager )
				)
				( attribute "CDS_LOCATION" "C8F14"
					( Origin gPackager )
				)
				( attribute "CDS_SEC" "1"
					( Origin gPackager )
				)
				( attribute "ATTRIBUTE" "470UF"
					( Origin gFrontEnd )
				)
				( attribute "PACK_SIZE" "ESR=35MOHM"
					( Origin gFrontEnd )
				)
				( attribute "RATED" "6.3V"
					( Origin gFrontEnd )
				)
				( attribute "TOLERANCE" "IRP=1.7A"
					( Origin gFrontEnd )
				)
				( attribute "TYPE" "TMAX=105C"
					( Origin gFrontEnd )
				)
				( objectStatus "C8F14" )
			)
			( gate "@baseboard_fab2_lib.baseboard_fab2(sch_1):page147_i159"
				( attribute "CDS_LIB" "mstr_discrete"
					( Origin gPackager )
				)
				( attribute "LOCATION" "R25W143"
					( Origin gFrontEnd )
				)
				( attribute "MATERIAL" "CHIP"
					( Origin gFrontEnd )
				)
				( attribute "PACK_TYPE" "0402"
					( Origin gFrontEnd )
				)
				( attribute "PART_NUMBER" "G21497-005"
					( Origin gFrontEnd )
				)
				( attribute "PHYS_PAGE" "147"
					( Origin gFrontEnd )
				)
				( attribute "ROOM" "DEBUG"
					( Origin gFrontEnd )
				)
				( attribute "ROT" "0"
					( Origin gFrontEnd )
				)
				( attribute "SEC" "1"
					( Origin gFrontEnd )
				)
				( attribute "SEC_TYPE" "0402"
					( Origin gFrontEnd )
				)
				( attribute "TOLERANCE" "5%"
					( Origin gFrontEnd )
				)
				( attribute "VALUE" "0.0"
					( Origin gFrontEnd )
				)
				( attribute "VER" "1"
					( Origin gFrontEnd )
				)
				( attribute "WATTAGE" "1/16W"
					( Origin gFrontEnd )
				)
				( attribute "XY" "(1500,3400)"
					( Origin gFrontEnd )
				)
				( attribute "CHIPS_PART_NAME" "RES"
					( Origin gPackager )
				)
				( attribute "CDS_PART_NAME" "RES_0402-0.0,5%,1/16W,CHIP,G21A"
					( Origin gPackager )
				)
				( attribute "CDS_LOCATION" "R25W143"
					( Origin gPackager )
				)
				( attribute "CDS_SEC" "1"
					( Origin gPackager )
				)
				( objectStatus "R25W143" )
			)
			( gate "@baseboard_fab2_lib.baseboard_fab2(sch_1):page240_i188"
				( attribute "CDS_LIB" "w_hdl"
					( Origin gPackager )
				)
				( attribute "CDS_LMAN_SYM_OUTLINE" "-50,100,50,-100"
					( Origin gPackager )
				)
				( attribute "LOCATION" "L8F1"
					( Origin gFrontEnd )
				)
				( attribute "PACK_TYPE" "DISCRET-GC1"
					( Origin gFrontEnd )
				)
				( attribute "PART_NUMBER" "068.1R010.1781"
					( Origin gFrontEnd )
				)
				( attribute "PHYS_PAGE" "240"
					( Origin gFrontEnd )
				)
				( attribute "ROT" "1"
					( Origin gFrontEnd )
				)
				( attribute "SEC" "1"
					( Origin gFrontEnd )
				)
				( attribute "SEC_TYPE" "DISCRET-GC1"
					( Origin gFrontEnd )
				)
				( attribute "VALUE" "IND-1UH-361-GP"
					( Origin gFrontEnd )
				)
				( attribute "VER" "1"
					( Origin gFrontEnd )
				)
				( attribute "XY" "(10500,4050)"
					( Origin gFrontEnd )
				)
				( attribute "CHIPS_PART_NAME" "IND-1UH-361-GP"
					( Origin gPackager )
				)
				( attribute "CDS_PART_NAME" "IND-1UH-361-GP_DISCRET-GC1-INDA"
					( Origin gPackager )
				)
				( attribute "CDS_LOCATION" "L8F1"
					( Origin gPackager )
				)
				( attribute "CDS_SEC" "1"
					( Origin gPackager )
				)
				( attribute "ATTRIBUTE" "1.0UH"
					( Origin gFrontEnd )
				)
				( attribute "PACK_SIZE" "DCR=4.6MOHM"
					( Origin gFrontEnd )
				)
				( attribute "RATED" "ISAT=24A@25C"
					( Origin gFrontEnd )
				)
				( objectStatus "L8F1" )
			)
			( gate "@baseboard_fab2_lib.baseboard_fab2(sch_1):page240_i190"
				( attribute "CDS_LIB" "w_hdl"
					( Origin gPackager )
				)
				( attribute "CDS_LMAN_SYM_OUTLINE" "-50,25,50,-25"
					( Origin gPackager )
				)
				( attribute "LOCATION" "C8F8"
					( Origin gFrontEnd )
				)
				( attribute "PACK_TYPE" "SMD-TCG4"
					( Origin gFrontEnd )
				)
				( attribute "PART_NUMBER" "077.C4771.0061"
					( Origin gFrontEnd )
				)
				( attribute "PHYS_PAGE" "240"
					( Origin gFrontEnd )
				)
				( attribute "ROT" "0"
					( Origin gFrontEnd )
				)
				( attribute "SEC" "1"
					( Origin gFrontEnd )
				)
				( attribute "SEC_TYPE" "SMD-TCG4"
					( Origin gFrontEnd )
				)
				( attribute "VALUE" "ST470U6D3VDM-7-GP"
					( Origin gFrontEnd )
				)
				( attribute "VER" "1"
					( Origin gFrontEnd )
				)
				( attribute "XY" "(11500,3825)"
					( Origin gFrontEnd )
				)
				( attribute "CHIPS_PART_NAME" "ST470U6D3VDM-7-GP"
					( Origin gPackager )
				)
				( attribute "CDS_PART_NAME" "ST470U6D3VDM-7-GP_SMD-TCG4-ST4A"
					( Origin gPackager )
				)
				( attribute "CDS_LOCATION" "C8F8"
					( Origin gPackager )
				)
				( attribute "CDS_SEC" "1"
					( Origin gPackager )
				)
				( attribute "ATTRIBUTE" "470UF"
					( Origin gFrontEnd )
				)
				( attribute "PACK_SIZE" "ESR=35MOHM"
					( Origin gFrontEnd )
				)
				( attribute "RATED" "6.3V"
					( Origin gFrontEnd )
				)
				( attribute "TOLERANCE" "IRP=1.7A"
					( Origin gFrontEnd )
				)
				( attribute "TYPE" "TMAX=105C"
					( Origin gFrontEnd )
				)
				( objectStatus "C8F8" )
			)
			( gate "@baseboard_fab2_lib.baseboard_fab2(sch_1):page185_i143"
				( attribute "CDS_LIB" "w_hdl"
					( Origin gPackager )
				)
				( attribute "CDS_LMAN_SYM_OUTLINE" "-150,1050,150,-1050"
					( Origin gPackager )
				)
				( attribute "LOCATION" "J8F1"
					( Origin gFrontEnd )
				)
				( attribute "PACK_TYPE" "SOCKET-G4"
					( Origin gFrontEnd )
				)
				( attribute "PART_NUMBER" "062.10003.0B21"
					( Origin gFrontEnd )
				)
				( attribute "PHYS_PAGE" "185"
					( Origin gFrontEnd )
				)
				( attribute "ROT" "0"
					( Origin gFrontEnd )
				)
				( attribute "SEC" "1"
					( Origin gFrontEnd )
				)
				( attribute "SEC_TYPE" "SOCKET-G4"
					( Origin gFrontEnd )
				)
				( attribute "VALUE" "SKT-MINI67P-41-GP"
					( Origin gFrontEnd )
				)
				( attribute "VER" "1"
					( Origin gFrontEnd )
				)
				( attribute "XY" "(-6450,3650)"
					( Origin gFrontEnd )
				)
				( attribute "CHIPS_PART_NAME" "SKT-MINI67P-41-GP"
					( Origin gPackager )
				)
				( attribute "CDS_PART_NAME" "SKT-MINI67P-41-GP_SOCKET-G4-SKA"
					( Origin gPackager )
				)
				( attribute "CDS_LOCATION" "J8F1"
					( Origin gPackager )
				)
				( attribute "CDS_SEC" "1"
					( Origin gPackager )
				)
				( objectStatus "J8F1" )
			)
			( gate "@baseboard_fab2_lib.baseboard_fab2(sch_1):page185_i167"
				( attribute "BOM_COST" "ST_FLASH"
					( Origin gFrontEnd )
				)
				( attribute "CDS_LIB" "mstr_discrete"
					( Origin gPackager )
				)
				( attribute "CDS_LOCATION" "C2T11"
					( Origin gPackager )
				)
				( attribute "LOCATION" "C2T11"
					( Origin gFrontEnd )
				)
				( attribute "MATERIAL" "X7R"
					( Origin gFrontEnd )
				)
				( attribute "PACK_TYPE" "0402"
					( Origin gFrontEnd )
				)
				( attribute "PART_NUMBER" "A36096-155"
					( Origin gFrontEnd )
				)
				( attribute "PHYS_PAGE" "185"
					( Origin gFrontEnd )
				)
				( attribute "ROOM" "M_2"
					( Origin gFrontEnd )
				)
				( attribute "ROT" "0"
					( Origin gFrontEnd )
				)
				( attribute "SEC" "1"
					( Origin gFrontEnd )
				)
				( attribute "SEC_TYPE" "0402"
					( Origin gFrontEnd )
				)
				( attribute "TOLERANCE" "10%"
					( Origin gFrontEnd )
				)
				( attribute "VALUE" "0.22UF"
					( Origin gFrontEnd )
				)
				( attribute "VER" "2"
					( Origin gFrontEnd )
				)
				( attribute "VOLTAGE" "16V"
					( Units "uVoltage" "V" 1.000000)
					( Origin gFrontEnd )
				)
				( attribute "XY" "(-4850,3650)"
					( Origin gFrontEnd )
				)
				( attribute "CHIPS_PART_NAME" "CAP"
					( Origin gPackager )
				)
				( attribute "CDS_PART_NAME" "CAP_0402-0.22UF,16V,10%,X7R,A3A"
					( Origin gPackager )
				)
				( attribute "CDS_SEC" "1"
					( Origin gPackager )
				)
				( objectStatus "C2T11" )
			)
			( gate "@baseboard_fab2_lib.baseboard_fab2(sch_1):page185_i168"
				( attribute "BOM_COST" "ST_FLASH"
					( Origin gFrontEnd )
				)
				( attribute "CDS_LIB" "mstr_discrete"
					( Origin gPackager )
				)
				( attribute "CDS_LOCATION" "C2T10"
					( Origin gPackager )
				)
				( attribute "LOCATION" "C2T10"
					( Origin gFrontEnd )
				)
				( attribute "MATERIAL" "X7R"
					( Origin gFrontEnd )
				)
				( attribute "PACK_TYPE" "0402"
					( Origin gFrontEnd )
				)
				( attribute "PART_NUMBER" "A36096-155"
					( Origin gFrontEnd )
				)
				( attribute "PHYS_PAGE" "185"
					( Origin gFrontEnd )
				)
				( attribute "ROOM" "M_2"
					( Origin gFrontEnd )
				)
				( attribute "ROT" "0"
					( Origin gFrontEnd )
				)
				( attribute "SEC" "1"
					( Origin gFrontEnd )
				)
				( attribute "SEC_TYPE" "0402"
					( Origin gFrontEnd )
				)
				( attribute "TOLERANCE" "10%"
					( Origin gFrontEnd )
				)
				( attribute "VALUE" "0.22UF"
					( Origin gFrontEnd )
				)
				( attribute "VER" "2"
					( Origin gFrontEnd )
				)
				( attribute "VOLTAGE" "16V"
					( Units "uVoltage" "V" 1.000000)
					( Origin gFrontEnd )
				)
				( attribute "XY" "(-4850,3600)"
					( Origin gFrontEnd )
				)
				( attribute "CHIPS_PART_NAME" "CAP"
					( Origin gPackager )
				)
				( attribute "CDS_PART_NAME" "CAP_0402-0.22UF,16V,10%,X7R,A3A"
					( Origin gPackager )
				)
				( attribute "CDS_SEC" "1"
					( Origin gPackager )
				)
				( objectStatus "C2T10" )
			)
			( gate "@baseboard_fab2_lib.baseboard_fab2(sch_1):page101_i134"
				( attribute "CDS_LIB" "mstr_discrete"
					( Origin gPackager )
				)
				( attribute "CDS_LOCATION" "R1W22"
					( Origin gPackager )
				)
				( attribute "CDS_SEC" "1"
					( Origin gPackager )
				)
				( attribute "LOCATION" "R1W22"
					( Origin gFrontEnd )
				)
				( attribute "MATERIAL" "CHIP"
					( Origin gFrontEnd )
				)
				( attribute "PACK_TYPE" "0402"
					( Origin gFrontEnd )
				)
				( attribute "PART_NUMBER" "G21497-005"
					( Origin gFrontEnd )
				)
				( attribute "PHYS_PAGE" "101"
					( Origin gFrontEnd )
				)
				( attribute "ROOM" "IO_SLOT"
					( Origin gFrontEnd )
				)
				( attribute "ROT" "0"
					( Origin gFrontEnd )
				)
				( attribute "SEC" "1"
					( Origin gFrontEnd )
				)
				( attribute "SEC_TYPE" "0402"
					( Origin gFrontEnd )
				)
				( attribute "TOLERANCE" "5%"
					( Origin gFrontEnd )
				)
				( attribute "VALUE" "0.0"
					( Origin gFrontEnd )
				)
				( attribute "VER" "1"
					( Origin gFrontEnd )
				)
				( attribute "WATTAGE" "1/16W"
					( Origin gFrontEnd )
				)
				( attribute "XY" "(-7125,1950)"
					( Origin gFrontEnd )
				)
				( attribute "CHIPS_PART_NAME" "RES"
					( Origin gPackager )
				)
				( attribute "CDS_PART_NAME" "RES_0402-0.0,5%,1/16W,CHIP,G21A"
					( Origin gPackager )
				)
				( objectStatus "R1W22" )
			)
			( gate "@baseboard_fab2_lib.baseboard_fab2(sch_1):page101_i135"
				( attribute "CDS_LIB" "mstr_discrete"
					( Origin gPackager )
				)
				( attribute "CDS_LOCATION" "R1W23"
					( Origin gPackager )
				)
				( attribute "CDS_SEC" "1"
					( Origin gPackager )
				)
				( attribute "LOCATION" "R1W23"
					( Origin gFrontEnd )
				)
				( attribute "MATERIAL" "CHIP"
					( Origin gFrontEnd )
				)
				( attribute "PACK_TYPE" "0402"
					( Origin gFrontEnd )
				)
				( attribute "PART_NUMBER" "G21497-005"
					( Origin gFrontEnd )
				)
				( attribute "PHYS_PAGE" "101"
					( Origin gFrontEnd )
				)
				( attribute "ROOM" "IO_SLOT"
					( Origin gFrontEnd )
				)
				( attribute "ROT" "0"
					( Origin gFrontEnd )
				)
				( attribute "SEC" "1"
					( Origin gFrontEnd )
				)
				( attribute "SEC_TYPE" "0402"
					( Origin gFrontEnd )
				)
				( attribute "TOLERANCE" "5%"
					( Origin gFrontEnd )
				)
				( attribute "VALUE" "0.0"
					( Origin gFrontEnd )
				)
				( attribute "VER" "1"
					( Origin gFrontEnd )
				)
				( attribute "WATTAGE" "1/16W"
					( Origin gFrontEnd )
				)
				( attribute "XY" "(-7125,1825)"
					( Origin gFrontEnd )
				)
				( attribute "CHIPS_PART_NAME" "RES"
					( Origin gPackager )
				)
				( attribute "CDS_PART_NAME" "RES_0402-0.0,5%,1/16W,CHIP,G21A"
					( Origin gPackager )
				)
				( objectStatus "R1W23" )
			)
			( gate "@baseboard_fab2_lib.baseboard_fab2(sch_1):page101_i138"
				( attribute "CDS_LIB" "mstr_discrete"
					( Origin gPackager )
				)
				( attribute "CDS_LOCATION" "R1W24"
					( Origin gPackager )
				)
				( attribute "CDS_SEC" "1"
					( Origin gPackager )
				)
				( attribute "LOCATION" "R1W24"
					( Origin gFrontEnd )
				)
				( attribute "MATERIAL" "CHIP"
					( Origin gFrontEnd )
				)
				( attribute "PACK_TYPE" "0402"
					( Origin gFrontEnd )
				)
				( attribute "PART_NUMBER" "G21497-005"
					( Origin gFrontEnd )
				)
				( attribute "PHYS_PAGE" "101"
					( Origin gFrontEnd )
				)
				( attribute "ROOM" "IO_SLOT"
					( Origin gFrontEnd )
				)
				( attribute "ROT" "0"
					( Origin gFrontEnd )
				)
				( attribute "SEC" "1"
					( Origin gFrontEnd )
				)
				( attribute "SEC_TYPE" "0402"
					( Origin gFrontEnd )
				)
				( attribute "TOLERANCE" "5%"
					( Origin gFrontEnd )
				)
				( attribute "VALUE" "0.0"
					( Origin gFrontEnd )
				)
				( attribute "VER" "1"
					( Origin gFrontEnd )
				)
				( attribute "WATTAGE" "1/16W"
					( Origin gFrontEnd )
				)
				( attribute "XY" "(-6925,1250)"
					( Origin gFrontEnd )
				)
				( attribute "CHIPS_PART_NAME" "RES"
					( Origin gPackager )
				)
				( attribute "CDS_PART_NAME" "RES_0402-0.0,5%,1/16W,CHIP,G21A"
					( Origin gPackager )
				)
				( objectStatus "R1W24" )
			)
			( gate "@baseboard_fab2_lib.baseboard_fab2(sch_1):page101_i139"
				( attribute "CDS_LIB" "mstr_discrete"
					( Origin gPackager )
				)
				( attribute "LOCATION" "C1W17"
					( Origin gFrontEnd )
				)
				( attribute "MATERIAL" "EMPTY"
					( Origin gFrontEnd )
				)
				( attribute "PACK_TYPE" "0805"
					( Origin gFrontEnd )
				)
				( attribute "PART_NUMBER" "C95333-007"
					( Origin gFrontEnd )
				)
				( attribute "PHYS_PAGE" "101"
					( Origin gFrontEnd )
				)
				( attribute "ROT" "0"
					( Origin gFrontEnd )
				)
				( attribute "SEC" "1"
					( Origin gFrontEnd )
				)
				( attribute "SEC_TYPE" "0805"
					( Origin gFrontEnd )
				)
				( attribute "TOLERANCE" "10%"
					( Origin gFrontEnd )
				)
				( attribute "VALUE" "10UF"
					( Origin gFrontEnd )
				)
				( attribute "VER" "1"
					( Origin gFrontEnd )
				)
				( attribute "VOLTAGE" "16V"
					( Units "uVoltage" "V" 1.000000)
					( Origin gFrontEnd )
				)
				( attribute "XY" "(-1900,4000)"
					( Origin gFrontEnd )
				)
				( attribute "CHIPS_PART_NAME" "CAP"
					( Origin gPackager )
				)
				( attribute "CDS_PART_NAME" "CAP_0805-10UF,16V,10%,EMPTY,C9A"
					( Origin gPackager )
				)
				( attribute "CDS_LOCATION" "C1W17"
					( Origin gPackager )
				)
				( attribute "CDS_SEC" "1"
					( Origin gPackager )
				)
				( objectStatus "C1W17" )
			)
			( gate "@baseboard_fab2_lib.baseboard_fab2(sch_1):page101_i140"
				( attribute "BOM_COST" "SM_CONTROLLER"
					( Origin gFrontEnd )
				)
				( attribute "CDS_LIB" "mstr_discrete"
					( Origin gPackager )
				)
				( attribute "CDS_LOCATION" "R1W25"
					( Origin gPackager )
				)
				( attribute "CDS_SEC" "1"
					( Origin gPackager )
				)
				( attribute "LOCATION" "R1W25"
					( Origin gFrontEnd )
				)
				( attribute "MATERIAL" "CHIP"
					( Origin gFrontEnd )
				)
				( attribute "PACK_TYPE" "0402"
					( Origin gFrontEnd )
				)
				( attribute "PART_NUMBER" "G21796-026"
					( Origin gFrontEnd )
				)
				( attribute "PHYS_PAGE" "101"
					( Origin gFrontEnd )
				)
				( attribute "ROOM" "SYS_CLOCK"
					( Origin gFrontEnd )
				)
				( attribute "ROT" "0"
					( Origin gFrontEnd )
				)
				( attribute "SEC" "1"
					( Origin gFrontEnd )
				)
				( attribute "SEC_TYPE" "0402"
					( Origin gFrontEnd )
				)
				( attribute "TOLERANCE" "1%"
					( Origin gFrontEnd )
				)
				( attribute "VALUE" "1.00K"
					( Origin gFrontEnd )
				)
				( attribute "VER" "2"
					( Origin gFrontEnd )
				)
				( attribute "WATTAGE" "1/16W"
					( Origin gFrontEnd )
				)
				( attribute "XY" "(-8325,1400)"
					( Origin gFrontEnd )
				)
				( attribute "CHIPS_PART_NAME" "RES"
					( Origin gPackager )
				)
				( attribute "CDS_PART_NAME" "RES_0402-1.00K,1%,1/16W,CHIP,GA"
					( Origin gPackager )
				)
				( objectStatus "R1W25" )
			)
			( gate "@baseboard_fab2_lib.baseboard_fab2(sch_1):page251_i26"
				( attribute "BOM_COST" "SM_THERM"
					( Origin gFrontEnd )
				)
				( attribute "CDS_LIB" "mstr_discrete"
					( Origin gPackager )
				)
				( attribute "CDS_LOCATION" "CR10W3"
					( Origin gPackager )
				)
				( attribute "CDS_SEC" "1"
					( Origin gPackager )
				)
				( attribute "LOCATION" "CR10W3"
					( Origin gFrontEnd )
				)
				( attribute "MATERIAL" "IC"
					( Origin gFrontEnd )
				)
				( attribute "PACK_TYPE" "SM"
					( Origin gFrontEnd )
				)
				( attribute "PART_NUMBER" "H71799-001"
					( Origin gFrontEnd )
				)
				( attribute "PHYS_PAGE" "251"
					( Origin gFrontEnd )
				)
				( attribute "ROOM" "CPU_FANS"
					( Origin gFrontEnd )
				)
				( attribute "ROT" "0"
					( Origin gFrontEnd )
				)
				( attribute "SEC" "1"
					( Origin gFrontEnd )
				)
				( attribute "SEC_TYPE" "SM"
					( Origin gFrontEnd )
				)
				( attribute "VALUE" "SDMK0340L"
					( Origin gFrontEnd )
				)
				( attribute "VER" "1"
					( Origin gFrontEnd )
				)
				( attribute "XY" "(-3200,3700)"
					( Origin gFrontEnd )
				)
				( attribute "CHIPS_PART_NAME" "DIODE"
					( Origin gPackager )
				)
				( attribute "CDS_PART_NAME" "DIODE_SM-SDMK0340L,IC,H71799-0A"
					( Origin gPackager )
				)
				( objectStatus "CR10W3" )
			)
			( gate "@baseboard_fab2_lib.baseboard_fab2(sch_1):page101_i142"
				( attribute "BOM_COST" "SM_CONTROLLER"
					( Origin gFrontEnd )
				)
				( attribute "CDS_LIB" "mstr_discrete"
					( Origin gPackager )
				)
				( attribute "CDS_LOCATION" "R8F27"
					( Origin gPackager )
				)
				( attribute "CDS_SEC" "1"
					( Origin gPackager )
				)
				( attribute "LOCATION" "R8F27"
					( Origin gFrontEnd )
				)
				( attribute "MATERIAL" "CHIP"
					( Origin gFrontEnd )
				)
				( attribute "PACK_TYPE" "0402"
					( Origin gFrontEnd )
				)
				( attribute "PART_NUMBER" "G21796-074"
					( Origin gFrontEnd )
				)
				( attribute "PHYS_PAGE" "101"
					( Origin gFrontEnd )
				)
				( attribute "ROOM" "SYS_CLOCK"
					( Origin gFrontEnd )
				)
				( attribute "ROT" "0"
					( Origin gFrontEnd )
				)
				( attribute "SEC" "1"
					( Origin gFrontEnd )
				)
				( attribute "SEC_TYPE" "0402"
					( Origin gFrontEnd )
				)
				( attribute "TOLERANCE" "1%"
					( Origin gFrontEnd )
				)
				( attribute "VALUE" "33.2"
					( Origin gFrontEnd )
				)
				( attribute "VER" "1"
					( Origin gFrontEnd )
				)
				( attribute "WATTAGE" "1/16W"
					( Origin gFrontEnd )
				)
				( attribute "XY" "(-3050,2775)"
					( Origin gFrontEnd )
				)
				( attribute "CHIPS_PART_NAME" "RES"
					( Origin gPackager )
				)
				( attribute "CDS_PART_NAME" "RES_0402-33.2,1%,1/16W,CHIP,G2A"
					( Origin gPackager )
				)
				( objectStatus "R8F27" )
			)
			( gate "@baseboard_fab2_lib.baseboard_fab2(sch_1):page101_i144"
				( attribute "BOM_COST" "SM_CONTROLLER"
					( Origin gFrontEnd )
				)
				( attribute "CDS_LIB" "mstr_discrete"
					( Origin gPackager )
				)
				( attribute "CDS_LOCATION" "R8G25"
					( Origin gPackager )
				)
				( attribute "CDS_SEC" "1"
					( Origin gPackager )
				)
				( attribute "LOCATION" "R8G25"
					( Origin gFrontEnd )
				)
				( attribute "MATERIAL" "CHIP"
					( Origin gFrontEnd )
				)
				( attribute "PACK_TYPE" "0402"
					( Origin gFrontEnd )
				)
				( attribute "PART_NUMBER" "G21796-250"
					( Origin gFrontEnd )
				)
				( attribute "PHYS_PAGE" "101"
					( Origin gFrontEnd )
				)
				( attribute "ROOM" "SYS_CLOCK"
					( Origin gFrontEnd )
				)
				( attribute "ROT" "0"
					( Origin gFrontEnd )
				)
				( attribute "SEC" "1"
					( Origin gFrontEnd )
				)
				( attribute "SEC_TYPE" "0402"
					( Origin gFrontEnd )
				)
				( attribute "TOLERANCE" "1.0%"
					( Origin gFrontEnd )
				)
				( attribute "VALUE" "22.1"
					( Origin gFrontEnd )
				)
				( attribute "VER" "1"
					( Origin gFrontEnd )
				)
				( attribute "WATTAGE" "1/16W"
					( Origin gFrontEnd )
				)
				( attribute "XY" "(-3050,2000)"
					( Origin gFrontEnd )
				)
				( attribute "CHIPS_PART_NAME" "RES"
					( Origin gPackager )
				)
				( attribute "CDS_PART_NAME" "RES_0402-22.1,1.0%,1/16W,CHIP,A"
					( Origin gPackager )
				)
				( attribute "GROUP" "NI_I210&RJ45"
					( Origin gFrontEnd )
				)
				( objectStatus "R8G25" )
			)
			( gate "@baseboard_fab2_lib.baseboard_fab2(sch_1):page101_i145"
				( attribute "BOM_COST" "SM_CONTROLLER"
					( Origin gFrontEnd )
				)
				( attribute "CDS_LIB" "mstr_discrete"
					( Origin gPackager )
				)
				( attribute "CDS_LOCATION" "R8G1"
					( Origin gPackager )
				)
				( attribute "CDS_SEC" "1"
					( Origin gPackager )
				)
				( attribute "LOCATION" "R8G1"
					( Origin gFrontEnd )
				)
				( attribute "MATERIAL" "CHIP"
					( Origin gFrontEnd )
				)
				( attribute "PACK_TYPE" "0402"
					( Origin gFrontEnd )
				)
				( attribute "PART_NUMBER" "G21796-250"
					( Origin gFrontEnd )
				)
				( attribute "PHYS_PAGE" "101"
					( Origin gFrontEnd )
				)
				( attribute "ROOM" "SYS_CLOCK"
					( Origin gFrontEnd )
				)
				( attribute "ROT" "0"
					( Origin gFrontEnd )
				)
				( attribute "SEC" "1"
					( Origin gFrontEnd )
				)
				( attribute "SEC_TYPE" "0402"
					( Origin gFrontEnd )
				)
				( attribute "TOLERANCE" "1.0%"
					( Origin gFrontEnd )
				)
				( attribute "VALUE" "22.1"
					( Origin gFrontEnd )
				)
				( attribute "VER" "1"
					( Origin gFrontEnd )
				)
				( attribute "WATTAGE" "1/16W"
					( Origin gFrontEnd )
				)
				( attribute "XY" "(-3050,1850)"
					( Origin gFrontEnd )
				)
				( attribute "CHIPS_PART_NAME" "RES"
					( Origin gPackager )
				)
				( attribute "CDS_PART_NAME" "RES_0402-22.1,1.0%,1/16W,CHIP,A"
					( Origin gPackager )
				)
				( objectStatus "R8G1" )
			)
			( gate "@baseboard_fab2_lib.baseboard_fab2(sch_1):page150_i216"
				( attribute "BOM_COST" "SM_CONTROLLER"
					( Origin gFrontEnd )
				)
				( attribute "CDS_LIB" "mstr_discrete"
					( Origin gPackager )
				)
				( attribute "LOCATION" "R25W148"
					( Origin gFrontEnd )
				)
				( attribute "MATERIAL" "CHIP"
					( Origin gFrontEnd )
				)
				( attribute "PACK_TYPE" "0402"
					( Origin gFrontEnd )
				)
				( attribute "PART_NUMBER" "G21796-072"
					( Origin gFrontEnd )
				)
				( attribute "PHYS_PAGE" "150"
					( Origin gFrontEnd )
				)
				( attribute "ROOM" "BMC"
					( Origin gFrontEnd )
				)
				( attribute "ROT" "0"
					( Origin gFrontEnd )
				)
				( attribute "TOLERANCE" "1%"
					( Origin gFrontEnd )
				)
				( attribute "VALUE" "4.75K"
					( Origin gFrontEnd )
				)
				( attribute "VER" "1"
					( Origin gFrontEnd )
				)
				( attribute "WATTAGE" "1/16W"
					( Origin gFrontEnd )
				)
				( attribute "XY" "(-600,-2300)"
					( Origin gFrontEnd )
				)
				( attribute "CHIPS_PART_NAME" "RES"
					( Origin gPackager )
				)
				( attribute "CDS_PART_NAME" "RES_0402-4.75K,1%,1/16W,CHIP,GA"
					( Origin gPackager )
				)
				( attribute "SEC" "1"
					( Origin gFrontEnd )
				)
				( attribute "SEC_TYPE" "0402"
					( Origin gFrontEnd )
				)
				( attribute "CDS_LOCATION" "R25W148"
					( Origin gPackager )
				)
				( attribute "CDS_SEC" "1"
					( Origin gPackager )
				)
				( objectStatus "R25W148" )
			)
			( gate "@baseboard_fab2_lib.baseboard_fab2(sch_1):page190_i349"
				( attribute "BOM_COST" "SYS_CLOCK"
					( Origin gFrontEnd )
				)
				( attribute "CDS_LIB" "mstr_discrete"
					( Origin gPackager )
				)
				( attribute "CDS_LOCATION" "R1W26"
					( Origin gPackager )
				)
				( attribute "CDS_SEC" "1"
					( Origin gPackager )
				)
				( attribute "LOCATION" "R1W26"
					( Origin gFrontEnd )
				)
				( attribute "MATERIAL" "EMPTY"
					( Origin gFrontEnd )
				)
				( attribute "PACK_TYPE" "0402"
					( Origin gFrontEnd )
				)
				( attribute "PART_NUMBER" "G21796-016"
					( Origin gFrontEnd )
				)
				( attribute "PHYS_PAGE" "190"
					( Origin gFrontEnd )
				)
				( attribute "ROOM" "DB1200ZL"
					( Origin gFrontEnd )
				)
				( attribute "ROT" "0"
					( Origin gFrontEnd )
				)
				( attribute "SEC" "1"
					( Origin gFrontEnd )
				)
				( attribute "SEC_TYPE" "0402"
					( Origin gFrontEnd )
				)
				( attribute "TOLERANCE" "1%"
					( Origin gFrontEnd )
				)
				( attribute "VALUE" "10.0K"
					( Origin gFrontEnd )
				)
				( attribute "VER" "2"
					( Origin gFrontEnd )
				)
				( attribute "WATTAGE" "1/16W"
					( Origin gFrontEnd )
				)
				( attribute "XY" "(-1800,5000)"
					( Origin gFrontEnd )
				)
				( attribute "CHIPS_PART_NAME" "RES"
					( Origin gPackager )
				)
				( attribute "CDS_PART_NAME" "RES_0402-10.0K,1%,1/16W,EMPTY,A"
					( Origin gPackager )
				)
				( objectStatus "R1W26" )
			)
			( gate "@baseboard_fab2_lib.baseboard_fab2(sch_1):page201_i187"
				( attribute "CDS_LIB" "mstr_discrete"
					( Origin gPackager )
				)
				( attribute "CDS_LOCATION" "R4E4"
					( Origin gPackager )
				)
				( attribute "CDS_SEC" "1"
					( Origin gPackager )
				)
				( attribute "LOCATION" "R4E4"
					( Origin gFrontEnd )
				)
				( attribute "MATERIAL" "CHIP"
					( Origin gFrontEnd )
				)
				( attribute "PACK_TYPE" "0402"
					( Origin gFrontEnd )
				)
				( attribute "PART_NUMBER" "G21796-026"
					( Origin gFrontEnd )
				)
				( attribute "PHYS_PAGE" "201"
					( Origin gFrontEnd )
				)
				( attribute "ROOM" "PVCCIN_CPU0_VR"
					( Origin gFrontEnd )
				)
				( attribute "ROT" "2"
					( Origin gFrontEnd )
				)
				( attribute "SEC" "1"
					( Origin gFrontEnd )
				)
				( attribute "SEC_TYPE" "0402"
					( Origin gFrontEnd )
				)
				( attribute "TOLERANCE" "1%"
					( Origin gFrontEnd )
				)
				( attribute "VALUE" "1.00K"
					( Origin gFrontEnd )
				)
				( attribute "VER" "2"
					( Origin gFrontEnd )
				)
				( attribute "WATTAGE" "1/16W"
					( Origin gFrontEnd )
				)
				( attribute "XY" "(-1925,4100)"
					( Origin gFrontEnd )
				)
				( attribute "CHIPS_PART_NAME" "RES"
					( Origin gPackager )
				)
				( attribute "CDS_PART_NAME" "RES_0402-1.00K,1%,1/16W,CHIP,GA"
					( Origin gPackager )
				)
				( objectStatus "R4E4" )
			)
			( gate "@baseboard_fab2_lib.baseboard_fab2(sch_1):page235_i247"
				( attribute "CDS_LIB" "mstr_discrete"
					( Origin gPackager )
				)
				( attribute "CDS_LOCATION" "R8W2"
					( Origin gPackager )
				)
				( attribute "CDS_SEC" "1"
					( Origin gPackager )
				)
				( attribute "LOCATION" "R8W2"
					( Origin gFrontEnd )
				)
				( attribute "MATERIAL" "CHIP"
					( Origin gFrontEnd )
				)
				( attribute "PACK_TYPE" "0402"
					( Origin gFrontEnd )
				)
				( attribute "PART_NUMBER" "G21796-026"
					( Origin gFrontEnd )
				)
				( attribute "PHYS_PAGE" "235"
					( Origin gFrontEnd )
				)
				( attribute "ROOM" "PVNN_PCH_STBY"
					( Origin gFrontEnd )
				)
				( attribute "ROT" "0"
					( Origin gFrontEnd )
				)
				( attribute "SEC" "1"
					( Origin gFrontEnd )
				)
				( attribute "SEC_TYPE" "0402"
					( Origin gFrontEnd )
				)
				( attribute "TOLERANCE" "1%"
					( Origin gFrontEnd )
				)
				( attribute "VALUE" "1.00K"
					( Origin gFrontEnd )
				)
				( attribute "VER" "2"
					( Origin gFrontEnd )
				)
				( attribute "WATTAGE" "1/16W"
					( Origin gFrontEnd )
				)
				( attribute "XY" "(-11100,4600)"
					( Origin gFrontEnd )
				)
				( attribute "CHIPS_PART_NAME" "RES"
					( Origin gPackager )
				)
				( attribute "CDS_PART_NAME" "RES_0402-1.00K,1%,1/16W,CHIP,GA"
					( Origin gPackager )
				)
				( objectStatus "R8W2" )
			)
			( gate "@baseboard_fab2_lib.baseboard_fab2(sch_1):page235_i248"
				( attribute "CDS_LIB" "mstr_discrete"
					( Origin gPackager )
				)
				( attribute "CDS_LOCATION" "R8W3"
					( Origin gPackager )
				)
				( attribute "CDS_SEC" "1"
					( Origin gPackager )
				)
				( attribute "LOCATION" "R8W3"
					( Origin gFrontEnd )
				)
				( attribute "MATERIAL" "CHIP"
					( Origin gFrontEnd )
				)
				( attribute "PACK_TYPE" "0402"
					( Origin gFrontEnd )
				)
				( attribute "PART_NUMBER" "G21796-026"
					( Origin gFrontEnd )
				)
				( attribute "PHYS_PAGE" "235"
					( Origin gFrontEnd )
				)
				( attribute "ROOM" "PVNN_PCH_STBY"
					( Origin gFrontEnd )
				)
				( attribute "ROT" "0"
					( Origin gFrontEnd )
				)
				( attribute "SEC" "1"
					( Origin gFrontEnd )
				)
				( attribute "SEC_TYPE" "0402"
					( Origin gFrontEnd )
				)
				( attribute "TOLERANCE" "1%"
					( Origin gFrontEnd )
				)
				( attribute "VALUE" "1.00K"
					( Origin gFrontEnd )
				)
				( attribute "VER" "2"
					( Origin gFrontEnd )
				)
				( attribute "WATTAGE" "1/16W"
					( Origin gFrontEnd )
				)
				( attribute "XY" "(-11800,3750)"
					( Origin gFrontEnd )
				)
				( attribute "CHIPS_PART_NAME" "RES"
					( Origin gPackager )
				)
				( attribute "CDS_PART_NAME" "RES_0402-1.00K,1%,1/16W,CHIP,GA"
					( Origin gPackager )
				)
				( objectStatus "R8W3" )
			)
			( gate "@baseboard_fab2_lib.baseboard_fab2(sch_1):page231_i229"
				( attribute "BOM_COST" "NT_GBE_BASE"
					( Origin gFrontEnd )
				)
				( attribute "CDS_LIB" "mstr_discrete"
					( Origin gPackager )
				)
				( attribute "CDS_LOCATION" "R7F8"
					( Origin gPackager )
				)
				( attribute "CDS_SEC" "1"
					( Origin gPackager )
				)
				( attribute "LOCATION" "R7F8"
					( Origin gFrontEnd )
				)
				( attribute "MATERIAL" "CHIP"
					( Origin gFrontEnd )
				)
				( attribute "PACK_TYPE" "0603"
					( Origin gFrontEnd )
				)
				( attribute "PART_NUMBER" "G22178-002"
					( Origin gFrontEnd )
				)
				( attribute "PHYS_PAGE" "231"
					( Origin gFrontEnd )
				)
				( attribute "ROOM" "NIC_SPRV"
					( Origin gFrontEnd )
				)
				( attribute "ROT" "0"
					( Origin gFrontEnd )
				)
				( attribute "SEC" "1"
					( Origin gFrontEnd )
				)
				( attribute "SEC_TYPE" "0603"
					( Origin gFrontEnd )
				)
				( attribute "TOLERANCE" "5.0%"
					( Origin gFrontEnd )
				)
				( attribute "VALUE" "0"
					( Origin gFrontEnd )
				)
				( attribute "VER" "1"
					( Origin gFrontEnd )
				)
				( attribute "WATTAGE" "1/10W"
					( Origin gFrontEnd )
				)
				( attribute "XY" "(-3800,4450)"
					( Origin gFrontEnd )
				)
				( attribute "CHIPS_PART_NAME" "RES"
					( Origin gPackager )
				)
				( attribute "CDS_PART_NAME" "RES_0603-0,5.0%,1/10W,CHIP,G22A"
					( Origin gPackager )
				)
				( objectStatus "R7F8" )
			)
			( gate "@baseboard_fab2_lib.baseboard_fab2(sch_1):page190_i351"
				( attribute "BOM_COST" "SM_CONTROLLER"
					( Origin gFrontEnd )
				)
				( attribute "CDS_LIB" "mstr_discrete"
					( Origin gPackager )
				)
				( attribute "CDS_LOCATION" "R1W27"
					( Origin gPackager )
				)
				( attribute "CDS_SEC" "1"
					( Origin gPackager )
				)
				( attribute "LOCATION" "R1W27"
					( Origin gFrontEnd )
				)
				( attribute "MATERIAL" "CHIP"
					( Origin gFrontEnd )
				)
				( attribute "PACK_TYPE" "0402"
					( Origin gFrontEnd )
				)
				( attribute "PART_NUMBER" "G21497-005"
					( Origin gFrontEnd )
				)
				( attribute "PHYS_PAGE" "190"
					( Origin gFrontEnd )
				)
				( attribute "ROOM" "BMC"
					( Origin gFrontEnd )
				)
				( attribute "ROT" "0"
					( Origin gFrontEnd )
				)
				( attribute "SEC" "1"
					( Origin gFrontEnd )
				)
				( attribute "SEC_TYPE" "0402"
					( Origin gFrontEnd )
				)
				( attribute "TOLERANCE" "5%"
					( Origin gFrontEnd )
				)
				( attribute "VALUE" "0.0"
					( Origin gFrontEnd )
				)
				( attribute "VER" "1"
					( Origin gFrontEnd )
				)
				( attribute "WATTAGE" "1/16W"
					( Origin gFrontEnd )
				)
				( attribute "XY" "(-3300,3900)"
					( Origin gFrontEnd )
				)
				( attribute "CHIPS_PART_NAME" "RES"
					( Origin gPackager )
				)
				( attribute "CDS_PART_NAME" "RES_0402-0.0,5%,1/16W,CHIP,G21A"
					( Origin gPackager )
				)
				( objectStatus "R1W27" )
			)
			( gate "@baseboard_fab2_lib.baseboard_fab2(sch_1):page145_i173"
				( attribute "BOM_COST" "SM_CONTROLLER"
					( Origin gFrontEnd )
				)
				( attribute "CDS_LIB" "mstr_discrete"
					( Origin gPackager )
				)
				( attribute "CDS_LOCATION" "R25W144"
					( Origin gPackager )
				)
				( attribute "CDS_SEC" "1"
					( Origin gPackager )
				)
				( attribute "LOCATION" "R25W144"
					( Origin gFrontEnd )
				)
				( attribute "MATERIAL" "CHIP"
					( Origin gFrontEnd )
				)
				( attribute "PACK_TYPE" "0402"
					( Origin gFrontEnd )
				)
				( attribute "PART_NUMBER" "G21497-005"
					( Origin gFrontEnd )
				)
				( attribute "PHYS_PAGE" "145"
					( Origin gFrontEnd )
				)
				( attribute "ROOM" "BMC"
					( Origin gFrontEnd )
				)
				( attribute "ROT" "0"
					( Origin gFrontEnd )
				)
				( attribute "SEC" "1"
					( Origin gFrontEnd )
				)
				( attribute "SEC_TYPE" "0402"
					( Origin gFrontEnd )
				)
				( attribute "TOLERANCE" "5%"
					( Origin gFrontEnd )
				)
				( attribute "VALUE" "0.0"
					( Origin gFrontEnd )
				)
				( attribute "VER" "1"
					( Origin gFrontEnd )
				)
				( attribute "WATTAGE" "1/16W"
					( Origin gFrontEnd )
				)
				( attribute "XY" "(-1500,-2900)"
					( Origin gFrontEnd )
				)
				( attribute "CHIPS_PART_NAME" "RES"
					( Origin gPackager )
				)
				( attribute "CDS_PART_NAME" "RES_0402-0.0,5%,1/16W,CHIP,G21A"
					( Origin gPackager )
				)
				( objectStatus "R25W144" )
			)
			( gate "@baseboard_fab2_lib.baseboard_fab2(sch_1):page191_i197"
				( attribute "BOM_COST" "SM_CONTROLLER"
					( Origin gFrontEnd )
				)
				( attribute "CDS_LIB" "mstr_discrete"
					( Origin gPackager )
				)
				( attribute "CDS_LOCATION" "R1W28"
					( Origin gPackager )
				)
				( attribute "CDS_SEC" "1"
					( Origin gPackager )
				)
				( attribute "LOCATION" "R1W28"
					( Origin gFrontEnd )
				)
				( attribute "MATERIAL" "CHIP"
					( Origin gFrontEnd )
				)
				( attribute "PACK_TYPE" "0402"
					( Origin gFrontEnd )
				)
				( attribute "PART_NUMBER" "G21497-005"
					( Origin gFrontEnd )
				)
				( attribute "PHYS_PAGE" "191"
					( Origin gFrontEnd )
				)
				( attribute "ROOM" "BMC"
					( Origin gFrontEnd )
				)
				( attribute "ROT" "0"
					( Origin gFrontEnd )
				)
				( attribute "SEC" "1"
					( Origin gFrontEnd )
				)
				( attribute "SEC_TYPE" "0402"
					( Origin gFrontEnd )
				)
				( attribute "TOLERANCE" "5%"
					( Origin gFrontEnd )
				)
				( attribute "VALUE" "0.0"
					( Origin gFrontEnd )
				)
				( attribute "VER" "1"
					( Origin gFrontEnd )
				)
				( attribute "WATTAGE" "1/16W"
					( Origin gFrontEnd )
				)
				( attribute "XY" "(-3100,1375)"
					( Origin gFrontEnd )
				)
				( attribute "CHIPS_PART_NAME" "RES"
					( Origin gPackager )
				)
				( attribute "CDS_PART_NAME" "RES_0402-0.0,5%,1/16W,CHIP,G21A"
					( Origin gPackager )
				)
				( objectStatus "R1W28" )
			)
			( gate "@baseboard_fab2_lib.baseboard_fab2(sch_1):page145_i175"
				( attribute "BOM_COST" "SM_CONTROLLER"
					( Origin gFrontEnd )
				)
				( attribute "CDS_LIB" "mstr_discrete"
					( Origin gPackager )
				)
				( attribute "CDS_LOCATION" "R25W145"
					( Origin gPackager )
				)
				( attribute "CDS_SEC" "1"
					( Origin gPackager )
				)
				( attribute "LOCATION" "R25W145"
					( Origin gFrontEnd )
				)
				( attribute "MATERIAL" "CHIP"
					( Origin gFrontEnd )
				)
				( attribute "PACK_TYPE" "0402"
					( Origin gFrontEnd )
				)
				( attribute "PART_NUMBER" "G21497-005"
					( Origin gFrontEnd )
				)
				( attribute "PHYS_PAGE" "145"
					( Origin gFrontEnd )
				)
				( attribute "ROOM" "BMC"
					( Origin gFrontEnd )
				)
				( attribute "ROT" "0"
					( Origin gFrontEnd )
				)
				( attribute "SEC" "1"
					( Origin gFrontEnd )
				)
				( attribute "SEC_TYPE" "0402"
					( Origin gFrontEnd )
				)
				( attribute "TOLERANCE" "5%"
					( Origin gFrontEnd )
				)
				( attribute "VALUE" "0.0"
					( Origin gFrontEnd )
				)
				( attribute "VER" "1"
					( Origin gFrontEnd )
				)
				( attribute "WATTAGE" "1/16W"
					( Origin gFrontEnd )
				)
				( attribute "XY" "(-1500,-3000)"
					( Origin gFrontEnd )
				)
				( attribute "CHIPS_PART_NAME" "RES"
					( Origin gPackager )
				)
				( attribute "CDS_PART_NAME" "RES_0402-0.0,5%,1/16W,CHIP,G21A"
					( Origin gPackager )
				)
				( objectStatus "R25W145" )
			)
			( gate "@baseboard_fab2_lib.baseboard_fab2(sch_1):page191_i198"
				( attribute "BOM_COST" "SM_CONTROLLER"
					( Origin gFrontEnd )
				)
				( attribute "CDS_LIB" "mstr_discrete"
					( Origin gPackager )
				)
				( attribute "CDS_LOCATION" "R1W29"
					( Origin gPackager )
				)
				( attribute "CDS_SEC" "1"
					( Origin gPackager )
				)
				( attribute "LOCATION" "R1W29"
					( Origin gFrontEnd )
				)
				( attribute "MATERIAL" "CHIP"
					( Origin gFrontEnd )
				)
				( attribute "PACK_TYPE" "0402"
					( Origin gFrontEnd )
				)
				( attribute "PART_NUMBER" "G21497-005"
					( Origin gFrontEnd )
				)
				( attribute "PHYS_PAGE" "191"
					( Origin gFrontEnd )
				)
				( attribute "ROOM" "BMC"
					( Origin gFrontEnd )
				)
				( attribute "ROT" "0"
					( Origin gFrontEnd )
				)
				( attribute "SEC" "1"
					( Origin gFrontEnd )
				)
				( attribute "SEC_TYPE" "0402"
					( Origin gFrontEnd )
				)
				( attribute "TOLERANCE" "5%"
					( Origin gFrontEnd )
				)
				( attribute "VALUE" "0.0"
					( Origin gFrontEnd )
				)
				( attribute "VER" "1"
					( Origin gFrontEnd )
				)
				( attribute "WATTAGE" "1/16W"
					( Origin gFrontEnd )
				)
				( attribute "XY" "(-6200,3525)"
					( Origin gFrontEnd )
				)
				( attribute "CHIPS_PART_NAME" "RES"
					( Origin gPackager )
				)
				( attribute "CDS_PART_NAME" "RES_0402-0.0,5%,1/16W,CHIP,G21A"
					( Origin gPackager )
				)
				( objectStatus "R1W29" )
			)
			( gate "@baseboard_fab2_lib.baseboard_fab2(sch_1):page118_i168"
				( attribute "BOM_COST" "MEM_NV"
					( Origin gFrontEnd )
				)
				( attribute "CDS_LIB" "mstr_discrete"
					( Origin gPackager )
				)
				( attribute "CDS_LOCATION" "R1W30"
					( Origin gPackager )
				)
				( attribute "LOCATION" "R1W30"
					( Origin gFrontEnd )
				)
				( attribute "MATERIAL" "EMPTY"
					( Origin gFrontEnd )
				)
				( attribute "PACK_TYPE" "0402"
					( Origin gFrontEnd )
				)
				( attribute "PART_NUMBER" "G21497-005"
					( Origin gFrontEnd )
				)
				( attribute "PHYS_PAGE" "118"
					( Origin gFrontEnd )
				)
				( attribute "ROOM" "NV_DIMM"
					( Origin gFrontEnd )
				)
				( attribute "ROT" "0"
					( Origin gFrontEnd )
				)
				( attribute "SEC" "1"
					( Origin gFrontEnd )
				)
				( attribute "SEC_TYPE" "0402"
					( Origin gFrontEnd )
				)
				( attribute "TOLERANCE" "5%"
					( Origin gFrontEnd )
				)
				( attribute "VALUE" "0.0"
					( Origin gFrontEnd )
				)
				( attribute "VER" "1"
					( Origin gFrontEnd )
				)
				( attribute "WATTAGE" "1/16W"
					( Origin gFrontEnd )
				)
				( attribute "XY" "(-2725,3650)"
					( Origin gFrontEnd )
				)
				( attribute "CHIPS_PART_NAME" "RES"
					( Origin gPackager )
				)
				( attribute "CDS_PART_NAME" "RES_0402-0.0,5%,1/16W,EMPTY,G2A"
					( Origin gPackager )
				)
				( attribute "CDS_SEC" "1"
					( Origin gPackager )
				)
				( objectStatus "R1W30" )
			)
			( gate "@baseboard_fab2_lib.baseboard_fab2(sch_1):page150_i196"
				( attribute "BOM_COST" "SM_CONTROLLER"
					( Origin gFrontEnd )
				)
				( attribute "CDS_LIB" "mstr_discrete"
					( Origin gPackager )
				)
				( attribute "CDS_LOCATION" "R25W105"
					( Origin gPackager )
				)
				( attribute "LOCATION" "R25W105"
					( Origin gFrontEnd )
				)
				( attribute "MATERIAL" "EMPTY"
					( Origin gFrontEnd )
				)
				( attribute "PACK_TYPE" "0402"
					( Origin gFrontEnd )
				)
				( attribute "PART_NUMBER" "G21796-072"
					( Origin gFrontEnd )
				)
				( attribute "PHYS_PAGE" "150"
					( Origin gFrontEnd )
				)
				( attribute "ROOM" "BMC"
					( Origin gFrontEnd )
				)
				( attribute "ROT" "0"
					( Origin gFrontEnd )
				)
				( attribute "SEC" "1"
					( Origin gFrontEnd )
				)
				( attribute "SEC_TYPE" "0402"
					( Origin gFrontEnd )
				)
				( attribute "TOLERANCE" "1%"
					( Origin gFrontEnd )
				)
				( attribute "VALUE" "4.75K"
					( Origin gFrontEnd )
				)
				( attribute "VER" "1"
					( Origin gFrontEnd )
				)
				( attribute "WATTAGE" "1/16W"
					( Origin gFrontEnd )
				)
				( attribute "XY" "(-600,-400)"
					( Origin gFrontEnd )
				)
				( attribute "CHIPS_PART_NAME" "RES"
					( Origin gPackager )
				)
				( attribute "CDS_PART_NAME" "RES_0402-4.75K,1%,1/16W,EMPTY,A"
					( Origin gPackager )
				)
				( attribute "CDS_SEC" "1"
					( Origin gPackager )
				)
				( objectStatus "R25W105" )
			)
			( gate "@baseboard_fab2_lib.baseboard_fab2(sch_1):page162_i35"
				( attribute "BOM_COST" "SM_MEM"
					( Origin gFrontEnd )
				)
				( attribute "CDS_LIB" "mstr_discrete"
					( Origin gPackager )
				)
				( attribute "CDS_LOCATION" "R8F13"
					( Origin gPackager )
				)
				( attribute "CDS_SEC" "1"
					( Origin gPackager )
				)
				( attribute "LOCATION" "R8F13"
					( Origin gFrontEnd )
				)
				( attribute "MATERIAL" "CHIP"
					( Origin gFrontEnd )
				)
				( attribute "PACK_TYPE" "0402"
					( Origin gFrontEnd )
				)
				( attribute "PART_NUMBER" "G21796-072"
					( Origin gFrontEnd )
				)
				( attribute "PHYS_PAGE" "162"
					( Origin gFrontEnd )
				)
				( attribute "ROOM" "BMC_BOOT_SPI"
					( Origin gFrontEnd )
				)
				( attribute "ROT" "2"
					( Origin gFrontEnd )
				)
				( attribute "SEC" "1"
					( Origin gFrontEnd )
				)
				( attribute "SEC_TYPE" "0402"
					( Origin gFrontEnd )
				)
				( attribute "TOLERANCE" "1%"
					( Origin gFrontEnd )
				)
				( attribute "VALUE" "4.75K"
					( Origin gFrontEnd )
				)
				( attribute "VER" "2"
					( Origin gFrontEnd )
				)
				( attribute "WATTAGE" "1/16W"
					( Origin gFrontEnd )
				)
				( attribute "XY" "(4550,3325)"
					( Origin gFrontEnd )
				)
				( attribute "CHIPS_PART_NAME" "RES"
					( Origin gPackager )
				)
				( attribute "CDS_PART_NAME" "RES_0402-4.75K,1%,1/16W,CHIP,GA"
					( Origin gPackager )
				)
				( objectStatus "R8F13" )
			)
			( gate "@baseboard_fab2_lib.baseboard_fab2(sch_1):page150_i199"
				( attribute "BOM_COST" "SM_CONTROLLER"
					( Origin gFrontEnd )
				)
				( attribute "CDS_LIB" "mstr_discrete"
					( Origin gPackager )
				)
				( attribute "LOCATION" "R25W146"
					( Origin gFrontEnd )
				)
				( attribute "MATERIAL" "CHIP"
					( Origin gFrontEnd )
				)
				( attribute "PACK_TYPE" "0402"
					( Origin gFrontEnd )
				)
				( attribute "PART_NUMBER" "G21796-072"
					( Origin gFrontEnd )
				)
				( attribute "PHYS_PAGE" "150"
					( Origin gFrontEnd )
				)
				( attribute "ROOM" "BMC"
					( Origin gFrontEnd )
				)
				( attribute "ROT" "0"
					( Origin gFrontEnd )
				)
				( attribute "TOLERANCE" "1%"
					( Origin gFrontEnd )
				)
				( attribute "VALUE" "4.75K"
					( Origin gFrontEnd )
				)
				( attribute "VER" "1"
					( Origin gFrontEnd )
				)
				( attribute "WATTAGE" "1/16W"
					( Origin gFrontEnd )
				)
				( attribute "XY" "(-600,-1300)"
					( Origin gFrontEnd )
				)
				( attribute "CHIPS_PART_NAME" "RES"
					( Origin gPackager )
				)
				( attribute "CDS_PART_NAME" "RES_0402-4.75K,1%,1/16W,CHIP,GA"
					( Origin gPackager )
				)
				( attribute "SEC" "1"
					( Origin gFrontEnd )
				)
				( attribute "SEC_TYPE" "0402"
					( Origin gFrontEnd )
				)
				( attribute "CDS_LOCATION" "R25W146"
					( Origin gPackager )
				)
				( attribute "CDS_SEC" "1"
					( Origin gPackager )
				)
				( objectStatus "R25W146" )
			)
			( gate "@baseboard_fab2_lib.baseboard_fab2(sch_1):page150_i209"
				( attribute "BOM_COST" "SM_CONTROLLER"
					( Origin gFrontEnd )
				)
				( attribute "CDS_LIB" "mstr_discrete"
					( Origin gPackager )
				)
				( attribute "LOCATION" "R25W98"
					( Origin gFrontEnd )
				)
				( attribute "MATERIAL" "EMPTY"
					( Origin gFrontEnd )
				)
				( attribute "PACK_TYPE" "0402"
					( Origin gFrontEnd )
				)
				( attribute "PART_NUMBER" "G21796-072"
					( Origin gFrontEnd )
				)
				( attribute "PHYS_PAGE" "150"
					( Origin gFrontEnd )
				)
				( attribute "ROOM" "BMC"
					( Origin gFrontEnd )
				)
				( attribute "ROT" "0"
					( Origin gFrontEnd )
				)
				( attribute "SEC" "1"
					( Origin gFrontEnd )
				)
				( attribute "SEC_TYPE" "0402"
					( Origin gFrontEnd )
				)
				( attribute "TOLERANCE" "1%"
					( Origin gFrontEnd )
				)
				( attribute "VALUE" "4.75K"
					( Origin gFrontEnd )
				)
				( attribute "VER" "1"
					( Origin gFrontEnd )
				)
				( attribute "WATTAGE" "1/16W"
					( Origin gFrontEnd )
				)
				( attribute "XY" "(1850,-200)"
					( Origin gFrontEnd )
				)
				( attribute "CHIPS_PART_NAME" "RES"
					( Origin gPackager )
				)
				( attribute "CDS_PART_NAME" "RES_0402-4.75K,1%,1/16W,EMPTY,A"
					( Origin gPackager )
				)
				( attribute "CDS_LOCATION" "R25W98"
					( Origin gPackager )
				)
				( attribute "CDS_SEC" "1"
					( Origin gPackager )
				)
				( objectStatus "R25W98" )
			)
			( gate "@baseboard_fab2_lib.baseboard_fab2(sch_1):page150_i210"
				( attribute "BOM_COST" "SM_CONTROLLER"
					( Origin gFrontEnd )
				)
				( attribute "CDS_LIB" "mstr_discrete"
					( Origin gPackager )
				)
				( attribute "CDS_LOCATION" "R25W99"
					( Origin gPackager )
				)
				( attribute "LOCATION" "R25W99"
					( Origin gFrontEnd )
				)
				( attribute "MATERIAL" "EMPTY"
					( Origin gFrontEnd )
				)
				( attribute "PACK_TYPE" "0402"
					( Origin gFrontEnd )
				)
				( attribute "PART_NUMBER" "G21796-072"
					( Origin gFrontEnd )
				)
				( attribute "PHYS_PAGE" "150"
					( Origin gFrontEnd )
				)
				( attribute "ROOM" "BMC"
					( Origin gFrontEnd )
				)
				( attribute "ROT" "0"
					( Origin gFrontEnd )
				)
				( attribute "SEC" "1"
					( Origin gFrontEnd )
				)
				( attribute "SEC_TYPE" "0402"
					( Origin gFrontEnd )
				)
				( attribute "TOLERANCE" "1%"
					( Origin gFrontEnd )
				)
				( attribute "VALUE" "4.75K"
					( Origin gFrontEnd )
				)
				( attribute "VER" "1"
					( Origin gFrontEnd )
				)
				( attribute "WATTAGE" "1/16W"
					( Origin gFrontEnd )
				)
				( attribute "XY" "(1850,-400)"
					( Origin gFrontEnd )
				)
				( attribute "CHIPS_PART_NAME" "RES"
					( Origin gPackager )
				)
				( attribute "CDS_PART_NAME" "RES_0402-4.75K,1%,1/16W,EMPTY,A"
					( Origin gPackager )
				)
				( attribute "CDS_SEC" "1"
					( Origin gPackager )
				)
				( objectStatus "R25W99" )
			)
			( gate "@baseboard_fab2_lib.baseboard_fab2(sch_1):page150_i211"
				( attribute "BOM_COST" "SM_CONTROLLER"
					( Origin gFrontEnd )
				)
				( attribute "CDS_LIB" "mstr_discrete"
					( Origin gPackager )
				)
				( attribute "CDS_LOCATION" "R25W100"
					( Origin gPackager )
				)
				( attribute "CDS_SEC" "1"
					( Origin gPackager )
				)
				( attribute "LOCATION" "R25W100"
					( Origin gFrontEnd )
				)
				( attribute "MATERIAL" "CHIP"
					( Origin gFrontEnd )
				)
				( attribute "PACK_TYPE" "0402"
					( Origin gFrontEnd )
				)
				( attribute "PART_NUMBER" "G21796-072"
					( Origin gFrontEnd )
				)
				( attribute "PHYS_PAGE" "150"
					( Origin gFrontEnd )
				)
				( attribute "ROOM" "BMC"
					( Origin gFrontEnd )
				)
				( attribute "ROT" "0"
					( Origin gFrontEnd )
				)
				( attribute "SEC" "1"
					( Origin gFrontEnd )
				)
				( attribute "SEC_TYPE" "0402"
					( Origin gFrontEnd )
				)
				( attribute "TOLERANCE" "1%"
					( Origin gFrontEnd )
				)
				( attribute "VALUE" "4.75K"
					( Origin gFrontEnd )
				)
				( attribute "VER" "1"
					( Origin gFrontEnd )
				)
				( attribute "WATTAGE" "1/16W"
					( Origin gFrontEnd )
				)
				( attribute "XY" "(1850,-600)"
					( Origin gFrontEnd )
				)
				( attribute "CHIPS_PART_NAME" "RES"
					( Origin gPackager )
				)
				( attribute "CDS_PART_NAME" "RES_0402-4.75K,1%,1/16W,CHIP,GA"
					( Origin gPackager )
				)
				( objectStatus "R25W100" )
			)
			( gate "@baseboard_fab2_lib.baseboard_fab2(sch_1):page144_i148"
				( attribute "BOM_COST" "MEM_NV"
					( Origin gFrontEnd )
				)
				( attribute "CDS_LIB" "mstr_discrete"
					( Origin gPackager )
				)
				( attribute "CDS_LOCATION" "R25W140"
					( Origin gPackager )
				)
				( attribute "LOCATION" "R25W140"
					( Origin gFrontEnd )
				)
				( attribute "MATERIAL" "EMPTY"
					( Origin gFrontEnd )
				)
				( attribute "PACK_TYPE" "0402"
					( Origin gFrontEnd )
				)
				( attribute "PART_NUMBER" "G21497-005"
					( Origin gFrontEnd )
				)
				( attribute "PHYS_PAGE" "144"
					( Origin gFrontEnd )
				)
				( attribute "ROOM" "NV_DIMM"
					( Origin gFrontEnd )
				)
				( attribute "ROT" "0"
					( Origin gFrontEnd )
				)
				( attribute "SEC" "1"
					( Origin gFrontEnd )
				)
				( attribute "SEC_TYPE" "0402"
					( Origin gFrontEnd )
				)
				( attribute "TOLERANCE" "5%"
					( Origin gFrontEnd )
				)
				( attribute "VALUE" "0.0"
					( Origin gFrontEnd )
				)
				( attribute "VER" "1"
					( Origin gFrontEnd )
				)
				( attribute "WATTAGE" "1/16W"
					( Origin gFrontEnd )
				)
				( attribute "XY" "(-6700,-4300)"
					( Origin gFrontEnd )
				)
				( attribute "CHIPS_PART_NAME" "RES"
					( Origin gPackager )
				)
				( attribute "CDS_PART_NAME" "RES_0402-0.0,5%,1/16W,EMPTY,G2A"
					( Origin gPackager )
				)
				( attribute "CDS_SEC" "1"
					( Origin gPackager )
				)
				( objectStatus "R25W140" )
			)
			( gate "@baseboard_fab2_lib.baseboard_fab2(sch_1):page150_i214"
				( attribute "BOM_COST" "SM_CONTROLLER"
					( Origin gFrontEnd )
				)
				( attribute "CDS_LIB" "mstr_discrete"
					( Origin gPackager )
				)
				( attribute "CDS_LOCATION" "R25W103"
					( Origin gPackager )
				)
				( attribute "CDS_SEC" "1"
					( Origin gPackager )
				)
				( attribute "LOCATION" "R25W103"
					( Origin gFrontEnd )
				)
				( attribute "MATERIAL" "EMPTY"
					( Origin gFrontEnd )
				)
				( attribute "PACK_TYPE" "0402"
					( Origin gFrontEnd )
				)
				( attribute "PART_NUMBER" "G21796-072"
					( Origin gFrontEnd )
				)
				( attribute "PHYS_PAGE" "150"
					( Origin gFrontEnd )
				)
				( attribute "ROOM" "BMC"
					( Origin gFrontEnd )
				)
				( attribute "ROT" "0"
					( Origin gFrontEnd )
				)
				( attribute "SEC" "1"
					( Origin gFrontEnd )
				)
				( attribute "SEC_TYPE" "0402"
					( Origin gFrontEnd )
				)
				( attribute "TOLERANCE" "1%"
					( Origin gFrontEnd )
				)
				( attribute "VALUE" "4.75K"
					( Origin gFrontEnd )
				)
				( attribute "VER" "1"
					( Origin gFrontEnd )
				)
				( attribute "WATTAGE" "1/16W"
					( Origin gFrontEnd )
				)
				( attribute "XY" "(1850,-1200)"
					( Origin gFrontEnd )
				)
				( attribute "CHIPS_PART_NAME" "RES"
					( Origin gPackager )
				)
				( attribute "CDS_PART_NAME" "RES_0402-4.75K,1%,1/16W,EMPTY,A"
					( Origin gPackager )
				)
				( objectStatus "R25W103" )
			)
			( gate "@baseboard_fab2_lib.baseboard_fab2(sch_1):page150_i215"
				( attribute "BOM_COST" "SM_CONTROLLER"
					( Origin gFrontEnd )
				)
				( attribute "CDS_LIB" "mstr_discrete"
					( Origin gPackager )
				)
				( attribute "CDS_LOCATION" "R25W104"
					( Origin gPackager )
				)
				( attribute "CDS_SEC" "1"
					( Origin gPackager )
				)
				( attribute "LOCATION" "R25W104"
					( Origin gFrontEnd )
				)
				( attribute "MATERIAL" "CHIP"
					( Origin gFrontEnd )
				)
				( attribute "PACK_TYPE" "0402"
					( Origin gFrontEnd )
				)
				( attribute "PART_NUMBER" "G21796-072"
					( Origin gFrontEnd )
				)
				( attribute "PHYS_PAGE" "150"
					( Origin gFrontEnd )
				)
				( attribute "ROOM" "BMC"
					( Origin gFrontEnd )
				)
				( attribute "ROT" "0"
					( Origin gFrontEnd )
				)
				( attribute "SEC" "1"
					( Origin gFrontEnd )
				)
				( attribute "SEC_TYPE" "0402"
					( Origin gFrontEnd )
				)
				( attribute "TOLERANCE" "1%"
					( Origin gFrontEnd )
				)
				( attribute "VALUE" "4.75K"
					( Origin gFrontEnd )
				)
				( attribute "VER" "1"
					( Origin gFrontEnd )
				)
				( attribute "WATTAGE" "1/16W"
					( Origin gFrontEnd )
				)
				( attribute "XY" "(1850,-1400)"
					( Origin gFrontEnd )
				)
				( attribute "CHIPS_PART_NAME" "RES"
					( Origin gPackager )
				)
				( attribute "CDS_PART_NAME" "RES_0402-4.75K,1%,1/16W,CHIP,GA"
					( Origin gPackager )
				)
				( objectStatus "R25W104" )
			)
			( gate "@baseboard_fab2_lib.baseboard_fab2(sch_1):page150_i218"
				( attribute "BOM_COST" "SM_CONTROLLER"
					( Origin gFrontEnd )
				)
				( attribute "CDS_LIB" "mstr_discrete"
					( Origin gPackager )
				)
				( attribute "CDS_LOCATION" "R25W114"
					( Origin gPackager )
				)
				( attribute "CDS_SEC" "1"
					( Origin gPackager )
				)
				( attribute "LOCATION" "R25W114"
					( Origin gFrontEnd )
				)
				( attribute "MATERIAL" "EMPTY"
					( Origin gFrontEnd )
				)
				( attribute "PACK_TYPE" "0402"
					( Origin gFrontEnd )
				)
				( attribute "PART_NUMBER" "G21796-072"
					( Origin gFrontEnd )
				)
				( attribute "PHYS_PAGE" "150"
					( Origin gFrontEnd )
				)
				( attribute "ROOM" "BMC"
					( Origin gFrontEnd )
				)
				( attribute "ROT" "0"
					( Origin gFrontEnd )
				)
				( attribute "SEC" "1"
					( Origin gFrontEnd )
				)
				( attribute "SEC_TYPE" "0402"
					( Origin gFrontEnd )
				)
				( attribute "TOLERANCE" "1%"
					( Origin gFrontEnd )
				)
				( attribute "VALUE" "4.75K"
					( Origin gFrontEnd )
				)
				( attribute "VER" "1"
					( Origin gFrontEnd )
				)
				( attribute "WATTAGE" "1/16W"
					( Origin gFrontEnd )
				)
				( attribute "XY" "(-600,-2500)"
					( Origin gFrontEnd )
				)
				( attribute "CHIPS_PART_NAME" "RES"
					( Origin gPackager )
				)
				( attribute "CDS_PART_NAME" "RES_0402-4.75K,1%,1/16W,EMPTY,A"
					( Origin gPackager )
				)
				( objectStatus "R25W114" )
			)
			( gate "@baseboard_fab2_lib.baseboard_fab2(sch_1):page150_i219"
				( attribute "BOM_COST" "SM_CONTROLLER"
					( Origin gFrontEnd )
				)
				( attribute "CDS_LIB" "mstr_discrete"
					( Origin gPackager )
				)
				( attribute "LOCATION" "R25W149"
					( Origin gFrontEnd )
				)
				( attribute "MATERIAL" "CHIP"
					( Origin gFrontEnd )
				)
				( attribute "PACK_TYPE" "0402"
					( Origin gFrontEnd )
				)
				( attribute "PART_NUMBER" "G21796-072"
					( Origin gFrontEnd )
				)
				( attribute "PHYS_PAGE" "150"
					( Origin gFrontEnd )
				)
				( attribute "ROOM" "BMC"
					( Origin gFrontEnd )
				)
				( attribute "ROT" "0"
					( Origin gFrontEnd )
				)
				( attribute "SEC" "1"
					( Origin gFrontEnd )
				)
				( attribute "SEC_TYPE" "0402"
					( Origin gFrontEnd )
				)
				( attribute "TOLERANCE" "1%"
					( Origin gFrontEnd )
				)
				( attribute "VALUE" "4.75K"
					( Origin gFrontEnd )
				)
				( attribute "VER" "1"
					( Origin gFrontEnd )
				)
				( attribute "WATTAGE" "1/16W"
					( Origin gFrontEnd )
				)
				( attribute "XY" "(-600,-2700)"
					( Origin gFrontEnd )
				)
				( attribute "CHIPS_PART_NAME" "RES"
					( Origin gPackager )
				)
				( attribute "CDS_PART_NAME" "RES_0402-4.75K,1%,1/16W,CHIP,GA"
					( Origin gPackager )
				)
				( attribute "CDS_LOCATION" "R25W149"
					( Origin gPackager )
				)
				( attribute "CDS_SEC" "1"
					( Origin gPackager )
				)
				( objectStatus "R25W149" )
			)
			( gate "@baseboard_fab2_lib.baseboard_fab2(sch_1):page199_i138"
				( attribute "CDS_LIB" "mstr_discrete"
					( Origin gPackager )
				)
				( attribute "CDS_LOCATION" "R9P28"
					( Origin gPackager )
				)
				( attribute "CDS_SEC" "1"
					( Origin gPackager )
				)
				( attribute "LOCATION" "R9P28"
					( Origin gFrontEnd )
				)
				( attribute "MATERIAL" "CHIP"
					( Origin gFrontEnd )
				)
				( attribute "PACK_TYPE" "0402"
					( Origin gFrontEnd )
				)
				( attribute "PART_NUMBER" "G21796-010"
					( Origin gFrontEnd )
				)
				( attribute "PHYS_PAGE" "199"
					( Origin gFrontEnd )
				)
				( attribute "ROOM" "HOT_SWAP"
					( Origin gFrontEnd )
				)
				( attribute "ROT" "0"
					( Origin gFrontEnd )
				)
				( attribute "SEC" "1"
					( Origin gFrontEnd )
				)
				( attribute "SEC_TYPE" "0402"
					( Origin gFrontEnd )
				)
				( attribute "TOLERANCE" "1%"
					( Origin gFrontEnd )
				)
				( attribute "VALUE" "100.0K"
					( Origin gFrontEnd )
				)
				( attribute "VER" "2"
					( Origin gFrontEnd )
				)
				( attribute "WATTAGE" "1/16W"
					( Origin gFrontEnd )
				)
				( attribute "XY" "(-7200,4025)"
					( Origin gFrontEnd )
				)
				( attribute "CHIPS_PART_NAME" "RES"
					( Origin gPackager )
				)
				( attribute "CDS_PART_NAME" "RES_0402-100.0K,1%,1/16W,CHIP,A"
					( Origin gPackager )
				)
				( objectStatus "R9P28" )
			)
			( gate "@baseboard_fab2_lib.baseboard_fab2(sch_1):page150_i229"
				( attribute "BOM_COST" "SM_CONTROLLER"
					( Origin gFrontEnd )
				)
				( attribute "CDS_LIB" "mstr_discrete"
					( Origin gPackager )
				)
				( attribute "LOCATION" "R25W150"
					( Origin gFrontEnd )
				)
				( attribute "MATERIAL" "CHIP"
					( Origin gFrontEnd )
				)
				( attribute "PACK_TYPE" "0402"
					( Origin gFrontEnd )
				)
				( attribute "PART_NUMBER" "G21796-072"
					( Origin gFrontEnd )
				)
				( attribute "PHYS_PAGE" "150"
					( Origin gFrontEnd )
				)
				( attribute "ROOM" "BMC"
					( Origin gFrontEnd )
				)
				( attribute "ROT" "0"
					( Origin gFrontEnd )
				)
				( attribute "SEC" "1"
					( Origin gFrontEnd )
				)
				( attribute "SEC_TYPE" "0402"
					( Origin gFrontEnd )
				)
				( attribute "TOLERANCE" "1%"
					( Origin gFrontEnd )
				)
				( attribute "VALUE" "4.75K"
					( Origin gFrontEnd )
				)
				( attribute "VER" "1"
					( Origin gFrontEnd )
				)
				( attribute "WATTAGE" "1/16W"
					( Origin gFrontEnd )
				)
				( attribute "XY" "(-600,-3300)"
					( Origin gFrontEnd )
				)
				( attribute "CHIPS_PART_NAME" "RES"
					( Origin gPackager )
				)
				( attribute "CDS_PART_NAME" "RES_0402-4.75K,1%,1/16W,CHIP,GA"
					( Origin gPackager )
				)
				( attribute "CDS_LOCATION" "R25W150"
					( Origin gPackager )
				)
				( attribute "CDS_SEC" "1"
					( Origin gPackager )
				)
				( objectStatus "R25W150" )
			)
			( gate "@baseboard_fab2_lib.baseboard_fab2(sch_1):page150_i233"
				( attribute "BOM_COST" "SM_CONTROLLER"
					( Origin gFrontEnd )
				)
				( attribute "CDS_LIB" "mstr_discrete"
					( Origin gPackager )
				)
				( attribute "CDS_LOCATION" "R25W110"
					( Origin gPackager )
				)
				( attribute "CDS_SEC" "1"
					( Origin gPackager )
				)
				( attribute "LOCATION" "R25W110"
					( Origin gFrontEnd )
				)
				( attribute "MATERIAL" "EMPTY"
					( Origin gFrontEnd )
				)
				( attribute "PACK_TYPE" "0402"
					( Origin gFrontEnd )
				)
				( attribute "PART_NUMBER" "G21796-072"
					( Origin gFrontEnd )
				)
				( attribute "PHYS_PAGE" "150"
					( Origin gFrontEnd )
				)
				( attribute "ROOM" "BMC"
					( Origin gFrontEnd )
				)
				( attribute "ROT" "0"
					( Origin gFrontEnd )
				)
				( attribute "SEC" "1"
					( Origin gFrontEnd )
				)
				( attribute "SEC_TYPE" "0402"
					( Origin gFrontEnd )
				)
				( attribute "TOLERANCE" "1%"
					( Origin gFrontEnd )
				)
				( attribute "VALUE" "4.75K"
					( Origin gFrontEnd )
				)
				( attribute "VER" "1"
					( Origin gFrontEnd )
				)
				( attribute "WATTAGE" "1/16W"
					( Origin gFrontEnd )
				)
				( attribute "XY" "(1850,400)"
					( Origin gFrontEnd )
				)
				( attribute "CHIPS_PART_NAME" "RES"
					( Origin gPackager )
				)
				( attribute "CDS_PART_NAME" "RES_0402-4.75K,1%,1/16W,EMPTY,A"
					( Origin gPackager )
				)
				( objectStatus "R25W110" )
			)
			( gate "@baseboard_fab2_lib.baseboard_fab2(sch_1):page150_i234"
				( attribute "BOM_COST" "SM_CONTROLLER"
					( Origin gFrontEnd )
				)
				( attribute "CDS_LIB" "mstr_discrete"
					( Origin gPackager )
				)
				( attribute "LOCATION" "R25W152"
					( Origin gFrontEnd )
				)
				( attribute "MATERIAL" "CHIP"
					( Origin gFrontEnd )
				)
				( attribute "PACK_TYPE" "0402"
					( Origin gFrontEnd )
				)
				( attribute "PART_NUMBER" "G21796-072"
					( Origin gFrontEnd )
				)
				( attribute "PHYS_PAGE" "150"
					( Origin gFrontEnd )
				)
				( attribute "ROOM" "BMC"
					( Origin gFrontEnd )
				)
				( attribute "ROT" "0"
					( Origin gFrontEnd )
				)
				( attribute "SEC" "1"
					( Origin gFrontEnd )
				)
				( attribute "SEC_TYPE" "0402"
					( Origin gFrontEnd )
				)
				( attribute "TOLERANCE" "1%"
					( Origin gFrontEnd )
				)
				( attribute "VALUE" "4.75K"
					( Origin gFrontEnd )
				)
				( attribute "VER" "1"
					( Origin gFrontEnd )
				)
				( attribute "WATTAGE" "1/16W"
					( Origin gFrontEnd )
				)
				( attribute "XY" "(1850,200)"
					( Origin gFrontEnd )
				)
				( attribute "CHIPS_PART_NAME" "RES"
					( Origin gPackager )
				)
				( attribute "CDS_PART_NAME" "RES_0402-4.75K,1%,1/16W,CHIP,GA"
					( Origin gPackager )
				)
				( attribute "CDS_LOCATION" "R25W152"
					( Origin gPackager )
				)
				( attribute "CDS_SEC" "1"
					( Origin gPackager )
				)
				( objectStatus "R25W152" )
			)
			( gate "@baseboard_fab2_lib.baseboard_fab2(sch_1):page150_i236"
				( attribute "BOM_COST" "SM_CONTROLLER"
					( Origin gFrontEnd )
				)
				( attribute "CDS_LIB" "mstr_discrete"
					( Origin gPackager )
				)
				( attribute "LOCATION" "R25W109"
					( Origin gFrontEnd )
				)
				( attribute "MATERIAL" "CHIP"
					( Origin gFrontEnd )
				)
				( attribute "PACK_TYPE" "0402"
					( Origin gFrontEnd )
				)
				( attribute "PART_NUMBER" "G21796-072"
					( Origin gFrontEnd )
				)
				( attribute "PHYS_PAGE" "150"
					( Origin gFrontEnd )
				)
				( attribute "ROOM" "BMC"
					( Origin gFrontEnd )
				)
				( attribute "ROT" "0"
					( Origin gFrontEnd )
				)
				( attribute "SEC" "1"
					( Origin gFrontEnd )
				)
				( attribute "SEC_TYPE" "0402"
					( Origin gFrontEnd )
				)
				( attribute "TOLERANCE" "1%"
					( Origin gFrontEnd )
				)
				( attribute "VALUE" "4.75K"
					( Origin gFrontEnd )
				)
				( attribute "VER" "1"
					( Origin gFrontEnd )
				)
				( attribute "WATTAGE" "1/16W"
					( Origin gFrontEnd )
				)
				( attribute "XY" "(1850,0)"
					( Origin gFrontEnd )
				)
				( attribute "CHIPS_PART_NAME" "RES"
					( Origin gPackager )
				)
				( attribute "CDS_PART_NAME" "RES_0402-4.75K,1%,1/16W,CHIP,GA"
					( Origin gPackager )
				)
				( attribute "CDS_LOCATION" "R25W109"
					( Origin gPackager )
				)
				( attribute "CDS_SEC" "1"
					( Origin gPackager )
				)
				( objectStatus "R25W109" )
			)
			( gate "@baseboard_fab2_lib.baseboard_fab2(sch_1):page151_i210"
				( attribute "BOM_COST" "MIO_BIOS_MEM"
					( Origin gFrontEnd )
				)
				( attribute "CDS_LIB" "mstr_discrete"
					( Origin gPackager )
				)
				( attribute "CDS_LOCATION" "R25W119"
					( Origin gPackager )
				)
				( attribute "CDS_SEC" "1"
					( Origin gPackager )
				)
				( attribute "LOCATION" "R25W119"
					( Origin gFrontEnd )
				)
				( attribute "MATERIAL" "EMPTY"
					( Origin gFrontEnd )
				)
				( attribute "NO_XNET_CONNECTION" "1"
					( Origin gFrontEnd )
				)
				( attribute "PACK_TYPE" "0402"
					( Origin gFrontEnd )
				)
				( attribute "PART_NUMBER" "G21796-072"
					( Origin gFrontEnd )
				)
				( attribute "PHYS_PAGE" "151"
					( Origin gFrontEnd )
				)
				( attribute "ROOM" "SB_SPI"
					( Origin gFrontEnd )
				)
				( attribute "ROT" "2"
					( Origin gFrontEnd )
				)
				( attribute "SEC" "1"
					( Origin gFrontEnd )
				)
				( attribute "SEC_TYPE" "0402"
					( Origin gFrontEnd )
				)
				( attribute "TOLERANCE" "1%"
					( Origin gFrontEnd )
				)
				( attribute "VALUE" "4.75K"
					( Origin gFrontEnd )
				)
				( attribute "VER" "2"
					( Origin gFrontEnd )
				)
				( attribute "WATTAGE" "1/16W"
					( Origin gFrontEnd )
				)
				( attribute "XY" "(-150,-1500)"
					( Origin gFrontEnd )
				)
				( attribute "CHIPS_PART_NAME" "RES"
					( Origin gPackager )
				)
				( attribute "CDS_PART_NAME" "RES_0402-4.75K,1%,1/16W,EMPTY,A"
					( Origin gPackager )
				)
				( objectStatus "R25W119" )
			)
			( gate "@baseboard_fab2_lib.baseboard_fab2(sch_1):page157_i394"
				( attribute "CDS_LIB" "mstr_ttl"
					( Origin gPackager )
				)
				( attribute "CDS_LOCATION" "U25W9"
					( Origin gPackager )
				)
				( attribute "CDS_SEC" "1"
					( Origin gPackager )
				)
				( attribute "LOCATION" "U25W9"
					( Origin gFrontEnd )
				)
				( attribute "MATERIAL" "IC"
					( Origin gFrontEnd )
				)
				( attribute "PACK_TYPE" "SOP"
					( Origin gFrontEnd )
				)
				( attribute "PART_NUMBER" "C88419-001"
					( Origin gFrontEnd )
				)
				( attribute "PHYS_PAGE" "157"
					( Origin gFrontEnd )
				)
				( attribute "ROT" "0"
					( Origin gFrontEnd )
				)
				( attribute "SEC" "1"
					( Origin gFrontEnd )
				)
				( attribute "SEC_TYPE" "SOP"
					( Origin gFrontEnd )
				)
				( attribute "VALUE" "74LVC1G07"
					( Origin gFrontEnd )
				)
				( attribute "VER" "1"
					( Origin gFrontEnd )
				)
				( attribute "XY" "(-2800,500)"
					( Origin gFrontEnd )
				)
				( attribute "CHIPS_PART_NAME" "TTL1G07_A"
					( Origin gPackager )
				)
				( attribute "CDS_PART_NAME" "TTL1G07_A_SOP-74LVC1G07,IC,C88B"
					( Origin gPackager )
				)
				( objectStatus "U25W9" )
			)
			( gate "@baseboard_fab2_lib.baseboard_fab2(sch_1):page157_i396"
				( attribute "BOM_COST" "SM_CONTROLLER"
					( Origin gFrontEnd )
				)
				( attribute "CDS_LIB" "mstr_discrete"
					( Origin gPackager )
				)
				( attribute "CDS_LOCATION" "R25W153"
					( Origin gPackager )
				)
				( attribute "CDS_SEC" "1"
					( Origin gPackager )
				)
				( attribute "LOCATION" "R25W153"
					( Origin gFrontEnd )
				)
				( attribute "MATERIAL" "CHIP"
					( Origin gFrontEnd )
				)
				( attribute "PACK_TYPE" "0402"
					( Origin gFrontEnd )
				)
				( attribute "PART_NUMBER" "G21796-072"
					( Origin gFrontEnd )
				)
				( attribute "PHYS_PAGE" "157"
					( Origin gFrontEnd )
				)
				( attribute "ROOM" "BMC_MISC"
					( Origin gFrontEnd )
				)
				( attribute "ROT" "0"
					( Origin gFrontEnd )
				)
				( attribute "SEC" "1"
					( Origin gFrontEnd )
				)
				( attribute "SEC_TYPE" "0402"
					( Origin gFrontEnd )
				)
				( attribute "TOLERANCE" "1%"
					( Origin gFrontEnd )
				)
				( attribute "VALUE" "4.75K"
					( Origin gFrontEnd )
				)
				( attribute "VER" "2"
					( Origin gFrontEnd )
				)
				( attribute "WATTAGE" "1/16W"
					( Origin gFrontEnd )
				)
				( attribute "XY" "(-2275,700)"
					( Origin gFrontEnd )
				)
				( attribute "CHIPS_PART_NAME" "RES"
					( Origin gPackager )
				)
				( attribute "CDS_PART_NAME" "RES_0402-4.75K,1%,1/16W,CHIP,GA"
					( Origin gPackager )
				)
				( objectStatus "R25W153" )
			)
			( gate "@baseboard_fab2_lib.baseboard_fab2(sch_1):page138_i186"
				( attribute "CDS_LIB" "mstr_discrete"
					( Origin gPackager )
				)
				( attribute "LOCATION" "R8B24"
					( Origin gFrontEnd )
				)
				( attribute "MATERIAL" "CHIP"
					( Origin gFrontEnd )
				)
				( attribute "PACK_TYPE" "0402"
					( Origin gFrontEnd )
				)
				( attribute "PART_NUMBER" "G21497-013"
					( Origin gFrontEnd )
				)
				( attribute "PHYS_PAGE" "138"
					( Origin gFrontEnd )
				)
				( attribute "ROT" "5"
					( Origin gFrontEnd )
				)
				( attribute "TOLERANCE" "5%"
					( Origin gFrontEnd )
				)
				( attribute "VALUE" "3.3K"
					( Origin gFrontEnd )
				)
				( attribute "VER" "1"
					( Origin gFrontEnd )
				)
				( attribute "WATTAGE" "1/16W"
					( Origin gFrontEnd )
				)
				( attribute "XY" "(-3175,2975)"
					( Origin gFrontEnd )
				)
				( attribute "CHIPS_PART_NAME" "RES"
					( Origin gPackager )
				)
				( attribute "CDS_PART_NAME" "RES_0402-3.3K,5%,1/16W,CHIP,G2A"
					( Origin gPackager )
				)
				( attribute "SEC" "1"
					( Origin gFrontEnd )
				)
				( attribute "SEC_TYPE" "0402"
					( Origin gFrontEnd )
				)
				( attribute "CDS_LOCATION" "R8B24"
					( Origin gPackager )
				)
				( attribute "CDS_SEC" "1"
					( Origin gPackager )
				)
				( objectStatus "R8B24" )
			)
			( gate "@baseboard_fab2_lib.baseboard_fab2(sch_1):page138_i187"
				( attribute "CDS_LIB" "mstr_discrete"
					( Origin gPackager )
				)
				( attribute "LOCATION" "R8B26"
					( Origin gFrontEnd )
				)
				( attribute "MATERIAL" "CHIP"
					( Origin gFrontEnd )
				)
				( attribute "PACK_TYPE" "0402"
					( Origin gFrontEnd )
				)
				( attribute "PART_NUMBER" "G21497-013"
					( Origin gFrontEnd )
				)
				( attribute "PHYS_PAGE" "138"
					( Origin gFrontEnd )
				)
				( attribute "ROT" "5"
					( Origin gFrontEnd )
				)
				( attribute "SEC" "1"
					( Origin gFrontEnd )
				)
				( attribute "SEC_TYPE" "0402"
					( Origin gFrontEnd )
				)
				( attribute "TOLERANCE" "5%"
					( Origin gFrontEnd )
				)
				( attribute "VALUE" "3.3K"
					( Origin gFrontEnd )
				)
				( attribute "VER" "1"
					( Origin gFrontEnd )
				)
				( attribute "WATTAGE" "1/16W"
					( Origin gFrontEnd )
				)
				( attribute "XY" "(-2775,2925)"
					( Origin gFrontEnd )
				)
				( attribute "CHIPS_PART_NAME" "RES"
					( Origin gPackager )
				)
				( attribute "CDS_PART_NAME" "RES_0402-3.3K,5%,1/16W,CHIP,G2A"
					( Origin gPackager )
				)
				( attribute "CDS_LOCATION" "R8B26"
					( Origin gPackager )
				)
				( attribute "CDS_SEC" "1"
					( Origin gPackager )
				)
				( objectStatus "R8B26" )
			)
			( gate "@baseboard_fab2_lib.baseboard_fab2(sch_1):page195_i114"
				( attribute "CDS_LIB" "w_hdl"
					( Origin gPackager )
				)
				( attribute "CDS_LMAN_SYM_OUTLINE" "-175,300,175,-300"
					( Origin gPackager )
				)
				( attribute "LOCATION" "J1E1"
					( Origin gFrontEnd )
				)
				( attribute "PACK_TYPE" "CONN-G5"
					( Origin gFrontEnd )
				)
				( attribute "PART_NUMBER" "20.82093.012"
					( Origin gFrontEnd )
				)
				( attribute "PHYS_PAGE" "195"
					( Origin gFrontEnd )
				)
				( attribute "ROT" "0"
					( Origin gFrontEnd )
				)
				( attribute "SEC" "1"
					( Origin gFrontEnd )
				)
				( attribute "SEC_TYPE" "CONN-G5"
					( Origin gFrontEnd )
				)
				( attribute "VALUE" "FCI-CONN12-2R-GP"
					( Origin gFrontEnd )
				)
				( attribute "VER" "1"
					( Origin gFrontEnd )
				)
				( attribute "XY" "(-3025,2150)"
					( Origin gFrontEnd )
				)
				( attribute "CHIPS_PART_NAME" "FCI-CONN12-2R-GP"
					( Origin gPackager )
				)
				( attribute "CDS_PART_NAME" "FCI-CONN12-2R-GP_CONN-G5-FCI-CA"
					( Origin gPackager )
				)
				( attribute "CDS_LOCATION" "J1E1"
					( Origin gPackager )
				)
				( attribute "CDS_SEC" "1"
					( Origin gPackager )
				)
				( objectStatus "J1E1" )
			)
			( gate "@baseboard_fab2_lib.baseboard_fab2(sch_1):page195_i115"
				( attribute "CDS_LIB" "w_hdl"
					( Origin gPackager )
				)
				( attribute "CDS_LMAN_SYM_OUTLINE" "-175,300,175,-300"
					( Origin gPackager )
				)
				( attribute "CDS_LOCATION" "J1D1"
					( Origin gPackager )
				)
				( attribute "CDS_SEC" "1"
					( Origin gPackager )
				)
				( attribute "LOCATION" "J1D1"
					( Origin gFrontEnd )
				)
				( attribute "PACK_TYPE" "CONN-G5"
					( Origin gFrontEnd )
				)
				( attribute "PART_NUMBER" "20.82093.012"
					( Origin gFrontEnd )
				)
				( attribute "PHYS_PAGE" "195"
					( Origin gFrontEnd )
				)
				( attribute "POP" "NOPOP"
					( Origin gFrontEnd )
				)
				( attribute "ROT" "0"
					( Origin gFrontEnd )
				)
				( attribute "SEC" "1"
					( Origin gFrontEnd )
				)
				( attribute "SEC_TYPE" "CONN-G5"
					( Origin gFrontEnd )
				)
				( attribute "VALUE" "FCI-CONN12-2R-GP"
					( Origin gFrontEnd )
				)
				( attribute "VER" "1"
					( Origin gFrontEnd )
				)
				( attribute "XY" "(-1250,2150)"
					( Origin gFrontEnd )
				)
				( attribute "CHIPS_PART_NAME" "FCI-CONN12-2R-GP"
					( Origin gPackager )
				)
				( attribute "CDS_PART_NAME" "FCI-CONN12-2R-GP_CONN-G5-FCI-CA"
					( Origin gPackager )
				)
				( objectStatus "J1D1" )
			)
			( gate "@baseboard_fab2_lib.baseboard_fab2(sch_1):page253_i26"
				( attribute "CDS_LIB" "w_hdl"
					( Origin gPackager )
				)
				( attribute "CDS_LMAN_SYM_OUTLINE" "-250,675,250,-675"
					( Origin gPackager )
				)
				( attribute "LOCATION" "J30W1"
					( Origin gFrontEnd )
				)
				( attribute "PACK_TYPE" "SOCKET-G4"
					( Origin gFrontEnd )
				)
				( attribute "PART_NUMBER" "062.10009.0621"
					( Origin gFrontEnd )
				)
				( attribute "PHYS_PAGE" "253"
					( Origin gFrontEnd )
				)
				( attribute "ROT" "0"
					( Origin gFrontEnd )
				)
				( attribute "SEC" "1"
					( Origin gFrontEnd )
				)
				( attribute "SEC_TYPE" "SOCKET-G4"
					( Origin gFrontEnd )
				)
				( attribute "VALUE" "SKT-USB32-8-GP"
					( Origin gFrontEnd )
				)
				( attribute "VER" "1"
					( Origin gFrontEnd )
				)
				( attribute "XY" "(-1750,3775)"
					( Origin gFrontEnd )
				)
				( attribute "CHIPS_PART_NAME" "SKT-USB32-8-GP"
					( Origin gPackager )
				)
				( attribute "CDS_PART_NAME" "SKT-USB32-8-GP_SOCKET-G4-SKT-UA"
					( Origin gPackager )
				)
				( attribute "CDS_LOCATION" "J30W1"
					( Origin gPackager )
				)
				( attribute "CDS_SEC" "1"
					( Origin gPackager )
				)
				( attribute "GROUP" "NO_KR"
					( Origin gFrontEnd )
				)
				( objectStatus "J30W1" )
			)
			( gate "@baseboard_fab2_lib.baseboard_fab2(sch_1):page230_i20"
				( attribute "BOM_COST" "MEM_VRD_VTT_KLM"
					( Origin gFrontEnd )
				)
				( attribute "CDS_LIB" "mstr_discrete"
					( Origin gPackager )
				)
				( attribute "CDS_LOCATION" "C4A13"
					( Origin gPackager )
				)
				( attribute "CDS_SEC" "1"
					( Origin gPackager )
				)
				( attribute "LOCATION" "C4A13"
					( Origin gFrontEnd )
				)
				( attribute "MATERIAL" "X6S"
					( Origin gFrontEnd )
				)
				( attribute "PACK_TYPE" "0805LF"
					( Origin gFrontEnd )
				)
				( attribute "PART_NUMBER" "C95333-002"
					( Origin gFrontEnd )
				)
				( attribute "PHYS_PAGE" "230"
					( Origin gFrontEnd )
				)
				( attribute "ROOM" "VTT_KLM_PWR_VR"
					( Origin gFrontEnd )
				)
				( attribute "ROT" "0"
					( Origin gFrontEnd )
				)
				( attribute "SEC" "1"
					( Origin gFrontEnd )
				)
				( attribute "SEC_TYPE" "0805LF"
					( Origin gFrontEnd )
				)
				( attribute "TOLERANCE" "20%"
					( Origin gFrontEnd )
				)
				( attribute "VALUE" "22UF"
					( Origin gFrontEnd )
				)
				( attribute "VER" "1"
					( Origin gFrontEnd )
				)
				( attribute "VOLTAGE" "4V"
					( Units "uVoltage" "V" 1.000000)
					( Origin gFrontEnd )
				)
				( attribute "XY" "(2325,300)"
					( Origin gFrontEnd )
				)
				( attribute "CHIPS_PART_NAME" "CAP"
					( Origin gPackager )
				)
				( attribute "CDS_PART_NAME" "CAP_0805LF-22UF,4V,20%,X6S,C95A"
					( Origin gPackager )
				)
				( attribute "GROUP" "PWR_MLCC_CAP"
					( Origin gFrontEnd )
				)
				( objectStatus "C4A13" )
			)
			( gate "@baseboard_fab2_lib.baseboard_fab2(sch_1):page230_i13"
				( attribute "BOM_COST" "MEM_VRD_VTT_KLM"
					( Origin gFrontEnd )
				)
				( attribute "CDS_LIB" "mstr_discrete"
					( Origin gPackager )
				)
				( attribute "CDS_LOCATION" "R6L8"
					( Origin gPackager )
				)
				( attribute "CDS_SEC" "1"
					( Origin gPackager )
				)
				( attribute "LOCATION" "R6L8"
					( Origin gFrontEnd )
				)
				( attribute "MATERIAL" "CHIP"
					( Origin gFrontEnd )
				)
				( attribute "PACK_TYPE" "0402"
					( Origin gFrontEnd )
				)
				( attribute "PART_NUMBER" "G21497-005"
					( Origin gFrontEnd )
				)
				( attribute "PHYS_PAGE" "230"
					( Origin gFrontEnd )
				)
				( attribute "ROOM" "VTT_KLM_PWR_VR"
					( Origin gFrontEnd )
				)
				( attribute "ROT" "0"
					( Origin gFrontEnd )
				)
				( attribute "SEC" "1"
					( Origin gFrontEnd )
				)
				( attribute "SEC_TYPE" "0402"
					( Origin gFrontEnd )
				)
				( attribute "TOLERANCE" "5%"
					( Origin gFrontEnd )
				)
				( attribute "VALUE" "0.0"
					( Origin gFrontEnd )
				)
				( attribute "VER" "1"
					( Origin gFrontEnd )
				)
				( attribute "WATTAGE" "1/16W"
					( Origin gFrontEnd )
				)
				( attribute "XY" "(-1525,1025)"
					( Origin gFrontEnd )
				)
				( attribute "CHIPS_PART_NAME" "RES"
					( Origin gPackager )
				)
				( attribute "CDS_PART_NAME" "RES_0402-0.0,5%,1/16W,CHIP,G21A"
					( Origin gPackager )
				)
				( objectStatus "R6L8" )
			)
			( gate "@baseboard_fab2_lib.baseboard_fab2(sch_1):page230_i12"
				( attribute "BOM_COST" "MEM_VRD_VTT_KLM"
					( Origin gFrontEnd )
				)
				( attribute "CDS_LIB" "mstr_discrete"
					( Origin gPackager )
				)
				( attribute "CDS_LOCATION" "C4A8"
					( Origin gPackager )
				)
				( attribute "CDS_SEC" "1"
					( Origin gPackager )
				)
				( attribute "LOCATION" "C4A8"
					( Origin gFrontEnd )
				)
				( attribute "MATERIAL" "X6S"
					( Origin gFrontEnd )
				)
				( attribute "PACK_TYPE" "0402"
					( Origin gFrontEnd )
				)
				( attribute "PART_NUMBER" "D97712-011"
					( Origin gFrontEnd )
				)
				( attribute "PHYS_PAGE" "230"
					( Origin gFrontEnd )
				)
				( attribute "ROOM" "VTT_KLM_PWR_VR"
					( Origin gFrontEnd )
				)
				( attribute "ROT" "0"
					( Origin gFrontEnd )
				)
				( attribute "SEC" "1"
					( Origin gFrontEnd )
				)
				( attribute "SEC_TYPE" "0402"
					( Origin gFrontEnd )
				)
				( attribute "TOLERANCE" "10%"
					( Origin gFrontEnd )
				)
				( attribute "VALUE" "1.0UF"
					( Origin gFrontEnd )
				)
				( attribute "VER" "1"
					( Origin gFrontEnd )
				)
				( attribute "VOLTAGE" "16V"
					( Units "uVoltage" "V" 1.000000)
					( Origin gFrontEnd )
				)
				( attribute "XY" "(-1200,775)"
					( Origin gFrontEnd )
				)
				( attribute "CHIPS_PART_NAME" "CAP"
					( Origin gPackager )
				)
				( attribute "CDS_PART_NAME" "CAP_0402-1.0UF,16V,10%,X6S,D97A"
					( Origin gPackager )
				)
				( objectStatus "C4A8" )
			)
			( gate "@baseboard_fab2_lib.baseboard_fab2(sch_1):page230_i10"
				( attribute "CDS_LIB" "mstr_discrete"
					( Origin gPackager )
				)
				( attribute "CDS_LOCATION" "C4A7"
					( Origin gPackager )
				)
				( attribute "CDS_SEC" "1"
					( Origin gPackager )
				)
				( attribute "LOCATION" "C4A7"
					( Origin gFrontEnd )
				)
				( attribute "MATERIAL" "X6S"
					( Origin gFrontEnd )
				)
				( attribute "PACK_TYPE" "0603"
					( Origin gFrontEnd )
				)
				( attribute "PART_NUMBER" "E15431-003"
					( Origin gFrontEnd )
				)
				( attribute "PHYS_PAGE" "230"
					( Origin gFrontEnd )
				)
				( attribute "ROOM" "VTT_KLM_PWR_VR"
					( Origin gFrontEnd )
				)
				( attribute "ROT" "0"
					( Origin gFrontEnd )
				)
				( attribute "SEC" "1"
					( Origin gFrontEnd )
				)
				( attribute "SEC_TYPE" "0603"
					( Origin gFrontEnd )
				)
				( attribute "TOLERANCE" "10%"
					( Origin gFrontEnd )
				)
				( attribute "VALUE" "4.7UF"
					( Origin gFrontEnd )
				)
				( attribute "VER" "1"
					( Origin gFrontEnd )
				)
				( attribute "VOLTAGE" "6.3V"
					( Units "uVoltage" "V" 1.000000)
					( Origin gFrontEnd )
				)
				( attribute "XY" "(-1300,225)"
					( Origin gFrontEnd )
				)
				( attribute "CHIPS_PART_NAME" "CAP"
					( Origin gPackager )
				)
				( attribute "CDS_PART_NAME" "CAP_0603-4.7UF,6.3V,10%,X6S,E1A"
					( Origin gPackager )
				)
				( objectStatus "C4A7" )
			)
			( gate "@baseboard_fab2_lib.baseboard_fab2(sch_1):page230_i6"
				( attribute "BOM_COST" "MEM_VRD_VTT_KLM"
					( Origin gFrontEnd )
				)
				( attribute "CDS_LIB" "mstr_discrete"
					( Origin gPackager )
				)
				( attribute "CDS_LOCATION" "R6L6"
					( Origin gPackager )
				)
				( attribute "CDS_SEC" "1"
					( Origin gPackager )
				)
				( attribute "LOCATION" "R6L6"
					( Origin gFrontEnd )
				)
				( attribute "MATERIAL" "CHIP"
					( Origin gFrontEnd )
				)
				( attribute "NO_XNET_CONNECTION" "1"
					( Origin gFrontEnd )
				)
				( attribute "PACK_TYPE" "0402"
					( Origin gFrontEnd )
				)
				( attribute "PART_NUMBER" "G21497-005"
					( Origin gFrontEnd )
				)
				( attribute "PHYS_PAGE" "230"
					( Origin gFrontEnd )
				)
				( attribute "ROOM" "VTT_KLM_PWR_VR"
					( Origin gFrontEnd )
				)
				( attribute "ROT" "1"
					( Origin gFrontEnd )
				)
				( attribute "SEC" "1"
					( Origin gFrontEnd )
				)
				( attribute "SEC_TYPE" "0402"
					( Origin gFrontEnd )
				)
				( attribute "TOLERANCE" "5%"
					( Origin gFrontEnd )
				)
				( attribute "VALUE" "0.0"
					( Origin gFrontEnd )
				)
				( attribute "VER" "2"
					( Origin gFrontEnd )
				)
				( attribute "WATTAGE" "1/16W"
					( Origin gFrontEnd )
				)
				( attribute "XY" "(-2350,825)"
					( Origin gFrontEnd )
				)
				( attribute "CHIPS_PART_NAME" "RES"
					( Origin gPackager )
				)
				( attribute "CDS_PART_NAME" "RES_0402-0.0,5%,1/16W,CHIP,G21A"
					( Origin gPackager )
				)
				( objectStatus "R6L6" )
			)
			( gate "@baseboard_fab2_lib.baseboard_fab2(sch_1):page230_i5"
				( attribute "BOM_COST" "MEM_VRD_VTT_KLM"
					( Origin gFrontEnd )
				)
				( attribute "CDS_LIB" "mstr_discrete"
					( Origin gPackager )
				)
				( attribute "CDS_LOCATION" "R6L5"
					( Origin gPackager )
				)
				( attribute "CDS_SEC" "1"
					( Origin gPackager )
				)
				( attribute "LOCATION" "R6L5"
					( Origin gFrontEnd )
				)
				( attribute "MATERIAL" "EMPTY"
					( Origin gFrontEnd )
				)
				( attribute "PACK_TYPE" "0402"
					( Origin gFrontEnd )
				)
				( attribute "PART_NUMBER" "G21796-021"
					( Origin gFrontEnd )
				)
				( attribute "PHYS_PAGE" "230"
					( Origin gFrontEnd )
				)
				( attribute "ROOM" "VTT_KLM_PWR_VR"
					( Origin gFrontEnd )
				)
				( attribute "ROT" "2"
					( Origin gFrontEnd )
				)
				( attribute "SEC" "1"
					( Origin gFrontEnd )
				)
				( attribute "SEC_TYPE" "0402"
					( Origin gFrontEnd )
				)
				( attribute "TOLERANCE" "1%"
					( Origin gFrontEnd )
				)
				( attribute "VALUE" "1.0M"
					( Origin gFrontEnd )
				)
				( attribute "VER" "2"
					( Origin gFrontEnd )
				)
				( attribute "WATTAGE" "1/16W"
					( Origin gFrontEnd )
				)
				( attribute "XY" "(-1975,-75)"
					( Origin gFrontEnd )
				)
				( attribute "CHIPS_PART_NAME" "RES"
					( Origin gPackager )
				)
				( attribute "CDS_PART_NAME" "RES_0402-1.0M,1%,1/16W,EMPTY,GA"
					( Origin gPackager )
				)
				( objectStatus "R6L5" )
			)
			( gate "@baseboard_fab2_lib.baseboard_fab2(sch_1):page230_i4"
				( attribute "BOM_COST" "MEM_VRD_VTT_KLM"
					( Origin gFrontEnd )
				)
				( attribute "CDS_LIB" "mstr_discrete"
					( Origin gPackager )
				)
				( attribute "CDS_LOCATION" "R4A3"
					( Origin gPackager )
				)
				( attribute "CDS_SEC" "1"
					( Origin gPackager )
				)
				( attribute "LOCATION" "R4A3"
					( Origin gFrontEnd )
				)
				( attribute "MATERIAL" "CHIP"
					( Origin gFrontEnd )
				)
				( attribute "PACK_TYPE" "0402"
					( Origin gFrontEnd )
				)
				( attribute "PART_NUMBER" "G21497-005"
					( Origin gFrontEnd )
				)
				( attribute "PHYS_PAGE" "230"
					( Origin gFrontEnd )
				)
				( attribute "ROOM" "VTT_KLM_PWR_VR"
					( Origin gFrontEnd )
				)
				( attribute "ROT" "0"
					( Origin gFrontEnd )
				)
				( attribute "SEC" "1"
					( Origin gFrontEnd )
				)
				( attribute "SEC_TYPE" "0402"
					( Origin gFrontEnd )
				)
				( attribute "TOLERANCE" "5%"
					( Origin gFrontEnd )
				)
				( attribute "VALUE" "0.0"
					( Origin gFrontEnd )
				)
				( attribute "VER" "1"
					( Origin gFrontEnd )
				)
				( attribute "WATTAGE" "1/16W"
					( Origin gFrontEnd )
				)
				( attribute "XY" "(-2225,-600)"
					( Origin gFrontEnd )
				)
				( attribute "CHIPS_PART_NAME" "RES"
					( Origin gPackager )
				)
				( attribute "CDS_PART_NAME" "RES_0402-0.0,5%,1/16W,CHIP,G21A"
					( Origin gPackager )
				)
				( objectStatus "R4A3" )
			)
			( gate "@baseboard_fab2_lib.baseboard_fab2(sch_1):page230_i2"
				( attribute "BOM_COST" "MEM_VRD_VTT_KLM"
					( Origin gFrontEnd )
				)
				( attribute "CDS_LIB" "mstr_discrete"
					( Origin gPackager )
				)
				( attribute "CDS_LOCATION" "C4A6"
					( Origin gPackager )
				)
				( attribute "CDS_SEC" "1"
					( Origin gPackager )
				)
				( attribute "LOCATION" "C4A6"
					( Origin gFrontEnd )
				)
				( attribute "MATERIAL" "EMPTY"
					( Origin gFrontEnd )
				)
				( attribute "PACK_TYPE" "0402LF"
					( Origin gFrontEnd )
				)
				( attribute "PART_NUMBER" "A36096-046"
					( Origin gFrontEnd )
				)
				( attribute "PHYS_PAGE" "230"
					( Origin gFrontEnd )
				)
				( attribute "ROOM" "VTT_KLM_PWR_VR"
					( Origin gFrontEnd )
				)
				( attribute "ROT" "2"
					( Origin gFrontEnd )
				)
				( attribute "SEC" "1"
					( Origin gFrontEnd )
				)
				( attribute "SEC_TYPE" "0402LF"
					( Origin gFrontEnd )
				)
				( attribute "TOLERANCE" "10%"
					( Origin gFrontEnd )
				)
				( attribute "VALUE" "1000PF"
					( Origin gFrontEnd )
				)
				( attribute "VER" "1"
					( Origin gFrontEnd )
				)
				( attribute "VOLTAGE" "50V"
					( Units "uVoltage" "V" 1.000000)
					( Origin gFrontEnd )
				)
				( attribute "XY" "(-2025,-1125)"
					( Origin gFrontEnd )
				)
				( attribute "CHIPS_PART_NAME" "CAP"
					( Origin gPackager )
				)
				( attribute "CDS_PART_NAME" "CAP_0402LF-1000PF,50V,10%,EMPTA"
					( Origin gPackager )
				)
				( objectStatus "C4A6" )
			)
			( gate "@baseboard_fab2_lib.baseboard_fab2(sch_1):page201_i189"
				( attribute "CDS_LIB" "mstr_discrete"
					( Origin gPackager )
				)
				( attribute "CDS_LOCATION" "R4E9"
					( Origin gPackager )
				)
				( attribute "CDS_SEC" "1"
					( Origin gPackager )
				)
				( attribute "LOCATION" "R4E9"
					( Origin gFrontEnd )
				)
				( attribute "MATERIAL" "EMPTY"
					( Origin gFrontEnd )
				)
				( attribute "PACK_TYPE" "0402"
					( Origin gFrontEnd )
				)
				( attribute "PART_NUMBER" "G21796-047"
					( Origin gFrontEnd )
				)
				( attribute "PHYS_PAGE" "201"
					( Origin gFrontEnd )
				)
				( attribute "ROOM" "PVCCIO_CPU0"
					( Origin gFrontEnd )
				)
				( attribute "ROT" "0"
					( Origin gFrontEnd )
				)
				( attribute "SEC" "1"
					( Origin gFrontEnd )
				)
				( attribute "SEC_TYPE" "0402"
					( Origin gFrontEnd )
				)
				( attribute "TOLERANCE" "1%"
					( Origin gFrontEnd )
				)
				( attribute "VALUE" "49.9"
					( Origin gFrontEnd )
				)
				( attribute "VER" "2"
					( Origin gFrontEnd )
				)
				( attribute "WATTAGE" "1/16W"
					( Origin gFrontEnd )
				)
				( attribute "XY" "(-5650,4275)"
					( Origin gFrontEnd )
				)
				( attribute "CHIPS_PART_NAME" "RES"
					( Origin gPackager )
				)
				( attribute "CDS_PART_NAME" "RES_0402-49.9,1%,1/16W,EMPTY,GA"
					( Origin gPackager )
				)
				( objectStatus "R4E9" )
			)
			( gate "@baseboard_fab2_lib.baseboard_fab2(sch_1):page133_i368"
				( attribute "CDS_LIB" "mstr_discrete"
					( Origin gPackager )
				)
				( attribute "CDS_LOCATION" "R3N15"
					( Origin gPackager )
				)
				( attribute "CDS_SEC" "1"
					( Origin gPackager )
				)
				( attribute "LOCATION" "R3N15"
					( Origin gFrontEnd )
				)
				( attribute "MATERIAL" "EMPTY"
					( Origin gFrontEnd )
				)
				( attribute "PACK_TYPE" "0402"
					( Origin gFrontEnd )
				)
				( attribute "PART_NUMBER" "G21796-026"
					( Origin gFrontEnd )
				)
				( attribute "PHYS_PAGE" "133"
					( Origin gFrontEnd )
				)
				( attribute "ROOM" "DEBUG"
					( Origin gFrontEnd )
				)
				( attribute "ROT" "3"
					( Origin gFrontEnd )
				)
				( attribute "SEC" "1"
					( Origin gFrontEnd )
				)
				( attribute "SEC_TYPE" "0402"
					( Origin gFrontEnd )
				)
				( attribute "TOLERANCE" "1%"
					( Origin gFrontEnd )
				)
				( attribute "VALUE" "1.00K"
					( Origin gFrontEnd )
				)
				( attribute "VER" "2"
					( Origin gFrontEnd )
				)
				( attribute "WATTAGE" "1/16W"
					( Origin gFrontEnd )
				)
				( attribute "XY" "(-375,4400)"
					( Origin gFrontEnd )
				)
				( attribute "CHIPS_PART_NAME" "RES"
					( Origin gPackager )
				)
				( attribute "CDS_PART_NAME" "RES_0402-1.00K,1%,1/16W,EMPTY,A"
					( Origin gPackager )
				)
				( objectStatus "R3N15" )
			)
			( gate "@baseboard_fab2_lib.baseboard_fab2(sch_1):page133_i369"
				( attribute "CDS_LIB" "mstr_discrete"
					( Origin gPackager )
				)
				( attribute "CDS_LOCATION" "R3N16"
					( Origin gPackager )
				)
				( attribute "CDS_SEC" "1"
					( Origin gPackager )
				)
				( attribute "LOCATION" "R3N16"
					( Origin gFrontEnd )
				)
				( attribute "MATERIAL" "EMPTY"
					( Origin gFrontEnd )
				)
				( attribute "PACK_TYPE" "0402"
					( Origin gFrontEnd )
				)
				( attribute "PART_NUMBER" "G21796-026"
					( Origin gFrontEnd )
				)
				( attribute "PHYS_PAGE" "133"
					( Origin gFrontEnd )
				)
				( attribute "ROOM" "DEBUG"
					( Origin gFrontEnd )
				)
				( attribute "ROT" "3"
					( Origin gFrontEnd )
				)
				( attribute "SEC" "1"
					( Origin gFrontEnd )
				)
				( attribute "SEC_TYPE" "0402"
					( Origin gFrontEnd )
				)
				( attribute "TOLERANCE" "1%"
					( Origin gFrontEnd )
				)
				( attribute "VALUE" "1.00K"
					( Origin gFrontEnd )
				)
				( attribute "VER" "2"
					( Origin gFrontEnd )
				)
				( attribute "WATTAGE" "1/16W"
					( Origin gFrontEnd )
				)
				( attribute "XY" "(-375,4175)"
					( Origin gFrontEnd )
				)
				( attribute "CHIPS_PART_NAME" "RES"
					( Origin gPackager )
				)
				( attribute "CDS_PART_NAME" "RES_0402-1.00K,1%,1/16W,EMPTY,A"
					( Origin gPackager )
				)
				( objectStatus "R3N16" )
			)
			( gate "@baseboard_fab2_lib.baseboard_fab2(sch_1):page133_i366"
				( attribute "CDS_LIB" "mstr_discrete"
					( Origin gPackager )
				)
				( attribute "CDS_LOCATION" "R3P5"
					( Origin gPackager )
				)
				( attribute "CDS_SEC" "1"
					( Origin gPackager )
				)
				( attribute "LOCATION" "R3P5"
					( Origin gFrontEnd )
				)
				( attribute "MATERIAL" "EMPTY"
					( Origin gFrontEnd )
				)
				( attribute "PACK_TYPE" "0402"
					( Origin gFrontEnd )
				)
				( attribute "PART_NUMBER" "G21796-026"
					( Origin gFrontEnd )
				)
				( attribute "PHYS_PAGE" "133"
					( Origin gFrontEnd )
				)
				( attribute "ROOM" "DEBUG"
					( Origin gFrontEnd )
				)
				( attribute "ROT" "3"
					( Origin gFrontEnd )
				)
				( attribute "SEC" "1"
					( Origin gFrontEnd )
				)
				( attribute "SEC_TYPE" "0402"
					( Origin gFrontEnd )
				)
				( attribute "TOLERANCE" "1%"
					( Origin gFrontEnd )
				)
				( attribute "VALUE" "1.00K"
					( Origin gFrontEnd )
				)
				( attribute "VER" "2"
					( Origin gFrontEnd )
				)
				( attribute "WATTAGE" "1/16W"
					( Origin gFrontEnd )
				)
				( attribute "XY" "(-400,4875)"
					( Origin gFrontEnd )
				)
				( attribute "CHIPS_PART_NAME" "RES"
					( Origin gPackager )
				)
				( attribute "CDS_PART_NAME" "RES_0402-1.00K,1%,1/16W,EMPTY,A"
					( Origin gPackager )
				)
				( objectStatus "R3P5" )
			)
			( gate "@baseboard_fab2_lib.baseboard_fab2(sch_1):page133_i367"
				( attribute "CDS_LIB" "mstr_discrete"
					( Origin gPackager )
				)
				( attribute "CDS_LOCATION" "R3P6"
					( Origin gPackager )
				)
				( attribute "CDS_SEC" "1"
					( Origin gPackager )
				)
				( attribute "LOCATION" "R3P6"
					( Origin gFrontEnd )
				)
				( attribute "MATERIAL" "EMPTY"
					( Origin gFrontEnd )
				)
				( attribute "PACK_TYPE" "0402"
					( Origin gFrontEnd )
				)
				( attribute "PART_NUMBER" "G21796-026"
					( Origin gFrontEnd )
				)
				( attribute "PHYS_PAGE" "133"
					( Origin gFrontEnd )
				)
				( attribute "ROOM" "DEBUG"
					( Origin gFrontEnd )
				)
				( attribute "ROT" "3"
					( Origin gFrontEnd )
				)
				( attribute "SEC" "1"
					( Origin gFrontEnd )
				)
				( attribute "SEC_TYPE" "0402"
					( Origin gFrontEnd )
				)
				( attribute "TOLERANCE" "1%"
					( Origin gFrontEnd )
				)
				( attribute "VALUE" "1.00K"
					( Origin gFrontEnd )
				)
				( attribute "VER" "2"
					( Origin gFrontEnd )
				)
				( attribute "WATTAGE" "1/16W"
					( Origin gFrontEnd )
				)
				( attribute "XY" "(-375,4650)"
					( Origin gFrontEnd )
				)
				( attribute "CHIPS_PART_NAME" "RES"
					( Origin gPackager )
				)
				( attribute "CDS_PART_NAME" "RES_0402-1.00K,1%,1/16W,EMPTY,A"
					( Origin gPackager )
				)
				( objectStatus "R3P6" )
			)
			( gate "@baseboard_fab2_lib.baseboard_fab2(sch_1):page182_i37"
				( attribute "BOM_COST" "IO_SLOT"
					( Origin gFrontEnd )
				)
				( attribute "CDS_LIB" "mstr_discrete"
					( Origin gPackager )
				)
				( attribute "CDS_LOCATION" "C9N12"
					( Origin gPackager )
				)
				( attribute "CDS_SEC" "1"
					( Origin gPackager )
				)
				( attribute "LOCATION" "C9N12"
					( Origin gFrontEnd )
				)
				( attribute "MATERIAL" "X7R"
					( Origin gFrontEnd )
				)
				( attribute "PACK_TYPE" "0402"
					( Origin gFrontEnd )
				)
				( attribute "PART_NUMBER" "A36096-155"
					( Origin gFrontEnd )
				)
				( attribute "PHYS_PAGE" "182"
					( Origin gFrontEnd )
				)
				( attribute "ROOM" "IO_SLOT"
					( Origin gFrontEnd )
				)
				( attribute "ROT" "0"
					( Origin gFrontEnd )
				)
				( attribute "SEC" "1"
					( Origin gFrontEnd )
				)
				( attribute "SEC_TYPE" "0402"
					( Origin gFrontEnd )
				)
				( attribute "TOLERANCE" "10%"
					( Origin gFrontEnd )
				)
				( attribute "VALUE" "0.22UF"
					( Origin gFrontEnd )
				)
				( attribute "VER" "2"
					( Origin gFrontEnd )
				)
				( attribute "VOLTAGE" "16V"
					( Units "uVoltage" "V" 1.000000)
					( Origin gFrontEnd )
				)
				( attribute "XY" "(-3400,1275)"
					( Origin gFrontEnd )
				)
				( attribute "CHIPS_PART_NAME" "CAP"
					( Origin gPackager )
				)
				( attribute "CDS_PART_NAME" "CAP_0402-0.22UF,16V,10%,X7R,A3A"
					( Origin gPackager )
				)
				( objectStatus "C9N12" )
			)
			( gate "@baseboard_fab2_lib.baseboard_fab2(sch_1):page182_i36"
				( attribute "BOM_COST" "IO_SLOT"
					( Origin gFrontEnd )
				)
				( attribute "CDS_LIB" "mstr_discrete"
					( Origin gPackager )
				)
				( attribute "CDS_LOCATION" "C9N2"
					( Origin gPackager )
				)
				( attribute "CDS_SEC" "1"
					( Origin gPackager )
				)
				( attribute "LOCATION" "C9N2"
					( Origin gFrontEnd )
				)
				( attribute "MATERIAL" "X7R"
					( Origin gFrontEnd )
				)
				( attribute "PACK_TYPE" "0402"
					( Origin gFrontEnd )
				)
				( attribute "PART_NUMBER" "A36096-155"
					( Origin gFrontEnd )
				)
				( attribute "PHYS_PAGE" "182"
					( Origin gFrontEnd )
				)
				( attribute "ROOM" "IO_SLOT"
					( Origin gFrontEnd )
				)
				( attribute "ROT" "0"
					( Origin gFrontEnd )
				)
				( attribute "SEC" "1"
					( Origin gFrontEnd )
				)
				( attribute "SEC_TYPE" "0402"
					( Origin gFrontEnd )
				)
				( attribute "TOLERANCE" "10%"
					( Origin gFrontEnd )
				)
				( attribute "VALUE" "0.22UF"
					( Origin gFrontEnd )
				)
				( attribute "VER" "2"
					( Origin gFrontEnd )
				)
				( attribute "VOLTAGE" "16V"
					( Units "uVoltage" "V" 1.000000)
					( Origin gFrontEnd )
				)
				( attribute "XY" "(-3400,1125)"
					( Origin gFrontEnd )
				)
				( attribute "CHIPS_PART_NAME" "CAP"
					( Origin gPackager )
				)
				( attribute "CDS_PART_NAME" "CAP_0402-0.22UF,16V,10%,X7R,A3A"
					( Origin gPackager )
				)
				( objectStatus "C9N2" )
			)
			( gate "@baseboard_fab2_lib.baseboard_fab2(sch_1):page182_i10"
				( attribute "CDS_LIB" "mstr_discrete"
					( Origin gPackager )
				)
				( attribute "CDS_LOCATION" "R1C11"
					( Origin gPackager )
				)
				( attribute "CDS_SEC" "1"
					( Origin gPackager )
				)
				( attribute "LOCATION" "R1C11"
					( Origin gFrontEnd )
				)
				( attribute "MATERIAL" "EMPTY"
					( Origin gFrontEnd )
				)
				( attribute "NO_XNET_CONNECTION" "1"
					( Origin gFrontEnd )
				)
				( attribute "PACK_TYPE" "0402"
					( Origin gFrontEnd )
				)
				( attribute "PART_NUMBER" "G21497-005"
					( Origin gFrontEnd )
				)
				( attribute "PHYS_PAGE" "182"
					( Origin gFrontEnd )
				)
				( attribute "ROOM" "IO_SLOT"
					( Origin gFrontEnd )
				)
				( attribute "ROT" "0"
					( Origin gFrontEnd )
				)
				( attribute "SEC" "1"
					( Origin gFrontEnd )
				)
				( attribute "SEC_TYPE" "0402"
					( Origin gFrontEnd )
				)
				( attribute "TOLERANCE" "5%"
					( Origin gFrontEnd )
				)
				( attribute "VALUE" "0.0"
					( Origin gFrontEnd )
				)
				( attribute "VER" "1"
					( Origin gFrontEnd )
				)
				( attribute "WATTAGE" "1/16W"
					( Origin gFrontEnd )
				)
				( attribute "XY" "(-7000,350)"
					( Origin gFrontEnd )
				)
				( attribute "CHIPS_PART_NAME" "RES"
					( Origin gPackager )
				)
				( attribute "CDS_PART_NAME" "RES_0402-0.0,5%,1/16W,EMPTY,G2A"
					( Origin gPackager )
				)
				( objectStatus "R1C11" )
			)
			( gate "@baseboard_fab2_lib.baseboard_fab2(sch_1):page182_i9"
				( attribute "CDS_LIB" "mstr_discrete"
					( Origin gPackager )
				)
				( attribute "CDS_LOCATION" "R1C10"
					( Origin gPackager )
				)
				( attribute "CDS_SEC" "1"
					( Origin gPackager )
				)
				( attribute "LOCATION" "R1C10"
					( Origin gFrontEnd )
				)
				( attribute "MATERIAL" "EMPTY"
					( Origin gFrontEnd )
				)
				( attribute "NO_XNET_CONNECTION" "1"
					( Origin gFrontEnd )
				)
				( attribute "PACK_TYPE" "0402"
					( Origin gFrontEnd )
				)
				( attribute "PART_NUMBER" "G21497-005"
					( Origin gFrontEnd )
				)
				( attribute "PHYS_PAGE" "182"
					( Origin gFrontEnd )
				)
				( attribute "ROOM" "IO_SLOT"
					( Origin gFrontEnd )
				)
				( attribute "ROT" "0"
					( Origin gFrontEnd )
				)
				( attribute "SEC" "1"
					( Origin gFrontEnd )
				)
				( attribute "SEC_TYPE" "0402"
					( Origin gFrontEnd )
				)
				( attribute "TOLERANCE" "5%"
					( Origin gFrontEnd )
				)
				( attribute "VALUE" "0.0"
					( Origin gFrontEnd )
				)
				( attribute "VER" "1"
					( Origin gFrontEnd )
				)
				( attribute "WATTAGE" "1/16W"
					( Origin gFrontEnd )
				)
				( attribute "XY" "(-7000,225)"
					( Origin gFrontEnd )
				)
				( attribute "CHIPS_PART_NAME" "RES"
					( Origin gPackager )
				)
				( attribute "CDS_PART_NAME" "RES_0402-0.0,5%,1/16W,EMPTY,G2A"
					( Origin gPackager )
				)
				( objectStatus "R1C10" )
			)
			( gate "@baseboard_fab2_lib.baseboard_fab2(sch_1):page182_i8"
				( attribute "CDS_LIB" "mstr_discrete"
					( Origin gPackager )
				)
				( attribute "CDS_LOCATION" "R1C9"
					( Origin gPackager )
				)
				( attribute "CDS_SEC" "1"
					( Origin gPackager )
				)
				( attribute "LOCATION" "R1C9"
					( Origin gFrontEnd )
				)
				( attribute "MATERIAL" "EMPTY"
					( Origin gFrontEnd )
				)
				( attribute "NO_XNET_CONNECTION" "1"
					( Origin gFrontEnd )
				)
				( attribute "PACK_TYPE" "0402"
					( Origin gFrontEnd )
				)
				( attribute "PART_NUMBER" "G21497-005"
					( Origin gFrontEnd )
				)
				( attribute "PHYS_PAGE" "182"
					( Origin gFrontEnd )
				)
				( attribute "ROOM" "IO_SLOT"
					( Origin gFrontEnd )
				)
				( attribute "ROT" "0"
					( Origin gFrontEnd )
				)
				( attribute "SEC" "1"
					( Origin gFrontEnd )
				)
				( attribute "SEC_TYPE" "0402"
					( Origin gFrontEnd )
				)
				( attribute "TOLERANCE" "5%"
					( Origin gFrontEnd )
				)
				( attribute "VALUE" "0.0"
					( Origin gFrontEnd )
				)
				( attribute "VER" "1"
					( Origin gFrontEnd )
				)
				( attribute "WATTAGE" "1/16W"
					( Origin gFrontEnd )
				)
				( attribute "XY" "(-7000,100)"
					( Origin gFrontEnd )
				)
				( attribute "CHIPS_PART_NAME" "RES"
					( Origin gPackager )
				)
				( attribute "CDS_PART_NAME" "RES_0402-0.0,5%,1/16W,EMPTY,G2A"
					( Origin gPackager )
				)
				( objectStatus "R1C9" )
			)
			( gate "@baseboard_fab2_lib.baseboard_fab2(sch_1):page182_i7"
				( attribute "CDS_LIB" "mstr_discrete"
					( Origin gPackager )
				)
				( attribute "CDS_LOCATION" "R1F9"
					( Origin gPackager )
				)
				( attribute "CDS_SEC" "1"
					( Origin gPackager )
				)
				( attribute "LOCATION" "R1F9"
					( Origin gFrontEnd )
				)
				( attribute "MATERIAL" "EMPTY"
					( Origin gFrontEnd )
				)
				( attribute "NO_XNET_CONNECTION" "1"
					( Origin gFrontEnd )
				)
				( attribute "PACK_TYPE" "0402"
					( Origin gFrontEnd )
				)
				( attribute "PART_NUMBER" "G21497-005"
					( Origin gFrontEnd )
				)
				( attribute "PHYS_PAGE" "182"
					( Origin gFrontEnd )
				)
				( attribute "ROOM" "IO_SLOT"
					( Origin gFrontEnd )
				)
				( attribute "ROT" "0"
					( Origin gFrontEnd )
				)
				( attribute "SEC" "1"
					( Origin gFrontEnd )
				)
				( attribute "SEC_TYPE" "0402"
					( Origin gFrontEnd )
				)
				( attribute "TOLERANCE" "5%"
					( Origin gFrontEnd )
				)
				( attribute "VALUE" "0.0"
					( Origin gFrontEnd )
				)
				( attribute "VER" "1"
					( Origin gFrontEnd )
				)
				( attribute "WATTAGE" "1/16W"
					( Origin gFrontEnd )
				)
				( attribute "XY" "(-7000,-25)"
					( Origin gFrontEnd )
				)
				( attribute "CHIPS_PART_NAME" "RES"
					( Origin gPackager )
				)
				( attribute "CDS_PART_NAME" "RES_0402-0.0,5%,1/16W,EMPTY,G2A"
					( Origin gPackager )
				)
				( objectStatus "R1F9" )
			)
			( gate "@baseboard_fab2_lib.baseboard_fab2(sch_1):page182_i6"
				( attribute "CDS_LIB" "mstr_discrete"
					( Origin gPackager )
				)
				( attribute "CDS_LOCATION" "R1C31"
					( Origin gPackager )
				)
				( attribute "CDS_SEC" "1"
					( Origin gPackager )
				)
				( attribute "LOCATION" "R1C31"
					( Origin gFrontEnd )
				)
				( attribute "MATERIAL" "EMPTY"
					( Origin gFrontEnd )
				)
				( attribute "NO_XNET_CONNECTION" "1"
					( Origin gFrontEnd )
				)
				( attribute "PACK_TYPE" "0402"
					( Origin gFrontEnd )
				)
				( attribute "PART_NUMBER" "G21497-005"
					( Origin gFrontEnd )
				)
				( attribute "PHYS_PAGE" "182"
					( Origin gFrontEnd )
				)
				( attribute "ROOM" "IO_SLOT"
					( Origin gFrontEnd )
				)
				( attribute "ROT" "0"
					( Origin gFrontEnd )
				)
				( attribute "SEC" "1"
					( Origin gFrontEnd )
				)
				( attribute "SEC_TYPE" "0402"
					( Origin gFrontEnd )
				)
				( attribute "TOLERANCE" "5%"
					( Origin gFrontEnd )
				)
				( attribute "VALUE" "0.0"
					( Origin gFrontEnd )
				)
				( attribute "VER" "1"
					( Origin gFrontEnd )
				)
				( attribute "WATTAGE" "1/16W"
					( Origin gFrontEnd )
				)
				( attribute "XY" "(-7000,-175)"
					( Origin gFrontEnd )
				)
				( attribute "CHIPS_PART_NAME" "RES"
					( Origin gPackager )
				)
				( attribute "CDS_PART_NAME" "RES_0402-0.0,5%,1/16W,EMPTY,G2A"
					( Origin gPackager )
				)
				( objectStatus "R1C31" )
			)
			( gate "@baseboard_fab2_lib.baseboard_fab2(sch_1):page181_i243"
				( attribute "CHIPS_PART_NAME" "TTL08"
					( Origin gPackager )
				)
			)
			( gate "@baseboard_fab2_lib.baseboard_fab2(sch_1):page137_i142"
				( attribute "BOM_COST" "SM_MEM"
					( Origin gFrontEnd )
				)
				( attribute "CDS_LIB" "mstr_discrete"
					( Origin gPackager )
				)
				( attribute "CDS_LOCATION" "RN8F1"
					( Origin gPackager )
				)
				( attribute "CDS_SEC" "1"
					( Origin gPackager )
				)
				( attribute "LOCATION" "RN8F1"
					( Origin gFrontEnd )
				)
				( attribute "MATERIAL" "CHIP"
					( Origin gFrontEnd )
				)
				( attribute "PACK_TYPE" "0402"
					( Origin gFrontEnd )
				)
				( attribute "PART_NUMBER" "G21796-072"
					( Origin gFrontEnd )
				)
				( attribute "PHYS_PAGE" "137"
					( Origin gFrontEnd )
				)
				( attribute "ROOM" "BMC_BOOT_SPI"
					( Origin gFrontEnd )
				)
				( attribute "ROT" "2"
					( Origin gFrontEnd )
				)
				( attribute "SEC" "1"
					( Origin gFrontEnd )
				)
				( attribute "SEC_TYPE" "0402"
					( Origin gFrontEnd )
				)
				( attribute "TOLERANCE" "1%"
					( Origin gFrontEnd )
				)
				( attribute "VALUE" "4.75K"
					( Origin gFrontEnd )
				)
				( attribute "VER" "2"
					( Origin gFrontEnd )
				)
				( attribute "WATTAGE" "1/16W"
					( Origin gFrontEnd )
				)
				( attribute "XY" "(-1250,4100)"
					( Origin gFrontEnd )
				)
				( attribute "CHIPS_PART_NAME" "RES"
					( Origin gPackager )
				)
				( attribute "CDS_PART_NAME" "RES_0402-4.75K,1%,1/16W,CHIP,GA"
					( Origin gPackager )
				)
				( objectStatus "RN8F1" )
			)
			( gate "@baseboard_fab2_lib.baseboard_fab2(sch_1):page137_i144"
				( attribute "CDS_LIB" "mstr_discrete"
					( Origin gPackager )
				)
				( attribute "CDS_LOCATION" "R6W2"
					( Origin gPackager )
				)
				( attribute "CDS_SEC" "1"
					( Origin gPackager )
				)
				( attribute "LOCATION" "R6W2"
					( Origin gFrontEnd )
				)
				( attribute "MATERIAL" "CHIP"
					( Origin gFrontEnd )
				)
				( attribute "PACK_TYPE" "0402"
					( Origin gFrontEnd )
				)
				( attribute "PART_NUMBER" "G21796-016"
					( Origin gFrontEnd )
				)
				( attribute "PHYS_PAGE" "137"
					( Origin gFrontEnd )
				)
				( attribute "ROOM" "HOT_SWAP"
					( Origin gFrontEnd )
				)
				( attribute "ROT" "0"
					( Origin gFrontEnd )
				)
				( attribute "SEC" "1"
					( Origin gPackager )
				)
				( attribute "TOLERANCE" "1%"
					( Origin gFrontEnd )
				)
				( attribute "VALUE" "10.0K"
					( Origin gFrontEnd )
				)
				( attribute "VER" "2"
					( Origin gFrontEnd )
				)
				( attribute "WATTAGE" "1/16W"
					( Origin gFrontEnd )
				)
				( attribute "XY" "(-4500,3450)"
					( Origin gFrontEnd )
				)
				( attribute "CHIPS_PART_NAME" "RES"
					( Origin gPackager )
				)
				( attribute "CDS_PART_NAME" "RES_0402-10.0K,1%,1/16W,CHIP,GA"
					( Origin gPackager )
				)
				( objectStatus "R6W2" )
			)
			( gate "@baseboard_fab2_lib.baseboard_fab2(sch_1):page215_i14"
				( attribute "CDS_LIB" "mstr_discrete"
					( Origin gPackager )
				)
				( attribute "CDS_LOCATION" "C7G4"
					( Origin gPackager )
				)
				( attribute "CDS_SEC" "1"
					( Origin gPackager )
				)
				( attribute "LOCATION" "C7G4"
					( Origin gFrontEnd )
				)
				( attribute "MATERIAL" "X7R"
					( Origin gFrontEnd )
				)
				( attribute "NO_XNET_CONNECTION" "1"
					( Origin gFrontEnd )
				)
				( attribute "PACK_TYPE" "0402LF"
					( Origin gFrontEnd )
				)
				( attribute "PART_NUMBER" "A36096-050"
					( Origin gFrontEnd )
				)
				( attribute "PHYS_PAGE" "215"
					( Origin gFrontEnd )
				)
				( attribute "ROOM" "VDDQ_ABC_PWR_VR"
					( Origin gFrontEnd )
				)
				( attribute "ROT" "0"
					( Origin gFrontEnd )
				)
				( attribute "SEC" "1"
					( Origin gFrontEnd )
				)
				( attribute "SEC_TYPE" "0402LF"
					( Origin gFrontEnd )
				)
				( attribute "TOLERANCE" "10%"
					( Origin gFrontEnd )
				)
				( attribute "VALUE" "220PF"
					( Origin gFrontEnd )
				)
				( attribute "VER" "1"
					( Origin gFrontEnd )
				)
				( attribute "VOLTAGE" "50V"
					( Units "uVoltage" "V" 1.000000)
					( Origin gFrontEnd )
				)
				( attribute "XY" "(-300,850)"
					( Origin gFrontEnd )
				)
				( attribute "CHIPS_PART_NAME" "CAP"
					( Origin gPackager )
				)
				( attribute "CDS_PART_NAME" "CAP_0402LF-220PF,50V,10%,X7R,AA"
					( Origin gPackager )
				)
				( objectStatus "C7G4" )
			)
			( gate "@baseboard_fab2_lib.baseboard_fab2(sch_1):page215_i15"
				( attribute "CDS_LIB" "mstr_discrete"
					( Origin gPackager )
				)
				( attribute "CDS_LOCATION" "RF15"
					( Origin gPackager )
				)
				( attribute "CDS_SEC" "1"
					( Origin gPackager )
				)
				( attribute "LOCATION" "RF15"
					( Origin gFrontEnd )
				)
				( attribute "MATERIAL" "CHIP"
					( Origin gFrontEnd )
				)
				( attribute "PACK_TYPE" "0402"
					( Origin gFrontEnd )
				)
				( attribute "PART_NUMBER" "G85996-004"
					( Origin gFrontEnd )
				)
				( attribute "PHYS_PAGE" "215"
					( Origin gFrontEnd )
				)
				( attribute "ROOM" "SB"
					( Origin gFrontEnd )
				)
				( attribute "ROT" "0"
					( Origin gFrontEnd )
				)
				( attribute "SEC" "1"
					( Origin gFrontEnd )
				)
				( attribute "SEC_TYPE" "0402"
					( Origin gFrontEnd )
				)
				( attribute "TOLERANCE" "0.1%"
					( Origin gFrontEnd )
				)
				( attribute "VALUE" "1.0K"
					( Origin gFrontEnd )
				)
				( attribute "VER" "1"
					( Origin gFrontEnd )
				)
				( attribute "WATTAGE" "1/16W"
					( Origin gFrontEnd )
				)
				( attribute "XY" "(-250,2525)"
					( Origin gFrontEnd )
				)
				( attribute "CHIPS_PART_NAME" "RES"
					( Origin gPackager )
				)
				( attribute "CDS_PART_NAME" "RES_0402-1.0K,0.1%,1/16W,CHIP,A"
					( Origin gPackager )
				)
				( attribute "GROUP" "POWER_FAIR"
					( Origin gFrontEnd )
				)
				( attribute "FAIR_SS" "064.9090D.M001"
					( Origin gFrontEnd )
				)
				( objectStatus "RF15" )
			)
			( gate "@baseboard_fab2_lib.baseboard_fab2(sch_1):page215_i16"
				( attribute "CDS_LIB" "w_hdl"
					( Origin gPackager )
				)
				( attribute "CDS_LMAN_SYM_OUTLINE" "-50,25,50,-25"
					( Origin gPackager )
				)
				( attribute "CDS_LOCATION" "CF15"
					( Origin gPackager )
				)
				( attribute "CDS_SEC" "1"
					( Origin gPackager )
				)
				( attribute "LOCATION" "CF15"
					( Origin gFrontEnd )
				)
				( attribute "PACK_TYPE" "SMD-BCG"
					( Origin gFrontEnd )
				)
				( attribute "PART_NUMBER" "78.22034.1FL"
					( Origin gFrontEnd )
				)
				( attribute "PHYS_PAGE" "215"
					( Origin gFrontEnd )
				)
				( attribute "ROT" "1"
					( Origin gFrontEnd )
				)
				( attribute "SEC" "1"
					( Origin gPackager )
				)
				( attribute "VALUE" "SC22P50V2JN-4GP"
					( Origin gFrontEnd )
				)
				( attribute "VER" "1"
					( Origin gFrontEnd )
				)
				( attribute "XY" "(-275,2325)"
					( Origin gFrontEnd )
				)
				( attribute "CHIPS_PART_NAME" "SC22P50V2JN-4GP"
					( Origin gPackager )
				)
				( attribute "CDS_PART_NAME" "SC22P50V2JN-4GP_SMD-BCG-SC22P5A"
					( Origin gPackager )
				)
				( attribute "ATTRIBUTE" "22PF"
					( Origin gFrontEnd )
				)
				( attribute "PACK_SIZE" "0402"
					( Origin gFrontEnd )
				)
				( attribute "RATED" "50V"
					( Origin gFrontEnd )
				)
				( attribute "TOLERANCE" "5%"
					( Origin gFrontEnd )
				)
				( attribute "TYPE" "NPO"
					( Origin gFrontEnd )
				)
				( attribute "GROUP" "POWER_FAIR"
					( Origin gFrontEnd )
				)
				( objectStatus "CF15" )
			)
			( gate "@baseboard_fab2_lib.baseboard_fab2(sch_1):page226_i70"
				( attribute "CDS_LIB" "mstr_discrete"
					( Origin gPackager )
				)
				( attribute "CDS_LOCATION" "R9M6"
					( Origin gPackager )
				)
				( attribute "CDS_SEC" "1"
					( Origin gPackager )
				)
				( attribute "LOCATION" "R9M6"
					( Origin gFrontEnd )
				)
				( attribute "MATERIAL" "EMPTY"
					( Origin gFrontEnd )
				)
				( attribute "PACK_TYPE" "0402"
					( Origin gFrontEnd )
				)
				( attribute "PART_NUMBER" "G21796-047"
					( Origin gFrontEnd )
				)
				( attribute "PHYS_PAGE" "226"
					( Origin gFrontEnd )
				)
				( attribute "ROOM" "VDDQ_GHJ_PWR_VR"
					( Origin gFrontEnd )
				)
				( attribute "ROT" "0"
					( Origin gFrontEnd )
				)
				( attribute "SEC" "1"
					( Origin gFrontEnd )
				)
				( attribute "SEC_TYPE" "0402"
					( Origin gFrontEnd )
				)
				( attribute "TOLERANCE" "1%"
					( Origin gFrontEnd )
				)
				( attribute "VALUE" "49.9"
					( Origin gFrontEnd )
				)
				( attribute "VER" "2"
					( Origin gFrontEnd )
				)
				( attribute "WATTAGE" "1/16W"
					( Origin gFrontEnd )
				)
				( attribute "XY" "(-925,2850)"
					( Origin gFrontEnd )
				)
				( attribute "CHIPS_PART_NAME" "RES"
					( Origin gPackager )
				)
				( attribute "CDS_PART_NAME" "RES_0402-49.9,1%,1/16W,EMPTY,GA"
					( Origin gPackager )
				)
				( objectStatus "R9M6" )
			)
			( gate "@baseboard_fab2_lib.baseboard_fab2(sch_1):page235_i252"
				( attribute "CDS_LIB" "mstr_discrete"
					( Origin gPackager )
				)
				( attribute "LOCATION" "R2L25"
					( Origin gFrontEnd )
				)
				( attribute "MATERIAL" "CHIP"
					( Origin gFrontEnd )
				)
				( attribute "PACK_TYPE" "0402"
					( Origin gFrontEnd )
				)
				( attribute "PART_NUMBER" "G21796-010"
					( Origin gFrontEnd )
				)
				( attribute "PHYS_PAGE" "235"
					( Origin gFrontEnd )
				)
				( attribute "ROOM" "SB"
					( Origin gFrontEnd )
				)
				( attribute "ROT" "0"
					( Origin gFrontEnd )
				)
				( attribute "SEC" "1"
					( Origin gFrontEnd )
				)
				( attribute "SEC_TYPE" "0402"
					( Origin gFrontEnd )
				)
				( attribute "TOLERANCE" "1%"
					( Origin gFrontEnd )
				)
				( attribute "VALUE" "100.0K"
					( Origin gFrontEnd )
				)
				( attribute "VER" "2"
					( Origin gFrontEnd )
				)
				( attribute "WATTAGE" "1/16W"
					( Origin gFrontEnd )
				)
				( attribute "XY" "(-7750,4950)"
					( Origin gFrontEnd )
				)
				( attribute "CHIPS_PART_NAME" "RES"
					( Origin gPackager )
				)
				( attribute "CDS_PART_NAME" "RES_0402-100.0K,1%,1/16W,CHIP,A"
					( Origin gPackager )
				)
				( attribute "CDS_LOCATION" "R2L25"
					( Origin gPackager )
				)
				( attribute "CDS_SEC" "1"
					( Origin gPackager )
				)
				( objectStatus "R2L25" )
			)
			( gate "@baseboard_fab2_lib.baseboard_fab2(sch_1):page215_i22"
				( attribute "CDS_LIB" "mstr_discrete"
					( Origin gPackager )
				)
				( attribute "CDS_LOCATION" "C7G3"
					( Origin gPackager )
				)
				( attribute "CDS_SEC" "1"
					( Origin gPackager )
				)
				( attribute "LOCATION" "C7G3"
					( Origin gFrontEnd )
				)
				( attribute "MATERIAL" "X7R"
					( Origin gFrontEnd )
				)
				( attribute "PACK_TYPE" "0402LF"
					( Origin gFrontEnd )
				)
				( attribute "PART_NUMBER" "A36096-050"
					( Origin gFrontEnd )
				)
				( attribute "PHYS_PAGE" "215"
					( Origin gFrontEnd )
				)
				( attribute "ROOM" "VDDQ_ABC_PWR_VR"
					( Origin gFrontEnd )
				)
				( attribute "ROT" "2"
					( Origin gFrontEnd )
				)
				( attribute "SEC" "1"
					( Origin gFrontEnd )
				)
				( attribute "SEC_TYPE" "0402LF"
					( Origin gFrontEnd )
				)
				( attribute "TOLERANCE" "10%"
					( Origin gFrontEnd )
				)
				( attribute "VALUE" "220PF"
					( Origin gFrontEnd )
				)
				( attribute "VER" "1"
					( Origin gFrontEnd )
				)
				( attribute "VOLTAGE" "50V"
					( Units "uVoltage" "V" 1.000000)
					( Origin gFrontEnd )
				)
				( attribute "XY" "(875,550)"
					( Origin gFrontEnd )
				)
				( attribute "CHIPS_PART_NAME" "CAP"
					( Origin gPackager )
				)
				( attribute "CDS_PART_NAME" "CAP_0402LF-220PF,50V,10%,X7R,AA"
					( Origin gPackager )
				)
				( objectStatus "C7G3" )
			)
			( gate "@baseboard_fab2_lib.baseboard_fab2(sch_1):page218_i73"
				( attribute "CDS_LIB" "mstr_discrete"
					( Origin gPackager )
				)
				( attribute "CDS_LOCATION" "R7A10"
					( Origin gPackager )
				)
				( attribute "CDS_SEC" "1"
					( Origin gPackager )
				)
				( attribute "LOCATION" "R7A10"
					( Origin gFrontEnd )
				)
				( attribute "MATERIAL" "CHIP"
					( Origin gFrontEnd )
				)
				( attribute "PACK_TYPE" "0402"
					( Origin gFrontEnd )
				)
				( attribute "PART_NUMBER" "G21796-317"
					( Origin gFrontEnd )
				)
				( attribute "PHYS_PAGE" "218"
					( Origin gFrontEnd )
				)
				( attribute "ROOM" "VDDQ_ABC_PWR_VR"
					( Origin gFrontEnd )
				)
				( attribute "ROT" "0"
					( Origin gFrontEnd )
				)
				( attribute "SEC" "1"
					( Origin gFrontEnd )
				)
				( attribute "SEC_TYPE" "0402"
					( Origin gFrontEnd )
				)
				( attribute "TOLERANCE" "1.0%"
					( Origin gFrontEnd )
				)
				( attribute "VALUE" "16K"
					( Origin gFrontEnd )
				)
				( attribute "VER" "2"
					( Origin gFrontEnd )
				)
				( attribute "WATTAGE" "1/16W"
					( Origin gFrontEnd )
				)
				( attribute "XY" "(-1075,-150)"
					( Origin gFrontEnd )
				)
				( attribute "CHIPS_PART_NAME" "RES"
					( Origin gPackager )
				)
				( attribute "CDS_PART_NAME" "RES_0402-16K,1.0%,1/16W,CHIP,GA"
					( Origin gPackager )
				)
				( objectStatus "R7A10" )
			)
			( gate "@baseboard_fab2_lib.baseboard_fab2(sch_1):page215_i26"
				( attribute "CDS_LIB" "w_hdl"
					( Origin gPackager )
				)
				( attribute "CDS_LMAN_SYM_OUTLINE" "-50,25,50,-25"
					( Origin gPackager )
				)
				( attribute "CDS_LOCATION" "CF16"
					( Origin gPackager )
				)
				( attribute "CDS_SEC" "1"
					( Origin gPackager )
				)
				( attribute "LOCATION" "CF16"
					( Origin gFrontEnd )
				)
				( attribute "PACK_TYPE" "SMD-BCG"
					( Origin gFrontEnd )
				)
				( attribute "PART_NUMBER" "78.22034.1FL"
					( Origin gFrontEnd )
				)
				( attribute "PHYS_PAGE" "215"
					( Origin gFrontEnd )
				)
				( attribute "ROT" "1"
					( Origin gFrontEnd )
				)
				( attribute "SEC" "1"
					( Origin gPackager )
				)
				( attribute "VALUE" "SC22P50V2JN-4GP"
					( Origin gFrontEnd )
				)
				( attribute "VER" "1"
					( Origin gFrontEnd )
				)
				( attribute "XY" "(625,2450)"
					( Origin gFrontEnd )
				)
				( attribute "CHIPS_PART_NAME" "SC22P50V2JN-4GP"
					( Origin gPackager )
				)
				( attribute "CDS_PART_NAME" "SC22P50V2JN-4GP_SMD-BCG-SC22P5A"
					( Origin gPackager )
				)
				( attribute "ATTRIBUTE" "22PF"
					( Origin gFrontEnd )
				)
				( attribute "PACK_SIZE" "0402"
					( Origin gFrontEnd )
				)
				( attribute "RATED" "50V"
					( Origin gFrontEnd )
				)
				( attribute "TOLERANCE" "5%"
					( Origin gFrontEnd )
				)
				( attribute "TYPE" "NPO"
					( Origin gFrontEnd )
				)
				( attribute "GROUP" "POWER_FAIR"
					( Origin gFrontEnd )
				)
				( attribute "BOM_SS" "NOPOP"
					( Origin gFrontEnd )
				)
				( objectStatus "CF16" )
			)
			( gate "@baseboard_fab2_lib.baseboard_fab2(sch_1):page215_i27"
				( attribute "CDS_LIB" "mstr_discrete"
					( Origin gPackager )
				)
				( attribute "CDS_LOCATION" "RF16"
					( Origin gPackager )
				)
				( attribute "CDS_SEC" "1"
					( Origin gPackager )
				)
				( attribute "LOCATION" "RF16"
					( Origin gFrontEnd )
				)
				( attribute "MATERIAL" "CHIP"
					( Origin gFrontEnd )
				)
				( attribute "PACK_TYPE" "0402"
					( Origin gFrontEnd )
				)
				( attribute "PART_NUMBER" "G85996-004"
					( Origin gFrontEnd )
				)
				( attribute "PHYS_PAGE" "215"
					( Origin gFrontEnd )
				)
				( attribute "ROOM" "SB"
					( Origin gFrontEnd )
				)
				( attribute "ROT" "0"
					( Origin gFrontEnd )
				)
				( attribute "SEC" "1"
					( Origin gFrontEnd )
				)
				( attribute "SEC_TYPE" "0402"
					( Origin gFrontEnd )
				)
				( attribute "TOLERANCE" "0.1%"
					( Origin gFrontEnd )
				)
				( attribute "VALUE" "1.0K"
					( Origin gFrontEnd )
				)
				( attribute "VER" "1"
					( Origin gFrontEnd )
				)
				( attribute "WATTAGE" "1/16W"
					( Origin gFrontEnd )
				)
				( attribute "XY" "(650,2600)"
					( Origin gFrontEnd )
				)
				( attribute "CHIPS_PART_NAME" "RES"
					( Origin gPackager )
				)
				( attribute "CDS_PART_NAME" "RES_0402-1.0K,0.1%,1/16W,CHIP,A"
					( Origin gPackager )
				)
				( attribute "GROUP" "POWER_FAIR"
					( Origin gFrontEnd )
				)
				( attribute "BOM_SS" "NOPOP"
					( Origin gFrontEnd )
				)
				( objectStatus "RF16" )
			)
			( gate "@baseboard_fab2_lib.baseboard_fab2(sch_1):page215_i28"
				( attribute "CDS_LIB" "mstr_discrete"
					( Origin gPackager )
				)
				( attribute "CDS_LOCATION" "R7G24"
					( Origin gPackager )
				)
				( attribute "CDS_SEC" "1"
					( Origin gPackager )
				)
				( attribute "LOCATION" "R7G24"
					( Origin gFrontEnd )
				)
				( attribute "MATERIAL" "CHIP"
					( Origin gFrontEnd )
				)
				( attribute "PACK_TYPE" "0402"
					( Origin gFrontEnd )
				)
				( attribute "PART_NUMBER" "G21796-009"
					( Origin gFrontEnd )
				)
				( attribute "PHYS_PAGE" "215"
					( Origin gFrontEnd )
				)
				( attribute "ROOM" "VDDQ_ABC_PWR_VR"
					( Origin gFrontEnd )
				)
				( attribute "ROT" "0"
					( Origin gFrontEnd )
				)
				( attribute "SEC" "1"
					( Origin gFrontEnd )
				)
				( attribute "SEC_TYPE" "0402"
					( Origin gFrontEnd )
				)
				( attribute "TOLERANCE" "1%"
					( Origin gFrontEnd )
				)
				( attribute "VALUE" "150.0"
					( Origin gFrontEnd )
				)
				( attribute "VER" "1"
					( Origin gFrontEnd )
				)
				( attribute "WATTAGE" "1/16W"
					( Origin gFrontEnd )
				)
				( attribute "XY" "(675,2800)"
					( Origin gFrontEnd )
				)
				( attribute "CHIPS_PART_NAME" "RES"
					( Origin gPackager )
				)
				( attribute "CDS_PART_NAME" "RES_0402-150.0,1%,1/16W,CHIP,GA"
					( Origin gPackager )
				)
				( objectStatus "R7G24" )
			)
			( gate "@baseboard_fab2_lib.baseboard_fab2(sch_1):page215_i29"
				( attribute "BOM_COST" "SM_CONTROLLER"
					( Origin gFrontEnd )
				)
				( attribute "CDS_LIB" "mstr_discrete"
					( Origin gPackager )
				)
				( attribute "CDS_LOCATION" "R7F20"
					( Origin gPackager )
				)
				( attribute "CDS_SEC" "1"
					( Origin gPackager )
				)
				( attribute "LOCATION" "R7F20"
					( Origin gFrontEnd )
				)
				( attribute "MATERIAL" "EMPTY"
					( Origin gFrontEnd )
				)
				( attribute "PACK_TYPE" "0402"
					( Origin gFrontEnd )
				)
				( attribute "PART_NUMBER" "G21796-010"
					( Origin gFrontEnd )
				)
				( attribute "PHYS_PAGE" "215"
					( Origin gFrontEnd )
				)
				( attribute "ROOM" "BMC"
					( Origin gFrontEnd )
				)
				( attribute "ROT" "0"
					( Origin gFrontEnd )
				)
				( attribute "SEC" "1"
					( Origin gFrontEnd )
				)
				( attribute "SEC_TYPE" "0402"
					( Origin gFrontEnd )
				)
				( attribute "TOLERANCE" "1%"
					( Origin gFrontEnd )
				)
				( attribute "VALUE" "100.0K"
					( Origin gFrontEnd )
				)
				( attribute "VER" "2"
					( Origin gFrontEnd )
				)
				( attribute "WATTAGE" "1/16W"
					( Origin gFrontEnd )
				)
				( attribute "XY" "(975,3325)"
					( Origin gFrontEnd )
				)
				( attribute "CHIPS_PART_NAME" "RES"
					( Origin gPackager )
				)
				( attribute "CDS_PART_NAME" "RES_0402-100.0K,1%,1/16W,EMPTYA"
					( Origin gPackager )
				)
				( objectStatus "R7F20" )
			)
			( gate "@baseboard_fab2_lib.baseboard_fab2(sch_1):page215_i33"
				( attribute "CDS_LIB" "mstr_discrete"
					( Origin gPackager )
				)
				( attribute "CDS_LOCATION" "R3T13"
					( Origin gPackager )
				)
				( attribute "CDS_SEC" "1"
					( Origin gPackager )
				)
				( attribute "LOCATION" "R3T13"
					( Origin gFrontEnd )
				)
				( attribute "MATERIAL" "CHIP"
					( Origin gFrontEnd )
				)
				( attribute "PACK_TYPE" "0402"
					( Origin gFrontEnd )
				)
				( attribute "PART_NUMBER" "G21497-005"
					( Origin gFrontEnd )
				)
				( attribute "PHYS_PAGE" "215"
					( Origin gFrontEnd )
				)
				( attribute "ROOM" "VDDQ_ABC_PWR_VR"
					( Origin gFrontEnd )
				)
				( attribute "ROT" "0"
					( Origin gFrontEnd )
				)
				( attribute "SEC" "1"
					( Origin gFrontEnd )
				)
				( attribute "SEC_TYPE" "0402"
					( Origin gFrontEnd )
				)
				( attribute "TOLERANCE" "5%"
					( Origin gFrontEnd )
				)
				( attribute "VALUE" "0.0"
					( Origin gFrontEnd )
				)
				( attribute "VER" "2"
					( Origin gFrontEnd )
				)
				( attribute "WATTAGE" "1/16W"
					( Origin gFrontEnd )
				)
				( attribute "XY" "(1675,3250)"
					( Origin gFrontEnd )
				)
				( attribute "CHIPS_PART_NAME" "RES"
					( Origin gPackager )
				)
				( attribute "CDS_PART_NAME" "RES_0402-0.0,5%,1/16W,CHIP,G21A"
					( Origin gPackager )
				)
				( objectStatus "R3T13" )
			)
			( gate "@baseboard_fab2_lib.baseboard_fab2(sch_1):page215_i34"
				( attribute "CDS_LIB" "dev_discrete"
					( Origin gPackager )
				)
				( attribute "CDS_LOCATION" "C7F17"
					( Origin gPackager )
				)
				( attribute "CDS_SEC" "1"
					( Origin gPackager )
				)
				( attribute "LOCATION" "C7F17"
					( Origin gFrontEnd )
				)
				( attribute "MATERIAL" "X7R"
					( Origin gFrontEnd )
				)
				( attribute "PACK_TYPE" "0402V"
					( Origin gFrontEnd )
				)
				( attribute "PART_NUMBER" "A36096-030"
					( Origin gFrontEnd )
				)
				( attribute "PHYS_PAGE" "215"
					( Origin gFrontEnd )
				)
				( attribute "ROOM" "VDDQ_ABC_PWR_VR"
					( Origin gFrontEnd )
				)
				( attribute "ROT" "0"
					( Origin gFrontEnd )
				)
				( attribute "SEC" "1"
					( Origin gFrontEnd )
				)
				( attribute "SEC_TYPE" "0402V"
					( Origin gFrontEnd )
				)
				( attribute "TOLERANCE" "10%"
					( Origin gFrontEnd )
				)
				( attribute "VALUE" "0.1UF"
					( Origin gFrontEnd )
				)
				( attribute "VER" "1"
					( Origin gFrontEnd )
				)
				( attribute "VOLTAGE" "16V"
					( Units "uVoltage" "V" 1.000000)
					( Origin gFrontEnd )
				)
				( attribute "XY" "(1975,2900)"
					( Origin gFrontEnd )
				)
				( attribute "CHIPS_PART_NAME" "CAP_A"
					( Origin gPackager )
				)
				( attribute "CDS_PART_NAME" "CAP_A_0402V-0.1UF,16V,10%,X7R,A"
					( Origin gPackager )
				)
				( objectStatus "C7F17" )
			)
			( gate "@baseboard_fab2_lib.baseboard_fab2(sch_1):page215_i35"
				( attribute "CDS_LIB" "dev_discrete"
					( Origin gPackager )
				)
				( attribute "CDS_LOCATION" "C7F18"
					( Origin gPackager )
				)
				( attribute "CDS_SEC" "1"
					( Origin gPackager )
				)
				( attribute "LOCATION" "C7F18"
					( Origin gFrontEnd )
				)
				( attribute "MATERIAL" "X6S"
					( Origin gFrontEnd )
				)
				( attribute "PACK_TYPE" "0402V"
					( Origin gFrontEnd )
				)
				( attribute "PART_NUMBER" "D97712-004"
					( Origin gFrontEnd )
				)
				( attribute "PHYS_PAGE" "215"
					( Origin gFrontEnd )
				)
				( attribute "ROOM" "VDDQ_ABC_PWR_VR"
					( Origin gFrontEnd )
				)
				( attribute "ROT" "0"
					( Origin gFrontEnd )
				)
				( attribute "SEC" "1"
					( Origin gFrontEnd )
				)
				( attribute "SEC_TYPE" "0402V"
					( Origin gFrontEnd )
				)
				( attribute "TOLERANCE" "10%"
					( Origin gFrontEnd )
				)
				( attribute "VALUE" "1.0UF"
					( Origin gFrontEnd )
				)
				( attribute "VER" "1"
					( Origin gFrontEnd )
				)
				( attribute "VOLTAGE" "6.3V"
					( Units "uVoltage" "V" 1.000000)
					( Origin gFrontEnd )
				)
				( attribute "XY" "(2375,2900)"
					( Origin gFrontEnd )
				)
				( attribute "CHIPS_PART_NAME" "CAP_A"
					( Origin gPackager )
				)
				( attribute "CDS_PART_NAME" "CAP_A_0402V-1.0UF,6.3V,10%,X6SA"
					( Origin gPackager )
				)
				( objectStatus "C7F18" )
			)
			( gate "@baseboard_fab2_lib.baseboard_fab2(sch_1):page215_i38"
				( attribute "CDS_LIB" "dev_discrete"
					( Origin gPackager )
				)
				( attribute "CDS_LOCATION" "C7F15"
					( Origin gPackager )
				)
				( attribute "CDS_SEC" "1"
					( Origin gPackager )
				)
				( attribute "LOCATION" "C7F15"
					( Origin gFrontEnd )
				)
				( attribute "MATERIAL" "X7R"
					( Origin gFrontEnd )
				)
				( attribute "PACK_TYPE" "0402V"
					( Origin gFrontEnd )
				)
				( attribute "PART_NUMBER" "A36096-030"
					( Origin gFrontEnd )
				)
				( attribute "PHYS_PAGE" "215"
					( Origin gFrontEnd )
				)
				( attribute "ROOM" "VDDQ_ABC_PWR_VR"
					( Origin gFrontEnd )
				)
				( attribute "ROT" "0"
					( Origin gFrontEnd )
				)
				( attribute "SEC" "1"
					( Origin gFrontEnd )
				)
				( attribute "SEC_TYPE" "0402V"
					( Origin gFrontEnd )
				)
				( attribute "TOLERANCE" "10%"
					( Origin gFrontEnd )
				)
				( attribute "VALUE" "0.1UF"
					( Origin gFrontEnd )
				)
				( attribute "VER" "1"
					( Origin gFrontEnd )
				)
				( attribute "VOLTAGE" "16V"
					( Units "uVoltage" "V" 1.000000)
					( Origin gFrontEnd )
				)
				( attribute "XY" "(3150,200)"
					( Origin gFrontEnd )
				)
				( attribute "CHIPS_PART_NAME" "CAP_A"
					( Origin gPackager )
				)
				( attribute "CDS_PART_NAME" "CAP_A_0402V-0.1UF,16V,10%,X7R,A"
					( Origin gPackager )
				)
				( objectStatus "C7F15" )
			)
			( gate "@baseboard_fab2_lib.baseboard_fab2(sch_1):page215_i40"
				( attribute "CDS_LIB" "dev_discrete"
					( Origin gPackager )
				)
				( attribute "CDS_LOCATION" "C7F16"
					( Origin gPackager )
				)
				( attribute "CDS_SEC" "1"
					( Origin gPackager )
				)
				( attribute "LOCATION" "C7F16"
					( Origin gFrontEnd )
				)
				( attribute "MATERIAL" "X6S"
					( Origin gFrontEnd )
				)
				( attribute "PACK_TYPE" "0402V"
					( Origin gFrontEnd )
				)
				( attribute "PART_NUMBER" "D97712-004"
					( Origin gFrontEnd )
				)
				( attribute "PHYS_PAGE" "215"
					( Origin gFrontEnd )
				)
				( attribute "ROOM" "VDDQ_ABC_PWR_VR"
					( Origin gFrontEnd )
				)
				( attribute "ROT" "0"
					( Origin gFrontEnd )
				)
				( attribute "SEC" "1"
					( Origin gFrontEnd )
				)
				( attribute "SEC_TYPE" "0402V"
					( Origin gFrontEnd )
				)
				( attribute "TOLERANCE" "10%"
					( Origin gFrontEnd )
				)
				( attribute "VALUE" "1.0UF"
					( Origin gFrontEnd )
				)
				( attribute "VER" "1"
					( Origin gFrontEnd )
				)
				( attribute "VOLTAGE" "6.3V"
					( Units "uVoltage" "V" 1.000000)
					( Origin gFrontEnd )
				)
				( attribute "XY" "(3550,200)"
					( Origin gFrontEnd )
				)
				( attribute "CHIPS_PART_NAME" "CAP_A"
					( Origin gPackager )
				)
				( attribute "CDS_PART_NAME" "CAP_A_0402V-1.0UF,6.3V,10%,X6SA"
					( Origin gPackager )
				)
				( objectStatus "C7F16" )
			)
			( gate "@baseboard_fab2_lib.baseboard_fab2(sch_1):page215_i41"
				( attribute "CDS_LIB" "mstr_discrete"
					( Origin gPackager )
				)
				( attribute "CDS_LOCATION" "R7G2"
					( Origin gPackager )
				)
				( attribute "CDS_SEC" "1"
					( Origin gPackager )
				)
				( attribute "LOCATION" "R7G2"
					( Origin gFrontEnd )
				)
				( attribute "MATERIAL" "CHIP"
					( Origin gFrontEnd )
				)
				( attribute "PACK_TYPE" "0402"
					( Origin gFrontEnd )
				)
				( attribute "PART_NUMBER" "G21497-005"
					( Origin gFrontEnd )
				)
				( attribute "PHYS_PAGE" "215"
					( Origin gFrontEnd )
				)
				( attribute "ROOM" "VDDQ_ABC_PWR_VR"
					( Origin gFrontEnd )
				)
				( attribute "ROT" "0"
					( Origin gFrontEnd )
				)
				( attribute "SEC" "1"
					( Origin gFrontEnd )
				)
				( attribute "SEC_TYPE" "0402"
					( Origin gFrontEnd )
				)
				( attribute "TOLERANCE" "5%"
					( Origin gFrontEnd )
				)
				( attribute "VALUE" "0.0"
					( Origin gFrontEnd )
				)
				( attribute "VER" "1"
					( Origin gFrontEnd )
				)
				( attribute "WATTAGE" "1/16W"
					( Origin gFrontEnd )
				)
				( attribute "XY" "(3625,1500)"
					( Origin gFrontEnd )
				)
				( attribute "CHIPS_PART_NAME" "RES"
					( Origin gPackager )
				)
				( attribute "CDS_PART_NAME" "RES_0402-0.0,5%,1/16W,CHIP,G21A"
					( Origin gPackager )
				)
				( objectStatus "R7G2" )
			)
			( gate "@baseboard_fab2_lib.baseboard_fab2(sch_1):page215_i44"
				( attribute "CDS_LIB" "mstr_discrete"
					( Origin gPackager )
				)
				( attribute "CDS_LOCATION" "C7F14"
					( Origin gPackager )
				)
				( attribute "CDS_SEC" "1"
					( Origin gPackager )
				)
				( attribute "LOCATION" "C7F14"
					( Origin gFrontEnd )
				)
				( attribute "MATERIAL" "X7R"
					( Origin gFrontEnd )
				)
				( attribute "PACK_TYPE" "0402LF"
					( Origin gFrontEnd )
				)
				( attribute "PART_NUMBER" "A36096-046"
					( Origin gFrontEnd )
				)
				( attribute "PHYS_PAGE" "215"
					( Origin gFrontEnd )
				)
				( attribute "ROOM" "VDDQ_ABC_PWR_VR"
					( Origin gFrontEnd )
				)
				( attribute "ROT" "0"
					( Origin gFrontEnd )
				)
				( attribute "SEC" "1"
					( Origin gFrontEnd )
				)
				( attribute "SEC_TYPE" "0402LF"
					( Origin gFrontEnd )
				)
				( attribute "TOLERANCE" "10%"
					( Origin gFrontEnd )
				)
				( attribute "VALUE" "1000PF"
					( Origin gFrontEnd )
				)
				( attribute "VER" "1"
					( Origin gFrontEnd )
				)
				( attribute "VOLTAGE" "50V"
					( Units "uVoltage" "V" 1.000000)
					( Origin gFrontEnd )
				)
				( attribute "XY" "(3800,1050)"
					( Origin gFrontEnd )
				)
				( attribute "CHIPS_PART_NAME" "CAP"
					( Origin gPackager )
				)
				( attribute "CDS_PART_NAME" "CAP_0402LF-1000PF,50V,10%,X7R,A"
					( Origin gPackager )
				)
				( objectStatus "C7F14" )
			)
			( gate "@baseboard_fab2_lib.baseboard_fab2(sch_1):page215_i45"
				( attribute "BOM_COST" "MEM_NV"
					( Origin gFrontEnd )
				)
				( attribute "CDS_LIB" "mstr_discrete"
					( Origin gPackager )
				)
				( attribute "CDS_LOCATION" "R12W26"
					( Origin gPackager )
				)
				( attribute "CDS_SEC" "1"
					( Origin gPackager )
				)
				( attribute "LOCATION" "R12W26"
					( Origin gFrontEnd )
				)
				( attribute "MATERIAL" "EMPTY"
					( Origin gFrontEnd )
				)
				( attribute "PACK_TYPE" "0402"
					( Origin gFrontEnd )
				)
				( attribute "PART_NUMBER" "G21497-005"
					( Origin gFrontEnd )
				)
				( attribute "PHYS_PAGE" "215"
					( Origin gFrontEnd )
				)
				( attribute "ROOM" "NV_DIMM"
					( Origin gFrontEnd )
				)
				( attribute "ROT" "0"
					( Origin gFrontEnd )
				)
				( attribute "SEC" "1"
					( Origin gFrontEnd )
				)
				( attribute "SEC_TYPE" "0402"
					( Origin gFrontEnd )
				)
				( attribute "TOLERANCE" "5%"
					( Origin gFrontEnd )
				)
				( attribute "VALUE" "0.0"
					( Origin gFrontEnd )
				)
				( attribute "VER" "1"
					( Origin gFrontEnd )
				)
				( attribute "WATTAGE" "1/16W"
					( Origin gFrontEnd )
				)
				( attribute "XY" "(4000,1650)"
					( Origin gFrontEnd )
				)
				( attribute "CHIPS_PART_NAME" "RES"
					( Origin gPackager )
				)
				( attribute "CDS_PART_NAME" "RES_0402-0.0,5%,1/16W,EMPTY,G2A"
					( Origin gPackager )
				)
				( objectStatus "R12W26" )
			)
			( gate "@baseboard_fab2_lib.baseboard_fab2(sch_1):page218_i75"
				( attribute "BOM_COST" "PROC_SIDEBAND"
					( Origin gFrontEnd )
				)
				( attribute "CDS_LIB" "mstr_discrete"
					( Origin gPackager )
				)
				( attribute "CDS_LOCATION" "R12W28"
					( Origin gPackager )
				)
				( attribute "CDS_SEC" "1"
					( Origin gPackager )
				)
				( attribute "LOCATION" "R12W28"
					( Origin gFrontEnd )
				)
				( attribute "MATERIAL" "CHIP"
					( Origin gFrontEnd )
				)
				( attribute "PACK_TYPE" "0402"
					( Origin gFrontEnd )
				)
				( attribute "PART_NUMBER" "G21497-005"
					( Origin gFrontEnd )
				)
				( attribute "PHYS_PAGE" "218"
					( Origin gFrontEnd )
				)
				( attribute "ROOM" "CPU0"
					( Origin gFrontEnd )
				)
				( attribute "ROT" "0"
					( Origin gFrontEnd )
				)
				( attribute "SEC" "1"
					( Origin gFrontEnd )
				)
				( attribute "SEC_TYPE" "0402"
					( Origin gFrontEnd )
				)
				( attribute "TOLERANCE" "5%"
					( Origin gFrontEnd )
				)
				( attribute "VALUE" "0.0"
					( Origin gFrontEnd )
				)
				( attribute "VER" "1"
					( Origin gFrontEnd )
				)
				( attribute "WATTAGE" "1/16W"
					( Origin gFrontEnd )
				)
				( attribute "XY" "(1825,1600)"
					( Origin gFrontEnd )
				)
				( attribute "CHIPS_PART_NAME" "RES"
					( Origin gPackager )
				)
				( attribute "CDS_PART_NAME" "RES_0402-0.0,5%,1/16W,CHIP,G21A"
					( Origin gPackager )
				)
				( objectStatus "R12W28" )
			)
			( gate "@baseboard_fab2_lib.baseboard_fab2(sch_1):page215_i49"
				( attribute "CDS_LIB" "mstr_discrete"
					( Origin gPackager )
				)
				( attribute "CDS_LOCATION" "R7G4"
					( Origin gPackager )
				)
				( attribute "CDS_SEC" "1"
					( Origin gPackager )
				)
				( attribute "LOCATION" "R7G4"
					( Origin gFrontEnd )
				)
				( attribute "MATERIAL" "CHIP"
					( Origin gFrontEnd )
				)
				( attribute "PACK_TYPE" "0402"
					( Origin gFrontEnd )
				)
				( attribute "PART_NUMBER" "G21497-005"
					( Origin gFrontEnd )
				)
				( attribute "PHYS_PAGE" "215"
					( Origin gFrontEnd )
				)
				( attribute "ROOM" "VDDQ_ABC_PWR_VR"
					( Origin gFrontEnd )
				)
				( attribute "ROT" "0"
					( Origin gFrontEnd )
				)
				( attribute "SEC" "1"
					( Origin gFrontEnd )
				)
				( attribute "SEC_TYPE" "0402"
					( Origin gFrontEnd )
				)
				( attribute "TOLERANCE" "5%"
					( Origin gFrontEnd )
				)
				( attribute "VALUE" "0.0"
					( Origin gFrontEnd )
				)
				( attribute "VER" "1"
					( Origin gFrontEnd )
				)
				( attribute "WATTAGE" "1/16W"
					( Origin gFrontEnd )
				)
				( attribute "XY" "(3475,2200)"
					( Origin gFrontEnd )
				)
				( attribute "CHIPS_PART_NAME" "RES"
					( Origin gPackager )
				)
				( attribute "CDS_PART_NAME" "RES_0402-0.0,5%,1/16W,CHIP,G21A"
					( Origin gPackager )
				)
				( objectStatus "R7G4" )
			)
			( gate "@baseboard_fab2_lib.baseboard_fab2(sch_1):page215_i50"
				( attribute "CDS_LIB" "mstr_discrete"
					( Origin gPackager )
				)
				( attribute "CDS_LOCATION" "R7F27"
					( Origin gPackager )
				)
				( attribute "CDS_SEC" "1"
					( Origin gPackager )
				)
				( attribute "LOCATION" "R7F27"
					( Origin gFrontEnd )
				)
				( attribute "MATERIAL" "CHIP"
					( Origin gFrontEnd )
				)
				( attribute "PACK_TYPE" "0402"
					( Origin gFrontEnd )
				)
				( attribute "PART_NUMBER" "G21796-026"
					( Origin gFrontEnd )
				)
				( attribute "PHYS_PAGE" "215"
					( Origin gFrontEnd )
				)
				( attribute "ROOM" "VDDQ_ABC_PWR_VR"
					( Origin gFrontEnd )
				)
				( attribute "ROT" "0"
					( Origin gFrontEnd )
				)
				( attribute "SEC" "1"
					( Origin gFrontEnd )
				)
				( attribute "SEC_TYPE" "0402"
					( Origin gFrontEnd )
				)
				( attribute "TOLERANCE" "1%"
					( Origin gFrontEnd )
				)
				( attribute "VALUE" "1.00K"
					( Origin gFrontEnd )
				)
				( attribute "VER" "2"
					( Origin gFrontEnd )
				)
				( attribute "WATTAGE" "1/16W"
					( Origin gFrontEnd )
				)
				( attribute "XY" "(2950,2900)"
					( Origin gFrontEnd )
				)
				( attribute "CHIPS_PART_NAME" "RES"
					( Origin gPackager )
				)
				( attribute "CDS_PART_NAME" "RES_0402-1.00K,1%,1/16W,CHIP,GA"
					( Origin gPackager )
				)
				( objectStatus "R7F27" )
			)
			( gate "@baseboard_fab2_lib.baseboard_fab2(sch_1):page215_i51"
				( attribute "CDS_LIB" "mstr_discrete"
					( Origin gPackager )
				)
				( attribute "CDS_LOCATION" "R7F22"
					( Origin gPackager )
				)
				( attribute "CDS_SEC" "1"
					( Origin gPackager )
				)
				( attribute "LOCATION" "R7F22"
					( Origin gFrontEnd )
				)
				( attribute "MATERIAL" "CHIP"
					( Origin gFrontEnd )
				)
				( attribute "PACK_TYPE" "0402"
					( Origin gFrontEnd )
				)
				( attribute "PART_NUMBER" "G21796-026"
					( Origin gFrontEnd )
				)
				( attribute "PHYS_PAGE" "215"
					( Origin gFrontEnd )
				)
				( attribute "ROOM" "VDDQ_ABC_PWR_VR"
					( Origin gFrontEnd )
				)
				( attribute "ROT" "0"
					( Origin gFrontEnd )
				)
				( attribute "SEC" "1"
					( Origin gFrontEnd )
				)
				( attribute "SEC_TYPE" "0402"
					( Origin gFrontEnd )
				)
				( attribute "TOLERANCE" "1%"
					( Origin gFrontEnd )
				)
				( attribute "VALUE" "1.00K"
					( Origin gFrontEnd )
				)
				( attribute "VER" "2"
					( Origin gFrontEnd )
				)
				( attribute "WATTAGE" "1/16W"
					( Origin gFrontEnd )
				)
				( attribute "XY" "(3300,2900)"
					( Origin gFrontEnd )
				)
				( attribute "CHIPS_PART_NAME" "RES"
					( Origin gPackager )
				)
				( attribute "CDS_PART_NAME" "RES_0402-1.00K,1%,1/16W,CHIP,GA"
					( Origin gPackager )
				)
				( objectStatus "R7F22" )
			)
			( gate "@baseboard_fab2_lib.baseboard_fab2(sch_1):page215_i53"
				( attribute "CDS_LIB" "mstr_discrete"
					( Origin gPackager )
				)
				( attribute "CDS_LOCATION" "R7F23"
					( Origin gPackager )
				)
				( attribute "CDS_SEC" "1"
					( Origin gPackager )
				)
				( attribute "LOCATION" "R7F23"
					( Origin gFrontEnd )
				)
				( attribute "MATERIAL" "CHIP"
					( Origin gFrontEnd )
				)
				( attribute "PACK_TYPE" "0402"
					( Origin gFrontEnd )
				)
				( attribute "PART_NUMBER" "G21796-074"
					( Origin gFrontEnd )
				)
				( attribute "PHYS_PAGE" "215"
					( Origin gFrontEnd )
				)
				( attribute "ROT" "0"
					( Origin gFrontEnd )
				)
				( attribute "SEC" "1"
					( Origin gFrontEnd )
				)
				( attribute "SEC_TYPE" "0402"
					( Origin gFrontEnd )
				)
				( attribute "TOLERANCE" "1%"
					( Origin gFrontEnd )
				)
				( attribute "VALUE" "33.2"
					( Origin gFrontEnd )
				)
				( attribute "VER" "1"
					( Origin gFrontEnd )
				)
				( attribute "WATTAGE" "1/16W"
					( Origin gFrontEnd )
				)
				( attribute "XY" "(3975,2250)"
					( Origin gFrontEnd )
				)
				( attribute "CHIPS_PART_NAME" "RES"
					( Origin gPackager )
				)
				( attribute "CDS_PART_NAME" "RES_0402-33.2,1%,1/16W,CHIP,G2A"
					( Origin gPackager )
				)
				( objectStatus "R7F23" )
			)
			( gate "@baseboard_fab2_lib.baseboard_fab2(sch_1):page215_i54"
				( attribute "BOM_COST" "MEM_NV"
					( Origin gFrontEnd )
				)
				( attribute "CDS_LIB" "mstr_discrete"
					( Origin gPackager )
				)
				( attribute "CDS_LOCATION" "R12W27"
					( Origin gPackager )
				)
				( attribute "CDS_SEC" "1"
					( Origin gPackager )
				)
				( attribute "LOCATION" "R12W27"
					( Origin gFrontEnd )
				)
				( attribute "MATERIAL" "EMPTY"
					( Origin gFrontEnd )
				)
				( attribute "PACK_TYPE" "0402"
					( Origin gFrontEnd )
				)
				( attribute "PART_NUMBER" "G21497-005"
					( Origin gFrontEnd )
				)
				( attribute "PHYS_PAGE" "215"
					( Origin gFrontEnd )
				)
				( attribute "ROOM" "NV_DIMM"
					( Origin gFrontEnd )
				)
				( attribute "ROT" "0"
					( Origin gFrontEnd )
				)
				( attribute "SEC" "1"
					( Origin gFrontEnd )
				)
				( attribute "SEC_TYPE" "0402"
					( Origin gFrontEnd )
				)
				( attribute "TOLERANCE" "5%"
					( Origin gFrontEnd )
				)
				( attribute "VALUE" "0.0"
					( Origin gFrontEnd )
				)
				( attribute "VER" "1"
					( Origin gFrontEnd )
				)
				( attribute "WATTAGE" "1/16W"
					( Origin gFrontEnd )
				)
				( attribute "XY" "(4000,2050)"
					( Origin gFrontEnd )
				)
				( attribute "CHIPS_PART_NAME" "RES"
					( Origin gPackager )
				)
				( attribute "CDS_PART_NAME" "RES_0402-0.0,5%,1/16W,EMPTY,G2A"
					( Origin gPackager )
				)
				( objectStatus "R12W27" )
			)
			( gate "@baseboard_fab2_lib.baseboard_fab2(sch_1):page215_i56"
				( attribute "CDS_LIB" "mstr_discrete"
					( Origin gPackager )
				)
				( attribute "CDS_LOCATION" "R7F24"
					( Origin gPackager )
				)
				( attribute "CDS_SEC" "1"
					( Origin gPackager )
				)
				( attribute "LOCATION" "R7F24"
					( Origin gFrontEnd )
				)
				( attribute "MATERIAL" "CHIP"
					( Origin gFrontEnd )
				)
				( attribute "PACK_TYPE" "0402"
					( Origin gFrontEnd )
				)
				( attribute "PART_NUMBER" "G21796-250"
					( Origin gFrontEnd )
				)
				( attribute "PHYS_PAGE" "215"
					( Origin gFrontEnd )
				)
				( attribute "ROOM" "VDDQ_ABC_PWR_VR"
					( Origin gFrontEnd )
				)
				( attribute "ROT" "0"
					( Origin gFrontEnd )
				)
				( attribute "SEC" "1"
					( Origin gFrontEnd )
				)
				( attribute "SEC_TYPE" "0402"
					( Origin gFrontEnd )
				)
				( attribute "TOLERANCE" "1.0%"
					( Origin gFrontEnd )
				)
				( attribute "VALUE" "22.1"
					( Origin gFrontEnd )
				)
				( attribute "VER" "1"
					( Origin gFrontEnd )
				)
				( attribute "WATTAGE" "1/16W"
					( Origin gFrontEnd )
				)
				( attribute "XY" "(4050,2350)"
					( Origin gFrontEnd )
				)
				( attribute "CHIPS_PART_NAME" "RES"
					( Origin gPackager )
				)
				( attribute "CDS_PART_NAME" "RES_0402-22.1,1.0%,1/16W,CHIP,A"
					( Origin gPackager )
				)
				( attribute "POP" "NOPOP"
					( Origin gFrontEnd )
				)
				( objectStatus "R7F24" )
			)
			( gate "@baseboard_fab2_lib.baseboard_fab2(sch_1):page218_i76"
				( attribute "BOM_COST" "SM_CONTROLLER"
					( Origin gFrontEnd )
				)
				( attribute "CDS_LIB" "mstr_discrete"
					( Origin gPackager )
				)
				( attribute "CDS_LOCATION" "R7A9"
					( Origin gPackager )
				)
				( attribute "CDS_SEC" "1"
					( Origin gPackager )
				)
				( attribute "LOCATION" "R7A9"
					( Origin gFrontEnd )
				)
				( attribute "MATERIAL" "CHIP"
					( Origin gFrontEnd )
				)
				( attribute "PACK_TYPE" "0402"
					( Origin gFrontEnd )
				)
				( attribute "PART_NUMBER" "G21796-311"
					( Origin gFrontEnd )
				)
				( attribute "PHYS_PAGE" "218"
					( Origin gFrontEnd )
				)
				( attribute "ROOM" "SMBUS"
					( Origin gFrontEnd )
				)
				( attribute "ROT" "0"
					( Origin gFrontEnd )
				)
				( attribute "SEC" "1"
					( Origin gFrontEnd )
				)
				( attribute "SEC_TYPE" "0402"
					( Origin gFrontEnd )
				)
				( attribute "SKU" "B"
					( Origin gFrontEnd )
				)
				( attribute "TOLERANCE" "1.0%"
					( Origin gFrontEnd )
				)
				( attribute "VALUE" "2.26K"
					( Origin gFrontEnd )
				)
				( attribute "VER" "2"
					( Origin gFrontEnd )
				)
				( attribute "WATTAGE" "1/16W"
					( Origin gFrontEnd )
				)
				( attribute "XY" "(2150,2800)"
					( Origin gFrontEnd )
				)
				( attribute "CHIPS_PART_NAME" "RES"
					( Origin gPackager )
				)
				( attribute "CDS_PART_NAME" "RES_0402-2.26K,1.0%,1/16W,CHIPA"
					( Origin gPackager )
				)
				( objectStatus "R7A9" )
			)
			( gate "@baseboard_fab2_lib.baseboard_fab2(sch_1):page215_i58"
				( attribute "CDS_LIB" "mstr_discrete"
					( Origin gPackager )
				)
				( attribute "CDS_LOCATION" "R3U2"
					( Origin gPackager )
				)
				( attribute "CDS_SEC" "1"
					( Origin gPackager )
				)
				( attribute "LOCATION" "R3U2"
					( Origin gFrontEnd )
				)
				( attribute "MATERIAL" "CHIP"
					( Origin gFrontEnd )
				)
				( attribute "PACK_TYPE" "0402"
					( Origin gFrontEnd )
				)
				( attribute "PART_NUMBER" "G21796-017"
					( Origin gFrontEnd )
				)
				( attribute "PHYS_PAGE" "215"
					( Origin gFrontEnd )
				)
				( attribute "ROOM" "VDDQ_ABC_PWR_VR"
					( Origin gFrontEnd )
				)
				( attribute "ROT" "0"
					( Origin gFrontEnd )
				)
				( attribute "SEC" "1"
					( Origin gFrontEnd )
				)
				( attribute "SEC_TYPE" "0402"
					( Origin gFrontEnd )
				)
				( attribute "TOLERANCE" "1%"
					( Origin gFrontEnd )
				)
				( attribute "VALUE" "100.0"
					( Origin gFrontEnd )
				)
				( attribute "VER" "2"
					( Origin gFrontEnd )
				)
				( attribute "WATTAGE" "1/16W"
					( Origin gFrontEnd )
				)
				( attribute "XY" "(4750,2650)"
					( Origin gFrontEnd )
				)
				( attribute "CHIPS_PART_NAME" "RES"
					( Origin gPackager )
				)
				( attribute "CDS_PART_NAME" "RES_0402-100.0,1%,1/16W,CHIP,GA"
					( Origin gPackager )
				)
				( objectStatus "R3U2" )
			)
			( gate "@baseboard_fab2_lib.baseboard_fab2(sch_1):page215_i69"
				( attribute "CDS_LIB" "mstr_controller"
					( Origin gPackager )
				)
				( attribute "CDS_LMAN_SYM_OUTLINE" "-400,900,400,-900"
					( Origin gPackager )
				)
				( attribute "CDS_LOCATION" "EU7G1"
					( Origin gPackager )
				)
				( attribute "CDS_SEC" "1"
					( Origin gPackager )
				)
				( attribute "LOCATION" "EU7G1"
					( Origin gFrontEnd )
				)
				( attribute "MATERIAL" "IC"
					( Origin gFrontEnd )
				)
				( attribute "PACK_TYPE" "QFN"
					( Origin gFrontEnd )
				)
				( attribute "PART_NUMBER" "H89186-001"
					( Origin gFrontEnd )
				)
				( attribute "PHYS_PAGE" "215"
					( Origin gFrontEnd )
				)
				( attribute "ROT" "0"
					( Origin gFrontEnd )
				)
				( attribute "SEC" "1"
					( Origin gPackager )
				)
				( attribute "VER" "2"
					( Origin gFrontEnd )
				)
				( attribute "XY" "(2275,1600)"
					( Origin gFrontEnd )
				)
				( attribute "CHIPS_PART_NAME" "PXM1310B"
					( Origin gPackager )
				)
				( attribute "CDS_PART_NAME" "PXM1310B_QFN-IC,H89186-001"
					( Origin gPackager )
				)
				( objectStatus "EU7G1" )
			)
			( gate "@baseboard_fab2_lib.baseboard_fab2(sch_1):page197_i37"
				( attribute "BOM_COST" "PROC_SOCKET"
					( Origin gFrontEnd )
				)
				( attribute "CDS_LIB" "mstr_discrete"
					( Origin gPackager )
				)
				( attribute "CDS_LOCATION" "R12W19"
					( Origin gPackager )
				)
				( attribute "CDS_SEC" "1"
					( Origin gPackager )
				)
				( attribute "LOCATION" "R12W19"
					( Origin gFrontEnd )
				)
				( attribute "MATERIAL" "CHIP"
					( Origin gFrontEnd )
				)
				( attribute "PACK_TYPE" "0603"
					( Origin gFrontEnd )
				)
				( attribute "PART_NUMBER" "G22026-050"
					( Origin gFrontEnd )
				)
				( attribute "PHYS_PAGE" "197"
					( Origin gFrontEnd )
				)
				( attribute "ROOM" "CPU0"
					( Origin gFrontEnd )
				)
				( attribute "ROT" "0"
					( Origin gFrontEnd )
				)
				( attribute "SEC" "1"
					( Origin gFrontEnd )
				)
				( attribute "SEC_TYPE" "0603"
					( Origin gFrontEnd )
				)
				( attribute "TOLERANCE" "1%"
					( Origin gFrontEnd )
				)
				( attribute "VALUE" "100.0K"
					( Origin gFrontEnd )
				)
				( attribute "VER" "2"
					( Origin gFrontEnd )
				)
				( attribute "WATTAGE" "1/10W"
					( Origin gFrontEnd )
				)
				( attribute "XY" "(-175,2400)"
					( Origin gFrontEnd )
				)
				( attribute "CHIPS_PART_NAME" "RES"
					( Origin gPackager )
				)
				( attribute "CDS_PART_NAME" "RES_0603-100.0K,1%,1/10W,CHIP,A"
					( Origin gPackager )
				)
				( objectStatus "R12W19" )
			)
			( gate "@baseboard_fab2_lib.baseboard_fab2(sch_1):page197_i42"
				( attribute "BOM_COST" "SM_HM"
					( Origin gFrontEnd )
				)
				( attribute "CDS_LIB" "mstr_discrete"
					( Origin gPackager )
				)
				( attribute "CDS_LOCATION" "C12W3"
					( Origin gPackager )
				)
				( attribute "CDS_SEC" "1"
					( Origin gPackager )
				)
				( attribute "LOCATION" "C12W3"
					( Origin gFrontEnd )
				)
				( attribute "MATERIAL" "COG"
					( Origin gFrontEnd )
				)
				( attribute "PACK_TYPE" "0402LF"
					( Origin gFrontEnd )
				)
				( attribute "PART_NUMBER" "A36095-025"
					( Origin gFrontEnd )
				)
				( attribute "PHYS_PAGE" "197"
					( Origin gFrontEnd )
				)
				( attribute "ROOM" "BMC_VOLT_MONITOR"
					( Origin gFrontEnd )
				)
				( attribute "ROT" "1"
					( Origin gFrontEnd )
				)
				( attribute "SEC" "1"
					( Origin gFrontEnd )
				)
				( attribute "SEC_TYPE" "0402LF"
					( Origin gFrontEnd )
				)
				( attribute "TOLERANCE" "5%"
					( Origin gFrontEnd )
				)
				( attribute "VALUE" "47.0PF"
					( Origin gFrontEnd )
				)
				( attribute "VER" "1"
					( Origin gFrontEnd )
				)
				( attribute "VOLTAGE" "50V"
					( Units "uVoltage" "V" 1.000000)
					( Origin gFrontEnd )
				)
				( attribute "XY" "(-1725,3550)"
					( Origin gFrontEnd )
				)
				( attribute "CHIPS_PART_NAME" "CAP"
					( Origin gPackager )
				)
				( attribute "CDS_PART_NAME" "CAP_0402LF-47.0PF,50V,5%,COG,AA"
					( Origin gPackager )
				)
				( objectStatus "C12W3" )
			)
			( gate "@baseboard_fab2_lib.baseboard_fab2(sch_1):page197_i43"
				( attribute "CDS_LIB" "w_hdl"
					( Origin gPackager )
				)
				( attribute "CDS_LMAN_SYM_OUTLINE" "-125,250,125,-250"
					( Origin gPackager )
				)
				( attribute "CDS_LOCATION" "Q12W1"
					( Origin gPackager )
				)
				( attribute "CDS_SEC" "1"
					( Origin gPackager )
				)
				( attribute "LOCATION" "Q12W1"
					( Origin gFrontEnd )
				)
				( attribute "PACK_TYPE" "DISCRET-GB1"
					( Origin gFrontEnd )
				)
				( attribute "PART_NUMBER" "075.00308.007C"
					( Origin gFrontEnd )
				)
				( attribute "PHYS_PAGE" "197"
					( Origin gFrontEnd )
				)
				( attribute "ROT" "0"
					( Origin gFrontEnd )
				)
				( attribute "SEC" "1"
					( Origin gFrontEnd )
				)
				( attribute "SEC_TYPE" "DISCRET-GB1"
					( Origin gFrontEnd )
				)
				( attribute "VALUE" "BSL308C-H6327-GP"
					( Origin gFrontEnd )
				)
				( attribute "VER" "1"
					( Origin gFrontEnd )
				)
				( attribute "XY" "(-3250,4100)"
					( Origin gFrontEnd )
				)
				( attribute "CHIPS_PART_NAME" "BSL308C-H6327-GP"
					( Origin gPackager )
				)
				( attribute "CDS_PART_NAME" "BSL308C-H6327-GP_DISCRET-GB1-BA"
					( Origin gPackager )
				)
				( objectStatus "Q12W1" )
			)
			( gate "@baseboard_fab2_lib.baseboard_fab2(sch_1):page197_i45"
				( attribute "BOM_COST" "PROC_SOCKET"
					( Origin gFrontEnd )
				)
				( attribute "CDS_LIB" "mstr_discrete"
					( Origin gPackager )
				)
				( attribute "CDS_LOCATION" "R12W4"
					( Origin gPackager )
				)
				( attribute "CDS_SEC" "1"
					( Origin gPackager )
				)
				( attribute "LOCATION" "R12W4"
					( Origin gFrontEnd )
				)
				( attribute "MATERIAL" "CHIP"
					( Origin gFrontEnd )
				)
				( attribute "PACK_TYPE" "0603"
					( Origin gFrontEnd )
				)
				( attribute "PART_NUMBER" "G22026-050"
					( Origin gFrontEnd )
				)
				( attribute "PHYS_PAGE" "197"
					( Origin gFrontEnd )
				)
				( attribute "ROOM" "CPU0"
					( Origin gFrontEnd )
				)
				( attribute "ROT" "0"
					( Origin gFrontEnd )
				)
				( attribute "SEC" "1"
					( Origin gFrontEnd )
				)
				( attribute "SEC_TYPE" "0603"
					( Origin gFrontEnd )
				)
				( attribute "TOLERANCE" "1%"
					( Origin gFrontEnd )
				)
				( attribute "VALUE" "100.0K"
					( Origin gFrontEnd )
				)
				( attribute "VER" "2"
					( Origin gFrontEnd )
				)
				( attribute "WATTAGE" "1/10W"
					( Origin gFrontEnd )
				)
				( attribute "XY" "(-2725,4500)"
					( Origin gFrontEnd )
				)
				( attribute "CHIPS_PART_NAME" "RES"
					( Origin gPackager )
				)
				( attribute "CDS_PART_NAME" "RES_0603-100.0K,1%,1/10W,CHIP,A"
					( Origin gPackager )
				)
				( objectStatus "R12W4" )
			)
			( gate "@baseboard_fab2_lib.baseboard_fab2(sch_1):page197_i113"
				( attribute "ATTRIBUTE" "4.02OHM"
					( Origin gFrontEnd )
				)
				( attribute "CDS_LIB" "w_hdl"
					( Origin gPackager )
				)
				( attribute "CDS_LMAN_SYM_OUTLINE" "-50,75,50,-75"
					( Origin gPackager )
				)
				( attribute "LOCATION" "R12W8"
					( Origin gFrontEnd )
				)
				( attribute "PACK_TYPE" "SMD-RG2"
					( Origin gFrontEnd )
				)
				( attribute "PART_NUMBER" "64.4R025.6DL"
					( Origin gFrontEnd )
				)
				( attribute "PHYS_PAGE" "197"
					( Origin gFrontEnd )
				)
				( attribute "RATED" "1/16W"
					( Origin gFrontEnd )
				)
				( attribute "ROT" "1"
					( Origin gFrontEnd )
				)
				( attribute "SEC" "1"
					( Origin gFrontEnd )
				)
				( attribute "SEC_TYPE" "SMD-RG2"
					( Origin gFrontEnd )
				)
				( attribute "TOLERANCE" "1%"
					( Origin gFrontEnd )
				)
				( attribute "VALUE" "4D02R2F-GP"
					( Origin gFrontEnd )
				)
				( attribute "VER" "1"
					( Origin gFrontEnd )
				)
				( attribute "XY" "(-4250,2450)"
					( Origin gFrontEnd )
				)
				( attribute "CHIPS_PART_NAME" "4D02R2F-GP"
					( Origin gPackager )
				)
				( attribute "CDS_PART_NAME" "4D02R2F-GP_SMD-RG2-4D02R2F-GP,A"
					( Origin gPackager )
				)
				( attribute "PACK_SIZE" "0402"
					( Origin gFrontEnd )
				)
				( attribute "CDS_LOCATION" "R12W8"
					( Origin gPackager )
				)
				( attribute "CDS_SEC" "1"
					( Origin gPackager )
				)
				( objectStatus "R12W8" )
			)
			( gate "@baseboard_fab2_lib.baseboard_fab2(sch_1):page101_i147"
				( attribute "BOM_COST" "SYS_CLOCK"
					( Origin gFrontEnd )
				)
				( attribute "CDS_LIB" "mstr_discrete"
					( Origin gPackager )
				)
				( attribute "CDS_LOCATION" "C8F18"
					( Origin gPackager )
				)
				( attribute "CDS_SEC" "1"
					( Origin gPackager )
				)
				( attribute "LOCATION" "C8F18"
					( Origin gFrontEnd )
				)
				( attribute "MATERIAL" "COG"
					( Origin gFrontEnd )
				)
				( attribute "PACK_TYPE" "0402LF"
					( Origin gFrontEnd )
				)
				( attribute "PART_NUMBER" "A36095-047"
					( Origin gFrontEnd )
				)
				( attribute "PHYS_PAGE" "101"
					( Origin gFrontEnd )
				)
				( attribute "ROOM" "SB"
					( Origin gFrontEnd )
				)
				( attribute "ROT" "0"
					( Origin gFrontEnd )
				)
				( attribute "SEC" "1"
					( Origin gFrontEnd )
				)
				( attribute "SEC_TYPE" "0402LF"
					( Origin gFrontEnd )
				)
				( attribute "TOLERANCE" "5%"
					( Origin gFrontEnd )
				)
				( attribute "VALUE" "15.0PF"
					( Origin gFrontEnd )
				)
				( attribute "VER" "1"
					( Origin gFrontEnd )
				)
				( attribute "VOLTAGE" "50V"
					( Units "uVoltage" "V" 1.000000)
					( Origin gFrontEnd )
				)
				( attribute "XY" "(-7150,800)"
					( Origin gFrontEnd )
				)
				( attribute "CHIPS_PART_NAME" "CAP"
					( Origin gPackager )
				)
				( attribute "CDS_PART_NAME" "CAP_0402LF-15.0PF,50V,5%,COG,AA"
					( Origin gPackager )
				)
				( objectStatus "C8F18" )
			)
			( gate "@baseboard_fab2_lib.baseboard_fab2(sch_1):page197_i50"
				( attribute "BOM_COST" "PVDDQ_ABC_VR"
					( Origin gFrontEnd )
				)
				( attribute "CDS_LIB" "mstr_discrete"
					( Origin gPackager )
				)
				( attribute "CDS_LOCATION" "R1F3"
					( Origin gPackager )
				)
				( attribute "CDS_SEC" "1"
					( Origin gPackager )
				)
				( attribute "LOCATION" "R1F3"
					( Origin gFrontEnd )
				)
				( attribute "MATERIAL" "CHIP"
					( Origin gFrontEnd )
				)
				( attribute "PACK_TYPE" "1206"
					( Origin gFrontEnd )
				)
				( attribute "PART_NUMBER" "G52199-004"
					( Origin gFrontEnd )
				)
				( attribute "PHYS_PAGE" "197"
					( Origin gFrontEnd )
				)
				( attribute "ROOM" "PVDDQ_ABC_PWR_VR"
					( Origin gFrontEnd )
				)
				( attribute "ROT" "0"
					( Origin gFrontEnd )
				)
				( attribute "SEC" "1"
					( Origin gFrontEnd )
				)
				( attribute "SEC_TYPE" "1206"
					( Origin gFrontEnd )
				)
				( attribute "TOLERANCE" "1%"
					( Origin gFrontEnd )
				)
				( attribute "VALUE" "0.002"
					( Origin gFrontEnd )
				)
				( attribute "VER" "1"
					( Origin gFrontEnd )
				)
				( attribute "WATTAGE" "1W"
					( Origin gFrontEnd )
				)
				( attribute "XY" "(-1725,4800)"
					( Origin gFrontEnd )
				)
				( attribute "CHIPS_PART_NAME" "RES"
					( Origin gPackager )
				)
				( attribute "CDS_PART_NAME" "RES_1206-0.002,1%,1W,CHIP,G521A"
					( Origin gPackager )
				)
				( attribute "CONFIG" "064.R0045.0711"
					( Origin gFrontEnd )
				)
				( attribute "NEW_VALUE" "0.004 OHM"
					( Origin gFrontEnd )
				)
				( objectStatus "R1F3" )
			)
			( gate "@baseboard_fab2_lib.baseboard_fab2(sch_1):page197_i53"
				( attribute "BOM_COST" "PROC_SOCKET"
					( Origin gFrontEnd )
				)
				( attribute "CDS_LIB" "mstr_discrete"
					( Origin gPackager )
				)
				( attribute "CDS_LOCATION" "R12W14"
					( Origin gPackager )
				)
				( attribute "CDS_SEC" "1"
					( Origin gPackager )
				)
				( attribute "LOCATION" "R12W14"
					( Origin gFrontEnd )
				)
				( attribute "MATERIAL" "CHIP"
					( Origin gFrontEnd )
				)
				( attribute "PACK_TYPE" "0603"
					( Origin gFrontEnd )
				)
				( attribute "PART_NUMBER" "G22026-050"
					( Origin gFrontEnd )
				)
				( attribute "PHYS_PAGE" "197"
					( Origin gFrontEnd )
				)
				( attribute "ROOM" "CPU0"
					( Origin gFrontEnd )
				)
				( attribute "ROT" "0"
					( Origin gFrontEnd )
				)
				( attribute "SEC" "1"
					( Origin gFrontEnd )
				)
				( attribute "SEC_TYPE" "0603"
					( Origin gFrontEnd )
				)
				( attribute "TOLERANCE" "1%"
					( Origin gFrontEnd )
				)
				( attribute "VALUE" "100.0K"
					( Origin gFrontEnd )
				)
				( attribute "VER" "2"
					( Origin gFrontEnd )
				)
				( attribute "WATTAGE" "1/10W"
					( Origin gFrontEnd )
				)
				( attribute "XY" "(-175,4500)"
					( Origin gFrontEnd )
				)
				( attribute "CHIPS_PART_NAME" "RES"
					( Origin gPackager )
				)
				( attribute "CDS_PART_NAME" "RES_0603-100.0K,1%,1/10W,CHIP,A"
					( Origin gPackager )
				)
				( objectStatus "R12W14" )
			)
			( gate "@baseboard_fab2_lib.baseboard_fab2(sch_1):page197_i56"
				( attribute "CDS_LIB" "mstr_discrete"
					( Origin gPackager )
				)
				( attribute "CDS_LOCATION" "C9T8"
					( Origin gPackager )
				)
				( attribute "CDS_SEC" "1"
					( Origin gPackager )
				)
				( attribute "LOCATION" "C9T8"
					( Origin gFrontEnd )
				)
				( attribute "MATERIAL" "X7R"
					( Origin gFrontEnd )
				)
				( attribute "PACK_TYPE" "0805"
					( Origin gFrontEnd )
				)
				( attribute "PART_NUMBER" "G10601-001"
					( Origin gFrontEnd )
				)
				( attribute "PHYS_PAGE" "197"
					( Origin gFrontEnd )
				)
				( attribute "ROOM" "PVDDQ_GHJ_PWR_VR"
					( Origin gFrontEnd )
				)
				( attribute "ROT" "0"
					( Origin gFrontEnd )
				)
				( attribute "SEC" "1"
					( Origin gPackager )
				)
				( attribute "TOLERANCE" "10%"
					( Origin gFrontEnd )
				)
				( attribute "VALUE" "10UF"
					( Origin gFrontEnd )
				)
				( attribute "VER" "1"
					( Origin gFrontEnd )
				)
				( attribute "VOLTAGE" "16V"
					( Units "uVoltage" "V" 1.000000)
					( Origin gFrontEnd )
				)
				( attribute "XY" "(1325,1275)"
					( Origin gFrontEnd )
				)
				( attribute "CHIPS_PART_NAME" "CAP"
					( Origin gPackager )
				)
				( attribute "CDS_PART_NAME" "CAP_0805-10UF,16V,10%,X7R,G106A"
					( Origin gPackager )
				)
				( objectStatus "C9T8" )
			)
			( gate "@baseboard_fab2_lib.baseboard_fab2(sch_1):page197_i60"
				( attribute "CDS_LIB" "mstr_discrete"
					( Origin gPackager )
				)
				( attribute "CDS_LOCATION" "C1A4"
					( Origin gPackager )
				)
				( attribute "CDS_SEC" "1"
					( Origin gPackager )
				)
				( attribute "LOCATION" "C1A4"
					( Origin gFrontEnd )
				)
				( attribute "MATERIAL" "X7R"
					( Origin gFrontEnd )
				)
				( attribute "PACK_TYPE" "0805"
					( Origin gFrontEnd )
				)
				( attribute "PART_NUMBER" "G10601-001"
					( Origin gFrontEnd )
				)
				( attribute "PHYS_PAGE" "197"
					( Origin gFrontEnd )
				)
				( attribute "ROOM" "PVDDQ_KLM_PWR_VR"
					( Origin gFrontEnd )
				)
				( attribute "ROT" "0"
					( Origin gFrontEnd )
				)
				( attribute "SEC" "1"
					( Origin gPackager )
				)
				( attribute "TOLERANCE" "10%"
					( Origin gFrontEnd )
				)
				( attribute "VALUE" "10UF"
					( Origin gFrontEnd )
				)
				( attribute "VER" "1"
					( Origin gFrontEnd )
				)
				( attribute "VOLTAGE" "16V"
					( Units "uVoltage" "V" 1.000000)
					( Origin gFrontEnd )
				)
				( attribute "XY" "(2175,1275)"
					( Origin gFrontEnd )
				)
				( attribute "CHIPS_PART_NAME" "CAP"
					( Origin gPackager )
				)
				( attribute "CDS_PART_NAME" "CAP_0805-10UF,16V,10%,X7R,G106A"
					( Origin gPackager )
				)
				( objectStatus "C1A4" )
			)
			( gate "@baseboard_fab2_lib.baseboard_fab2(sch_1):page197_i63"
				( attribute "CDS_LIB" "mstr_discrete"
					( Origin gPackager )
				)
				( attribute "CDS_LOCATION" "C9U11"
					( Origin gPackager )
				)
				( attribute "CDS_SEC" "1"
					( Origin gPackager )
				)
				( attribute "LOCATION" "C9U11"
					( Origin gFrontEnd )
				)
				( attribute "MATERIAL" "X7R"
					( Origin gFrontEnd )
				)
				( attribute "PACK_TYPE" "0805"
					( Origin gFrontEnd )
				)
				( attribute "PART_NUMBER" "G10601-001"
					( Origin gFrontEnd )
				)
				( attribute "PHYS_PAGE" "197"
					( Origin gFrontEnd )
				)
				( attribute "ROOM" "PVDDQ_GHJ_PWR_VR"
					( Origin gFrontEnd )
				)
				( attribute "ROT" "0"
					( Origin gFrontEnd )
				)
				( attribute "SEC" "1"
					( Origin gPackager )
				)
				( attribute "TOLERANCE" "10%"
					( Origin gFrontEnd )
				)
				( attribute "VALUE" "10UF"
					( Origin gFrontEnd )
				)
				( attribute "VER" "1"
					( Origin gFrontEnd )
				)
				( attribute "VOLTAGE" "16V"
					( Units "uVoltage" "V" 1.000000)
					( Origin gFrontEnd )
				)
				( attribute "XY" "(1325,1850)"
					( Origin gFrontEnd )
				)
				( attribute "CHIPS_PART_NAME" "CAP"
					( Origin gPackager )
				)
				( attribute "CDS_PART_NAME" "CAP_0805-10UF,16V,10%,X7R,G106A"
					( Origin gPackager )
				)
				( objectStatus "C9U11" )
			)
			( gate "@baseboard_fab2_lib.baseboard_fab2(sch_1):page197_i66"
				( attribute "CDS_LIB" "mstr_discrete"
					( Origin gPackager )
				)
				( attribute "CDS_LOCATION" "C9U8"
					( Origin gPackager )
				)
				( attribute "CDS_SEC" "1"
					( Origin gPackager )
				)
				( attribute "LOCATION" "C9U8"
					( Origin gFrontEnd )
				)
				( attribute "MATERIAL" "X7R"
					( Origin gFrontEnd )
				)
				( attribute "PACK_TYPE" "0805"
					( Origin gFrontEnd )
				)
				( attribute "PART_NUMBER" "G10601-001"
					( Origin gFrontEnd )
				)
				( attribute "PHYS_PAGE" "197"
					( Origin gFrontEnd )
				)
				( attribute "ROOM" "PVDDQ_GHJ_PWR_VR"
					( Origin gFrontEnd )
				)
				( attribute "ROT" "0"
					( Origin gFrontEnd )
				)
				( attribute "SEC" "1"
					( Origin gPackager )
				)
				( attribute "TOLERANCE" "10%"
					( Origin gFrontEnd )
				)
				( attribute "VALUE" "10UF"
					( Origin gFrontEnd )
				)
				( attribute "VER" "1"
					( Origin gFrontEnd )
				)
				( attribute "VOLTAGE" "16V"
					( Units "uVoltage" "V" 1.000000)
					( Origin gFrontEnd )
				)
				( attribute "XY" "(1325,2500)"
					( Origin gFrontEnd )
				)
				( attribute "CHIPS_PART_NAME" "CAP"
					( Origin gPackager )
				)
				( attribute "CDS_PART_NAME" "CAP_0805-10UF,16V,10%,X7R,G106A"
					( Origin gPackager )
				)
				( objectStatus "C9U8" )
			)
			( gate "@baseboard_fab2_lib.baseboard_fab2(sch_1):page197_i69"
				( attribute "CDS_LIB" "mstr_discrete"
					( Origin gPackager )
				)
				( attribute "CDS_LOCATION" "C6U18"
					( Origin gPackager )
				)
				( attribute "CDS_SEC" "1"
					( Origin gPackager )
				)
				( attribute "LOCATION" "C6U18"
					( Origin gFrontEnd )
				)
				( attribute "MATERIAL" "X7R"
					( Origin gFrontEnd )
				)
				( attribute "PACK_TYPE" "0805"
					( Origin gFrontEnd )
				)
				( attribute "PART_NUMBER" "G10601-001"
					( Origin gFrontEnd )
				)
				( attribute "PHYS_PAGE" "197"
					( Origin gFrontEnd )
				)
				( attribute "ROOM" "PVDDQ_ABC_PWR_VR"
					( Origin gFrontEnd )
				)
				( attribute "ROT" "0"
					( Origin gFrontEnd )
				)
				( attribute "SEC" "1"
					( Origin gPackager )
				)
				( attribute "TOLERANCE" "10%"
					( Origin gFrontEnd )
				)
				( attribute "VALUE" "10UF"
					( Origin gFrontEnd )
				)
				( attribute "VER" "1"
					( Origin gFrontEnd )
				)
				( attribute "VOLTAGE" "16V"
					( Units "uVoltage" "V" 1.000000)
					( Origin gFrontEnd )
				)
				( attribute "XY" "(1325,3175)"
					( Origin gFrontEnd )
				)
				( attribute "CHIPS_PART_NAME" "CAP"
					( Origin gPackager )
				)
				( attribute "CDS_PART_NAME" "CAP_0805-10UF,16V,10%,X7R,G106A"
					( Origin gPackager )
				)
				( objectStatus "C6U18" )
			)
			( gate "@baseboard_fab2_lib.baseboard_fab2(sch_1):page197_i71"
				( attribute "CDS_LIB" "mstr_discrete"
					( Origin gPackager )
				)
				( attribute "CDS_LOCATION" "C6T2"
					( Origin gPackager )
				)
				( attribute "CDS_SEC" "1"
					( Origin gPackager )
				)
				( attribute "LOCATION" "C6T2"
					( Origin gFrontEnd )
				)
				( attribute "MATERIAL" "X7R"
					( Origin gFrontEnd )
				)
				( attribute "PACK_TYPE" "0805"
					( Origin gFrontEnd )
				)
				( attribute "PART_NUMBER" "G10601-001"
					( Origin gFrontEnd )
				)
				( attribute "PHYS_PAGE" "197"
					( Origin gFrontEnd )
				)
				( attribute "ROOM" "PVDDQ_ABC_PWR_VR"
					( Origin gFrontEnd )
				)
				( attribute "ROT" "0"
					( Origin gFrontEnd )
				)
				( attribute "SEC" "1"
					( Origin gPackager )
				)
				( attribute "TOLERANCE" "10%"
					( Origin gFrontEnd )
				)
				( attribute "VALUE" "10UF"
					( Origin gFrontEnd )
				)
				( attribute "VER" "1"
					( Origin gFrontEnd )
				)
				( attribute "VOLTAGE" "16V"
					( Units "uVoltage" "V" 1.000000)
					( Origin gFrontEnd )
				)
				( attribute "XY" "(1325,3750)"
					( Origin gFrontEnd )
				)
				( attribute "CHIPS_PART_NAME" "CAP"
					( Origin gPackager )
				)
				( attribute "CDS_PART_NAME" "CAP_0805-10UF,16V,10%,X7R,G106A"
					( Origin gPackager )
				)
				( objectStatus "C6T2" )
			)
			( gate "@baseboard_fab2_lib.baseboard_fab2(sch_1):page197_i72"
				( attribute "CDS_LIB" "mstr_discrete"
					( Origin gPackager )
				)
				( attribute "CDS_LOCATION" "C1B7"
					( Origin gPackager )
				)
				( attribute "CDS_SEC" "1"
					( Origin gPackager )
				)
				( attribute "LOCATION" "C1B7"
					( Origin gFrontEnd )
				)
				( attribute "MATERIAL" "X7R"
					( Origin gFrontEnd )
				)
				( attribute "PACK_TYPE" "0805"
					( Origin gFrontEnd )
				)
				( attribute "PART_NUMBER" "G10601-001"
					( Origin gFrontEnd )
				)
				( attribute "PHYS_PAGE" "197"
					( Origin gFrontEnd )
				)
				( attribute "ROOM" "PVDDQ_KLM_PWR_VR"
					( Origin gFrontEnd )
				)
				( attribute "ROT" "0"
					( Origin gFrontEnd )
				)
				( attribute "SEC" "1"
					( Origin gPackager )
				)
				( attribute "TOLERANCE" "10%"
					( Origin gFrontEnd )
				)
				( attribute "VALUE" "10UF"
					( Origin gFrontEnd )
				)
				( attribute "VER" "1"
					( Origin gFrontEnd )
				)
				( attribute "VOLTAGE" "16V"
					( Units "uVoltage" "V" 1.000000)
					( Origin gFrontEnd )
				)
				( attribute "XY" "(2175,1850)"
					( Origin gFrontEnd )
				)
				( attribute "CHIPS_PART_NAME" "CAP"
					( Origin gPackager )
				)
				( attribute "CDS_PART_NAME" "CAP_0805-10UF,16V,10%,X7R,G106A"
					( Origin gPackager )
				)
				( objectStatus "C1B7" )
			)
			( gate "@baseboard_fab2_lib.baseboard_fab2(sch_1):page197_i75"
				( attribute "CDS_LIB" "mstr_discrete"
					( Origin gPackager )
				)
				( attribute "CDS_LOCATION" "C1A16"
					( Origin gPackager )
				)
				( attribute "CDS_SEC" "1"
					( Origin gPackager )
				)
				( attribute "LOCATION" "C1A16"
					( Origin gFrontEnd )
				)
				( attribute "MATERIAL" "X7R"
					( Origin gFrontEnd )
				)
				( attribute "PACK_TYPE" "0805"
					( Origin gFrontEnd )
				)
				( attribute "PART_NUMBER" "G10601-001"
					( Origin gFrontEnd )
				)
				( attribute "PHYS_PAGE" "197"
					( Origin gFrontEnd )
				)
				( attribute "ROOM" "PVDDQ_KLM_PWR_VR"
					( Origin gFrontEnd )
				)
				( attribute "ROT" "0"
					( Origin gFrontEnd )
				)
				( attribute "SEC" "1"
					( Origin gPackager )
				)
				( attribute "TOLERANCE" "10%"
					( Origin gFrontEnd )
				)
				( attribute "VALUE" "10UF"
					( Origin gFrontEnd )
				)
				( attribute "VER" "1"
					( Origin gFrontEnd )
				)
				( attribute "VOLTAGE" "16V"
					( Units "uVoltage" "V" 1.000000)
					( Origin gFrontEnd )
				)
				( attribute "XY" "(2175,2500)"
					( Origin gFrontEnd )
				)
				( attribute "CHIPS_PART_NAME" "CAP"
					( Origin gPackager )
				)
				( attribute "CDS_PART_NAME" "CAP_0805-10UF,16V,10%,X7R,G106A"
					( Origin gPackager )
				)
				( objectStatus "C1A16" )
			)
			( gate "@baseboard_fab2_lib.baseboard_fab2(sch_1):page197_i78"
				( attribute "CDS_LIB" "mstr_discrete"
					( Origin gPackager )
				)
				( attribute "CDS_LOCATION" "C4B11"
					( Origin gPackager )
				)
				( attribute "CDS_SEC" "1"
					( Origin gPackager )
				)
				( attribute "LOCATION" "C4B11"
					( Origin gFrontEnd )
				)
				( attribute "MATERIAL" "X7R"
					( Origin gFrontEnd )
				)
				( attribute "PACK_TYPE" "0805"
					( Origin gFrontEnd )
				)
				( attribute "PART_NUMBER" "G10601-001"
					( Origin gFrontEnd )
				)
				( attribute "PHYS_PAGE" "197"
					( Origin gFrontEnd )
				)
				( attribute "ROOM" "PVDDQ_DEF_PWR_VR"
					( Origin gFrontEnd )
				)
				( attribute "ROT" "0"
					( Origin gFrontEnd )
				)
				( attribute "SEC" "1"
					( Origin gPackager )
				)
				( attribute "TOLERANCE" "10%"
					( Origin gFrontEnd )
				)
				( attribute "VALUE" "10UF"
					( Origin gFrontEnd )
				)
				( attribute "VER" "1"
					( Origin gFrontEnd )
				)
				( attribute "VOLTAGE" "16V"
					( Units "uVoltage" "V" 1.000000)
					( Origin gFrontEnd )
				)
				( attribute "XY" "(2175,3175)"
					( Origin gFrontEnd )
				)
				( attribute "CHIPS_PART_NAME" "CAP"
					( Origin gPackager )
				)
				( attribute "CDS_PART_NAME" "CAP_0805-10UF,16V,10%,X7R,G106A"
					( Origin gPackager )
				)
				( objectStatus "C4B11" )
			)
			( gate "@baseboard_fab2_lib.baseboard_fab2(sch_1):page197_i81"
				( attribute "CDS_LIB" "mstr_discrete"
					( Origin gPackager )
				)
				( attribute "CDS_LOCATION" "C4A4"
					( Origin gPackager )
				)
				( attribute "CDS_SEC" "1"
					( Origin gPackager )
				)
				( attribute "LOCATION" "C4A4"
					( Origin gFrontEnd )
				)
				( attribute "MATERIAL" "X7R"
					( Origin gFrontEnd )
				)
				( attribute "PACK_TYPE" "0805"
					( Origin gFrontEnd )
				)
				( attribute "PART_NUMBER" "G10601-001"
					( Origin gFrontEnd )
				)
				( attribute "PHYS_PAGE" "197"
					( Origin gFrontEnd )
				)
				( attribute "ROOM" "PVDDQ_DEF_PWR_VR"
					( Origin gFrontEnd )
				)
				( attribute "ROT" "0"
					( Origin gFrontEnd )
				)
				( attribute "SEC" "1"
					( Origin gPackager )
				)
				( attribute "TOLERANCE" "10%"
					( Origin gFrontEnd )
				)
				( attribute "VALUE" "10UF"
					( Origin gFrontEnd )
				)
				( attribute "VER" "1"
					( Origin gFrontEnd )
				)
				( attribute "VOLTAGE" "16V"
					( Units "uVoltage" "V" 1.000000)
					( Origin gFrontEnd )
				)
				( attribute "XY" "(2175,3750)"
					( Origin gFrontEnd )
				)
				( attribute "CHIPS_PART_NAME" "CAP"
					( Origin gPackager )
				)
				( attribute "CDS_PART_NAME" "CAP_0805-10UF,16V,10%,X7R,G106A"
					( Origin gPackager )
				)
				( objectStatus "C4A4" )
			)
			( gate "@baseboard_fab2_lib.baseboard_fab2(sch_1):page197_i84"
				( attribute "CDS_LIB" "mstr_discrete"
					( Origin gPackager )
				)
				( attribute "CDS_LOCATION" "C6U10"
					( Origin gPackager )
				)
				( attribute "CDS_SEC" "1"
					( Origin gPackager )
				)
				( attribute "LOCATION" "C6U10"
					( Origin gFrontEnd )
				)
				( attribute "MATERIAL" "X7R"
					( Origin gFrontEnd )
				)
				( attribute "PACK_TYPE" "0805"
					( Origin gFrontEnd )
				)
				( attribute "PART_NUMBER" "G10601-001"
					( Origin gFrontEnd )
				)
				( attribute "PHYS_PAGE" "197"
					( Origin gFrontEnd )
				)
				( attribute "ROOM" "PVDDQ_ABC_PWR_VR"
					( Origin gFrontEnd )
				)
				( attribute "ROT" "0"
					( Origin gFrontEnd )
				)
				( attribute "SEC" "1"
					( Origin gPackager )
				)
				( attribute "TOLERANCE" "10%"
					( Origin gFrontEnd )
				)
				( attribute "VALUE" "10UF"
					( Origin gFrontEnd )
				)
				( attribute "VER" "1"
					( Origin gFrontEnd )
				)
				( attribute "VOLTAGE" "16V"
					( Units "uVoltage" "V" 1.000000)
					( Origin gFrontEnd )
				)
				( attribute "XY" "(1325,4400)"
					( Origin gFrontEnd )
				)
				( attribute "CHIPS_PART_NAME" "CAP"
					( Origin gPackager )
				)
				( attribute "CDS_PART_NAME" "CAP_0805-10UF,16V,10%,X7R,G106A"
					( Origin gPackager )
				)
				( objectStatus "C6U10" )
			)
			( gate "@baseboard_fab2_lib.baseboard_fab2(sch_1):page197_i88"
				( attribute "CDS_LIB" "mstr_discrete"
					( Origin gPackager )
				)
				( attribute "CDS_LOCATION" "C4A17"
					( Origin gPackager )
				)
				( attribute "CDS_SEC" "1"
					( Origin gPackager )
				)
				( attribute "LOCATION" "C4A17"
					( Origin gFrontEnd )
				)
				( attribute "MATERIAL" "X7R"
					( Origin gFrontEnd )
				)
				( attribute "PACK_TYPE" "0805"
					( Origin gFrontEnd )
				)
				( attribute "PART_NUMBER" "G10601-001"
					( Origin gFrontEnd )
				)
				( attribute "PHYS_PAGE" "197"
					( Origin gFrontEnd )
				)
				( attribute "ROOM" "PVDDQ_DEF_PWR_VR"
					( Origin gFrontEnd )
				)
				( attribute "ROT" "0"
					( Origin gFrontEnd )
				)
				( attribute "SEC" "1"
					( Origin gPackager )
				)
				( attribute "TOLERANCE" "10%"
					( Origin gFrontEnd )
				)
				( attribute "VALUE" "10UF"
					( Origin gFrontEnd )
				)
				( attribute "VER" "1"
					( Origin gFrontEnd )
				)
				( attribute "VOLTAGE" "16V"
					( Units "uVoltage" "V" 1.000000)
					( Origin gFrontEnd )
				)
				( attribute "XY" "(2175,4400)"
					( Origin gFrontEnd )
				)
				( attribute "CHIPS_PART_NAME" "CAP"
					( Origin gPackager )
				)
				( attribute "CDS_PART_NAME" "CAP_0805-10UF,16V,10%,X7R,G106A"
					( Origin gPackager )
				)
				( objectStatus "C4A17" )
			)
			( gate "@baseboard_fab2_lib.baseboard_fab2(sch_1):page197_i91"
				( attribute "CDS_LIB" "w_hdl"
					( Origin gPackager )
				)
				( attribute "CDS_LMAN_SYM_OUTLINE" "-125,250,125,-250"
					( Origin gPackager )
				)
				( attribute "CDS_LOCATION" "Q12W3"
					( Origin gPackager )
				)
				( attribute "CDS_SEC" "1"
					( Origin gPackager )
				)
				( attribute "LOCATION" "Q12W3"
					( Origin gFrontEnd )
				)
				( attribute "PACK_TYPE" "DISCRET-GB1"
					( Origin gFrontEnd )
				)
				( attribute "PART_NUMBER" "075.00308.007C"
					( Origin gFrontEnd )
				)
				( attribute "PHYS_PAGE" "197"
					( Origin gFrontEnd )
				)
				( attribute "ROT" "0"
					( Origin gFrontEnd )
				)
				( attribute "SEC" "1"
					( Origin gFrontEnd )
				)
				( attribute "SEC_TYPE" "DISCRET-GB1"
					( Origin gFrontEnd )
				)
				( attribute "VALUE" "BSL308C-H6327-GP"
					( Origin gFrontEnd )
				)
				( attribute "VER" "1"
					( Origin gFrontEnd )
				)
				( attribute "XY" "(-700,4100)"
					( Origin gFrontEnd )
				)
				( attribute "CHIPS_PART_NAME" "BSL308C-H6327-GP"
					( Origin gPackager )
				)
				( attribute "CDS_PART_NAME" "BSL308C-H6327-GP_DISCRET-GB1-BA"
					( Origin gPackager )
				)
				( objectStatus "Q12W3" )
			)
			( gate "@baseboard_fab2_lib.baseboard_fab2(sch_1):page181_i4"
				( attribute "BOM_COST" "IO_SLOT"
					( Origin gFrontEnd )
				)
				( attribute "CDS_LIB" "mstr_discrete"
					( Origin gPackager )
				)
				( attribute "CDS_LOCATION" "R9T9"
					( Origin gPackager )
				)
				( attribute "CDS_SEC" "1"
					( Origin gPackager )
				)
				( attribute "LOCATION" "R9T9"
					( Origin gFrontEnd )
				)
				( attribute "MATERIAL" "CHIP"
					( Origin gFrontEnd )
				)
				( attribute "PACK_TYPE" "0402"
					( Origin gFrontEnd )
				)
				( attribute "PART_NUMBER" "G21796-072"
					( Origin gFrontEnd )
				)
				( attribute "PHYS_PAGE" "181"
					( Origin gFrontEnd )
				)
				( attribute "ROOM" "IO_SLOT"
					( Origin gFrontEnd )
				)
				( attribute "ROT" "0"
					( Origin gFrontEnd )
				)
				( attribute "SEC" "1"
					( Origin gFrontEnd )
				)
				( attribute "SEC_TYPE" "0402"
					( Origin gFrontEnd )
				)
				( attribute "TOLERANCE" "1%"
					( Origin gFrontEnd )
				)
				( attribute "VALUE" "4.75K"
					( Origin gFrontEnd )
				)
				( attribute "VER" "2"
					( Origin gFrontEnd )
				)
				( attribute "WATTAGE" "1/16W"
					( Origin gFrontEnd )
				)
				( attribute "XY" "(-2200,1750)"
					( Origin gFrontEnd )
				)
				( attribute "CHIPS_PART_NAME" "RES"
					( Origin gPackager )
				)
				( attribute "CDS_PART_NAME" "RES_0402-4.75K,1%,1/16W,CHIP,GA"
					( Origin gPackager )
				)
				( objectStatus "R9T9" )
			)
			( gate "@baseboard_fab2_lib.baseboard_fab2(sch_1):page181_i5"
				( attribute "BOM_COST" "IO_SLOT"
					( Origin gFrontEnd )
				)
				( attribute "CDS_LIB" "mstr_discrete"
					( Origin gPackager )
				)
				( attribute "CDS_LOCATION" "CR1F4"
					( Origin gPackager )
				)
				( attribute "CDS_SEC" "1"
					( Origin gPackager )
				)
				( attribute "LOCATION" "CR1F4"
					( Origin gFrontEnd )
				)
				( attribute "MATERIAL" "IC"
					( Origin gFrontEnd )
				)
				( attribute "PACK_TYPE" "SM"
					( Origin gFrontEnd )
				)
				( attribute "PART_NUMBER" "H71799-001"
					( Origin gFrontEnd )
				)
				( attribute "PHYS_PAGE" "181"
					( Origin gFrontEnd )
				)
				( attribute "ROOM" "IO_SLOT"
					( Origin gFrontEnd )
				)
				( attribute "ROT" "0"
					( Origin gFrontEnd )
				)
				( attribute "SEC" "1"
					( Origin gFrontEnd )
				)
				( attribute "SEC_TYPE" "SM"
					( Origin gFrontEnd )
				)
				( attribute "VALUE" "SDMK0340L"
					( Origin gFrontEnd )
				)
				( attribute "VER" "1"
					( Origin gFrontEnd )
				)
				( attribute "XY" "(-1550,1550)"
					( Origin gFrontEnd )
				)
				( attribute "CHIPS_PART_NAME" "DIODE"
					( Origin gPackager )
				)
				( attribute "CDS_PART_NAME" "DIODE_SM-SDMK0340L,IC,H71799-0A"
					( Origin gPackager )
				)
				( objectStatus "CR1F4" )
			)
			( gate "@baseboard_fab2_lib.baseboard_fab2(sch_1):page181_i22"
				( attribute "CDS_LIB" "mstr_discrete"
					( Origin gPackager )
				)
				( attribute "CDS_LOCATION" "R1F8"
					( Origin gPackager )
				)
				( attribute "CDS_SEC" "1"
					( Origin gPackager )
				)
				( attribute "LOCATION" "R1F8"
					( Origin gFrontEnd )
				)
				( attribute "MATERIAL" "CHIP"
					( Origin gFrontEnd )
				)
				( attribute "PACK_TYPE" "0402"
					( Origin gFrontEnd )
				)
				( attribute "PART_NUMBER" "G21497-005"
					( Origin gFrontEnd )
				)
				( attribute "PHYS_PAGE" "181"
					( Origin gFrontEnd )
				)
				( attribute "ROT" "0"
					( Origin gFrontEnd )
				)
				( attribute "SEC" "1"
					( Origin gFrontEnd )
				)
				( attribute "SEC_TYPE" "0402"
					( Origin gFrontEnd )
				)
				( attribute "TOLERANCE" "5%"
					( Origin gFrontEnd )
				)
				( attribute "VALUE" "0.0"
					( Origin gFrontEnd )
				)
				( attribute "VER" "1"
					( Origin gFrontEnd )
				)
				( attribute "WATTAGE" "1/16W"
					( Origin gFrontEnd )
				)
				( attribute "XY" "(-2225,2800)"
					( Origin gFrontEnd )
				)
				( attribute "CHIPS_PART_NAME" "RES"
					( Origin gPackager )
				)
				( attribute "CDS_PART_NAME" "RES_0402-0.0,5%,1/16W,CHIP,G21A"
					( Origin gPackager )
				)
				( objectStatus "R1F8" )
			)
			( gate "@baseboard_fab2_lib.baseboard_fab2(sch_1):page181_i26"
				( attribute "CDS_LIB" "mstr_discrete"
					( Origin gPackager )
				)
				( attribute "CDS_LOCATION" "R9T1"
					( Origin gPackager )
				)
				( attribute "CDS_SEC" "1"
					( Origin gPackager )
				)
				( attribute "LOCATION" "R9T1"
					( Origin gFrontEnd )
				)
				( attribute "MATERIAL" "CHIP"
					( Origin gFrontEnd )
				)
				( attribute "PACK_TYPE" "0402"
					( Origin gFrontEnd )
				)
				( attribute "PART_NUMBER" "G21497-005"
					( Origin gFrontEnd )
				)
				( attribute "PHYS_PAGE" "181"
					( Origin gFrontEnd )
				)
				( attribute "ROT" "0"
					( Origin gFrontEnd )
				)
				( attribute "SEC" "1"
					( Origin gFrontEnd )
				)
				( attribute "SEC_TYPE" "0402"
					( Origin gFrontEnd )
				)
				( attribute "TOLERANCE" "5%"
					( Origin gFrontEnd )
				)
				( attribute "VALUE" "0.0"
					( Origin gFrontEnd )
				)
				( attribute "VER" "1"
					( Origin gFrontEnd )
				)
				( attribute "WATTAGE" "1/16W"
					( Origin gFrontEnd )
				)
				( attribute "XY" "(-1500,2700)"
					( Origin gFrontEnd )
				)
				( attribute "CHIPS_PART_NAME" "RES"
					( Origin gPackager )
				)
				( attribute "CDS_PART_NAME" "RES_0402-0.0,5%,1/16W,CHIP,G21A"
					( Origin gPackager )
				)
				( objectStatus "R9T1" )
			)
			( gate "@baseboard_fab2_lib.baseboard_fab2(sch_1):page181_i27"
				( attribute "CDS_LIB" "mstr_discrete"
					( Origin gPackager )
				)
				( attribute "CDS_LOCATION" "R9R12"
					( Origin gPackager )
				)
				( attribute "CDS_SEC" "1"
					( Origin gPackager )
				)
				( attribute "LOCATION" "R9R12"
					( Origin gFrontEnd )
				)
				( attribute "MATERIAL" "CHIP"
					( Origin gFrontEnd )
				)
				( attribute "PACK_TYPE" "0402"
					( Origin gFrontEnd )
				)
				( attribute "PART_NUMBER" "G21497-005"
					( Origin gFrontEnd )
				)
				( attribute "PHYS_PAGE" "181"
					( Origin gFrontEnd )
				)
				( attribute "ROT" "0"
					( Origin gFrontEnd )
				)
				( attribute "SEC" "1"
					( Origin gFrontEnd )
				)
				( attribute "SEC_TYPE" "0402"
					( Origin gFrontEnd )
				)
				( attribute "TOLERANCE" "5%"
					( Origin gFrontEnd )
				)
				( attribute "VALUE" "0.0"
					( Origin gFrontEnd )
				)
				( attribute "VER" "1"
					( Origin gFrontEnd )
				)
				( attribute "WATTAGE" "1/16W"
					( Origin gFrontEnd )
				)
				( attribute "XY" "(-2225,2900)"
					( Origin gFrontEnd )
				)
				( attribute "CHIPS_PART_NAME" "RES"
					( Origin gPackager )
				)
				( attribute "CDS_PART_NAME" "RES_0402-0.0,5%,1/16W,CHIP,G21A"
					( Origin gPackager )
				)
				( objectStatus "R9R12" )
			)
			( gate "@baseboard_fab2_lib.baseboard_fab2(sch_1):page181_i28"
				( attribute "CDS_LIB" "mstr_discrete"
					( Origin gPackager )
				)
				( attribute "CDS_LOCATION" "R9F63"
					( Origin gPackager )
				)
				( attribute "CDS_SEC" "1"
					( Origin gPackager )
				)
				( attribute "LOCATION" "R9F63"
					( Origin gFrontEnd )
				)
				( attribute "MATERIAL" "EMPTY"
					( Origin gFrontEnd )
				)
				( attribute "PACK_TYPE" "0402"
					( Origin gFrontEnd )
				)
				( attribute "PART_NUMBER" "G21497-005"
					( Origin gFrontEnd )
				)
				( attribute "PHYS_PAGE" "181"
					( Origin gFrontEnd )
				)
				( attribute "ROOM" "UART_MUX"
					( Origin gFrontEnd )
				)
				( attribute "ROT" "0"
					( Origin gFrontEnd )
				)
				( attribute "SEC" "1"
					( Origin gFrontEnd )
				)
				( attribute "SEC_TYPE" "0402"
					( Origin gFrontEnd )
				)
				( attribute "TOLERANCE" "5%"
					( Origin gFrontEnd )
				)
				( attribute "VALUE" "0.0"
					( Origin gFrontEnd )
				)
				( attribute "VER" "1"
					( Origin gFrontEnd )
				)
				( attribute "WATTAGE" "1/16W"
					( Origin gFrontEnd )
				)
				( attribute "XY" "(-2125,3100)"
					( Origin gFrontEnd )
				)
				( attribute "CHIPS_PART_NAME" "RES"
					( Origin gPackager )
				)
				( attribute "CDS_PART_NAME" "RES_0402-0.0,5%,1/16W,EMPTY,G2A"
					( Origin gPackager )
				)
				( objectStatus "R9F63" )
			)
			( gate "@baseboard_fab2_lib.baseboard_fab2(sch_1):page181_i29"
				( attribute "CDS_LIB" "mstr_discrete"
					( Origin gPackager )
				)
				( attribute "CDS_LOCATION" "R9F64"
					( Origin gPackager )
				)
				( attribute "CDS_SEC" "1"
					( Origin gPackager )
				)
				( attribute "LOCATION" "R9F64"
					( Origin gFrontEnd )
				)
				( attribute "MATERIAL" "CHIP"
					( Origin gFrontEnd )
				)
				( attribute "PACK_TYPE" "0402"
					( Origin gFrontEnd )
				)
				( attribute "PART_NUMBER" "G21497-005"
					( Origin gFrontEnd )
				)
				( attribute "PHYS_PAGE" "181"
					( Origin gFrontEnd )
				)
				( attribute "ROOM" "UART_MUX"
					( Origin gFrontEnd )
				)
				( attribute "ROT" "0"
					( Origin gFrontEnd )
				)
				( attribute "SEC" "1"
					( Origin gFrontEnd )
				)
				( attribute "SEC_TYPE" "0402"
					( Origin gFrontEnd )
				)
				( attribute "TOLERANCE" "5%"
					( Origin gFrontEnd )
				)
				( attribute "VALUE" "0.0"
					( Origin gFrontEnd )
				)
				( attribute "VER" "1"
					( Origin gFrontEnd )
				)
				( attribute "WATTAGE" "1/16W"
					( Origin gFrontEnd )
				)
				( attribute "XY" "(-2175,3550)"
					( Origin gFrontEnd )
				)
				( attribute "CHIPS_PART_NAME" "RES"
					( Origin gPackager )
				)
				( attribute "CDS_PART_NAME" "RES_0402-0.0,5%,1/16W,CHIP,G21A"
					( Origin gPackager )
				)
				( objectStatus "R9F64" )
			)
			( gate "@baseboard_fab2_lib.baseboard_fab2(sch_1):page181_i30"
				( attribute "CDS_LIB" "mstr_discrete"
					( Origin gPackager )
				)
				( attribute "CDS_LOCATION" "R9F70"
					( Origin gPackager )
				)
				( attribute "CDS_SEC" "1"
					( Origin gPackager )
				)
				( attribute "LOCATION" "R9F70"
					( Origin gFrontEnd )
				)
				( attribute "MATERIAL" "EMPTY"
					( Origin gFrontEnd )
				)
				( attribute "PACK_TYPE" "0402"
					( Origin gFrontEnd )
				)
				( attribute "PART_NUMBER" "G21497-005"
					( Origin gFrontEnd )
				)
				( attribute "PHYS_PAGE" "181"
					( Origin gFrontEnd )
				)
				( attribute "ROOM" "UART_MUX"
					( Origin gFrontEnd )
				)
				( attribute "ROT" "0"
					( Origin gFrontEnd )
				)
				( attribute "SEC" "1"
					( Origin gFrontEnd )
				)
				( attribute "SEC_TYPE" "0402"
					( Origin gFrontEnd )
				)
				( attribute "TOLERANCE" "5%"
					( Origin gFrontEnd )
				)
				( attribute "VALUE" "0.0"
					( Origin gFrontEnd )
				)
				( attribute "VER" "1"
					( Origin gFrontEnd )
				)
				( attribute "WATTAGE" "1/16W"
					( Origin gFrontEnd )
				)
				( attribute "XY" "(-1750,3150)"
					( Origin gFrontEnd )
				)
				( attribute "CHIPS_PART_NAME" "RES"
					( Origin gPackager )
				)
				( attribute "CDS_PART_NAME" "RES_0402-0.0,5%,1/16W,EMPTY,G2A"
					( Origin gPackager )
				)
				( objectStatus "R9F70" )
			)
			( gate "@baseboard_fab2_lib.baseboard_fab2(sch_1):page181_i31"
				( attribute "CDS_LIB" "mstr_discrete"
					( Origin gPackager )
				)
				( attribute "CDS_LOCATION" "R9R10"
					( Origin gPackager )
				)
				( attribute "CDS_SEC" "1"
					( Origin gPackager )
				)
				( attribute "LOCATION" "R9R10"
					( Origin gFrontEnd )
				)
				( attribute "MATERIAL" "CHIP"
					( Origin gFrontEnd )
				)
				( attribute "PACK_TYPE" "0402"
					( Origin gFrontEnd )
				)
				( attribute "PART_NUMBER" "G21497-005"
					( Origin gFrontEnd )
				)
				( attribute "PHYS_PAGE" "181"
					( Origin gFrontEnd )
				)
				( attribute "ROT" "0"
					( Origin gFrontEnd )
				)
				( attribute "SEC" "1"
					( Origin gFrontEnd )
				)
				( attribute "SEC_TYPE" "0402"
					( Origin gFrontEnd )
				)
				( attribute "TOLERANCE" "5%"
					( Origin gFrontEnd )
				)
				( attribute "VALUE" "0.0"
					( Origin gFrontEnd )
				)
				( attribute "VER" "1"
					( Origin gFrontEnd )
				)
				( attribute "WATTAGE" "1/16W"
					( Origin gFrontEnd )
				)
				( attribute "XY" "(-1525,2850)"
					( Origin gFrontEnd )
				)
				( attribute "CHIPS_PART_NAME" "RES"
					( Origin gPackager )
				)
				( attribute "CDS_PART_NAME" "RES_0402-0.0,5%,1/16W,CHIP,G21A"
					( Origin gPackager )
				)
				( objectStatus "R9R10" )
			)
			( gate "@baseboard_fab2_lib.baseboard_fab2(sch_1):page181_i32"
				( attribute "CDS_LIB" "mstr_discrete"
					( Origin gPackager )
				)
				( attribute "CDS_LOCATION" "R9R9"
					( Origin gPackager )
				)
				( attribute "CDS_SEC" "1"
					( Origin gPackager )
				)
				( attribute "LOCATION" "R9R9"
					( Origin gFrontEnd )
				)
				( attribute "MATERIAL" "CHIP"
					( Origin gFrontEnd )
				)
				( attribute "PACK_TYPE" "0402"
					( Origin gFrontEnd )
				)
				( attribute "PART_NUMBER" "G21497-005"
					( Origin gFrontEnd )
				)
				( attribute "PHYS_PAGE" "181"
					( Origin gFrontEnd )
				)
				( attribute "ROT" "0"
					( Origin gFrontEnd )
				)
				( attribute "SEC" "1"
					( Origin gFrontEnd )
				)
				( attribute "SEC_TYPE" "0402"
					( Origin gFrontEnd )
				)
				( attribute "TOLERANCE" "5%"
					( Origin gFrontEnd )
				)
				( attribute "VALUE" "0.0"
					( Origin gFrontEnd )
				)
				( attribute "VER" "1"
					( Origin gFrontEnd )
				)
				( attribute "WATTAGE" "1/16W"
					( Origin gFrontEnd )
				)
				( attribute "XY" "(-1525,2950)"
					( Origin gFrontEnd )
				)
				( attribute "CHIPS_PART_NAME" "RES"
					( Origin gPackager )
				)
				( attribute "CDS_PART_NAME" "RES_0402-0.0,5%,1/16W,CHIP,G21A"
					( Origin gPackager )
				)
				( objectStatus "R9R9" )
			)
			( gate "@baseboard_fab2_lib.baseboard_fab2(sch_1):page181_i33"
				( attribute "CDS_LIB" "mstr_discrete"
					( Origin gPackager )
				)
				( attribute "CDS_LOCATION" "R9F67"
					( Origin gPackager )
				)
				( attribute "CDS_SEC" "1"
					( Origin gPackager )
				)
				( attribute "LOCATION" "R9F67"
					( Origin gFrontEnd )
				)
				( attribute "MATERIAL" "CHIP"
					( Origin gFrontEnd )
				)
				( attribute "PACK_TYPE" "0402"
					( Origin gFrontEnd )
				)
				( attribute "PART_NUMBER" "G21497-005"
					( Origin gFrontEnd )
				)
				( attribute "PHYS_PAGE" "181"
					( Origin gFrontEnd )
				)
				( attribute "ROOM" "UART_MUX"
					( Origin gFrontEnd )
				)
				( attribute "ROT" "0"
					( Origin gFrontEnd )
				)
				( attribute "SEC" "1"
					( Origin gPackager )
				)
				( attribute "TOLERANCE" "5%"
					( Origin gFrontEnd )
				)
				( attribute "VALUE" "0.0"
					( Origin gFrontEnd )
				)
				( attribute "VER" "1"
					( Origin gFrontEnd )
				)
				( attribute "WATTAGE" "1/16W"
					( Origin gFrontEnd )
				)
				( attribute "XY" "(-1775,3600)"
					( Origin gFrontEnd )
				)
				( attribute "CHIPS_PART_NAME" "RES"
					( Origin gPackager )
				)
				( attribute "CDS_PART_NAME" "RES_0402-0.0,5%,1/16W,CHIP,G21A"
					( Origin gPackager )
				)
				( objectStatus "R9F67" )
			)
			( gate "@baseboard_fab2_lib.baseboard_fab2(sch_1):page181_i34"
				( attribute "BOM_COST" "IO_SLOT"
					( Origin gFrontEnd )
				)
				( attribute "CDS_LIB" "dev_discrete"
					( Origin gPackager )
				)
				( attribute "CDS_LOCATION" "C8E1"
					( Origin gPackager )
				)
				( attribute "CDS_SEC" "1"
					( Origin gPackager )
				)
				( attribute "LOCATION" "C8E1"
					( Origin gFrontEnd )
				)
				( attribute "MATERIAL" "X7R"
					( Origin gFrontEnd )
				)
				( attribute "PACK_TYPE" "0402V"
					( Origin gFrontEnd )
				)
				( attribute "PART_NUMBER" "A36096-030"
					( Origin gFrontEnd )
				)
				( attribute "PHYS_PAGE" "181"
					( Origin gFrontEnd )
				)
				( attribute "ROOM" "IO_SLOT"
					( Origin gFrontEnd )
				)
				( attribute "ROT" "0"
					( Origin gFrontEnd )
				)
				( attribute "SEC" "1"
					( Origin gFrontEnd )
				)
				( attribute "SEC_TYPE" "0402V"
					( Origin gFrontEnd )
				)
				( attribute "TOLERANCE" "10%"
					( Origin gFrontEnd )
				)
				( attribute "VALUE" "0.1UF"
					( Origin gFrontEnd )
				)
				( attribute "VER" "1"
					( Origin gFrontEnd )
				)
				( attribute "VOLTAGE" "16V"
					( Units "uVoltage" "V" 1.000000)
					( Origin gFrontEnd )
				)
				( attribute "XY" "(-700,800)"
					( Origin gFrontEnd )
				)
				( attribute "CHIPS_PART_NAME" "CAP_A"
					( Origin gPackager )
				)
				( attribute "CDS_PART_NAME" "CAP_A_0402V-0.1UF,16V,10%,X7R,A"
					( Origin gPackager )
				)
				( objectStatus "C8E1" )
			)
			( gate "@baseboard_fab2_lib.baseboard_fab2(sch_1):page181_i37"
				( attribute "BOM_COST" "IO_SLOT"
					( Origin gFrontEnd )
				)
				( attribute "CDS_LIB" "mstr_discrete"
					( Origin gPackager )
				)
				( attribute "CDS_LOCATION" "CR1F3"
					( Origin gPackager )
				)
				( attribute "CDS_SEC" "1"
					( Origin gPackager )
				)
				( attribute "LOCATION" "CR1F3"
					( Origin gFrontEnd )
				)
				( attribute "MATERIAL" "IC"
					( Origin gFrontEnd )
				)
				( attribute "PACK_TYPE" "SM"
					( Origin gFrontEnd )
				)
				( attribute "PART_NUMBER" "H71799-001"
					( Origin gFrontEnd )
				)
				( attribute "PHYS_PAGE" "181"
					( Origin gFrontEnd )
				)
				( attribute "ROOM" "IO_SLOT"
					( Origin gFrontEnd )
				)
				( attribute "ROT" "0"
					( Origin gFrontEnd )
				)
				( attribute "SEC" "1"
					( Origin gFrontEnd )
				)
				( attribute "SEC_TYPE" "SM"
					( Origin gFrontEnd )
				)
				( attribute "VALUE" "SDMK0340L"
					( Origin gFrontEnd )
				)
				( attribute "VER" "1"
					( Origin gFrontEnd )
				)
				( attribute "XY" "(-425,1550)"
					( Origin gFrontEnd )
				)
				( attribute "CHIPS_PART_NAME" "DIODE"
					( Origin gPackager )
				)
				( attribute "CDS_PART_NAME" "DIODE_SM-SDMK0340L,IC,H71799-0A"
					( Origin gPackager )
				)
				( objectStatus "CR1F3" )
			)
			( gate "@baseboard_fab2_lib.baseboard_fab2(sch_1):page181_i40"
				( attribute "CDS_LIB" "mstr_discrete"
					( Origin gPackager )
				)
				( attribute "CDS_LOCATION" "C2R6"
					( Origin gPackager )
				)
				( attribute "CDS_SEC" "1"
					( Origin gPackager )
				)
				( attribute "LOCATION" "C2R6"
					( Origin gFrontEnd )
				)
				( attribute "MATERIAL" "EMPTY"
					( Origin gFrontEnd )
				)
				( attribute "PACK_TYPE" "0402LF"
					( Origin gFrontEnd )
				)
				( attribute "PART_NUMBER" "A36096-049"
					( Origin gFrontEnd )
				)
				( attribute "PHYS_PAGE" "181"
					( Origin gFrontEnd )
				)
				( attribute "ROOM" "IO_SLOT"
					( Origin gFrontEnd )
				)
				( attribute "ROT" "0"
					( Origin gFrontEnd )
				)
				( attribute "SEC" "1"
					( Origin gFrontEnd )
				)
				( attribute "SEC_TYPE" "0402LF"
					( Origin gFrontEnd )
				)
				( attribute "TOLERANCE" "10%"
					( Origin gFrontEnd )
				)
				( attribute "VALUE" "470PF"
					( Origin gFrontEnd )
				)
				( attribute "VER" "1"
					( Origin gFrontEnd )
				)
				( attribute "VOLTAGE" "50V"
					( Units "uVoltage" "V" 1.000000)
					( Origin gFrontEnd )
				)
				( attribute "XY" "(300,625)"
					( Origin gFrontEnd )
				)
				( attribute "CHIPS_PART_NAME" "CAP"
					( Origin gPackager )
				)
				( attribute "CDS_PART_NAME" "CAP_0402LF-470PF,50V,10%,EMPTYA"
					( Origin gPackager )
				)
				( objectStatus "C2R6" )
			)
			( gate "@baseboard_fab2_lib.baseboard_fab2(sch_1):page181_i42"
				( attribute "CDS_LIB" "mstr_discrete"
					( Origin gPackager )
				)
				( attribute "CDS_LOCATION" "Q9T1"
					( Origin gPackager )
				)
				( attribute "CDS_SEC" "1"
					( Origin gPackager )
				)
				( attribute "LOCATION" "Q9T1"
					( Origin gFrontEnd )
				)
				( attribute "MATERIAL" "IC"
					( Origin gFrontEnd )
				)
				( attribute "PACK_TYPE" "SM"
					( Origin gFrontEnd )
				)
				( attribute "PART_NUMBER" "C52245-001"
					( Origin gFrontEnd )
				)
				( attribute "PHYS_PAGE" "181"
					( Origin gFrontEnd )
				)
				( attribute "ROOM" "SB"
					( Origin gFrontEnd )
				)
				( attribute "ROT" "0"
					( Origin gFrontEnd )
				)
				( attribute "SEC" "1"
					( Origin gFrontEnd )
				)
				( attribute "SEC_TYPE" "SM"
					( Origin gFrontEnd )
				)
				( attribute "VALUE" "MMBT3904"
					( Origin gFrontEnd )
				)
				( attribute "VER" "1"
					( Origin gFrontEnd )
				)
				( attribute "XY" "(650,1550)"
					( Origin gFrontEnd )
				)
				( attribute "CHIPS_PART_NAME" "NPN"
					( Origin gPackager )
				)
				( attribute "CDS_PART_NAME" "NPN_SM-MMBT3904,IC,C52245-001"
					( Origin gPackager )
				)
				( objectStatus "Q9T1" )
			)
			( gate "@baseboard_fab2_lib.baseboard_fab2(sch_1):page181_i60"
				( attribute "BOM_COST" "FAST_PROCHOT"
					( Origin gFrontEnd )
				)
				( attribute "CDS_LIB" "mstr_ttl"
					( Origin gPackager )
				)
				( attribute "CDS_LOCATION" "U8E1"
					( Origin gPackager )
				)
				( attribute "CDS_SEC" "2"
					( Origin gPackager )
				)
				( attribute "LOCATION" "U8E1"
					( Origin gFrontEnd )
				)
				( attribute "MATERIAL" "IC"
					( Origin gFrontEnd )
				)
				( attribute "PACK_TYPE" "QFN15"
					( Origin gFrontEnd )
				)
				( attribute "PART_NUMBER" "D90404-001"
					( Origin gFrontEnd )
				)
				( attribute "PHYS_PAGE" "181"
					( Origin gFrontEnd )
				)
				( attribute "ROOM" "FAST_PROCHOT"
					( Origin gFrontEnd )
				)
				( attribute "ROT" "0"
					( Origin gFrontEnd )
				)
				( attribute "SEC" "2"
					( Origin gFrontEnd )
				)
				( attribute "SEC_TYPE" "QFN15"
					( Origin gFrontEnd )
				)
				( attribute "VALUE" "74LVC08A"
					( Origin gFrontEnd )
				)
				( attribute "VER" "1"
					( Origin gFrontEnd )
				)
				( attribute "XY" "(850,825)"
					( Origin gFrontEnd )
				)
				( attribute "CHIPS_PART_NAME" "TTL08"
					( Origin gPackager )
				)
				( attribute "CDS_PART_NAME" "TTL08_QFN15-74LVC08A,IC,D90404B"
					( Origin gPackager )
				)
				( objectStatus "U8E1" )
			)
			( gate "@baseboard_fab2_lib.baseboard_fab2(sch_1):page181_i63"
				( attribute "CDS_LIB" "mstr_discrete"
					( Origin gPackager )
				)
				( attribute "CDS_LOCATION" "R8E5"
					( Origin gPackager )
				)
				( attribute "CDS_SEC" "1"
					( Origin gPackager )
				)
				( attribute "LOCATION" "R8E5"
					( Origin gFrontEnd )
				)
				( attribute "MATERIAL" "CHIP"
					( Origin gFrontEnd )
				)
				( attribute "PACK_TYPE" "0402"
					( Origin gFrontEnd )
				)
				( attribute "PART_NUMBER" "G21796-074"
					( Origin gFrontEnd )
				)
				( attribute "PHYS_PAGE" "181"
					( Origin gFrontEnd )
				)
				( attribute "ROOM" "IO_SLOT"
					( Origin gFrontEnd )
				)
				( attribute "ROT" "0"
					( Origin gFrontEnd )
				)
				( attribute "SEC" "1"
					( Origin gFrontEnd )
				)
				( attribute "SEC_TYPE" "0402"
					( Origin gFrontEnd )
				)
				( attribute "TOLERANCE" "1%"
					( Origin gFrontEnd )
				)
				( attribute "VALUE" "33.2"
					( Origin gFrontEnd )
				)
				( attribute "VER" "1"
					( Origin gFrontEnd )
				)
				( attribute "WATTAGE" "1/16W"
					( Origin gFrontEnd )
				)
				( attribute "XY" "(1650,825)"
					( Origin gFrontEnd )
				)
				( attribute "CHIPS_PART_NAME" "RES"
					( Origin gPackager )
				)
				( attribute "CDS_PART_NAME" "RES_0402-33.2,1%,1/16W,CHIP,G2A"
					( Origin gPackager )
				)
				( objectStatus "R8E5" )
			)
			( gate "@baseboard_fab2_lib.baseboard_fab2(sch_1):page181_i64"
				( attribute "BOM_COST" "IO_SLOT"
					( Origin gFrontEnd )
				)
				( attribute "CDS_LIB" "mstr_discrete"
					( Origin gPackager )
				)
				( attribute "CDS_LOCATION" "R9T3"
					( Origin gPackager )
				)
				( attribute "CDS_SEC" "1"
					( Origin gPackager )
				)
				( attribute "LOCATION" "R9T3"
					( Origin gFrontEnd )
				)
				( attribute "MATERIAL" "CHIP"
					( Origin gFrontEnd )
				)
				( attribute "PACK_TYPE" "0402"
					( Origin gFrontEnd )
				)
				( attribute "PART_NUMBER" "G21796-161"
					( Origin gFrontEnd )
				)
				( attribute "PHYS_PAGE" "181"
					( Origin gFrontEnd )
				)
				( attribute "ROOM" "IO_SLOT"
					( Origin gFrontEnd )
				)
				( attribute "ROT" "0"
					( Origin gFrontEnd )
				)
				( attribute "SEC" "1"
					( Origin gFrontEnd )
				)
				( attribute "SEC_TYPE" "0402"
					( Origin gFrontEnd )
				)
				( attribute "TOLERANCE" "1%"
					( Origin gFrontEnd )
				)
				( attribute "VALUE" "6.19K"
					( Origin gFrontEnd )
				)
				( attribute "VER" "2"
					( Origin gFrontEnd )
				)
				( attribute "WATTAGE" "1/16W"
					( Origin gFrontEnd )
				)
				( attribute "XY" "(1150,1550)"
					( Origin gFrontEnd )
				)
				( attribute "CHIPS_PART_NAME" "RES"
					( Origin gPackager )
				)
				( attribute "CDS_PART_NAME" "RES_0402-6.19K,1%,1/16W,CHIP,GA"
					( Origin gPackager )
				)
				( objectStatus "R9T3" )
			)
			( gate "@baseboard_fab2_lib.baseboard_fab2(sch_1):page181_i68"
				( attribute "BOM_COST" "IO_SLOT"
					( Origin gFrontEnd )
				)
				( attribute "CDS_LIB" "mstr_discrete"
					( Origin gPackager )
				)
				( attribute "CDS_LOCATION" "R9T6"
					( Origin gPackager )
				)
				( attribute "CDS_SEC" "1"
					( Origin gPackager )
				)
				( attribute "LOCATION" "R9T6"
					( Origin gFrontEnd )
				)
				( attribute "MATERIAL" "CHIP"
					( Origin gFrontEnd )
				)
				( attribute "PACK_TYPE" "0402"
					( Origin gFrontEnd )
				)
				( attribute "PART_NUMBER" "G21796-107"
					( Origin gFrontEnd )
				)
				( attribute "PHYS_PAGE" "181"
					( Origin gFrontEnd )
				)
				( attribute "ROOM" "IO_SLOT"
					( Origin gFrontEnd )
				)
				( attribute "ROT" "2"
					( Origin gFrontEnd )
				)
				( attribute "SEC" "1"
					( Origin gFrontEnd )
				)
				( attribute "SEC_TYPE" "0402"
					( Origin gFrontEnd )
				)
				( attribute "TOLERANCE" "1%"
					( Origin gFrontEnd )
				)
				( attribute "VALUE" "15.0K"
					( Origin gFrontEnd )
				)
				( attribute "VER" "2"
					( Origin gFrontEnd )
				)
				( attribute "WATTAGE" "1/16W"
					( Origin gFrontEnd )
				)
				( attribute "XY" "(1050,1900)"
					( Origin gFrontEnd )
				)
				( attribute "CHIPS_PART_NAME" "RES"
					( Origin gPackager )
				)
				( attribute "CDS_PART_NAME" "RES_0402-15.0K,1%,1/16W,CHIP,GA"
					( Origin gPackager )
				)
				( objectStatus "R9T6" )
			)
			( gate "@baseboard_fab2_lib.baseboard_fab2(sch_1):page181_i70"
				( attribute "BOM_COST" "IO_SLOT"
					( Origin gFrontEnd )
				)
				( attribute "CDS_LIB" "mstr_discrete"
					( Origin gPackager )
				)
				( attribute "CDS_LOCATION" "C1F14"
					( Origin gPackager )
				)
				( attribute "CDS_SEC" "1"
					( Origin gPackager )
				)
				( attribute "LOCATION" "C1F14"
					( Origin gFrontEnd )
				)
				( attribute "MATERIAL" "X7R"
					( Origin gFrontEnd )
				)
				( attribute "PACK_TYPE" "0402"
					( Origin gFrontEnd )
				)
				( attribute "PART_NUMBER" "A36096-155"
					( Origin gFrontEnd )
				)
				( attribute "PHYS_PAGE" "181"
					( Origin gFrontEnd )
				)
				( attribute "ROOM" "IO_SLOT"
					( Origin gFrontEnd )
				)
				( attribute "ROT" "0"
					( Origin gFrontEnd )
				)
				( attribute "SEC" "1"
					( Origin gFrontEnd )
				)
				( attribute "SEC_TYPE" "0402"
					( Origin gFrontEnd )
				)
				( attribute "TOLERANCE" "10%"
					( Origin gFrontEnd )
				)
				( attribute "VALUE" "0.22UF"
					( Origin gFrontEnd )
				)
				( attribute "VER" "2"
					( Origin gFrontEnd )
				)
				( attribute "VOLTAGE" "16V"
					( Units "uVoltage" "V" 1.000000)
					( Origin gFrontEnd )
				)
				( attribute "XY" "(1775,2550)"
					( Origin gFrontEnd )
				)
				( attribute "CHIPS_PART_NAME" "CAP"
					( Origin gPackager )
				)
				( attribute "CDS_PART_NAME" "CAP_0402-0.22UF,16V,10%,X7R,A3A"
					( Origin gPackager )
				)
				( objectStatus "C1F14" )
			)
			( gate "@baseboard_fab2_lib.baseboard_fab2(sch_1):page181_i71"
				( attribute "BOM_COST" "IO_SLOT"
					( Origin gFrontEnd )
				)
				( attribute "CDS_LIB" "mstr_discrete"
					( Origin gPackager )
				)
				( attribute "CDS_LOCATION" "C1F17"
					( Origin gPackager )
				)
				( attribute "CDS_SEC" "1"
					( Origin gPackager )
				)
				( attribute "LOCATION" "C1F17"
					( Origin gFrontEnd )
				)
				( attribute "MATERIAL" "X7R"
					( Origin gFrontEnd )
				)
				( attribute "PACK_TYPE" "0402"
					( Origin gFrontEnd )
				)
				( attribute "PART_NUMBER" "A36096-155"
					( Origin gFrontEnd )
				)
				( attribute "PHYS_PAGE" "181"
					( Origin gFrontEnd )
				)
				( attribute "ROOM" "IO_SLOT"
					( Origin gFrontEnd )
				)
				( attribute "ROT" "0"
					( Origin gFrontEnd )
				)
				( attribute "SEC" "1"
					( Origin gFrontEnd )
				)
				( attribute "SEC_TYPE" "0402"
					( Origin gFrontEnd )
				)
				( attribute "TOLERANCE" "10%"
					( Origin gFrontEnd )
				)
				( attribute "VALUE" "0.22UF"
					( Origin gFrontEnd )
				)
				( attribute "VER" "2"
					( Origin gFrontEnd )
				)
				( attribute "VOLTAGE" "16V"
					( Units "uVoltage" "V" 1.000000)
					( Origin gFrontEnd )
				)
				( attribute "XY" "(1775,2700)"
					( Origin gFrontEnd )
				)
				( attribute "CHIPS_PART_NAME" "CAP"
					( Origin gPackager )
				)
				( attribute "CDS_PART_NAME" "CAP_0402-0.22UF,16V,10%,X7R,A3A"
					( Origin gPackager )
				)
				( objectStatus "C1F17" )
			)
			( gate "@baseboard_fab2_lib.baseboard_fab2(sch_1):page181_i72"
				( attribute "BOM_COST" "IO_SLOT"
					( Origin gFrontEnd )
				)
				( attribute "CDS_LIB" "mstr_discrete"
					( Origin gPackager )
				)
				( attribute "CDS_LOCATION" "C1F18"
					( Origin gPackager )
				)
				( attribute "CDS_SEC" "1"
					( Origin gPackager )
				)
				( attribute "LOCATION" "C1F18"
					( Origin gFrontEnd )
				)
				( attribute "MATERIAL" "X7R"
					( Origin gFrontEnd )
				)
				( attribute "PACK_TYPE" "0402"
					( Origin gFrontEnd )
				)
				( attribute "PART_NUMBER" "A36096-155"
					( Origin gFrontEnd )
				)
				( attribute "PHYS_PAGE" "181"
					( Origin gFrontEnd )
				)
				( attribute "ROOM" "IO_SLOT"
					( Origin gFrontEnd )
				)
				( attribute "ROT" "0"
					( Origin gFrontEnd )
				)
				( attribute "SEC" "1"
					( Origin gFrontEnd )
				)
				( attribute "SEC_TYPE" "0402"
					( Origin gFrontEnd )
				)
				( attribute "TOLERANCE" "10%"
					( Origin gFrontEnd )
				)
				( attribute "VALUE" "0.22UF"
					( Origin gFrontEnd )
				)
				( attribute "VER" "2"
					( Origin gFrontEnd )
				)
				( attribute "VOLTAGE" "16V"
					( Units "uVoltage" "V" 1.000000)
					( Origin gFrontEnd )
				)
				( attribute "XY" "(1775,2850)"
					( Origin gFrontEnd )
				)
				( attribute "CHIPS_PART_NAME" "CAP"
					( Origin gPackager )
				)
				( attribute "CDS_PART_NAME" "CAP_0402-0.22UF,16V,10%,X7R,A3A"
					( Origin gPackager )
				)
				( objectStatus "C1F18" )
			)
			( gate "@baseboard_fab2_lib.baseboard_fab2(sch_1):page181_i73"
				( attribute "BOM_COST" "IO_SLOT"
					( Origin gFrontEnd )
				)
				( attribute "CDS_LIB" "mstr_discrete"
					( Origin gPackager )
				)
				( attribute "CDS_LOCATION" "C1F8"
					( Origin gPackager )
				)
				( attribute "CDS_SEC" "1"
					( Origin gPackager )
				)
				( attribute "LOCATION" "C1F8"
					( Origin gFrontEnd )
				)
				( attribute "MATERIAL" "X7R"
					( Origin gFrontEnd )
				)
				( attribute "PACK_TYPE" "0402"
					( Origin gFrontEnd )
				)
				( attribute "PART_NUMBER" "A36096-155"
					( Origin gFrontEnd )
				)
				( attribute "PHYS_PAGE" "181"
					( Origin gFrontEnd )
				)
				( attribute "ROOM" "IO_SLOT"
					( Origin gFrontEnd )
				)
				( attribute "ROT" "0"
					( Origin gFrontEnd )
				)
				( attribute "SEC" "1"
					( Origin gFrontEnd )
				)
				( attribute "SEC_TYPE" "0402"
					( Origin gFrontEnd )
				)
				( attribute "TOLERANCE" "10%"
					( Origin gFrontEnd )
				)
				( attribute "VALUE" "0.22UF"
					( Origin gFrontEnd )
				)
				( attribute "VER" "2"
					( Origin gFrontEnd )
				)
				( attribute "VOLTAGE" "16V"
					( Units "uVoltage" "V" 1.000000)
					( Origin gFrontEnd )
				)
				( attribute "XY" "(1825,3100)"
					( Origin gFrontEnd )
				)
				( attribute "CHIPS_PART_NAME" "CAP"
					( Origin gPackager )
				)
				( attribute "CDS_PART_NAME" "CAP_0402-0.22UF,16V,10%,X7R,A3A"
					( Origin gPackager )
				)
				( objectStatus "C1F8" )
			)
			( gate "@baseboard_fab2_lib.baseboard_fab2(sch_1):page181_i74"
				( attribute "BOM_COST" "IO_SLOT"
					( Origin gFrontEnd )
				)
				( attribute "CDS_LIB" "mstr_discrete"
					( Origin gPackager )
				)
				( attribute "CDS_LOCATION" "C1F11"
					( Origin gPackager )
				)
				( attribute "CDS_SEC" "1"
					( Origin gPackager )
				)
				( attribute "LOCATION" "C1F11"
					( Origin gFrontEnd )
				)
				( attribute "MATERIAL" "X7R"
					( Origin gFrontEnd )
				)
				( attribute "PACK_TYPE" "0402"
					( Origin gFrontEnd )
				)
				( attribute "PART_NUMBER" "A36096-155"
					( Origin gFrontEnd )
				)
				( attribute "PHYS_PAGE" "181"
					( Origin gFrontEnd )
				)
				( attribute "ROOM" "IO_SLOT"
					( Origin gFrontEnd )
				)
				( attribute "ROT" "0"
					( Origin gFrontEnd )
				)
				( attribute "SEC" "1"
					( Origin gFrontEnd )
				)
				( attribute "SEC_TYPE" "0402"
					( Origin gFrontEnd )
				)
				( attribute "TOLERANCE" "10%"
					( Origin gFrontEnd )
				)
				( attribute "VALUE" "0.22UF"
					( Origin gFrontEnd )
				)
				( attribute "VER" "2"
					( Origin gFrontEnd )
				)
				( attribute "VOLTAGE" "16V"
					( Units "uVoltage" "V" 1.000000)
					( Origin gFrontEnd )
				)
				( attribute "XY" "(1825,3250)"
					( Origin gFrontEnd )
				)
				( attribute "CHIPS_PART_NAME" "CAP"
					( Origin gPackager )
				)
				( attribute "CDS_PART_NAME" "CAP_0402-0.22UF,16V,10%,X7R,A3A"
					( Origin gPackager )
				)
				( objectStatus "C1F11" )
			)
			( gate "@baseboard_fab2_lib.baseboard_fab2(sch_1):page181_i75"
				( attribute "BOM_COST" "IO_SLOT"
					( Origin gFrontEnd )
				)
				( attribute "CDS_LIB" "mstr_discrete"
					( Origin gPackager )
				)
				( attribute "CDS_LOCATION" "C1F12"
					( Origin gPackager )
				)
				( attribute "CDS_SEC" "1"
					( Origin gPackager )
				)
				( attribute "LOCATION" "C1F12"
					( Origin gFrontEnd )
				)
				( attribute "MATERIAL" "X7R"
					( Origin gFrontEnd )
				)
				( attribute "PACK_TYPE" "0402"
					( Origin gFrontEnd )
				)
				( attribute "PART_NUMBER" "A36096-155"
					( Origin gFrontEnd )
				)
				( attribute "PHYS_PAGE" "181"
					( Origin gFrontEnd )
				)
				( attribute "ROOM" "IO_SLOT"
					( Origin gFrontEnd )
				)
				( attribute "ROT" "0"
					( Origin gFrontEnd )
				)
				( attribute "SEC" "1"
					( Origin gFrontEnd )
				)
				( attribute "SEC_TYPE" "0402"
					( Origin gFrontEnd )
				)
				( attribute "TOLERANCE" "10%"
					( Origin gFrontEnd )
				)
				( attribute "VALUE" "0.22UF"
					( Origin gFrontEnd )
				)
				( attribute "VER" "2"
					( Origin gFrontEnd )
				)
				( attribute "VOLTAGE" "16V"
					( Units "uVoltage" "V" 1.000000)
					( Origin gFrontEnd )
				)
				( attribute "XY" "(1825,3400)"
					( Origin gFrontEnd )
				)
				( attribute "CHIPS_PART_NAME" "CAP"
					( Origin gPackager )
				)
				( attribute "CDS_PART_NAME" "CAP_0402-0.22UF,16V,10%,X7R,A3A"
					( Origin gPackager )
				)
				( objectStatus "C1F12" )
			)
			( gate "@baseboard_fab2_lib.baseboard_fab2(sch_1):page181_i76"
				( attribute "BOM_COST" "IO_SLOT"
					( Origin gFrontEnd )
				)
				( attribute "CDS_LIB" "mstr_discrete"
					( Origin gPackager )
				)
				( attribute "CDS_LOCATION" "C1F3"
					( Origin gPackager )
				)
				( attribute "CDS_SEC" "1"
					( Origin gPackager )
				)
				( attribute "LOCATION" "C1F3"
					( Origin gFrontEnd )
				)
				( attribute "MATERIAL" "X7R"
					( Origin gFrontEnd )
				)
				( attribute "PACK_TYPE" "0402"
					( Origin gFrontEnd )
				)
				( attribute "PART_NUMBER" "A36096-155"
					( Origin gFrontEnd )
				)
				( attribute "PHYS_PAGE" "181"
					( Origin gFrontEnd )
				)
				( attribute "ROOM" "IO_SLOT"
					( Origin gFrontEnd )
				)
				( attribute "ROT" "0"
					( Origin gFrontEnd )
				)
				( attribute "SEC" "1"
					( Origin gFrontEnd )
				)
				( attribute "SEC_TYPE" "0402"
					( Origin gFrontEnd )
				)
				( attribute "TOLERANCE" "10%"
					( Origin gFrontEnd )
				)
				( attribute "VALUE" "0.22UF"
					( Origin gFrontEnd )
				)
				( attribute "VER" "2"
					( Origin gFrontEnd )
				)
				( attribute "VOLTAGE" "16V"
					( Units "uVoltage" "V" 1.000000)
					( Origin gFrontEnd )
				)
				( attribute "XY" "(1825,3600)"
					( Origin gFrontEnd )
				)
				( attribute "CHIPS_PART_NAME" "CAP"
					( Origin gPackager )
				)
				( attribute "CDS_PART_NAME" "CAP_0402-0.22UF,16V,10%,X7R,A3A"
					( Origin gPackager )
				)
				( objectStatus "C1F3" )
			)
			( gate "@baseboard_fab2_lib.baseboard_fab2(sch_1):page181_i77"
				( attribute "BOM_COST" "IO_SLOT"
					( Origin gFrontEnd )
				)
				( attribute "CDS_LIB" "mstr_discrete"
					( Origin gPackager )
				)
				( attribute "CDS_LOCATION" "C1F5"
					( Origin gPackager )
				)
				( attribute "CDS_SEC" "1"
					( Origin gPackager )
				)
				( attribute "LOCATION" "C1F5"
					( Origin gFrontEnd )
				)
				( attribute "MATERIAL" "X7R"
					( Origin gFrontEnd )
				)
				( attribute "PACK_TYPE" "0402"
					( Origin gFrontEnd )
				)
				( attribute "PART_NUMBER" "A36096-155"
					( Origin gFrontEnd )
				)
				( attribute "PHYS_PAGE" "181"
					( Origin gFrontEnd )
				)
				( attribute "ROOM" "IO_SLOT"
					( Origin gFrontEnd )
				)
				( attribute "ROT" "0"
					( Origin gFrontEnd )
				)
				( attribute "SEC" "1"
					( Origin gFrontEnd )
				)
				( attribute "SEC_TYPE" "0402"
					( Origin gFrontEnd )
				)
				( attribute "TOLERANCE" "10%"
					( Origin gFrontEnd )
				)
				( attribute "VALUE" "0.22UF"
					( Origin gFrontEnd )
				)
				( attribute "VER" "2"
					( Origin gFrontEnd )
				)
				( attribute "VOLTAGE" "16V"
					( Units "uVoltage" "V" 1.000000)
					( Origin gFrontEnd )
				)
				( attribute "XY" "(1825,3750)"
					( Origin gFrontEnd )
				)
				( attribute "CHIPS_PART_NAME" "CAP"
					( Origin gPackager )
				)
				( attribute "CDS_PART_NAME" "CAP_0402-0.22UF,16V,10%,X7R,A3A"
					( Origin gPackager )
				)
				( objectStatus "C1F5" )
			)
			( gate "@baseboard_fab2_lib.baseboard_fab2(sch_1):page181_i78"
				( attribute "BOM_COST" "IO_SLOT"
					( Origin gFrontEnd )
				)
				( attribute "CDS_LIB" "mstr_discrete"
					( Origin gPackager )
				)
				( attribute "CDS_LOCATION" "C1F15"
					( Origin gPackager )
				)
				( attribute "CDS_SEC" "1"
					( Origin gPackager )
				)
				( attribute "LOCATION" "C1F15"
					( Origin gFrontEnd )
				)
				( attribute "MATERIAL" "X7R"
					( Origin gFrontEnd )
				)
				( attribute "PACK_TYPE" "0402"
					( Origin gFrontEnd )
				)
				( attribute "PART_NUMBER" "A36096-155"
					( Origin gFrontEnd )
				)
				( attribute "PHYS_PAGE" "181"
					( Origin gFrontEnd )
				)
				( attribute "ROOM" "IO_SLOT"
					( Origin gFrontEnd )
				)
				( attribute "ROT" "0"
					( Origin gFrontEnd )
				)
				( attribute "SEC" "1"
					( Origin gFrontEnd )
				)
				( attribute "SEC_TYPE" "0402"
					( Origin gFrontEnd )
				)
				( attribute "TOLERANCE" "10%"
					( Origin gFrontEnd )
				)
				( attribute "VALUE" "0.22UF"
					( Origin gFrontEnd )
				)
				( attribute "VER" "2"
					( Origin gFrontEnd )
				)
				( attribute "VOLTAGE" "16V"
					( Units "uVoltage" "V" 1.000000)
					( Origin gFrontEnd )
				)
				( attribute "XY" "(2275,2600)"
					( Origin gFrontEnd )
				)
				( attribute "CHIPS_PART_NAME" "CAP"
					( Origin gPackager )
				)
				( attribute "CDS_PART_NAME" "CAP_0402-0.22UF,16V,10%,X7R,A3A"
					( Origin gPackager )
				)
				( objectStatus "C1F15" )
			)
			( gate "@baseboard_fab2_lib.baseboard_fab2(sch_1):page181_i79"
				( attribute "BOM_COST" "IO_SLOT"
					( Origin gFrontEnd )
				)
				( attribute "CDS_LIB" "mstr_discrete"
					( Origin gPackager )
				)
				( attribute "CDS_LOCATION" "C1F16"
					( Origin gPackager )
				)
				( attribute "CDS_SEC" "1"
					( Origin gPackager )
				)
				( attribute "LOCATION" "C1F16"
					( Origin gFrontEnd )
				)
				( attribute "MATERIAL" "X7R"
					( Origin gFrontEnd )
				)
				( attribute "PACK_TYPE" "0402"
					( Origin gFrontEnd )
				)
				( attribute "PART_NUMBER" "A36096-155"
					( Origin gFrontEnd )
				)
				( attribute "PHYS_PAGE" "181"
					( Origin gFrontEnd )
				)
				( attribute "ROOM" "IO_SLOT"
					( Origin gFrontEnd )
				)
				( attribute "ROT" "0"
					( Origin gFrontEnd )
				)
				( attribute "SEC" "1"
					( Origin gFrontEnd )
				)
				( attribute "SEC_TYPE" "0402"
					( Origin gFrontEnd )
				)
				( attribute "TOLERANCE" "10%"
					( Origin gFrontEnd )
				)
				( attribute "VALUE" "0.22UF"
					( Origin gFrontEnd )
				)
				( attribute "VER" "2"
					( Origin gFrontEnd )
				)
				( attribute "VOLTAGE" "16V"
					( Units "uVoltage" "V" 1.000000)
					( Origin gFrontEnd )
				)
				( attribute "XY" "(2275,2750)"
					( Origin gFrontEnd )
				)
				( attribute "CHIPS_PART_NAME" "CAP"
					( Origin gPackager )
				)
				( attribute "CDS_PART_NAME" "CAP_0402-0.22UF,16V,10%,X7R,A3A"
					( Origin gPackager )
				)
				( objectStatus "C1F16" )
			)
			( gate "@baseboard_fab2_lib.baseboard_fab2(sch_1):page181_i80"
				( attribute "CDS_LIB" "mstr_discrete"
					( Origin gPackager )
				)
				( attribute "CDS_LOCATION" "R7D9"
					( Origin gPackager )
				)
				( attribute "CDS_SEC" "1"
					( Origin gPackager )
				)
				( attribute "LOCATION" "R7D9"
					( Origin gFrontEnd )
				)
				( attribute "MATERIAL" "CHIP"
					( Origin gFrontEnd )
				)
				( attribute "PACK_TYPE" "0402"
					( Origin gFrontEnd )
				)
				( attribute "PART_NUMBER" "G21796-311"
					( Origin gFrontEnd )
				)
				( attribute "PHYS_PAGE" "181"
					( Origin gFrontEnd )
				)
				( attribute "ROOM" "IO_SLOT"
					( Origin gFrontEnd )
				)
				( attribute "ROT" "0"
					( Origin gFrontEnd )
				)
				( attribute "SEC" "1"
					( Origin gFrontEnd )
				)
				( attribute "SEC_TYPE" "0402"
					( Origin gFrontEnd )
				)
				( attribute "TOLERANCE" "1.0%"
					( Origin gFrontEnd )
				)
				( attribute "VALUE" "2.26K"
					( Origin gFrontEnd )
				)
				( attribute "VER" "1"
					( Origin gFrontEnd )
				)
				( attribute "WATTAGE" "1/16W"
					( Origin gFrontEnd )
				)
				( attribute "XY" "(2650,2050)"
					( Origin gFrontEnd )
				)
				( attribute "CHIPS_PART_NAME" "RES"
					( Origin gPackager )
				)
				( attribute "CDS_PART_NAME" "RES_0402-2.26K,1.0%,1/16W,CHIPA"
					( Origin gPackager )
				)
				( objectStatus "R7D9" )
			)
			( gate "@baseboard_fab2_lib.baseboard_fab2(sch_1):page181_i81"
				( attribute "CDS_LIB" "mstr_discrete"
					( Origin gPackager )
				)
				( attribute "CDS_LOCATION" "R3P61"
					( Origin gPackager )
				)
				( attribute "CDS_SEC" "1"
					( Origin gPackager )
				)
				( attribute "LOCATION" "R3P61"
					( Origin gFrontEnd )
				)
				( attribute "MATERIAL" "CHIP"
					( Origin gFrontEnd )
				)
				( attribute "PACK_TYPE" "0402"
					( Origin gFrontEnd )
				)
				( attribute "PART_NUMBER" "G21796-311"
					( Origin gFrontEnd )
				)
				( attribute "PHYS_PAGE" "181"
					( Origin gFrontEnd )
				)
				( attribute "ROOM" "IO_SLOT"
					( Origin gFrontEnd )
				)
				( attribute "ROT" "0"
					( Origin gFrontEnd )
				)
				( attribute "SEC" "1"
					( Origin gFrontEnd )
				)
				( attribute "SEC_TYPE" "0402"
					( Origin gFrontEnd )
				)
				( attribute "TOLERANCE" "1.0%"
					( Origin gFrontEnd )
				)
				( attribute "VALUE" "2.26K"
					( Origin gFrontEnd )
				)
				( attribute "VER" "1"
					( Origin gFrontEnd )
				)
				( attribute "WATTAGE" "1/16W"
					( Origin gFrontEnd )
				)
				( attribute "XY" "(2650,1875)"
					( Origin gFrontEnd )
				)
				( attribute "CHIPS_PART_NAME" "RES"
					( Origin gPackager )
				)
				( attribute "CDS_PART_NAME" "RES_0402-2.26K,1.0%,1/16W,CHIPA"
					( Origin gPackager )
				)
				( objectStatus "R3P61" )
			)
			( gate "@baseboard_fab2_lib.baseboard_fab2(sch_1):page181_i82"
				( attribute "CDS_LIB" "mstr_discrete"
					( Origin gPackager )
				)
				( attribute "CDS_LOCATION" "R7D5"
					( Origin gPackager )
				)
				( attribute "CDS_SEC" "1"
					( Origin gPackager )
				)
				( attribute "LOCATION" "R7D5"
					( Origin gFrontEnd )
				)
				( attribute "MATERIAL" "CHIP"
					( Origin gFrontEnd )
				)
				( attribute "PACK_TYPE" "0402"
					( Origin gFrontEnd )
				)
				( attribute "PART_NUMBER" "G21796-311"
					( Origin gFrontEnd )
				)
				( attribute "PHYS_PAGE" "181"
					( Origin gFrontEnd )
				)
				( attribute "ROOM" "IO_SLOT"
					( Origin gFrontEnd )
				)
				( attribute "ROT" "0"
					( Origin gFrontEnd )
				)
				( attribute "SEC" "1"
					( Origin gFrontEnd )
				)
				( attribute "SEC_TYPE" "0402"
					( Origin gFrontEnd )
				)
				( attribute "TOLERANCE" "1.0%"
					( Origin gFrontEnd )
				)
				( attribute "VALUE" "2.26K"
					( Origin gFrontEnd )
				)
				( attribute "VER" "1"
					( Origin gFrontEnd )
				)
				( attribute "WATTAGE" "1/16W"
					( Origin gFrontEnd )
				)
				( attribute "XY" "(2650,2225)"
					( Origin gFrontEnd )
				)
				( attribute "CHIPS_PART_NAME" "RES"
					( Origin gPackager )
				)
				( attribute "CDS_PART_NAME" "RES_0402-2.26K,1.0%,1/16W,CHIPA"
					( Origin gPackager )
				)
				( objectStatus "R7D5" )
			)
			( gate "@baseboard_fab2_lib.baseboard_fab2(sch_1):page181_i86"
				( attribute "BOM_COST" "IO_SLOT"
					( Origin gFrontEnd )
				)
				( attribute "CDS_LIB" "mstr_discrete"
					( Origin gPackager )
				)
				( attribute "CDS_LOCATION" "C1F20"
					( Origin gPackager )
				)
				( attribute "CDS_SEC" "1"
					( Origin gPackager )
				)
				( attribute "LOCATION" "C1F20"
					( Origin gFrontEnd )
				)
				( attribute "MATERIAL" "X7R"
					( Origin gFrontEnd )
				)
				( attribute "PACK_TYPE" "0402"
					( Origin gFrontEnd )
				)
				( attribute "PART_NUMBER" "A36096-155"
					( Origin gFrontEnd )
				)
				( attribute "PHYS_PAGE" "181"
					( Origin gFrontEnd )
				)
				( attribute "ROOM" "IO_SLOT"
					( Origin gFrontEnd )
				)
				( attribute "ROT" "0"
					( Origin gFrontEnd )
				)
				( attribute "SEC" "1"
					( Origin gFrontEnd )
				)
				( attribute "SEC_TYPE" "0402"
					( Origin gFrontEnd )
				)
				( attribute "TOLERANCE" "10%"
					( Origin gFrontEnd )
				)
				( attribute "VALUE" "0.22UF"
					( Origin gFrontEnd )
				)
				( attribute "VER" "2"
					( Origin gFrontEnd )
				)
				( attribute "VOLTAGE" "16V"
					( Units "uVoltage" "V" 1.000000)
					( Origin gFrontEnd )
				)
				( attribute "XY" "(2275,2900)"
					( Origin gFrontEnd )
				)
				( attribute "CHIPS_PART_NAME" "CAP"
					( Origin gPackager )
				)
				( attribute "CDS_PART_NAME" "CAP_0402-0.22UF,16V,10%,X7R,A3A"
					( Origin gPackager )
				)
				( objectStatus "C1F20" )
			)
			( gate "@baseboard_fab2_lib.baseboard_fab2(sch_1):page181_i87"
				( attribute "BOM_COST" "IO_SLOT"
					( Origin gFrontEnd )
				)
				( attribute "CDS_LIB" "mstr_discrete"
					( Origin gPackager )
				)
				( attribute "CDS_LOCATION" "C1F10"
					( Origin gPackager )
				)
				( attribute "CDS_SEC" "1"
					( Origin gPackager )
				)
				( attribute "LOCATION" "C1F10"
					( Origin gFrontEnd )
				)
				( attribute "MATERIAL" "X7R"
					( Origin gFrontEnd )
				)
				( attribute "PACK_TYPE" "0402"
					( Origin gFrontEnd )
				)
				( attribute "PART_NUMBER" "A36096-155"
					( Origin gFrontEnd )
				)
				( attribute "PHYS_PAGE" "181"
					( Origin gFrontEnd )
				)
				( attribute "ROOM" "IO_SLOT"
					( Origin gFrontEnd )
				)
				( attribute "ROT" "0"
					( Origin gFrontEnd )
				)
				( attribute "SEC" "1"
					( Origin gFrontEnd )
				)
				( attribute "SEC_TYPE" "0402"
					( Origin gFrontEnd )
				)
				( attribute "TOLERANCE" "10%"
					( Origin gFrontEnd )
				)
				( attribute "VALUE" "0.22UF"
					( Origin gFrontEnd )
				)
				( attribute "VER" "2"
					( Origin gFrontEnd )
				)
				( attribute "VOLTAGE" "16V"
					( Units "uVoltage" "V" 1.000000)
					( Origin gFrontEnd )
				)
				( attribute "XY" "(2275,3300)"
					( Origin gFrontEnd )
				)
				( attribute "CHIPS_PART_NAME" "CAP"
					( Origin gPackager )
				)
				( attribute "CDS_PART_NAME" "CAP_0402-0.22UF,16V,10%,X7R,A3A"
					( Origin gPackager )
				)
				( objectStatus "C1F10" )
			)
			( gate "@baseboard_fab2_lib.baseboard_fab2(sch_1):page181_i88"
				( attribute "BOM_COST" "IO_SLOT"
					( Origin gFrontEnd )
				)
				( attribute "CDS_LIB" "mstr_discrete"
					( Origin gPackager )
				)
				( attribute "CDS_LOCATION" "C1F6"
					( Origin gPackager )
				)
				( attribute "CDS_SEC" "1"
					( Origin gPackager )
				)
				( attribute "LOCATION" "C1F6"
					( Origin gFrontEnd )
				)
				( attribute "MATERIAL" "X7R"
					( Origin gFrontEnd )
				)
				( attribute "PACK_TYPE" "0402"
					( Origin gFrontEnd )
				)
				( attribute "PART_NUMBER" "A36096-155"
					( Origin gFrontEnd )
				)
				( attribute "PHYS_PAGE" "181"
					( Origin gFrontEnd )
				)
				( attribute "ROOM" "IO_SLOT"
					( Origin gFrontEnd )
				)
				( attribute "ROT" "0"
					( Origin gFrontEnd )
				)
				( attribute "SEC" "1"
					( Origin gFrontEnd )
				)
				( attribute "SEC_TYPE" "0402"
					( Origin gFrontEnd )
				)
				( attribute "TOLERANCE" "10%"
					( Origin gFrontEnd )
				)
				( attribute "VALUE" "0.22UF"
					( Origin gFrontEnd )
				)
				( attribute "VER" "2"
					( Origin gFrontEnd )
				)
				( attribute "VOLTAGE" "16V"
					( Units "uVoltage" "V" 1.000000)
					( Origin gFrontEnd )
				)
				( attribute "XY" "(2275,3150)"
					( Origin gFrontEnd )
				)
				( attribute "CHIPS_PART_NAME" "CAP"
					( Origin gPackager )
				)
				( attribute "CDS_PART_NAME" "CAP_0402-0.22UF,16V,10%,X7R,A3A"
					( Origin gPackager )
				)
				( objectStatus "C1F6" )
			)
			( gate "@baseboard_fab2_lib.baseboard_fab2(sch_1):page181_i89"
				( attribute "BOM_COST" "IO_SLOT"
					( Origin gFrontEnd )
				)
				( attribute "CDS_LIB" "mstr_discrete"
					( Origin gPackager )
				)
				( attribute "CDS_LOCATION" "C1F13"
					( Origin gPackager )
				)
				( attribute "CDS_SEC" "1"
					( Origin gPackager )
				)
				( attribute "LOCATION" "C1F13"
					( Origin gFrontEnd )
				)
				( attribute "MATERIAL" "X7R"
					( Origin gFrontEnd )
				)
				( attribute "PACK_TYPE" "0402"
					( Origin gFrontEnd )
				)
				( attribute "PART_NUMBER" "A36096-155"
					( Origin gFrontEnd )
				)
				( attribute "PHYS_PAGE" "181"
					( Origin gFrontEnd )
				)
				( attribute "ROOM" "IO_SLOT"
					( Origin gFrontEnd )
				)
				( attribute "ROT" "0"
					( Origin gFrontEnd )
				)
				( attribute "SEC" "1"
					( Origin gFrontEnd )
				)
				( attribute "SEC_TYPE" "0402"
					( Origin gFrontEnd )
				)
				( attribute "TOLERANCE" "10%"
					( Origin gFrontEnd )
				)
				( attribute "VALUE" "0.22UF"
					( Origin gFrontEnd )
				)
				( attribute "VER" "2"
					( Origin gFrontEnd )
				)
				( attribute "VOLTAGE" "16V"
					( Units "uVoltage" "V" 1.000000)
					( Origin gFrontEnd )
				)
				( attribute "XY" "(2250,3450)"
					( Origin gFrontEnd )
				)
				( attribute "CHIPS_PART_NAME" "CAP"
					( Origin gPackager )
				)
				( attribute "CDS_PART_NAME" "CAP_0402-0.22UF,16V,10%,X7R,A3A"
					( Origin gPackager )
				)
				( objectStatus "C1F13" )
			)
			( gate "@baseboard_fab2_lib.baseboard_fab2(sch_1):page181_i90"
				( attribute "BOM_COST" "IO_SLOT"
					( Origin gFrontEnd )
				)
				( attribute "CDS_LIB" "mstr_discrete"
					( Origin gPackager )
				)
				( attribute "CDS_LOCATION" "C1F2"
					( Origin gPackager )
				)
				( attribute "CDS_SEC" "1"
					( Origin gPackager )
				)
				( attribute "LOCATION" "C1F2"
					( Origin gFrontEnd )
				)
				( attribute "MATERIAL" "X7R"
					( Origin gFrontEnd )
				)
				( attribute "PACK_TYPE" "0402"
					( Origin gFrontEnd )
				)
				( attribute "PART_NUMBER" "A36096-155"
					( Origin gFrontEnd )
				)
				( attribute "PHYS_PAGE" "181"
					( Origin gFrontEnd )
				)
				( attribute "ROOM" "IO_SLOT"
					( Origin gFrontEnd )
				)
				( attribute "ROT" "0"
					( Origin gFrontEnd )
				)
				( attribute "SEC" "1"
					( Origin gFrontEnd )
				)
				( attribute "SEC_TYPE" "0402"
					( Origin gFrontEnd )
				)
				( attribute "TOLERANCE" "10%"
					( Origin gFrontEnd )
				)
				( attribute "VALUE" "0.22UF"
					( Origin gFrontEnd )
				)
				( attribute "VER" "2"
					( Origin gFrontEnd )
				)
				( attribute "VOLTAGE" "16V"
					( Units "uVoltage" "V" 1.000000)
					( Origin gFrontEnd )
				)
				( attribute "XY" "(2250,3650)"
					( Origin gFrontEnd )
				)
				( attribute "CHIPS_PART_NAME" "CAP"
					( Origin gPackager )
				)
				( attribute "CDS_PART_NAME" "CAP_0402-0.22UF,16V,10%,X7R,A3A"
					( Origin gPackager )
				)
				( objectStatus "C1F2" )
			)
			( gate "@baseboard_fab2_lib.baseboard_fab2(sch_1):page181_i91"
				( attribute "BOM_COST" "IO_SLOT"
					( Origin gFrontEnd )
				)
				( attribute "CDS_LIB" "mstr_discrete"
					( Origin gPackager )
				)
				( attribute "CDS_LOCATION" "C1F4"
					( Origin gPackager )
				)
				( attribute "CDS_SEC" "1"
					( Origin gPackager )
				)
				( attribute "LOCATION" "C1F4"
					( Origin gFrontEnd )
				)
				( attribute "MATERIAL" "X7R"
					( Origin gFrontEnd )
				)
				( attribute "PACK_TYPE" "0402"
					( Origin gFrontEnd )
				)
				( attribute "PART_NUMBER" "A36096-155"
					( Origin gFrontEnd )
				)
				( attribute "PHYS_PAGE" "181"
					( Origin gFrontEnd )
				)
				( attribute "ROOM" "IO_SLOT"
					( Origin gFrontEnd )
				)
				( attribute "ROT" "0"
					( Origin gFrontEnd )
				)
				( attribute "SEC" "1"
					( Origin gFrontEnd )
				)
				( attribute "SEC_TYPE" "0402"
					( Origin gFrontEnd )
				)
				( attribute "TOLERANCE" "10%"
					( Origin gFrontEnd )
				)
				( attribute "VALUE" "0.22UF"
					( Origin gFrontEnd )
				)
				( attribute "VER" "2"
					( Origin gFrontEnd )
				)
				( attribute "VOLTAGE" "16V"
					( Units "uVoltage" "V" 1.000000)
					( Origin gFrontEnd )
				)
				( attribute "XY" "(2250,3800)"
					( Origin gFrontEnd )
				)
				( attribute "CHIPS_PART_NAME" "CAP"
					( Origin gPackager )
				)
				( attribute "CDS_PART_NAME" "CAP_0402-0.22UF,16V,10%,X7R,A3A"
					( Origin gPackager )
				)
				( objectStatus "C1F4" )
			)
			( gate "@baseboard_fab2_lib.baseboard_fab2(sch_1):page181_i106"
				( attribute "CDS_LIB" "mstr_conn"
					( Origin gPackager )
				)
				( attribute "CDS_LOCATION" "J1F3"
					( Origin gPackager )
				)
				( attribute "CDS_SEC" "1"
					( Origin gPackager )
				)
				( attribute "LOCATION" "J1F3"
					( Origin gFrontEnd )
				)
				( attribute "MATERIAL" "CONN"
					( Origin gFrontEnd )
				)
				( attribute "PACK_TYPE" "PIP"
					( Origin gFrontEnd )
				)
				( attribute "PART_NUMBER" "H62179-001"
					( Origin gFrontEnd )
				)
				( attribute "PHYS_PAGE" "181"
					( Origin gFrontEnd )
				)
				( attribute "ROOM" "IO_SLOT"
					( Origin gFrontEnd )
				)
				( attribute "ROT" "0"
					( Origin gFrontEnd )
				)
				( attribute "SEC" "1"
					( Origin gPackager )
				)
				( attribute "VER" "1"
					( Origin gFrontEnd )
				)
				( attribute "XY" "(4100,1250)"
					( Origin gFrontEnd )
				)
				( attribute "CHIPS_PART_NAME" "CONN8_H62179001"
					( Origin gPackager )
				)
				( attribute "CDS_PART_NAME" "CONN8_H62179001_PIP-CONN,H6217A"
					( Origin gPackager )
				)
				( attribute "POP" "NOPOP"
					( Origin gFrontEnd )
				)
				( objectStatus "J1F3" )
			)
			( gate "@baseboard_fab2_lib.baseboard_fab2(sch_1):page182_i79"
				( attribute "CDS_LIB" "w_hdl"
					( Origin gPackager )
				)
				( attribute "CDS_LMAN_SYM_OUTLINE" "-475,1225,475,-1225"
					( Origin gPackager )
				)
				( attribute "LOCATION" "J1C1"
					( Origin gFrontEnd )
				)
				( attribute "PACK_TYPE" "CONN-G4"
					( Origin gFrontEnd )
				)
				( attribute "PART_NUMBER" "ZZ.82092.07601"
					( Origin gFrontEnd )
				)
				( attribute "PHYS_PAGE" "182"
					( Origin gFrontEnd )
				)
				( attribute "ROT" "0"
					( Origin gFrontEnd )
				)
				( attribute "SEC" "1"
					( Origin gFrontEnd )
				)
				( attribute "SEC_TYPE" "CONN-G4"
					( Origin gFrontEnd )
				)
				( attribute "VALUE" "DM-FCI-CONN76-8R-GP-U-01"
					( Origin gFrontEnd )
				)
				( attribute "VER" "1"
					( Origin gFrontEnd )
				)
				( attribute "XY" "(-5000,2050)"
					( Origin gFrontEnd )
				)
				( attribute "CHIPS_PART_NAME" "DM-FCI-CONN76-8R-GP-U-01"
					( Origin gPackager )
				)
				( attribute "CDS_PART_NAME" "DM-FCI-CONN76-8R-GP-U-01_CONN-A"
					( Origin gPackager )
				)
				( attribute "CDS_LOCATION" "J1C1"
					( Origin gPackager )
				)
				( attribute "CDS_SEC" "1"
					( Origin gPackager )
				)
				( attribute "NEW_PN" "20.82092.076"
					( Origin gFrontEnd )
				)
				( attribute "CONFIG" "H22707-001"
					( Origin gFrontEnd )
				)
				( objectStatus "J1C1" )
			)
			( gate "@baseboard_fab2_lib.baseboard_fab2(sch_1):page241_i100"
				( attribute "CDS_LIB" "w_hdl"
					( Origin gPackager )
				)
				( attribute "CDS_LMAN_SYM_OUTLINE" "-50,25,50,-25"
					( Origin gPackager )
				)
				( attribute "LOCATION" "C8E4"
					( Origin gFrontEnd )
				)
				( attribute "PACK_TYPE" "SMD-TCG"
					( Origin gFrontEnd )
				)
				( attribute "PART_NUMBER" "77.22271.L03"
					( Origin gFrontEnd )
				)
				( attribute "PHYS_PAGE" "241"
					( Origin gFrontEnd )
				)
				( attribute "ROT" "0"
					( Origin gFrontEnd )
				)
				( attribute "SEC" "1"
					( Origin gFrontEnd )
				)
				( attribute "SEC_TYPE" "SMD-TCG"
					( Origin gFrontEnd )
				)
				( attribute "VALUE" "ST220U10VDM-LGP"
					( Origin gFrontEnd )
				)
				( attribute "VER" "1"
					( Origin gFrontEnd )
				)
				( attribute "XY" "(2850,3825)"
					( Origin gFrontEnd )
				)
				( attribute "CHIPS_PART_NAME" "ST220U10VDM-LGP"
					( Origin gPackager )
				)
				( attribute "CDS_PART_NAME" "ST220U10VDM-LGP_SMD-TCG-ST220UA"
					( Origin gPackager )
				)
				( attribute "CDS_LOCATION" "C8E4"
					( Origin gPackager )
				)
				( attribute "CDS_SEC" "1"
					( Origin gPackager )
				)
				( attribute "ATTRIBUTE" "220UF"
					( Origin gFrontEnd )
				)
				( attribute "PACK_SIZE" "ESR=25MOHM"
					( Origin gFrontEnd )
				)
				( attribute "RATED" "10V"
					( Origin gFrontEnd )
				)
				( attribute "TOLERANCE" "IRP=2400MA"
					( Origin gFrontEnd )
				)
				( attribute "TYPE" "TMAX=105C"
					( Origin gFrontEnd )
				)
				( objectStatus "C8E4" )
			)
			( gate "@baseboard_fab2_lib.baseboard_fab2(sch_1):page181_i134"
				( attribute "CDS_LIB" "w_hdl"
					( Origin gPackager )
				)
				( attribute "CDS_LMAN_SYM_OUTLINE" "-475,1225,475,-1225"
					( Origin gPackager )
				)
				( attribute "LOCATION" "J1F1"
					( Origin gFrontEnd )
				)
				( attribute "PACK_TYPE" "CONN-G4"
					( Origin gFrontEnd )
				)
				( attribute "PART_NUMBER" "ZZ.82092.07601"
					( Origin gFrontEnd )
				)
				( attribute "PHYS_PAGE" "181"
					( Origin gFrontEnd )
				)
				( attribute "ROT" "0"
					( Origin gFrontEnd )
				)
				( attribute "SEC" "1"
					( Origin gFrontEnd )
				)
				( attribute "SEC_TYPE" "CONN-G4"
					( Origin gFrontEnd )
				)
				( attribute "VALUE" "DM-FCI-CONN76-8R-GP-U-01"
					( Origin gFrontEnd )
				)
				( attribute "VER" "1"
					( Origin gFrontEnd )
				)
				( attribute "XY" "(100,3475)"
					( Origin gFrontEnd )
				)
				( attribute "CHIPS_PART_NAME" "DM-FCI-CONN76-8R-GP-U-01"
					( Origin gPackager )
				)
				( attribute "CDS_PART_NAME" "DM-FCI-CONN76-8R-GP-U-01_CONN-A"
					( Origin gPackager )
				)
				( attribute "CDS_LOCATION" "J1F1"
					( Origin gPackager )
				)
				( attribute "CDS_SEC" "1"
					( Origin gPackager )
				)
				( attribute "NEW_PN" "20.82092.076"
					( Origin gFrontEnd )
				)
				( attribute "CONFIG" "H22707-001"
					( Origin gFrontEnd )
				)
				( objectStatus "J1F1" )
			)
			( gate "@baseboard_fab2_lib.baseboard_fab2(sch_1):page108_i350"
				( attribute "BOM_COST" "SM_CONTROLLER"
					( Origin gFrontEnd )
				)
				( attribute "CDS_LIB" "mstr_discrete"
					( Origin gPackager )
				)
				( attribute "CDS_LOCATION" "R2U35"
					( Origin gPackager )
				)
				( attribute "CDS_SEC" "1"
					( Origin gPackager )
				)
				( attribute "LOCATION" "R2U35"
					( Origin gFrontEnd )
				)
				( attribute "MATERIAL" "EMPTY"
					( Origin gFrontEnd )
				)
				( attribute "PACK_TYPE" "0402"
					( Origin gFrontEnd )
				)
				( attribute "PART_NUMBER" "G21796-173"
					( Origin gFrontEnd )
				)
				( attribute "PHYS_PAGE" "108"
					( Origin gFrontEnd )
				)
				( attribute "ROOM" "SMBUS"
					( Origin gFrontEnd )
				)
				( attribute "ROT" "0"
					( Origin gFrontEnd )
				)
				( attribute "SEC" "1"
					( Origin gPackager )
				)
				( attribute "SKU" "A"
					( Origin gFrontEnd )
				)
				( attribute "TOLERANCE" "1%"
					( Origin gFrontEnd )
				)
				( attribute "VALUE" "20.0"
					( Origin gFrontEnd )
				)
				( attribute "VER" "1"
					( Origin gFrontEnd )
				)
				( attribute "WATTAGE" "1/16W"
					( Origin gFrontEnd )
				)
				( attribute "XY" "(-2275,4625)"
					( Origin gFrontEnd )
				)
				( attribute "CHIPS_PART_NAME" "RES"
					( Origin gPackager )
				)
				( attribute "CDS_PART_NAME" "RES_0402-20.0,1%,1/16W,EMPTY,GA"
					( Origin gPackager )
				)
				( objectStatus "R2U35" )
			)
			( gate "@baseboard_fab2_lib.baseboard_fab2(sch_1):page108_i351"
				( attribute "BOM_COST" "SM_CONTROLLER"
					( Origin gFrontEnd )
				)
				( attribute "CDS_LIB" "mstr_discrete"
					( Origin gPackager )
				)
				( attribute "CDS_LOCATION" "R2U36"
					( Origin gPackager )
				)
				( attribute "CDS_SEC" "1"
					( Origin gPackager )
				)
				( attribute "LOCATION" "R2U36"
					( Origin gFrontEnd )
				)
				( attribute "MATERIAL" "EMPTY"
					( Origin gFrontEnd )
				)
				( attribute "PACK_TYPE" "0402"
					( Origin gFrontEnd )
				)
				( attribute "PART_NUMBER" "G21796-173"
					( Origin gFrontEnd )
				)
				( attribute "PHYS_PAGE" "108"
					( Origin gFrontEnd )
				)
				( attribute "ROOM" "SMBUS"
					( Origin gFrontEnd )
				)
				( attribute "ROT" "0"
					( Origin gFrontEnd )
				)
				( attribute "SEC" "1"
					( Origin gPackager )
				)
				( attribute "SKU" "A"
					( Origin gFrontEnd )
				)
				( attribute "TOLERANCE" "1%"
					( Origin gFrontEnd )
				)
				( attribute "VALUE" "20.0"
					( Origin gFrontEnd )
				)
				( attribute "VER" "1"
					( Origin gFrontEnd )
				)
				( attribute "WATTAGE" "1/16W"
					( Origin gFrontEnd )
				)
				( attribute "XY" "(-2275,4375)"
					( Origin gFrontEnd )
				)
				( attribute "CHIPS_PART_NAME" "RES"
					( Origin gPackager )
				)
				( attribute "CDS_PART_NAME" "RES_0402-20.0,1%,1/16W,EMPTY,GA"
					( Origin gPackager )
				)
				( objectStatus "R2U36" )
			)
			( gate "@baseboard_fab2_lib.baseboard_fab2(sch_1):page138_i198"
				( attribute "CDS_LIB" "mstr_discrete"
					( Origin gPackager )
				)
				( attribute "CDS_LOCATION" "R24W1"
					( Origin gPackager )
				)
				( attribute "CDS_SEC" "1"
					( Origin gPackager )
				)
				( attribute "LOCATION" "R24W1"
					( Origin gFrontEnd )
				)
				( attribute "MATERIAL" "CHIP"
					( Origin gFrontEnd )
				)
				( attribute "PACK_TYPE" "0402"
					( Origin gFrontEnd )
				)
				( attribute "PART_NUMBER" "G21497-013"
					( Origin gFrontEnd )
				)
				( attribute "PHYS_PAGE" "138"
					( Origin gFrontEnd )
				)
				( attribute "ROT" "5"
					( Origin gFrontEnd )
				)
				( attribute "SEC" "1"
					( Origin gFrontEnd )
				)
				( attribute "SEC_TYPE" "0402"
					( Origin gFrontEnd )
				)
				( attribute "TOLERANCE" "5%"
					( Origin gFrontEnd )
				)
				( attribute "VALUE" "3.3K"
					( Origin gFrontEnd )
				)
				( attribute "VER" "1"
					( Origin gFrontEnd )
				)
				( attribute "WATTAGE" "1/16W"
					( Origin gFrontEnd )
				)
				( attribute "XY" "(-600,1650)"
					( Origin gFrontEnd )
				)
				( attribute "CHIPS_PART_NAME" "RES"
					( Origin gPackager )
				)
				( attribute "CDS_PART_NAME" "RES_0402-3.3K,5%,1/16W,CHIP,G2A"
					( Origin gPackager )
				)
				( objectStatus "R24W1" )
			)
			( gate "@baseboard_fab2_lib.baseboard_fab2(sch_1):page138_i199"
				( attribute "CDS_LIB" "mstr_discrete"
					( Origin gPackager )
				)
				( attribute "CDS_LOCATION" "R24W2"
					( Origin gPackager )
				)
				( attribute "CDS_SEC" "1"
					( Origin gPackager )
				)
				( attribute "LOCATION" "R24W2"
					( Origin gFrontEnd )
				)
				( attribute "MATERIAL" "CHIP"
					( Origin gFrontEnd )
				)
				( attribute "PACK_TYPE" "0402"
					( Origin gFrontEnd )
				)
				( attribute "PART_NUMBER" "G21497-013"
					( Origin gFrontEnd )
				)
				( attribute "PHYS_PAGE" "138"
					( Origin gFrontEnd )
				)
				( attribute "ROT" "5"
					( Origin gFrontEnd )
				)
				( attribute "SEC" "1"
					( Origin gFrontEnd )
				)
				( attribute "SEC_TYPE" "0402"
					( Origin gFrontEnd )
				)
				( attribute "TOLERANCE" "5%"
					( Origin gFrontEnd )
				)
				( attribute "VALUE" "3.3K"
					( Origin gFrontEnd )
				)
				( attribute "VER" "1"
					( Origin gFrontEnd )
				)
				( attribute "WATTAGE" "1/16W"
					( Origin gFrontEnd )
				)
				( attribute "XY" "(-200,1650)"
					( Origin gFrontEnd )
				)
				( attribute "CHIPS_PART_NAME" "RES"
					( Origin gPackager )
				)
				( attribute "CDS_PART_NAME" "RES_0402-3.3K,5%,1/16W,CHIP,G2A"
					( Origin gPackager )
				)
				( objectStatus "R24W2" )
			)
			( gate "@baseboard_fab2_lib.baseboard_fab2(sch_1):page164_i41"
				( attribute "BOM_COST" "SM_CONTROLLER"
					( Origin gFrontEnd )
				)
				( attribute "CDS_LIB" "mstr_discrete"
					( Origin gPackager )
				)
				( attribute "CDS_LOCATION" "R1U21"
					( Origin gPackager )
				)
				( attribute "CDS_SEC" "1"
					( Origin gPackager )
				)
				( attribute "LOCATION" "R1U21"
					( Origin gFrontEnd )
				)
				( attribute "MATERIAL" "CHIP"
					( Origin gFrontEnd )
				)
				( attribute "PACK_TYPE" "0402"
					( Origin gFrontEnd )
				)
				( attribute "PART_NUMBER" "G21796-344"
					( Origin gFrontEnd )
				)
				( attribute "PHYS_PAGE" "164"
					( Origin gFrontEnd )
				)
				( attribute "ROOM" "BMC_MISC"
					( Origin gFrontEnd )
				)
				( attribute "ROT" "0"
					( Origin gFrontEnd )
				)
				( attribute "SEC" "1"
					( Origin gFrontEnd )
				)
				( attribute "SEC_TYPE" "0402"
					( Origin gFrontEnd )
				)
				( attribute "TOLERANCE" "1%"
					( Origin gFrontEnd )
				)
				( attribute "VALUE" "2.7K"
					( Origin gFrontEnd )
				)
				( attribute "VER" "1"
					( Origin gFrontEnd )
				)
				( attribute "WATTAGE" "1/16W"
					( Origin gFrontEnd )
				)
				( attribute "XY" "(-7175,4275)"
					( Origin gFrontEnd )
				)
				( attribute "CHIPS_PART_NAME" "RES"
					( Origin gPackager )
				)
				( attribute "CDS_PART_NAME" "RES_0402-2.7K,1%,1/16W,CHIP,G2A"
					( Origin gPackager )
				)
				( attribute "GROUP" "PU_SKU_ID3"
					( Origin gFrontEnd )
				)
				( objectStatus "R1U21" )
			)
			( gate "@baseboard_fab2_lib.baseboard_fab2(sch_1):page164_i43"
				( attribute "BOM_COST" "SM_CONTROLLER"
					( Origin gFrontEnd )
				)
				( attribute "CDS_LIB" "mstr_discrete"
					( Origin gPackager )
				)
				( attribute "CDS_LOCATION" "R1U22"
					( Origin gPackager )
				)
				( attribute "CDS_SEC" "1"
					( Origin gPackager )
				)
				( attribute "LOCATION" "R1U22"
					( Origin gFrontEnd )
				)
				( attribute "MATERIAL" "CHIP"
					( Origin gFrontEnd )
				)
				( attribute "PACK_TYPE" "0402"
					( Origin gFrontEnd )
				)
				( attribute "PART_NUMBER" "G21796-344"
					( Origin gFrontEnd )
				)
				( attribute "PHYS_PAGE" "164"
					( Origin gFrontEnd )
				)
				( attribute "ROOM" "BMC_MISC"
					( Origin gFrontEnd )
				)
				( attribute "ROT" "0"
					( Origin gFrontEnd )
				)
				( attribute "SEC" "1"
					( Origin gFrontEnd )
				)
				( attribute "SEC_TYPE" "0402"
					( Origin gFrontEnd )
				)
				( attribute "TOLERANCE" "1%"
					( Origin gFrontEnd )
				)
				( attribute "VALUE" "2.7K"
					( Origin gFrontEnd )
				)
				( attribute "VER" "1"
					( Origin gFrontEnd )
				)
				( attribute "WATTAGE" "1/16W"
					( Origin gFrontEnd )
				)
				( attribute "XY" "(-7175,3875)"
					( Origin gFrontEnd )
				)
				( attribute "CHIPS_PART_NAME" "RES"
					( Origin gPackager )
				)
				( attribute "CDS_PART_NAME" "RES_0402-2.7K,1%,1/16W,CHIP,G2A"
					( Origin gPackager )
				)
				( attribute "GROUP" "PU_SKU_ID1"
					( Origin gFrontEnd )
				)
				( objectStatus "R1U22" )
			)
			( gate "@baseboard_fab2_lib.baseboard_fab2(sch_1):page246_i21"
				( attribute "CDS_LIB" "dev_discrete"
					( Origin gPackager )
				)
				( attribute "CDS_LOCATION" "CN8F1"
					( Origin gPackager )
				)
				( attribute "CDS_SEC" "1"
					( Origin gPackager )
				)
				( attribute "LOCATION" "CN8F1"
					( Origin gFrontEnd )
				)
				( attribute "MATERIAL" "X6S"
					( Origin gFrontEnd )
				)
				( attribute "PACK_TYPE" "0402V"
					( Origin gFrontEnd )
				)
				( attribute "PART_NUMBER" "D97712-004"
					( Origin gFrontEnd )
				)
				( attribute "PHYS_PAGE" "246"
					( Origin gFrontEnd )
				)
				( attribute "ROOM" "VDDQ_KLM_PWR_VR"
					( Origin gFrontEnd )
				)
				( attribute "ROT" "0"
					( Origin gFrontEnd )
				)
				( attribute "SEC" "1"
					( Origin gFrontEnd )
				)
				( attribute "SEC_TYPE" "0402V"
					( Origin gFrontEnd )
				)
				( attribute "TOLERANCE" "10%"
					( Origin gFrontEnd )
				)
				( attribute "VALUE" "1.0UF"
					( Origin gFrontEnd )
				)
				( attribute "VER" "1"
					( Origin gFrontEnd )
				)
				( attribute "VOLTAGE" "6.3V"
					( Units "uVoltage" "V" 1.000000)
					( Origin gFrontEnd )
				)
				( attribute "XY" "(-3000,3275)"
					( Origin gFrontEnd )
				)
				( attribute "CHIPS_PART_NAME" "CAP_A"
					( Origin gPackager )
				)
				( attribute "CDS_PART_NAME" "CAP_A_0402V-1.0UF,6.3V,10%,X6SA"
					( Origin gPackager )
				)
				( objectStatus "CN8F1" )
			)
			( gate "@baseboard_fab2_lib.baseboard_fab2(sch_1):page151_i214"
				( attribute "BOM_COST" "MEM"
					( Origin gFrontEnd )
				)
				( attribute "CDS_LIB" "dev_discrete"
					( Origin gPackager )
				)
				( attribute "CDS_LOCATION" "C25W11"
					( Origin gPackager )
				)
				( attribute "CDS_SEC" "1"
					( Origin gPackager )
				)
				( attribute "LOCATION" "C25W11"
					( Origin gFrontEnd )
				)
				( attribute "MATERIAL" "X7R"
					( Origin gFrontEnd )
				)
				( attribute "PACK_TYPE" "0402V"
					( Origin gFrontEnd )
				)
				( attribute "PART_NUMBER" "A36096-045"
					( Origin gFrontEnd )
				)
				( attribute "PHYS_PAGE" "151"
					( Origin gFrontEnd )
				)
				( attribute "ROOM" "DDR4_CH_M"
					( Origin gFrontEnd )
				)
				( attribute "ROT" "2"
					( Origin gFrontEnd )
				)
				( attribute "SEC" "1"
					( Origin gFrontEnd )
				)
				( attribute "SEC_TYPE" "0402V"
					( Origin gFrontEnd )
				)
				( attribute "TOLERANCE" "10%"
					( Origin gFrontEnd )
				)
				( attribute "VALUE" "0.01UF"
					( Origin gFrontEnd )
				)
				( attribute "VER" "1"
					( Origin gFrontEnd )
				)
				( attribute "VOLTAGE" "25V"
					( Units "uVoltage" "V" 1.000000)
					( Origin gFrontEnd )
				)
				( attribute "XY" "(-2275,-2000)"
					( Origin gFrontEnd )
				)
				( attribute "CHIPS_PART_NAME" "CAP_A"
					( Origin gPackager )
				)
				( attribute "CDS_PART_NAME" "CAP_A_0402V-0.01UF,25V,10%,X7RA"
					( Origin gPackager )
				)
				( objectStatus "C25W11" )
			)
			( gate "@baseboard_fab2_lib.baseboard_fab2(sch_1):page149_i121"
				( attribute "CDS_LIB" "dev_discrete"
					( Origin gPackager )
				)
				( attribute "CDS_LOCATION" "C25W38"
					( Origin gPackager )
				)
				( attribute "CDS_SEC" "1"
					( Origin gPackager )
				)
				( attribute "LOCATION" "C25W38"
					( Origin gFrontEnd )
				)
				( attribute "MATERIAL" "X7R"
					( Origin gFrontEnd )
				)
				( attribute "PACK_TYPE" "0402V"
					( Origin gFrontEnd )
				)
				( attribute "PART_NUMBER" "A36096-030"
					( Origin gFrontEnd )
				)
				( attribute "PHYS_PAGE" "149"
					( Origin gFrontEnd )
				)
				( attribute "ROOM" "VDDQ_KLM_PWR_VR"
					( Origin gFrontEnd )
				)
				( attribute "ROT" "0"
					( Origin gFrontEnd )
				)
				( attribute "SEC" "1"
					( Origin gFrontEnd )
				)
				( attribute "SEC_TYPE" "0402V"
					( Origin gFrontEnd )
				)
				( attribute "TOLERANCE" "10%"
					( Origin gFrontEnd )
				)
				( attribute "VALUE" "0.1UF"
					( Origin gFrontEnd )
				)
				( attribute "VER" "1"
					( Origin gFrontEnd )
				)
				( attribute "VOLTAGE" "16V"
					( Units "uVoltage" "V" 1.000000)
					( Origin gFrontEnd )
				)
				( attribute "XY" "(3325,3975)"
					( Origin gFrontEnd )
				)
				( attribute "CHIPS_PART_NAME" "CAP_A"
					( Origin gPackager )
				)
				( attribute "CDS_PART_NAME" "CAP_A_0402V-0.1UF,16V,10%,X7R,A"
					( Origin gPackager )
				)
				( objectStatus "C25W38" )
			)
			( gate "@baseboard_fab2_lib.baseboard_fab2(sch_1):page149_i122"
				( attribute "CDS_LIB" "dev_discrete"
					( Origin gPackager )
				)
				( attribute "CDS_LOCATION" "C25W45"
					( Origin gPackager )
				)
				( attribute "CDS_SEC" "1"
					( Origin gPackager )
				)
				( attribute "LOCATION" "C25W45"
					( Origin gFrontEnd )
				)
				( attribute "MATERIAL" "X7R"
					( Origin gFrontEnd )
				)
				( attribute "PACK_TYPE" "0402V"
					( Origin gFrontEnd )
				)
				( attribute "PART_NUMBER" "A36096-030"
					( Origin gFrontEnd )
				)
				( attribute "PHYS_PAGE" "149"
					( Origin gFrontEnd )
				)
				( attribute "ROOM" "VDDQ_KLM_PWR_VR"
					( Origin gFrontEnd )
				)
				( attribute "ROT" "0"
					( Origin gFrontEnd )
				)
				( attribute "SEC" "1"
					( Origin gFrontEnd )
				)
				( attribute "SEC_TYPE" "0402V"
					( Origin gFrontEnd )
				)
				( attribute "TOLERANCE" "10%"
					( Origin gFrontEnd )
				)
				( attribute "VALUE" "0.1UF"
					( Origin gFrontEnd )
				)
				( attribute "VER" "1"
					( Origin gFrontEnd )
				)
				( attribute "VOLTAGE" "16V"
					( Units "uVoltage" "V" 1.000000)
					( Origin gFrontEnd )
				)
				( attribute "XY" "(-100,2900)"
					( Origin gFrontEnd )
				)
				( attribute "CHIPS_PART_NAME" "CAP_A"
					( Origin gPackager )
				)
				( attribute "CDS_PART_NAME" "CAP_A_0402V-0.1UF,16V,10%,X7R,A"
					( Origin gPackager )
				)
				( objectStatus "C25W45" )
			)
			( gate "@baseboard_fab2_lib.baseboard_fab2(sch_1):page220_i310"
				( attribute "BOM_COST" "MEM_VRD_PVDDQ_CD"
					( Origin gFrontEnd )
				)
				( attribute "CDS_LIB" "mstr_discrete"
					( Origin gPackager )
				)
				( attribute "CDS_LOCATION" "C5L3"
					( Origin gPackager )
				)
				( attribute "CDS_SEC" "1"
					( Origin gPackager )
				)
				( attribute "LOCATION" "C5L3"
					( Origin gFrontEnd )
				)
				( attribute "MATERIAL" "X5R"
					( Origin gFrontEnd )
				)
				( attribute "NEW_MATERIAL" "X6S"
					( Origin gFrontEnd )
				)
				( attribute "PACK_TYPE" "0805"
					( Origin gFrontEnd )
				)
				( attribute "PART_NUMBER" "602433-112"
					( Origin gFrontEnd )
				)
				( attribute "PHYS_PAGE" "220"
					( Origin gFrontEnd )
				)
				( attribute "ROOM" "VDDQ_ABC_PWR_VR"
					( Origin gFrontEnd )
				)
				( attribute "ROT" "0"
					( Origin gFrontEnd )
				)
				( attribute "SEC" "1"
					( Origin gFrontEnd )
				)
				( attribute "SEC_TYPE" "0805"
					( Origin gFrontEnd )
				)
				( attribute "TOLERANCE" "20%"
					( Origin gFrontEnd )
				)
				( attribute "VALUE" "100UF"
					( Origin gFrontEnd )
				)
				( attribute "VER" "1"
					( Origin gFrontEnd )
				)
				( attribute "VOLTAGE" "4V"
					( Units "uVoltage" "V" 1.000000)
					( Origin gFrontEnd )
				)
				( attribute "XY" "(3850,2825)"
					( Origin gFrontEnd )
				)
				( attribute "CHIPS_PART_NAME" "CAP"
					( Origin gPackager )
				)
				( attribute "CDS_PART_NAME" "CAP_0805-100UF,4V,20%,X5R,6024A"
					( Origin gPackager )
				)
				( attribute "GROUP" "PWR_MLCC_CAP"
					( Origin gFrontEnd )
				)
				( attribute "NEW_PN" "078.1071T.M002"
					( Origin gFrontEnd )
				)
				( attribute "BOM_SS" "NOPOP"
					( Origin gFrontEnd )
				)
				( objectStatus "C5L3" )
			)
			( gate "@baseboard_fab2_lib.baseboard_fab2(sch_1):page220_i309"
				( attribute "BOM_COST" "MEM_VRD_PVDDQ_CD"
					( Origin gFrontEnd )
				)
				( attribute "CDS_LIB" "mstr_discrete"
					( Origin gPackager )
				)
				( attribute "CDS_LOCATION" "C5L1"
					( Origin gPackager )
				)
				( attribute "CDS_SEC" "1"
					( Origin gPackager )
				)
				( attribute "LOCATION" "C5L1"
					( Origin gFrontEnd )
				)
				( attribute "MATERIAL" "X5R"
					( Origin gFrontEnd )
				)
				( attribute "NEW_MATERIAL" "X6S"
					( Origin gFrontEnd )
				)
				( attribute "PACK_TYPE" "0805"
					( Origin gFrontEnd )
				)
				( attribute "PART_NUMBER" "602433-112"
					( Origin gFrontEnd )
				)
				( attribute "PHYS_PAGE" "220"
					( Origin gFrontEnd )
				)
				( attribute "ROOM" "VDDQ_ABC_PWR_VR"
					( Origin gFrontEnd )
				)
				( attribute "ROT" "0"
					( Origin gFrontEnd )
				)
				( attribute "SEC" "1"
					( Origin gFrontEnd )
				)
				( attribute "SEC_TYPE" "0805"
					( Origin gFrontEnd )
				)
				( attribute "TOLERANCE" "20%"
					( Origin gFrontEnd )
				)
				( attribute "VALUE" "100UF"
					( Origin gFrontEnd )
				)
				( attribute "VER" "1"
					( Origin gFrontEnd )
				)
				( attribute "VOLTAGE" "4V"
					( Units "uVoltage" "V" 1.000000)
					( Origin gFrontEnd )
				)
				( attribute "XY" "(3150,2825)"
					( Origin gFrontEnd )
				)
				( attribute "CHIPS_PART_NAME" "CAP"
					( Origin gPackager )
				)
				( attribute "CDS_PART_NAME" "CAP_0805-100UF,4V,20%,X5R,6024A"
					( Origin gPackager )
				)
				( attribute "GROUP" "PWR_MLCC_CAP"
					( Origin gFrontEnd )
				)
				( attribute "NEW_PN" "078.1071T.M002"
					( Origin gFrontEnd )
				)
				( attribute "BOM_SS" "NOPOP"
					( Origin gFrontEnd )
				)
				( objectStatus "C5L1" )
			)
			( gate "@baseboard_fab2_lib.baseboard_fab2(sch_1):page217_i329"
				( attribute "BOM_COST" "MEM_VRD_PVDDQ_CD"
					( Origin gFrontEnd )
				)
				( attribute "CDS_LIB" "mstr_discrete"
					( Origin gPackager )
				)
				( attribute "CDS_LOCATION" "C5G20"
					( Origin gPackager )
				)
				( attribute "CDS_SEC" "1"
					( Origin gPackager )
				)
				( attribute "LOCATION" "C5G20"
					( Origin gFrontEnd )
				)
				( attribute "MATERIAL" "X5R"
					( Origin gFrontEnd )
				)
				( attribute "NEW_MATERIAL" "X6S"
					( Origin gFrontEnd )
				)
				( attribute "PACK_TYPE" "0805"
					( Origin gFrontEnd )
				)
				( attribute "PART_NUMBER" "602433-112"
					( Origin gFrontEnd )
				)
				( attribute "PHYS_PAGE" "217"
					( Origin gFrontEnd )
				)
				( attribute "ROOM" "VDDQ_ABC_PWR_VR"
					( Origin gFrontEnd )
				)
				( attribute "ROT" "0"
					( Origin gFrontEnd )
				)
				( attribute "SEC" "1"
					( Origin gFrontEnd )
				)
				( attribute "SEC_TYPE" "0805"
					( Origin gFrontEnd )
				)
				( attribute "TOLERANCE" "20%"
					( Origin gFrontEnd )
				)
				( attribute "VALUE" "100UF"
					( Origin gFrontEnd )
				)
				( attribute "VER" "1"
					( Origin gFrontEnd )
				)
				( attribute "VOLTAGE" "4V"
					( Units "uVoltage" "V" 1.000000)
					( Origin gFrontEnd )
				)
				( attribute "XY" "(2875,2850)"
					( Origin gFrontEnd )
				)
				( attribute "CHIPS_PART_NAME" "CAP"
					( Origin gPackager )
				)
				( attribute "CDS_PART_NAME" "CAP_0805-100UF,4V,20%,X5R,6024A"
					( Origin gPackager )
				)
				( attribute "GROUP" "PWR_MLCC_CAP"
					( Origin gFrontEnd )
				)
				( attribute "NEW_PN" "078.1071T.M002"
					( Origin gFrontEnd )
				)
				( attribute "BOM_SS" "NOPOP"
					( Origin gFrontEnd )
				)
				( objectStatus "C5G20" )
			)
			( gate "@baseboard_fab2_lib.baseboard_fab2(sch_1):page228_i303"
				( attribute "BOM_COST" "MEM_VRD_PVDDQ_CD"
					( Origin gFrontEnd )
				)
				( attribute "CDS_LIB" "mstr_discrete"
					( Origin gPackager )
				)
				( attribute "CDS_LOCATION" "C8P2"
					( Origin gPackager )
				)
				( attribute "CDS_SEC" "1"
					( Origin gPackager )
				)
				( attribute "LOCATION" "C8P2"
					( Origin gFrontEnd )
				)
				( attribute "MATERIAL" "X5R"
					( Origin gFrontEnd )
				)
				( attribute "NEW_MATERIAL" "X6S"
					( Origin gFrontEnd )
				)
				( attribute "PACK_TYPE" "0805"
					( Origin gFrontEnd )
				)
				( attribute "PART_NUMBER" "602433-112"
					( Origin gFrontEnd )
				)
				( attribute "PHYS_PAGE" "228"
					( Origin gFrontEnd )
				)
				( attribute "ROOM" "VDDQ_ABC_PWR_VR"
					( Origin gFrontEnd )
				)
				( attribute "ROT" "0"
					( Origin gFrontEnd )
				)
				( attribute "SEC" "1"
					( Origin gFrontEnd )
				)
				( attribute "SEC_TYPE" "0805"
					( Origin gFrontEnd )
				)
				( attribute "TOLERANCE" "20%"
					( Origin gFrontEnd )
				)
				( attribute "VALUE" "100UF"
					( Origin gFrontEnd )
				)
				( attribute "VER" "1"
					( Origin gFrontEnd )
				)
				( attribute "VOLTAGE" "4V"
					( Units "uVoltage" "V" 1.000000)
					( Origin gFrontEnd )
				)
				( attribute "XY" "(-2325,2975)"
					( Origin gFrontEnd )
				)
				( attribute "CHIPS_PART_NAME" "CAP"
					( Origin gPackager )
				)
				( attribute "CDS_PART_NAME" "CAP_0805-100UF,4V,20%,X5R,6024A"
					( Origin gPackager )
				)
				( attribute "GROUP" "PWR_MLCC_CAP"
					( Origin gFrontEnd )
				)
				( attribute "NEW_PN" "078.1071T.M002"
					( Origin gFrontEnd )
				)
				( attribute "BOM_SS" "NOPOP"
					( Origin gFrontEnd )
				)
				( objectStatus "C8P2" )
			)
			( gate "@baseboard_fab2_lib.baseboard_fab2(sch_1):page220_i320"
				( attribute "BOM_COST" "MEM_VRD_PVDDQ_CD"
					( Origin gFrontEnd )
				)
				( attribute "CDS_LIB" "mstr_discrete"
					( Origin gPackager )
				)
				( attribute "CDS_LOCATION" "C5P1"
					( Origin gPackager )
				)
				( attribute "CDS_SEC" "1"
					( Origin gPackager )
				)
				( attribute "LOCATION" "C5P1"
					( Origin gFrontEnd )
				)
				( attribute "MATERIAL" "X5R"
					( Origin gFrontEnd )
				)
				( attribute "NEW_MATERIAL" "X6S"
					( Origin gFrontEnd )
				)
				( attribute "PACK_TYPE" "0805"
					( Origin gFrontEnd )
				)
				( attribute "PART_NUMBER" "602433-112"
					( Origin gFrontEnd )
				)
				( attribute "PHYS_PAGE" "220"
					( Origin gFrontEnd )
				)
				( attribute "ROOM" "VDDQ_ABC_PWR_VR"
					( Origin gFrontEnd )
				)
				( attribute "ROT" "0"
					( Origin gFrontEnd )
				)
				( attribute "SEC" "1"
					( Origin gFrontEnd )
				)
				( attribute "SEC_TYPE" "0805"
					( Origin gFrontEnd )
				)
				( attribute "TOLERANCE" "20%"
					( Origin gFrontEnd )
				)
				( attribute "VALUE" "100UF"
					( Origin gFrontEnd )
				)
				( attribute "VER" "1"
					( Origin gFrontEnd )
				)
				( attribute "VOLTAGE" "4V"
					( Units "uVoltage" "V" 1.000000)
					( Origin gFrontEnd )
				)
				( attribute "XY" "(-1950,2975)"
					( Origin gFrontEnd )
				)
				( attribute "CHIPS_PART_NAME" "CAP"
					( Origin gPackager )
				)
				( attribute "CDS_PART_NAME" "CAP_0805-100UF,4V,20%,X5R,6024A"
					( Origin gPackager )
				)
				( attribute "GROUP" "PWR_MLCC_CAP"
					( Origin gFrontEnd )
				)
				( attribute "NEW_PN" "078.1071T.M002"
					( Origin gFrontEnd )
				)
				( attribute "BOM_SS" "NOPOP"
					( Origin gFrontEnd )
				)
				( objectStatus "C5P1" )
			)
			( gate "@baseboard_fab2_lib.baseboard_fab2(sch_1):page220_i319"
				( attribute "BOM_COST" "MEM_VRD_PVDDQ_CD"
					( Origin gFrontEnd )
				)
				( attribute "CDS_LIB" "mstr_discrete"
					( Origin gPackager )
				)
				( attribute "CDS_LOCATION" "C5P2"
					( Origin gPackager )
				)
				( attribute "CDS_SEC" "1"
					( Origin gPackager )
				)
				( attribute "LOCATION" "C5P2"
					( Origin gFrontEnd )
				)
				( attribute "MATERIAL" "X5R"
					( Origin gFrontEnd )
				)
				( attribute "NEW_MATERIAL" "X6S"
					( Origin gFrontEnd )
				)
				( attribute "PACK_TYPE" "0805"
					( Origin gFrontEnd )
				)
				( attribute "PART_NUMBER" "602433-112"
					( Origin gFrontEnd )
				)
				( attribute "PHYS_PAGE" "220"
					( Origin gFrontEnd )
				)
				( attribute "ROOM" "VDDQ_ABC_PWR_VR"
					( Origin gFrontEnd )
				)
				( attribute "ROT" "0"
					( Origin gFrontEnd )
				)
				( attribute "SEC" "1"
					( Origin gFrontEnd )
				)
				( attribute "SEC_TYPE" "0805"
					( Origin gFrontEnd )
				)
				( attribute "TOLERANCE" "20%"
					( Origin gFrontEnd )
				)
				( attribute "VALUE" "100UF"
					( Origin gFrontEnd )
				)
				( attribute "VER" "1"
					( Origin gFrontEnd )
				)
				( attribute "VOLTAGE" "4V"
					( Units "uVoltage" "V" 1.000000)
					( Origin gFrontEnd )
				)
				( attribute "XY" "(-2300,2975)"
					( Origin gFrontEnd )
				)
				( attribute "CHIPS_PART_NAME" "CAP"
					( Origin gPackager )
				)
				( attribute "CDS_PART_NAME" "CAP_0805-100UF,4V,20%,X5R,6024A"
					( Origin gPackager )
				)
				( attribute "GROUP" "PWR_MLCC_CAP"
					( Origin gFrontEnd )
				)
				( attribute "NEW_PN" "078.1071T.M002"
					( Origin gFrontEnd )
				)
				( attribute "BOM_SS" "NOPOP"
					( Origin gFrontEnd )
				)
				( objectStatus "C5P2" )
			)
			( gate "@baseboard_fab2_lib.baseboard_fab2(sch_1):page148_i29"
				( attribute "BOM_COST" "MIO_USB"
					( Origin gFrontEnd )
				)
				( attribute "CDS_LIB" "mstr_discrete"
					( Origin gPackager )
				)
				( attribute "CDS_LOCATION" "R25W155"
					( Origin gPackager )
				)
				( attribute "CDS_SEC" "1"
					( Origin gPackager )
				)
				( attribute "LOCATION" "R25W155"
					( Origin gFrontEnd )
				)
				( attribute "MATERIAL" "CHIP"
					( Origin gFrontEnd )
				)
				( attribute "PACK_TYPE" "0402"
					( Origin gFrontEnd )
				)
				( attribute "PART_NUMBER" "G21497-005"
					( Origin gFrontEnd )
				)
				( attribute "PHYS_PAGE" "148"
					( Origin gFrontEnd )
				)
				( attribute "ROOM" "USB"
					( Origin gFrontEnd )
				)
				( attribute "ROT" "0"
					( Origin gFrontEnd )
				)
				( attribute "SEC" "1"
					( Origin gFrontEnd )
				)
				( attribute "SEC_TYPE" "0402"
					( Origin gFrontEnd )
				)
				( attribute "TOLERANCE" "5%"
					( Origin gFrontEnd )
				)
				( attribute "VALUE" "0.0"
					( Origin gFrontEnd )
				)
				( attribute "VER" "1"
					( Origin gFrontEnd )
				)
				( attribute "WATTAGE" "1/16W"
					( Origin gFrontEnd )
				)
				( attribute "XY" "(-6850,2300)"
					( Origin gFrontEnd )
				)
				( attribute "CHIPS_PART_NAME" "RES"
					( Origin gPackager )
				)
				( attribute "CDS_PART_NAME" "RES_0402-0.0,5%,1/16W,CHIP,G21A"
					( Origin gPackager )
				)
				( objectStatus "R25W155" )
			)
			( gate "@baseboard_fab2_lib.baseboard_fab2(sch_1):page138_i202"
				( attribute "BOM_COST" "SM_CONTROLLER"
					( Origin gFrontEnd )
				)
				( attribute "CDS_LIB" "mstr_discrete"
					( Origin gPackager )
				)
				( attribute "CDS_LOCATION" "R8W7"
					( Origin gPackager )
				)
				( attribute "LOCATION" "R8W7"
					( Origin gFrontEnd )
				)
				( attribute "MATERIAL" "CHIP"
					( Origin gFrontEnd )
				)
				( attribute "PACK_TYPE" "0402"
					( Origin gFrontEnd )
				)
				( attribute "PART_NUMBER" "G21796-095"
					( Origin gFrontEnd )
				)
				( attribute "PHYS_PAGE" "138"
					( Origin gFrontEnd )
				)
				( attribute "ROOM" "SMBUS"
					( Origin gFrontEnd )
				)
				( attribute "ROT" "0"
					( Origin gFrontEnd )
				)
				( attribute "SEC" "1"
					( Origin gFrontEnd )
				)
				( attribute "SEC_TYPE" "0402"
					( Origin gFrontEnd )
				)
				( attribute "TOLERANCE" "1%"
					( Origin gFrontEnd )
				)
				( attribute "VALUE" "1.37K"
					( Origin gFrontEnd )
				)
				( attribute "VER" "2"
					( Origin gFrontEnd )
				)
				( attribute "WATTAGE" "1/16W"
					( Origin gFrontEnd )
				)
				( attribute "XY" "(-200,2550)"
					( Origin gFrontEnd )
				)
				( attribute "CHIPS_PART_NAME" "RES"
					( Origin gPackager )
				)
				( attribute "CDS_PART_NAME" "RES_0402-1.37K,1%,1/16W,CHIP,GA"
					( Origin gPackager )
				)
				( attribute "CDS_SEC" "1"
					( Origin gPackager )
				)
				( objectStatus "R8W7" )
			)
			( gate "@baseboard_fab2_lib.baseboard_fab2(sch_1):page138_i205"
				( attribute "BOM_COST" "SM_CONTROLLER"
					( Origin gFrontEnd )
				)
				( attribute "CDS_LIB" "mstr_discrete"
					( Origin gPackager )
				)
				( attribute "CDS_LOCATION" "R8W6"
					( Origin gPackager )
				)
				( attribute "LOCATION" "R8W6"
					( Origin gFrontEnd )
				)
				( attribute "MATERIAL" "CHIP"
					( Origin gFrontEnd )
				)
				( attribute "PACK_TYPE" "0402"
					( Origin gFrontEnd )
				)
				( attribute "PART_NUMBER" "G21796-095"
					( Origin gFrontEnd )
				)
				( attribute "PHYS_PAGE" "138"
					( Origin gFrontEnd )
				)
				( attribute "ROOM" "SMBUS"
					( Origin gFrontEnd )
				)
				( attribute "ROT" "0"
					( Origin gFrontEnd )
				)
				( attribute "SEC" "1"
					( Origin gFrontEnd )
				)
				( attribute "SEC_TYPE" "0402"
					( Origin gFrontEnd )
				)
				( attribute "TOLERANCE" "1%"
					( Origin gFrontEnd )
				)
				( attribute "VALUE" "1.37K"
					( Origin gFrontEnd )
				)
				( attribute "VER" "2"
					( Origin gFrontEnd )
				)
				( attribute "WATTAGE" "1/16W"
					( Origin gFrontEnd )
				)
				( attribute "XY" "(-575,2600)"
					( Origin gFrontEnd )
				)
				( attribute "CHIPS_PART_NAME" "RES"
					( Origin gPackager )
				)
				( attribute "CDS_PART_NAME" "RES_0402-1.37K,1%,1/16W,CHIP,GA"
					( Origin gPackager )
				)
				( attribute "CDS_SEC" "1"
					( Origin gPackager )
				)
				( objectStatus "R8W6" )
			)
			( gate "@baseboard_fab2_lib.baseboard_fab2(sch_1):page159_i235"
				( attribute "BOM_COST" "SM_CONTROLLER"
					( Origin gFrontEnd )
				)
				( attribute "CDS_LIB" "mstr_discrete"
					( Origin gPackager )
				)
				( attribute "CDS_LOCATION" "R8C15"
					( Origin gPackager )
				)
				( attribute "CDS_SEC" "1"
					( Origin gPackager )
				)
				( attribute "LOCATION" "R8C15"
					( Origin gFrontEnd )
				)
				( attribute "MATERIAL" "CHIP"
					( Origin gFrontEnd )
				)
				( attribute "PACK_TYPE" "0402"
					( Origin gFrontEnd )
				)
				( attribute "PART_NUMBER" "G21796-001"
					( Origin gFrontEnd )
				)
				( attribute "PHYS_PAGE" "159"
					( Origin gFrontEnd )
				)
				( attribute "ROOM" "SMBUS"
					( Origin gFrontEnd )
				)
				( attribute "ROT" "0"
					( Origin gFrontEnd )
				)
				( attribute "SEC" "1"
					( Origin gFrontEnd )
				)
				( attribute "SEC_TYPE" "0402"
					( Origin gFrontEnd )
				)
				( attribute "TOLERANCE" "1%"
					( Origin gFrontEnd )
				)
				( attribute "VALUE" "2.0K"
					( Origin gFrontEnd )
				)
				( attribute "VER" "2"
					( Origin gFrontEnd )
				)
				( attribute "WATTAGE" "1/16W"
					( Origin gFrontEnd )
				)
				( attribute "XY" "(-3500,4100)"
					( Origin gFrontEnd )
				)
				( attribute "CHIPS_PART_NAME" "RES"
					( Origin gPackager )
				)
				( attribute "CDS_PART_NAME" "RES_0402-2.0K,1%,1/16W,CHIP,G2A"
					( Origin gPackager )
				)
				( objectStatus "R8C15" )
			)
			( gate "@baseboard_fab2_lib.baseboard_fab2(sch_1):page159_i237"
				( attribute "BOM_COST" "SM_CONTROLLER"
					( Origin gFrontEnd )
				)
				( attribute "CDS_LIB" "mstr_discrete"
					( Origin gPackager )
				)
				( attribute "CDS_LOCATION" "R8C16"
					( Origin gPackager )
				)
				( attribute "CDS_SEC" "1"
					( Origin gPackager )
				)
				( attribute "LOCATION" "R8C16"
					( Origin gFrontEnd )
				)
				( attribute "MATERIAL" "CHIP"
					( Origin gFrontEnd )
				)
				( attribute "PACK_TYPE" "0402"
					( Origin gFrontEnd )
				)
				( attribute "PART_NUMBER" "G21796-001"
					( Origin gFrontEnd )
				)
				( attribute "PHYS_PAGE" "159"
					( Origin gFrontEnd )
				)
				( attribute "ROOM" "SMBUS"
					( Origin gFrontEnd )
				)
				( attribute "ROT" "0"
					( Origin gFrontEnd )
				)
				( attribute "SEC" "1"
					( Origin gFrontEnd )
				)
				( attribute "SEC_TYPE" "0402"
					( Origin gFrontEnd )
				)
				( attribute "TOLERANCE" "1%"
					( Origin gFrontEnd )
				)
				( attribute "VALUE" "2.0K"
					( Origin gFrontEnd )
				)
				( attribute "VER" "2"
					( Origin gFrontEnd )
				)
				( attribute "WATTAGE" "1/16W"
					( Origin gFrontEnd )
				)
				( attribute "XY" "(-3900,4150)"
					( Origin gFrontEnd )
				)
				( attribute "CHIPS_PART_NAME" "RES"
					( Origin gPackager )
				)
				( attribute "CDS_PART_NAME" "RES_0402-2.0K,1%,1/16W,CHIP,G2A"
					( Origin gPackager )
				)
				( objectStatus "R8C16" )
			)
			( gate "@baseboard_fab2_lib.baseboard_fab2(sch_1):page225_i261"
				( attribute "BOM_COST" "PROC"
					( Origin gFrontEnd )
				)
				( attribute "CDS_LIB" "dev_discrete"
					( Origin gPackager )
				)
				( attribute "CDS_LOCATION" "C2D45"
					( Origin gPackager )
				)
				( attribute "CDS_SEC" "1"
					( Origin gPackager )
				)
				( attribute "LOCATION" "C2D45"
					( Origin gFrontEnd )
				)
				( attribute "MATERIAL" "X6S"
					( Origin gFrontEnd )
				)
				( attribute "PACK_TYPE" "0603V"
					( Origin gFrontEnd )
				)
				( attribute "PART_NUMBER" "E15431-004"
					( Origin gFrontEnd )
				)
				( attribute "PHYS_PAGE" "225"
					( Origin gFrontEnd )
				)
				( attribute "ROOM" "PVCCIN_CPU1_DECAP_VR"
					( Origin gFrontEnd )
				)
				( attribute "ROT" "0"
					( Origin gFrontEnd )
				)
				( attribute "SEC" "1"
					( Origin gPackager )
				)
				( attribute "TOLERANCE" "20%"
					( Origin gFrontEnd )
				)
				( attribute "VALUE" "22.0UF"
					( Origin gFrontEnd )
				)
				( attribute "VER" "1"
					( Origin gFrontEnd )
				)
				( attribute "VOLTAGE" "4V"
					( Units "uVoltage" "V" 1.000000)
					( Origin gFrontEnd )
				)
				( attribute "XY" "(700,2100)"
					( Origin gFrontEnd )
				)
				( attribute "CHIPS_PART_NAME" "CAP_A"
					( Origin gPackager )
				)
				( attribute "CDS_PART_NAME" "CAP_A_0603V-22.0UF,4V,20%,X6S,A"
					( Origin gPackager )
				)
				( attribute "GROUP" "PWR_MLCC_CAP"
					( Origin gFrontEnd )
				)
				( objectStatus "C2D45" )
			)
			( gate "@baseboard_fab2_lib.baseboard_fab2(sch_1):page228_i256"
				( attribute "BOM_COST" "PROC"
					( Origin gFrontEnd )
				)
				( attribute "CDS_LIB" "dev_discrete"
					( Origin gPackager )
				)
				( attribute "CDS_LOCATION" "C2D3"
					( Origin gPackager )
				)
				( attribute "LOCATION" "C2D3"
					( Origin gFrontEnd )
				)
				( attribute "MATERIAL" "X6S"
					( Origin gFrontEnd )
				)
				( attribute "PACK_TYPE" "0603V"
					( Origin gFrontEnd )
				)
				( attribute "PART_NUMBER" "E15431-004"
					( Origin gFrontEnd )
				)
				( attribute "PHYS_PAGE" "228"
					( Origin gFrontEnd )
				)
				( attribute "ROOM" "PVCCIN_CPU1_DECAP_VR"
					( Origin gFrontEnd )
				)
				( attribute "ROT" "0"
					( Origin gFrontEnd )
				)
				( attribute "SEC" "1"
					( Origin gFrontEnd )
				)
				( attribute "SEC_TYPE" "0603V"
					( Origin gFrontEnd )
				)
				( attribute "TOLERANCE" "20%"
					( Origin gFrontEnd )
				)
				( attribute "VALUE" "22.0UF"
					( Origin gFrontEnd )
				)
				( attribute "VER" "1"
					( Origin gFrontEnd )
				)
				( attribute "VOLTAGE" "4V"
					( Units "uVoltage" "V" 1.000000)
					( Origin gFrontEnd )
				)
				( attribute "XY" "(1300,1800)"
					( Origin gFrontEnd )
				)
				( attribute "CHIPS_PART_NAME" "CAP_A"
					( Origin gPackager )
				)
				( attribute "CDS_PART_NAME" "CAP_A_0603V-22.0UF,4V,20%,X6S,A"
					( Origin gPackager )
				)
				( attribute "CDS_SEC" "1"
					( Origin gPackager )
				)
				( attribute "GROUP" "PWR_MLCC_CAP"
					( Origin gFrontEnd )
				)
				( objectStatus "C2D3" )
			)
			( gate "@baseboard_fab2_lib.baseboard_fab2(sch_1):page228_i255"
				( attribute "BOM_COST" "PROC"
					( Origin gFrontEnd )
				)
				( attribute "CDS_LIB" "dev_discrete"
					( Origin gPackager )
				)
				( attribute "CDS_LOCATION" "C3D1"
					( Origin gPackager )
				)
				( attribute "CDS_SEC" "1"
					( Origin gPackager )
				)
				( attribute "LOCATION" "C3D1"
					( Origin gFrontEnd )
				)
				( attribute "MATERIAL" "X6S"
					( Origin gFrontEnd )
				)
				( attribute "PACK_TYPE" "0603V"
					( Origin gFrontEnd )
				)
				( attribute "PART_NUMBER" "E15431-004"
					( Origin gFrontEnd )
				)
				( attribute "PHYS_PAGE" "228"
					( Origin gFrontEnd )
				)
				( attribute "ROOM" "PVCCIN_CPU1_DECAP_VR"
					( Origin gFrontEnd )
				)
				( attribute "ROT" "0"
					( Origin gFrontEnd )
				)
				( attribute "SEC" "1"
					( Origin gPackager )
				)
				( attribute "TOLERANCE" "20%"
					( Origin gFrontEnd )
				)
				( attribute "VALUE" "22.0UF"
					( Origin gFrontEnd )
				)
				( attribute "VER" "1"
					( Origin gFrontEnd )
				)
				( attribute "VOLTAGE" "4V"
					( Units "uVoltage" "V" 1.000000)
					( Origin gFrontEnd )
				)
				( attribute "XY" "(1650,1800)"
					( Origin gFrontEnd )
				)
				( attribute "CHIPS_PART_NAME" "CAP_A"
					( Origin gPackager )
				)
				( attribute "CDS_PART_NAME" "CAP_A_0603V-22.0UF,4V,20%,X6S,A"
					( Origin gPackager )
				)
				( attribute "GROUP" "PWR_MLCC_CAP"
					( Origin gFrontEnd )
				)
				( objectStatus "C3D1" )
			)
			( gate "@baseboard_fab2_lib.baseboard_fab2(sch_1):page195_i117"
				( attribute "CDS_LIB" "w_hdl"
					( Origin gPackager )
				)
				( attribute "CDS_LMAN_SYM_OUTLINE" "-100,100,100,-100"
					( Origin gPackager )
				)
				( attribute "LOCATION" "RM1G1"
					( Origin gFrontEnd )
				)
				( attribute "PACK_TYPE" "DISCRET-GC1"
					( Origin gFrontEnd )
				)
				( attribute "PART_NUMBER" "086.2AT24.04R6"
					( Origin gFrontEnd )
				)
				( attribute "PHYS_PAGE" "195"
					( Origin gFrontEnd )
				)
				( attribute "ROT" "0"
					( Origin gFrontEnd )
				)
				( attribute "VALUE" "STFT363B238R224H453-GP"
					( Origin gFrontEnd )
				)
				( attribute "VER" "1"
					( Origin gFrontEnd )
				)
				( attribute "XY" "(-7650,4750)"
					( Origin gFrontEnd )
				)
				( attribute "CHIPS_PART_NAME" "STFT363B238R224H453-GP"
					( Origin gPackager )
				)
				( attribute "CDS_PART_NAME" "STFT363B238R224H453-GP_DISCRETA"
					( Origin gPackager )
				)
				( attribute "SEC" "1"
					( Origin gFrontEnd )
				)
				( attribute "SEC_TYPE" "DISCRET-GC1"
					( Origin gFrontEnd )
				)
				( attribute "CDS_LOCATION" "RM1G1"
					( Origin gPackager )
				)
				( attribute "CDS_SEC" "1"
					( Origin gPackager )
				)
				( objectStatus "RM1G1" )
			)
			( gate "@baseboard_fab2_lib.baseboard_fab2(sch_1):page201_i190"
				( attribute "CDS_LIB" "mstr_discrete"
					( Origin gPackager )
				)
				( attribute "CDS_LOCATION" "R4E10"
					( Origin gPackager )
				)
				( attribute "CDS_SEC" "1"
					( Origin gPackager )
				)
				( attribute "LOCATION" "R4E10"
					( Origin gFrontEnd )
				)
				( attribute "MATERIAL" "EMPTY"
					( Origin gFrontEnd )
				)
				( attribute "PACK_TYPE" "0402"
					( Origin gFrontEnd )
				)
				( attribute "PART_NUMBER" "G21796-017"
					( Origin gFrontEnd )
				)
				( attribute "PHYS_PAGE" "201"
					( Origin gFrontEnd )
				)
				( attribute "ROOM" "PVCCIO_CPU0"
					( Origin gFrontEnd )
				)
				( attribute "ROT" "0"
					( Origin gFrontEnd )
				)
				( attribute "SEC" "1"
					( Origin gFrontEnd )
				)
				( attribute "SEC_TYPE" "0402"
					( Origin gFrontEnd )
				)
				( attribute "TOLERANCE" "1%"
					( Origin gFrontEnd )
				)
				( attribute "VALUE" "100.0"
					( Origin gFrontEnd )
				)
				( attribute "VER" "2"
					( Origin gFrontEnd )
				)
				( attribute "WATTAGE" "1/16W"
					( Origin gFrontEnd )
				)
				( attribute "XY" "(-1275,3750)"
					( Origin gFrontEnd )
				)
				( attribute "CHIPS_PART_NAME" "RES"
					( Origin gPackager )
				)
				( attribute "CDS_PART_NAME" "RES_0402-100.0,1%,1/16W,EMPTY,A"
					( Origin gPackager )
				)
				( objectStatus "R4E10" )
			)
			( gate "@baseboard_fab2_lib.baseboard_fab2(sch_1):page235_i249"
				( attribute "CDS_LIB" "mstr_discrete"
					( Origin gPackager )
				)
				( attribute "CDS_LOCATION" "R8W8"
					( Origin gPackager )
				)
				( attribute "CDS_SEC" "1"
					( Origin gPackager )
				)
				( attribute "LOCATION" "R8W8"
					( Origin gFrontEnd )
				)
				( attribute "MATERIAL" "CHIP"
					( Origin gFrontEnd )
				)
				( attribute "PACK_TYPE" "0402"
					( Origin gFrontEnd )
				)
				( attribute "PART_NUMBER" "G21796-026"
					( Origin gFrontEnd )
				)
				( attribute "PHYS_PAGE" "235"
					( Origin gFrontEnd )
				)
				( attribute "ROOM" "PVNN_PCH_STBY"
					( Origin gFrontEnd )
				)
				( attribute "ROT" "0"
					( Origin gFrontEnd )
				)
				( attribute "SEC" "1"
					( Origin gFrontEnd )
				)
				( attribute "SEC_TYPE" "0402"
					( Origin gFrontEnd )
				)
				( attribute "TOLERANCE" "1%"
					( Origin gFrontEnd )
				)
				( attribute "VALUE" "1.00K"
					( Origin gFrontEnd )
				)
				( attribute "VER" "2"
					( Origin gFrontEnd )
				)
				( attribute "WATTAGE" "1/16W"
					( Origin gFrontEnd )
				)
				( attribute "XY" "(-8750,4950)"
					( Origin gFrontEnd )
				)
				( attribute "CHIPS_PART_NAME" "RES"
					( Origin gPackager )
				)
				( attribute "CDS_PART_NAME" "RES_0402-1.00K,1%,1/16W,CHIP,GA"
					( Origin gPackager )
				)
				( objectStatus "R8W8" )
			)
			( gate "@baseboard_fab2_lib.baseboard_fab2(sch_1):page102_i103"
				( attribute "CDS_LIB" "mstr_discrete"
					( Origin gPackager )
				)
				( attribute "CDS_LOCATION" "R4W2"
					( Origin gPackager )
				)
				( attribute "CDS_SEC" "1"
					( Origin gPackager )
				)
				( attribute "LOCATION" "R4W2"
					( Origin gFrontEnd )
				)
				( attribute "MATERIAL" "CHIP"
					( Origin gFrontEnd )
				)
				( attribute "PACK_TYPE" "0402"
					( Origin gFrontEnd )
				)
				( attribute "PART_NUMBER" "G21796-026"
					( Origin gFrontEnd )
				)
				( attribute "PHYS_PAGE" "102"
					( Origin gFrontEnd )
				)
				( attribute "ROOM" "PROC_SIDEBAND"
					( Origin gFrontEnd )
				)
				( attribute "ROT" "0"
					( Origin gFrontEnd )
				)
				( attribute "SEC" "1"
					( Origin gFrontEnd )
				)
				( attribute "SEC_TYPE" "0402"
					( Origin gFrontEnd )
				)
				( attribute "TOLERANCE" "1%"
					( Origin gFrontEnd )
				)
				( attribute "VALUE" "1.00K"
					( Origin gFrontEnd )
				)
				( attribute "VER" "2"
					( Origin gFrontEnd )
				)
				( attribute "WATTAGE" "1/16W"
					( Origin gFrontEnd )
				)
				( attribute "XY" "(2450,4900)"
					( Origin gFrontEnd )
				)
				( attribute "CHIPS_PART_NAME" "RES"
					( Origin gPackager )
				)
				( attribute "CDS_PART_NAME" "RES_0402-1.00K,1%,1/16W,CHIP,GA"
					( Origin gPackager )
				)
				( objectStatus "R4W2" )
			)
			( gate "@baseboard_fab2_lib.baseboard_fab2(sch_1):page102_i101"
				( attribute "BOM_COST" "DEBUG"
					( Origin gFrontEnd )
				)
				( attribute "CDS_LIB" "mstr_discrete"
					( Origin gPackager )
				)
				( attribute "CDS_LOCATION" "Q4W1"
					( Origin gPackager )
				)
				( attribute "CDS_SEC" "2"
					( Origin gPackager )
				)
				( attribute "LOCATION" "Q4W1"
					( Origin gFrontEnd )
				)
				( attribute "MATERIAL" "FET"
					( Origin gFrontEnd )
				)
				( attribute "PACK_TYPE" "SMLF"
					( Origin gFrontEnd )
				)
				( attribute "PART_NUMBER" "D24280-001"
					( Origin gFrontEnd )
				)
				( attribute "PHYS_PAGE" "102"
					( Origin gFrontEnd )
				)
				( attribute "ROOM" "UART_MUX"
					( Origin gFrontEnd )
				)
				( attribute "ROT" "3"
					( Origin gFrontEnd )
				)
				( attribute "SEC" "2"
					( Origin gFrontEnd )
				)
				( attribute "SEC_TYPE" "SMLF"
					( Origin gFrontEnd )
				)
				( attribute "VALUE" "2N7002DW"
					( Origin gFrontEnd )
				)
				( attribute "VER" "5"
					( Origin gFrontEnd )
				)
				( attribute "XY" "(2000,4100)"
					( Origin gFrontEnd )
				)
				( attribute "CHIPS_PART_NAME" "FET_N_DUAL"
					( Origin gPackager )
				)
				( attribute "CDS_PART_NAME" "FET_N_DUAL_SMLF-2N7002DW,FET,DA"
					( Origin gPackager )
				)
				( objectStatus "Q4W1" )
			)
			( gate "@baseboard_fab2_lib.baseboard_fab2(sch_1):page102_i106"
				( attribute "CDS_LIB" "mstr_discrete"
					( Origin gPackager )
				)
				( attribute "CDS_LOCATION" "R4W4"
					( Origin gPackager )
				)
				( attribute "CDS_SEC" "1"
					( Origin gPackager )
				)
				( attribute "LOCATION" "R4W4"
					( Origin gFrontEnd )
				)
				( attribute "MATERIAL" "CHIP"
					( Origin gFrontEnd )
				)
				( attribute "PACK_TYPE" "0402"
					( Origin gFrontEnd )
				)
				( attribute "PART_NUMBER" "G21497-013"
					( Origin gFrontEnd )
				)
				( attribute "PHYS_PAGE" "102"
					( Origin gFrontEnd )
				)
				( attribute "ROT" "5"
					( Origin gFrontEnd )
				)
				( attribute "SEC" "1"
					( Origin gFrontEnd )
				)
				( attribute "SEC_TYPE" "0402"
					( Origin gFrontEnd )
				)
				( attribute "TOLERANCE" "5%"
					( Origin gFrontEnd )
				)
				( attribute "VALUE" "3.3K"
					( Origin gFrontEnd )
				)
				( attribute "VER" "1"
					( Origin gFrontEnd )
				)
				( attribute "WATTAGE" "1/16W"
					( Origin gFrontEnd )
				)
				( attribute "XY" "(3650,4750)"
					( Origin gFrontEnd )
				)
				( attribute "CHIPS_PART_NAME" "RES"
					( Origin gPackager )
				)
				( attribute "CDS_PART_NAME" "RES_0402-3.3K,5%,1/16W,CHIP,G2A"
					( Origin gPackager )
				)
				( objectStatus "R4W4" )
			)
			( gate "@baseboard_fab2_lib.baseboard_fab2(sch_1):page102_i112"
				( attribute "CDS_LIB" "mstr_discrete"
					( Origin gPackager )
				)
				( attribute "CDS_LOCATION" "Q4W2"
					( Origin gPackager )
				)
				( attribute "LOCATION" "Q4W2"
					( Origin gFrontEnd )
				)
				( attribute "MATERIAL" "FET"
					( Origin gFrontEnd )
				)
				( attribute "PACK_TYPE" "SOT23LF"
					( Origin gFrontEnd )
				)
				( attribute "PART_NUMBER" "C79254-001"
					( Origin gFrontEnd )
				)
				( attribute "PHYS_PAGE" "102"
					( Origin gFrontEnd )
				)
				( attribute "ROOM" "HOT_SWAP"
					( Origin gFrontEnd )
				)
				( attribute "ROT" "0"
					( Origin gFrontEnd )
				)
				( attribute "SEC" "1"
					( Origin gFrontEnd )
				)
				( attribute "SEC_TYPE" "SOT23LF"
					( Origin gFrontEnd )
				)
				( attribute "VALUE" "2N7002"
					( Origin gFrontEnd )
				)
				( attribute "VER" "8"
					( Origin gFrontEnd )
				)
				( attribute "XY" "(-950,1950)"
					( Origin gFrontEnd )
				)
				( attribute "CHIPS_PART_NAME" "FET_N"
					( Origin gPackager )
				)
				( attribute "CDS_PART_NAME" "FET_N_SOT23LF-2N7002,FET,C7925A"
					( Origin gPackager )
				)
				( attribute "CDS_SEC" "1"
					( Origin gPackager )
				)
				( objectStatus "Q4W2" )
			)
			( gate "@baseboard_fab2_lib.baseboard_fab2(sch_1):page102_i109"
				( attribute "BOM_COST" "SYS_CLOCK"
					( Origin gFrontEnd )
				)
				( attribute "CDS_LIB" "mstr_discrete"
					( Origin gPackager )
				)
				( attribute "CDS_LOCATION" "R4W6"
					( Origin gPackager )
				)
				( attribute "CDS_SEC" "1"
					( Origin gPackager )
				)
				( attribute "LOCATION" "R4W6"
					( Origin gFrontEnd )
				)
				( attribute "MATERIAL" "CHIP"
					( Origin gFrontEnd )
				)
				( attribute "PACK_TYPE" "0402"
					( Origin gFrontEnd )
				)
				( attribute "PART_NUMBER" "G21796-072"
					( Origin gFrontEnd )
				)
				( attribute "PHYS_PAGE" "102"
					( Origin gFrontEnd )
				)
				( attribute "ROOM" "DB1200ZL"
					( Origin gFrontEnd )
				)
				( attribute "ROT" "0"
					( Origin gFrontEnd )
				)
				( attribute "SEC" "1"
					( Origin gFrontEnd )
				)
				( attribute "SEC_TYPE" "0402"
					( Origin gFrontEnd )
				)
				( attribute "TOLERANCE" "1%"
					( Origin gFrontEnd )
				)
				( attribute "VALUE" "4.75K"
					( Origin gFrontEnd )
				)
				( attribute "VER" "2"
					( Origin gFrontEnd )
				)
				( attribute "WATTAGE" "1/16W"
					( Origin gFrontEnd )
				)
				( attribute "XY" "(-2400,2350)"
					( Origin gFrontEnd )
				)
				( attribute "CHIPS_PART_NAME" "RES"
					( Origin gPackager )
				)
				( attribute "CDS_PART_NAME" "RES_0402-4.75K,1%,1/16W,CHIP,GA"
					( Origin gPackager )
				)
				( objectStatus "R4W6" )
			)
			( gate "@baseboard_fab2_lib.baseboard_fab2(sch_1):page102_i114"
				( attribute "BOM_COST" "MEM_NV"
					( Origin gFrontEnd )
				)
				( attribute "CDS_LIB" "mstr_discrete"
					( Origin gPackager )
				)
				( attribute "CDS_LOCATION" "R4W5"
					( Origin gPackager )
				)
				( attribute "LOCATION" "R4W5"
					( Origin gFrontEnd )
				)
				( attribute "MATERIAL" "EMPTY"
					( Origin gFrontEnd )
				)
				( attribute "PACK_TYPE" "0402"
					( Origin gFrontEnd )
				)
				( attribute "PART_NUMBER" "G21497-005"
					( Origin gFrontEnd )
				)
				( attribute "PHYS_PAGE" "102"
					( Origin gFrontEnd )
				)
				( attribute "ROOM" "NV_DIMM"
					( Origin gFrontEnd )
				)
				( attribute "ROT" "1"
					( Origin gFrontEnd )
				)
				( attribute "SEC" "1"
					( Origin gFrontEnd )
				)
				( attribute "SEC_TYPE" "0402"
					( Origin gFrontEnd )
				)
				( attribute "TOLERANCE" "5%"
					( Origin gFrontEnd )
				)
				( attribute "VALUE" "0.0"
					( Origin gFrontEnd )
				)
				( attribute "VER" "1"
					( Origin gFrontEnd )
				)
				( attribute "WATTAGE" "1/16W"
					( Origin gFrontEnd )
				)
				( attribute "XY" "(-1650,2000)"
					( Origin gFrontEnd )
				)
				( attribute "CHIPS_PART_NAME" "RES"
					( Origin gPackager )
				)
				( attribute "CDS_PART_NAME" "RES_0402-0.0,5%,1/16W,EMPTY,G2A"
					( Origin gPackager )
				)
				( attribute "CDS_SEC" "1"
					( Origin gPackager )
				)
				( objectStatus "R4W5" )
			)
			( gate "@baseboard_fab2_lib.baseboard_fab2(sch_1):page197_i101"
				( attribute "CDS_LIB" "w_hdl"
					( Origin gPackager )
				)
				( attribute "CDS_LMAN_SYM_OUTLINE" "-50,75,50,-75"
					( Origin gPackager )
				)
				( attribute "LOCATION" "R12W1"
					( Origin gFrontEnd )
				)
				( attribute "PACK_TYPE" "SMD-RG3"
					( Origin gFrontEnd )
				)
				( attribute "PART_NUMBER" "064.6653F.M001"
					( Origin gFrontEnd )
				)
				( attribute "PHYS_PAGE" "197"
					( Origin gFrontEnd )
				)
				( attribute "ROT" "0"
					( Origin gFrontEnd )
				)
				( attribute "VALUE" "665KR5B-1-GP"
					( Origin gFrontEnd )
				)
				( attribute "VER" "1"
					( Origin gFrontEnd )
				)
				( attribute "XY" "(-4475,4125)"
					( Origin gFrontEnd )
				)
				( attribute "CHIPS_PART_NAME" "665KR5B-1-GP"
					( Origin gPackager )
				)
				( attribute "CDS_PART_NAME" "665KR5B-1-GP_SMD-RG3-665KR5B-1A"
					( Origin gPackager )
				)
				( attribute "CDS_LOCATION" "R12W1"
					( Origin gPackager )
				)
				( attribute "CDS_SEC" "1"
					( Origin gPackager )
				)
				( attribute "SEC" "1"
					( Origin gPackager )
				)
				( attribute "ATTRIBUTE" "665K OHM"
					( Origin gFrontEnd )
				)
				( attribute "PACK_SIZE" "AT0805"
					( Origin gFrontEnd )
				)
				( attribute "RATED" "1/8W"
					( Origin gFrontEnd )
				)
				( attribute "TOLERANCE" "0.1%"
					( Origin gFrontEnd )
				)
				( attribute "CONFIG" "064.1003F.M001"
					( Origin gFrontEnd )
				)
				( attribute "NEW_VALUE" "100K OHM"
					( Origin gFrontEnd )
				)
				( objectStatus "R12W1" )
			)
			( gate "@baseboard_fab2_lib.baseboard_fab2(sch_1):page197_i118"
				( attribute "ATTRIBUTE" "665K OHM"
					( Origin gFrontEnd )
				)
				( attribute "CDS_LIB" "w_hdl"
					( Origin gPackager )
				)
				( attribute "CDS_LMAN_SYM_OUTLINE" "-50,75,50,-75"
					( Origin gPackager )
				)
				( attribute "CDS_LOCATION" "R12W11"
					( Origin gPackager )
				)
				( attribute "CDS_SEC" "1"
					( Origin gPackager )
				)
				( attribute "CONFIG" "064.1003F.M001"
					( Origin gFrontEnd )
				)
				( attribute "LOCATION" "R12W11"
					( Origin gFrontEnd )
				)
				( attribute "NEW_VALUE" "100K OHM"
					( Origin gFrontEnd )
				)
				( attribute "PACK_SIZE" "AT0805"
					( Origin gFrontEnd )
				)
				( attribute "PACK_TYPE" "SMD-RG3"
					( Origin gFrontEnd )
				)
				( attribute "PART_NUMBER" "064.6653F.M001"
					( Origin gFrontEnd )
				)
				( attribute "PHYS_PAGE" "197"
					( Origin gFrontEnd )
				)
				( attribute "RATED" "1/8W"
					( Origin gFrontEnd )
				)
				( attribute "ROT" "0"
					( Origin gFrontEnd )
				)
				( attribute "SEC" "1"
					( Origin gPackager )
				)
				( attribute "TOLERANCE" "0.1%"
					( Origin gFrontEnd )
				)
				( attribute "VALUE" "665KR5B-1-GP"
					( Origin gFrontEnd )
				)
				( attribute "VER" "1"
					( Origin gFrontEnd )
				)
				( attribute "XY" "(-1925,4125)"
					( Origin gFrontEnd )
				)
				( attribute "CHIPS_PART_NAME" "665KR5B-1-GP"
					( Origin gPackager )
				)
				( attribute "CDS_PART_NAME" "665KR5B-1-GP_SMD-RG3-665KR5B-1A"
					( Origin gPackager )
				)
				( objectStatus "R12W11" )
			)
			( gate "@baseboard_fab2_lib.baseboard_fab2(sch_1):page225_i319"
				( attribute "BOM_COST" "MEM_VRD_PVDDQ_CD"
					( Origin gFrontEnd )
				)
				( attribute "CDS_LIB" "mstr_discrete"
					( Origin gPackager )
				)
				( attribute "CDS_LOCATION" "C8U1"
					( Origin gPackager )
				)
				( attribute "CDS_SEC" "1"
					( Origin gPackager )
				)
				( attribute "LOCATION" "C8U1"
					( Origin gFrontEnd )
				)
				( attribute "MATERIAL" "X5R"
					( Origin gFrontEnd )
				)
				( attribute "NEW_MATERIAL" "X6S"
					( Origin gFrontEnd )
				)
				( attribute "PACK_TYPE" "0805"
					( Origin gFrontEnd )
				)
				( attribute "PART_NUMBER" "602433-112"
					( Origin gFrontEnd )
				)
				( attribute "PHYS_PAGE" "225"
					( Origin gFrontEnd )
				)
				( attribute "ROOM" "VDDQ_ABC_PWR_VR"
					( Origin gFrontEnd )
				)
				( attribute "ROT" "0"
					( Origin gFrontEnd )
				)
				( attribute "SEC" "1"
					( Origin gFrontEnd )
				)
				( attribute "SEC_TYPE" "0805"
					( Origin gFrontEnd )
				)
				( attribute "TOLERANCE" "20%"
					( Origin gFrontEnd )
				)
				( attribute "VALUE" "100UF"
					( Origin gFrontEnd )
				)
				( attribute "VER" "1"
					( Origin gFrontEnd )
				)
				( attribute "VOLTAGE" "4V"
					( Units "uVoltage" "V" 1.000000)
					( Origin gFrontEnd )
				)
				( attribute "XY" "(5000,2825)"
					( Origin gFrontEnd )
				)
				( attribute "CHIPS_PART_NAME" "CAP"
					( Origin gPackager )
				)
				( attribute "CDS_PART_NAME" "CAP_0805-100UF,4V,20%,X5R,6024A"
					( Origin gPackager )
				)
				( attribute "GROUP" "PWR_MLCC_CAP"
					( Origin gFrontEnd )
				)
				( attribute "NEW_PN" "078.1071T.M002"
					( Origin gFrontEnd )
				)
				( attribute "BOM_SS" "NOPOP"
					( Origin gFrontEnd )
				)
				( objectStatus "C8U1" )
			)
			( gate "@baseboard_fab2_lib.baseboard_fab2(sch_1):page228_i309"
				( attribute "BOM_COST" "MEM_VRD_PVDDQ_CD"
					( Origin gFrontEnd )
				)
				( attribute "CDS_LIB" "mstr_discrete"
					( Origin gPackager )
				)
				( attribute "CDS_LOCATION" "C2A8"
					( Origin gPackager )
				)
				( attribute "CDS_SEC" "1"
					( Origin gPackager )
				)
				( attribute "LOCATION" "C2A8"
					( Origin gFrontEnd )
				)
				( attribute "MATERIAL" "X5R"
					( Origin gFrontEnd )
				)
				( attribute "NEW_MATERIAL" "X6S"
					( Origin gFrontEnd )
				)
				( attribute "PACK_TYPE" "0805"
					( Origin gFrontEnd )
				)
				( attribute "PART_NUMBER" "602433-112"
					( Origin gFrontEnd )
				)
				( attribute "PHYS_PAGE" "228"
					( Origin gFrontEnd )
				)
				( attribute "ROOM" "VDDQ_ABC_PWR_VR"
					( Origin gFrontEnd )
				)
				( attribute "ROT" "0"
					( Origin gFrontEnd )
				)
				( attribute "SEC" "1"
					( Origin gFrontEnd )
				)
				( attribute "SEC_TYPE" "0805"
					( Origin gFrontEnd )
				)
				( attribute "TOLERANCE" "20%"
					( Origin gFrontEnd )
				)
				( attribute "VALUE" "100UF"
					( Origin gFrontEnd )
				)
				( attribute "VER" "1"
					( Origin gFrontEnd )
				)
				( attribute "VOLTAGE" "4V"
					( Units "uVoltage" "V" 1.000000)
					( Origin gFrontEnd )
				)
				( attribute "XY" "(4950,2825)"
					( Origin gFrontEnd )
				)
				( attribute "CHIPS_PART_NAME" "CAP"
					( Origin gPackager )
				)
				( attribute "CDS_PART_NAME" "CAP_0805-100UF,4V,20%,X5R,6024A"
					( Origin gPackager )
				)
				( attribute "GROUP" "PWR_MLCC_CAP"
					( Origin gFrontEnd )
				)
				( attribute "NEW_PN" "078.1071T.M002"
					( Origin gFrontEnd )
				)
				( attribute "BOM_SS" "NOPOP"
					( Origin gFrontEnd )
				)
				( objectStatus "C2A8" )
			)
			( gate "@baseboard_fab2_lib.baseboard_fab2(sch_1):page217_i324"
				( attribute "BOM_COST" "MEM_VRD_PVDDQ_CD"
					( Origin gFrontEnd )
				)
				( attribute "CDS_LIB" "mstr_discrete"
					( Origin gPackager )
				)
				( attribute "CDS_LOCATION" "C5P44"
					( Origin gPackager )
				)
				( attribute "CDS_SEC" "1"
					( Origin gPackager )
				)
				( attribute "LOCATION" "C5P44"
					( Origin gFrontEnd )
				)
				( attribute "MATERIAL" "X5R"
					( Origin gFrontEnd )
				)
				( attribute "NEW_MATERIAL" "X6S"
					( Origin gFrontEnd )
				)
				( attribute "PACK_TYPE" "0805"
					( Origin gFrontEnd )
				)
				( attribute "PART_NUMBER" "602433-112"
					( Origin gFrontEnd )
				)
				( attribute "PHYS_PAGE" "217"
					( Origin gFrontEnd )
				)
				( attribute "ROOM" "VDDQ_ABC_PWR_VR"
					( Origin gFrontEnd )
				)
				( attribute "ROT" "0"
					( Origin gFrontEnd )
				)
				( attribute "SEC" "1"
					( Origin gFrontEnd )
				)
				( attribute "SEC_TYPE" "0805"
					( Origin gFrontEnd )
				)
				( attribute "TOLERANCE" "20%"
					( Origin gFrontEnd )
				)
				( attribute "VALUE" "100UF"
					( Origin gFrontEnd )
				)
				( attribute "VER" "1"
					( Origin gFrontEnd )
				)
				( attribute "VOLTAGE" "4V"
					( Units "uVoltage" "V" 1.000000)
					( Origin gFrontEnd )
				)
				( attribute "XY" "(700,2850)"
					( Origin gFrontEnd )
				)
				( attribute "CHIPS_PART_NAME" "CAP"
					( Origin gPackager )
				)
				( attribute "CDS_PART_NAME" "CAP_0805-100UF,4V,20%,X5R,6024A"
					( Origin gPackager )
				)
				( attribute "GROUP" "PWR_MLCC_CAP"
					( Origin gFrontEnd )
				)
				( attribute "NEW_PN" "078.1071T.M002"
					( Origin gFrontEnd )
				)
				( attribute "BOM_SS" "NOPOP"
					( Origin gFrontEnd )
				)
				( objectStatus "C5P44" )
			)
			( gate "@baseboard_fab2_lib.baseboard_fab2(sch_1):page217_i279"
				( attribute "BOM_COST" "PROC_SOCKET"
					( Origin gFrontEnd )
				)
				( attribute "CDS_LIB" "dev_discrete"
					( Origin gPackager )
				)
				( attribute "CDS_LOCATION" "C5D54"
					( Origin gPackager )
				)
				( attribute "CDS_SEC" "1"
					( Origin gPackager )
				)
				( attribute "LOCATION" "C5D54"
					( Origin gFrontEnd )
				)
				( attribute "MATERIAL" "X6S"
					( Origin gFrontEnd )
				)
				( attribute "PACK_TYPE" "0603V"
					( Origin gFrontEnd )
				)
				( attribute "PART_NUMBER" "E15431-004"
					( Origin gFrontEnd )
				)
				( attribute "PHYS_PAGE" "217"
					( Origin gFrontEnd )
				)
				( attribute "ROOM" "PVCCIN_CPU0_DECAP_VR"
					( Origin gFrontEnd )
				)
				( attribute "ROT" "0"
					( Origin gFrontEnd )
				)
				( attribute "SEC" "1"
					( Origin gPackager )
				)
				( attribute "TOLERANCE" "20%"
					( Origin gFrontEnd )
				)
				( attribute "VALUE" "22.0UF"
					( Origin gFrontEnd )
				)
				( attribute "VER" "1"
					( Origin gFrontEnd )
				)
				( attribute "VOLTAGE" "4V"
					( Units "uVoltage" "V" 1.000000)
					( Origin gFrontEnd )
				)
				( attribute "XY" "(-900,2850)"
					( Origin gFrontEnd )
				)
				( attribute "CHIPS_PART_NAME" "CAP_A"
					( Origin gPackager )
				)
				( attribute "CDS_PART_NAME" "CAP_A_0603V-22.0UF,4V,20%,X6S,A"
					( Origin gPackager )
				)
				( attribute "GROUP" "PWR_MLCC_CAP"
					( Origin gFrontEnd )
				)
				( objectStatus "C5D54" )
			)
			( gate "@baseboard_fab2_lib.baseboard_fab2(sch_1):page217_i280"
				( attribute "BOM_COST" "PROC_SOCKET"
					( Origin gFrontEnd )
				)
				( attribute "CDS_LIB" "dev_discrete"
					( Origin gPackager )
				)
				( attribute "CDS_LOCATION" "C5D55"
					( Origin gPackager )
				)
				( attribute "CDS_SEC" "1"
					( Origin gPackager )
				)
				( attribute "LOCATION" "C5D55"
					( Origin gFrontEnd )
				)
				( attribute "MATERIAL" "X6S"
					( Origin gFrontEnd )
				)
				( attribute "PACK_TYPE" "0603V"
					( Origin gFrontEnd )
				)
				( attribute "PART_NUMBER" "E15431-004"
					( Origin gFrontEnd )
				)
				( attribute "PHYS_PAGE" "217"
					( Origin gFrontEnd )
				)
				( attribute "ROOM" "PVCCIN_CPU0_DECAP_VR"
					( Origin gFrontEnd )
				)
				( attribute "ROT" "0"
					( Origin gFrontEnd )
				)
				( attribute "SEC" "1"
					( Origin gPackager )
				)
				( attribute "TOLERANCE" "20%"
					( Origin gFrontEnd )
				)
				( attribute "VALUE" "22.0UF"
					( Origin gFrontEnd )
				)
				( attribute "VER" "1"
					( Origin gFrontEnd )
				)
				( attribute "VOLTAGE" "4V"
					( Units "uVoltage" "V" 1.000000)
					( Origin gFrontEnd )
				)
				( attribute "XY" "(-550,2850)"
					( Origin gFrontEnd )
				)
				( attribute "CHIPS_PART_NAME" "CAP_A"
					( Origin gPackager )
				)
				( attribute "CDS_PART_NAME" "CAP_A_0603V-22.0UF,4V,20%,X6S,A"
					( Origin gPackager )
				)
				( attribute "GROUP" "PWR_MLCC_CAP"
					( Origin gFrontEnd )
				)
				( objectStatus "C5D55" )
			)
			( gate "@baseboard_fab2_lib.baseboard_fab2(sch_1):page217_i281"
				( attribute "BOM_COST" "PROC_SOCKET"
					( Origin gFrontEnd )
				)
				( attribute "CDS_LIB" "dev_discrete"
					( Origin gPackager )
				)
				( attribute "CDS_LOCATION" "C5D56"
					( Origin gPackager )
				)
				( attribute "CDS_SEC" "1"
					( Origin gPackager )
				)
				( attribute "LOCATION" "C5D56"
					( Origin gFrontEnd )
				)
				( attribute "MATERIAL" "X6S"
					( Origin gFrontEnd )
				)
				( attribute "PACK_TYPE" "0603V"
					( Origin gFrontEnd )
				)
				( attribute "PART_NUMBER" "E15431-004"
					( Origin gFrontEnd )
				)
				( attribute "PHYS_PAGE" "217"
					( Origin gFrontEnd )
				)
				( attribute "ROOM" "PVCCIN_CPU0_DECAP_VR"
					( Origin gFrontEnd )
				)
				( attribute "ROT" "0"
					( Origin gFrontEnd )
				)
				( attribute "SEC" "1"
					( Origin gPackager )
				)
				( attribute "TOLERANCE" "20%"
					( Origin gFrontEnd )
				)
				( attribute "VALUE" "22.0UF"
					( Origin gFrontEnd )
				)
				( attribute "VER" "1"
					( Origin gFrontEnd )
				)
				( attribute "VOLTAGE" "4V"
					( Units "uVoltage" "V" 1.000000)
					( Origin gFrontEnd )
				)
				( attribute "XY" "(-200,2850)"
					( Origin gFrontEnd )
				)
				( attribute "CHIPS_PART_NAME" "CAP_A"
					( Origin gPackager )
				)
				( attribute "CDS_PART_NAME" "CAP_A_0603V-22.0UF,4V,20%,X6S,A"
					( Origin gPackager )
				)
				( attribute "GROUP" "PWR_MLCC_CAP"
					( Origin gFrontEnd )
				)
				( objectStatus "C5D56" )
			)
			( gate "@baseboard_fab2_lib.baseboard_fab2(sch_1):page217_i282"
				( attribute "BOM_COST" "PROC_SOCKET"
					( Origin gFrontEnd )
				)
				( attribute "CDS_LIB" "dev_discrete"
					( Origin gPackager )
				)
				( attribute "CDS_LOCATION" "C5D57"
					( Origin gPackager )
				)
				( attribute "CDS_SEC" "1"
					( Origin gPackager )
				)
				( attribute "LOCATION" "C5D57"
					( Origin gFrontEnd )
				)
				( attribute "MATERIAL" "X6S"
					( Origin gFrontEnd )
				)
				( attribute "PACK_TYPE" "0603V"
					( Origin gFrontEnd )
				)
				( attribute "PART_NUMBER" "E15431-004"
					( Origin gFrontEnd )
				)
				( attribute "PHYS_PAGE" "217"
					( Origin gFrontEnd )
				)
				( attribute "ROOM" "PVCCIN_CPU0_DECAP_VR"
					( Origin gFrontEnd )
				)
				( attribute "ROT" "0"
					( Origin gFrontEnd )
				)
				( attribute "SEC" "1"
					( Origin gPackager )
				)
				( attribute "TOLERANCE" "20%"
					( Origin gFrontEnd )
				)
				( attribute "VALUE" "22.0UF"
					( Origin gFrontEnd )
				)
				( attribute "VER" "1"
					( Origin gFrontEnd )
				)
				( attribute "VOLTAGE" "4V"
					( Units "uVoltage" "V" 1.000000)
					( Origin gFrontEnd )
				)
				( attribute "XY" "(150,2850)"
					( Origin gFrontEnd )
				)
				( attribute "CHIPS_PART_NAME" "CAP_A"
					( Origin gPackager )
				)
				( attribute "CDS_PART_NAME" "CAP_A_0603V-22.0UF,4V,20%,X6S,A"
					( Origin gPackager )
				)
				( attribute "GROUP" "PWR_MLCC_CAP"
					( Origin gFrontEnd )
				)
				( objectStatus "C5D57" )
			)
			( gate "@baseboard_fab2_lib.baseboard_fab2(sch_1):page217_i287"
				( attribute "CDS_LIB" "dev_discrete"
					( Origin gPackager )
				)
				( attribute "CDS_LOCATION" "C5U6"
					( Origin gPackager )
				)
				( attribute "CDS_SEC" "1"
					( Origin gPackager )
				)
				( attribute "LOCATION" "C5U6"
					( Origin gFrontEnd )
				)
				( attribute "MATERIAL" "X5R"
					( Origin gFrontEnd )
				)
				( attribute "PACK_TYPE" "0603V"
					( Origin gFrontEnd )
				)
				( attribute "PART_NUMBER" "602433-106"
					( Origin gFrontEnd )
				)
				( attribute "PHYS_PAGE" "217"
					( Origin gFrontEnd )
				)
				( attribute "ROT" "0"
					( Origin gFrontEnd )
				)
				( attribute "SEC" "1"
					( Origin gFrontEnd )
				)
				( attribute "SEC_TYPE" "0603V"
					( Origin gFrontEnd )
				)
				( attribute "TOLERANCE" "20%"
					( Origin gFrontEnd )
				)
				( attribute "VALUE" "47UF"
					( Origin gFrontEnd )
				)
				( attribute "VER" "1"
					( Origin gFrontEnd )
				)
				( attribute "VOLTAGE" "4V"
					( Units "uVoltage" "V" 1.000000)
					( Origin gFrontEnd )
				)
				( attribute "XY" "(-675,50)"
					( Origin gFrontEnd )
				)
				( attribute "CHIPS_PART_NAME" "CAP_A"
					( Origin gPackager )
				)
				( attribute "CDS_PART_NAME" "CAP_A_0603V-47UF,4V,20%,X5R,60A"
					( Origin gPackager )
				)
				( attribute "GROUP" "PWR_MLCC_CAP"
					( Origin gFrontEnd )
				)
				( attribute "BOM_SS" "E15431-004"
					( Origin gFrontEnd )
				)
				( objectStatus "C5U6" )
			)
			( gate "@baseboard_fab2_lib.baseboard_fab2(sch_1):page217_i288"
				( attribute "CDS_LIB" "dev_discrete"
					( Origin gPackager )
				)
				( attribute "CDS_LOCATION" "C5U7"
					( Origin gPackager )
				)
				( attribute "CDS_SEC" "1"
					( Origin gPackager )
				)
				( attribute "LOCATION" "C5U7"
					( Origin gFrontEnd )
				)
				( attribute "MATERIAL" "X5R"
					( Origin gFrontEnd )
				)
				( attribute "PACK_TYPE" "0603V"
					( Origin gFrontEnd )
				)
				( attribute "PART_NUMBER" "602433-106"
					( Origin gFrontEnd )
				)
				( attribute "PHYS_PAGE" "217"
					( Origin gFrontEnd )
				)
				( attribute "ROT" "0"
					( Origin gFrontEnd )
				)
				( attribute "SEC" "1"
					( Origin gFrontEnd )
				)
				( attribute "SEC_TYPE" "0603V"
					( Origin gFrontEnd )
				)
				( attribute "TOLERANCE" "20%"
					( Origin gFrontEnd )
				)
				( attribute "VALUE" "47UF"
					( Origin gFrontEnd )
				)
				( attribute "VER" "1"
					( Origin gFrontEnd )
				)
				( attribute "VOLTAGE" "4V"
					( Units "uVoltage" "V" 1.000000)
					( Origin gFrontEnd )
				)
				( attribute "XY" "(-375,50)"
					( Origin gFrontEnd )
				)
				( attribute "CHIPS_PART_NAME" "CAP_A"
					( Origin gPackager )
				)
				( attribute "CDS_PART_NAME" "CAP_A_0603V-47UF,4V,20%,X5R,60A"
					( Origin gPackager )
				)
				( attribute "GROUP" "PWR_MLCC_CAP"
					( Origin gFrontEnd )
				)
				( attribute "BOM_SS" "E15431-004"
					( Origin gFrontEnd )
				)
				( objectStatus "C5U7" )
			)
			( gate "@baseboard_fab2_lib.baseboard_fab2(sch_1):page217_i289"
				( attribute "CDS_LIB" "dev_discrete"
					( Origin gPackager )
				)
				( attribute "CDS_LOCATION" "C5U8"
					( Origin gPackager )
				)
				( attribute "CDS_SEC" "1"
					( Origin gPackager )
				)
				( attribute "LOCATION" "C5U8"
					( Origin gFrontEnd )
				)
				( attribute "MATERIAL" "X5R"
					( Origin gFrontEnd )
				)
				( attribute "PACK_TYPE" "0603V"
					( Origin gFrontEnd )
				)
				( attribute "PART_NUMBER" "602433-106"
					( Origin gFrontEnd )
				)
				( attribute "PHYS_PAGE" "217"
					( Origin gFrontEnd )
				)
				( attribute "ROT" "0"
					( Origin gFrontEnd )
				)
				( attribute "SEC" "1"
					( Origin gFrontEnd )
				)
				( attribute "SEC_TYPE" "0603V"
					( Origin gFrontEnd )
				)
				( attribute "TOLERANCE" "20%"
					( Origin gFrontEnd )
				)
				( attribute "VALUE" "47UF"
					( Origin gFrontEnd )
				)
				( attribute "VER" "1"
					( Origin gFrontEnd )
				)
				( attribute "VOLTAGE" "4V"
					( Units "uVoltage" "V" 1.000000)
					( Origin gFrontEnd )
				)
				( attribute "XY" "(-75,50)"
					( Origin gFrontEnd )
				)
				( attribute "CHIPS_PART_NAME" "CAP_A"
					( Origin gPackager )
				)
				( attribute "CDS_PART_NAME" "CAP_A_0603V-47UF,4V,20%,X5R,60A"
					( Origin gPackager )
				)
				( attribute "GROUP" "PWR_MLCC_CAP"
					( Origin gFrontEnd )
				)
				( attribute "BOM_SS" "E15431-004"
					( Origin gFrontEnd )
				)
				( objectStatus "C5U8" )
			)
			( gate "@baseboard_fab2_lib.baseboard_fab2(sch_1):page217_i290"
				( attribute "CDS_LIB" "dev_discrete"
					( Origin gPackager )
				)
				( attribute "CDS_LOCATION" "C5U9"
					( Origin gPackager )
				)
				( attribute "CDS_SEC" "1"
					( Origin gPackager )
				)
				( attribute "LOCATION" "C5U9"
					( Origin gFrontEnd )
				)
				( attribute "MATERIAL" "X5R"
					( Origin gFrontEnd )
				)
				( attribute "PACK_TYPE" "0603V"
					( Origin gFrontEnd )
				)
				( attribute "PART_NUMBER" "602433-106"
					( Origin gFrontEnd )
				)
				( attribute "PHYS_PAGE" "217"
					( Origin gFrontEnd )
				)
				( attribute "ROT" "0"
					( Origin gFrontEnd )
				)
				( attribute "SEC" "1"
					( Origin gFrontEnd )
				)
				( attribute "SEC_TYPE" "0603V"
					( Origin gFrontEnd )
				)
				( attribute "TOLERANCE" "20%"
					( Origin gFrontEnd )
				)
				( attribute "VALUE" "47UF"
					( Origin gFrontEnd )
				)
				( attribute "VER" "1"
					( Origin gFrontEnd )
				)
				( attribute "VOLTAGE" "4V"
					( Units "uVoltage" "V" 1.000000)
					( Origin gFrontEnd )
				)
				( attribute "XY" "(200,50)"
					( Origin gFrontEnd )
				)
				( attribute "CHIPS_PART_NAME" "CAP_A"
					( Origin gPackager )
				)
				( attribute "CDS_PART_NAME" "CAP_A_0603V-47UF,4V,20%,X5R,60A"
					( Origin gPackager )
				)
				( attribute "GROUP" "PWR_MLCC_CAP"
					( Origin gFrontEnd )
				)
				( attribute "BOM_SS" "E15431-004"
					( Origin gFrontEnd )
				)
				( objectStatus "C5U9" )
			)
			( gate "@baseboard_fab2_lib.baseboard_fab2(sch_1):page217_i291"
				( attribute "CDS_LIB" "dev_discrete"
					( Origin gPackager )
				)
				( attribute "CDS_LOCATION" "C5T12"
					( Origin gPackager )
				)
				( attribute "CDS_SEC" "1"
					( Origin gPackager )
				)
				( attribute "LOCATION" "C5T12"
					( Origin gFrontEnd )
				)
				( attribute "MATERIAL" "X5R"
					( Origin gFrontEnd )
				)
				( attribute "PACK_TYPE" "0603V"
					( Origin gFrontEnd )
				)
				( attribute "PART_NUMBER" "602433-106"
					( Origin gFrontEnd )
				)
				( attribute "PHYS_PAGE" "217"
					( Origin gFrontEnd )
				)
				( attribute "ROT" "0"
					( Origin gFrontEnd )
				)
				( attribute "SEC" "1"
					( Origin gFrontEnd )
				)
				( attribute "SEC_TYPE" "0603V"
					( Origin gFrontEnd )
				)
				( attribute "TOLERANCE" "20%"
					( Origin gFrontEnd )
				)
				( attribute "VALUE" "47UF"
					( Origin gFrontEnd )
				)
				( attribute "VER" "1"
					( Origin gFrontEnd )
				)
				( attribute "VOLTAGE" "4V"
					( Units "uVoltage" "V" 1.000000)
					( Origin gFrontEnd )
				)
				( attribute "XY" "(525,50)"
					( Origin gFrontEnd )
				)
				( attribute "CHIPS_PART_NAME" "CAP_A"
					( Origin gPackager )
				)
				( attribute "CDS_PART_NAME" "CAP_A_0603V-47UF,4V,20%,X5R,60A"
					( Origin gPackager )
				)
				( attribute "GROUP" "PWR_MLCC_CAP"
					( Origin gFrontEnd )
				)
				( attribute "BOM_SS" "E15431-004"
					( Origin gFrontEnd )
				)
				( objectStatus "C5T12" )
			)
			( gate "@baseboard_fab2_lib.baseboard_fab2(sch_1):page217_i292"
				( attribute "CDS_LIB" "dev_discrete"
					( Origin gPackager )
				)
				( attribute "CDS_LOCATION" "C5T11"
					( Origin gPackager )
				)
				( attribute "CDS_SEC" "1"
					( Origin gPackager )
				)
				( attribute "LOCATION" "C5T11"
					( Origin gFrontEnd )
				)
				( attribute "MATERIAL" "X5R"
					( Origin gFrontEnd )
				)
				( attribute "PACK_TYPE" "0603V"
					( Origin gFrontEnd )
				)
				( attribute "PART_NUMBER" "602433-106"
					( Origin gFrontEnd )
				)
				( attribute "PHYS_PAGE" "217"
					( Origin gFrontEnd )
				)
				( attribute "ROT" "0"
					( Origin gFrontEnd )
				)
				( attribute "SEC" "1"
					( Origin gFrontEnd )
				)
				( attribute "SEC_TYPE" "0603V"
					( Origin gFrontEnd )
				)
				( attribute "TOLERANCE" "20%"
					( Origin gFrontEnd )
				)
				( attribute "VALUE" "47UF"
					( Origin gFrontEnd )
				)
				( attribute "VER" "1"
					( Origin gFrontEnd )
				)
				( attribute "VOLTAGE" "4V"
					( Units "uVoltage" "V" 1.000000)
					( Origin gFrontEnd )
				)
				( attribute "XY" "(825,50)"
					( Origin gFrontEnd )
				)
				( attribute "CHIPS_PART_NAME" "CAP_A"
					( Origin gPackager )
				)
				( attribute "CDS_PART_NAME" "CAP_A_0603V-47UF,4V,20%,X5R,60A"
					( Origin gPackager )
				)
				( attribute "GROUP" "PWR_MLCC_CAP"
					( Origin gFrontEnd )
				)
				( attribute "BOM_SS" "E15431-004"
					( Origin gFrontEnd )
				)
				( objectStatus "C5T11" )
			)
			( gate "@baseboard_fab2_lib.baseboard_fab2(sch_1):page217_i293"
				( attribute "CDS_LIB" "dev_discrete"
					( Origin gPackager )
				)
				( attribute "CDS_LOCATION" "C5T10"
					( Origin gPackager )
				)
				( attribute "CDS_SEC" "1"
					( Origin gPackager )
				)
				( attribute "LOCATION" "C5T10"
					( Origin gFrontEnd )
				)
				( attribute "MATERIAL" "X5R"
					( Origin gFrontEnd )
				)
				( attribute "PACK_TYPE" "0603V"
					( Origin gFrontEnd )
				)
				( attribute "PART_NUMBER" "602433-106"
					( Origin gFrontEnd )
				)
				( attribute "PHYS_PAGE" "217"
					( Origin gFrontEnd )
				)
				( attribute "ROT" "0"
					( Origin gFrontEnd )
				)
				( attribute "SEC" "1"
					( Origin gFrontEnd )
				)
				( attribute "SEC_TYPE" "0603V"
					( Origin gFrontEnd )
				)
				( attribute "TOLERANCE" "20%"
					( Origin gFrontEnd )
				)
				( attribute "VALUE" "47UF"
					( Origin gFrontEnd )
				)
				( attribute "VER" "1"
					( Origin gFrontEnd )
				)
				( attribute "VOLTAGE" "4V"
					( Units "uVoltage" "V" 1.000000)
					( Origin gFrontEnd )
				)
				( attribute "XY" "(1125,50)"
					( Origin gFrontEnd )
				)
				( attribute "CHIPS_PART_NAME" "CAP_A"
					( Origin gPackager )
				)
				( attribute "CDS_PART_NAME" "CAP_A_0603V-47UF,4V,20%,X5R,60A"
					( Origin gPackager )
				)
				( attribute "GROUP" "PWR_MLCC_CAP"
					( Origin gFrontEnd )
				)
				( attribute "BOM_SS" "E15431-004"
					( Origin gFrontEnd )
				)
				( objectStatus "C5T10" )
			)
			( gate "@baseboard_fab2_lib.baseboard_fab2(sch_1):page217_i294"
				( attribute "CDS_LIB" "dev_discrete"
					( Origin gPackager )
				)
				( attribute "CDS_LOCATION" "C5T9"
					( Origin gPackager )
				)
				( attribute "CDS_SEC" "1"
					( Origin gPackager )
				)
				( attribute "LOCATION" "C5T9"
					( Origin gFrontEnd )
				)
				( attribute "MATERIAL" "X5R"
					( Origin gFrontEnd )
				)
				( attribute "PACK_TYPE" "0603V"
					( Origin gFrontEnd )
				)
				( attribute "PART_NUMBER" "602433-106"
					( Origin gFrontEnd )
				)
				( attribute "PHYS_PAGE" "217"
					( Origin gFrontEnd )
				)
				( attribute "ROT" "0"
					( Origin gFrontEnd )
				)
				( attribute "SEC" "1"
					( Origin gFrontEnd )
				)
				( attribute "SEC_TYPE" "0603V"
					( Origin gFrontEnd )
				)
				( attribute "TOLERANCE" "20%"
					( Origin gFrontEnd )
				)
				( attribute "VALUE" "47UF"
					( Origin gFrontEnd )
				)
				( attribute "VER" "1"
					( Origin gFrontEnd )
				)
				( attribute "VOLTAGE" "4V"
					( Units "uVoltage" "V" 1.000000)
					( Origin gFrontEnd )
				)
				( attribute "XY" "(1400,50)"
					( Origin gFrontEnd )
				)
				( attribute "CHIPS_PART_NAME" "CAP_A"
					( Origin gPackager )
				)
				( attribute "CDS_PART_NAME" "CAP_A_0603V-47UF,4V,20%,X5R,60A"
					( Origin gPackager )
				)
				( attribute "GROUP" "PWR_MLCC_CAP"
					( Origin gFrontEnd )
				)
				( attribute "BOM_SS" "E15431-004"
					( Origin gFrontEnd )
				)
				( objectStatus "C5T9" )
			)
			( gate "@baseboard_fab2_lib.baseboard_fab2(sch_1):page217_i295"
				( attribute "CDS_LIB" "dev_discrete"
					( Origin gPackager )
				)
				( attribute "CDS_LOCATION" "C5T8"
					( Origin gPackager )
				)
				( attribute "CDS_SEC" "1"
					( Origin gPackager )
				)
				( attribute "LOCATION" "C5T8"
					( Origin gFrontEnd )
				)
				( attribute "MATERIAL" "X5R"
					( Origin gFrontEnd )
				)
				( attribute "PACK_TYPE" "0603V"
					( Origin gFrontEnd )
				)
				( attribute "PART_NUMBER" "602433-106"
					( Origin gFrontEnd )
				)
				( attribute "PHYS_PAGE" "217"
					( Origin gFrontEnd )
				)
				( attribute "ROT" "0"
					( Origin gFrontEnd )
				)
				( attribute "SEC" "1"
					( Origin gFrontEnd )
				)
				( attribute "SEC_TYPE" "0603V"
					( Origin gFrontEnd )
				)
				( attribute "TOLERANCE" "20%"
					( Origin gFrontEnd )
				)
				( attribute "VALUE" "47UF"
					( Origin gFrontEnd )
				)
				( attribute "VER" "1"
					( Origin gFrontEnd )
				)
				( attribute "VOLTAGE" "4V"
					( Units "uVoltage" "V" 1.000000)
					( Origin gFrontEnd )
				)
				( attribute "XY" "(1675,50)"
					( Origin gFrontEnd )
				)
				( attribute "CHIPS_PART_NAME" "CAP_A"
					( Origin gPackager )
				)
				( attribute "CDS_PART_NAME" "CAP_A_0603V-47UF,4V,20%,X5R,60A"
					( Origin gPackager )
				)
				( attribute "GROUP" "PWR_MLCC_CAP"
					( Origin gFrontEnd )
				)
				( attribute "BOM_SS" "E15431-004"
					( Origin gFrontEnd )
				)
				( objectStatus "C5T8" )
			)
			( gate "@baseboard_fab2_lib.baseboard_fab2(sch_1):page217_i296"
				( attribute "CDS_LIB" "dev_discrete"
					( Origin gPackager )
				)
				( attribute "CDS_LOCATION" "C5T7"
					( Origin gPackager )
				)
				( attribute "CDS_SEC" "1"
					( Origin gPackager )
				)
				( attribute "LOCATION" "C5T7"
					( Origin gFrontEnd )
				)
				( attribute "MATERIAL" "X5R"
					( Origin gFrontEnd )
				)
				( attribute "PACK_TYPE" "0603V"
					( Origin gFrontEnd )
				)
				( attribute "PART_NUMBER" "602433-106"
					( Origin gFrontEnd )
				)
				( attribute "PHYS_PAGE" "217"
					( Origin gFrontEnd )
				)
				( attribute "ROT" "0"
					( Origin gFrontEnd )
				)
				( attribute "SEC" "1"
					( Origin gFrontEnd )
				)
				( attribute "SEC_TYPE" "0603V"
					( Origin gFrontEnd )
				)
				( attribute "TOLERANCE" "20%"
					( Origin gFrontEnd )
				)
				( attribute "VALUE" "47UF"
					( Origin gFrontEnd )
				)
				( attribute "VER" "1"
					( Origin gFrontEnd )
				)
				( attribute "VOLTAGE" "4V"
					( Units "uVoltage" "V" 1.000000)
					( Origin gFrontEnd )
				)
				( attribute "XY" "(1975,50)"
					( Origin gFrontEnd )
				)
				( attribute "CHIPS_PART_NAME" "CAP_A"
					( Origin gPackager )
				)
				( attribute "CDS_PART_NAME" "CAP_A_0603V-47UF,4V,20%,X5R,60A"
					( Origin gPackager )
				)
				( attribute "GROUP" "PWR_MLCC_CAP"
					( Origin gFrontEnd )
				)
				( attribute "BOM_SS" "E15431-004"
					( Origin gFrontEnd )
				)
				( objectStatus "C5T7" )
			)
			( gate "@baseboard_fab2_lib.baseboard_fab2(sch_1):page217_i297"
				( attribute "CDS_LIB" "dev_discrete"
					( Origin gPackager )
				)
				( attribute "CDS_LOCATION" "C5T6"
					( Origin gPackager )
				)
				( attribute "CDS_SEC" "1"
					( Origin gPackager )
				)
				( attribute "LOCATION" "C5T6"
					( Origin gFrontEnd )
				)
				( attribute "MATERIAL" "X5R"
					( Origin gFrontEnd )
				)
				( attribute "PACK_TYPE" "0603V"
					( Origin gFrontEnd )
				)
				( attribute "PART_NUMBER" "602433-106"
					( Origin gFrontEnd )
				)
				( attribute "PHYS_PAGE" "217"
					( Origin gFrontEnd )
				)
				( attribute "ROT" "0"
					( Origin gFrontEnd )
				)
				( attribute "SEC" "1"
					( Origin gFrontEnd )
				)
				( attribute "SEC_TYPE" "0603V"
					( Origin gFrontEnd )
				)
				( attribute "TOLERANCE" "20%"
					( Origin gFrontEnd )
				)
				( attribute "VALUE" "47UF"
					( Origin gFrontEnd )
				)
				( attribute "VER" "1"
					( Origin gFrontEnd )
				)
				( attribute "VOLTAGE" "4V"
					( Units "uVoltage" "V" 1.000000)
					( Origin gFrontEnd )
				)
				( attribute "XY" "(2275,50)"
					( Origin gFrontEnd )
				)
				( attribute "CHIPS_PART_NAME" "CAP_A"
					( Origin gPackager )
				)
				( attribute "CDS_PART_NAME" "CAP_A_0603V-47UF,4V,20%,X5R,60A"
					( Origin gPackager )
				)
				( attribute "GROUP" "PWR_MLCC_CAP"
					( Origin gFrontEnd )
				)
				( attribute "BOM_SS" "E15431-004"
					( Origin gFrontEnd )
				)
				( objectStatus "C5T6" )
			)
			( gate "@baseboard_fab2_lib.baseboard_fab2(sch_1):page217_i298"
				( attribute "CDS_LIB" "dev_discrete"
					( Origin gPackager )
				)
				( attribute "CDS_LOCATION" "C5T5"
					( Origin gPackager )
				)
				( attribute "CDS_SEC" "1"
					( Origin gPackager )
				)
				( attribute "LOCATION" "C5T5"
					( Origin gFrontEnd )
				)
				( attribute "MATERIAL" "X5R"
					( Origin gFrontEnd )
				)
				( attribute "PACK_TYPE" "0603V"
					( Origin gFrontEnd )
				)
				( attribute "PART_NUMBER" "602433-106"
					( Origin gFrontEnd )
				)
				( attribute "PHYS_PAGE" "217"
					( Origin gFrontEnd )
				)
				( attribute "ROT" "0"
					( Origin gFrontEnd )
				)
				( attribute "SEC" "1"
					( Origin gFrontEnd )
				)
				( attribute "SEC_TYPE" "0603V"
					( Origin gFrontEnd )
				)
				( attribute "TOLERANCE" "20%"
					( Origin gFrontEnd )
				)
				( attribute "VALUE" "47UF"
					( Origin gFrontEnd )
				)
				( attribute "VER" "1"
					( Origin gFrontEnd )
				)
				( attribute "VOLTAGE" "4V"
					( Units "uVoltage" "V" 1.000000)
					( Origin gFrontEnd )
				)
				( attribute "XY" "(2550,50)"
					( Origin gFrontEnd )
				)
				( attribute "CHIPS_PART_NAME" "CAP_A"
					( Origin gPackager )
				)
				( attribute "CDS_PART_NAME" "CAP_A_0603V-47UF,4V,20%,X5R,60A"
					( Origin gPackager )
				)
				( attribute "GROUP" "PWR_MLCC_CAP"
					( Origin gFrontEnd )
				)
				( attribute "BOM_SS" "E15431-004"
					( Origin gFrontEnd )
				)
				( objectStatus "C5T5" )
			)
			( gate "@baseboard_fab2_lib.baseboard_fab2(sch_1):page225_i288"
				( attribute "CDS_LIB" "dev_discrete"
					( Origin gPackager )
				)
				( attribute "CDS_LOCATION" "C3G5"
					( Origin gPackager )
				)
				( attribute "CDS_SEC" "1"
					( Origin gPackager )
				)
				( attribute "LOCATION" "C3G5"
					( Origin gFrontEnd )
				)
				( attribute "MATERIAL" "X5R"
					( Origin gFrontEnd )
				)
				( attribute "PACK_TYPE" "0603V"
					( Origin gFrontEnd )
				)
				( attribute "PART_NUMBER" "602433-106"
					( Origin gFrontEnd )
				)
				( attribute "PHYS_PAGE" "225"
					( Origin gFrontEnd )
				)
				( attribute "ROT" "0"
					( Origin gFrontEnd )
				)
				( attribute "SEC" "1"
					( Origin gFrontEnd )
				)
				( attribute "SEC_TYPE" "0603V"
					( Origin gFrontEnd )
				)
				( attribute "TOLERANCE" "20%"
					( Origin gFrontEnd )
				)
				( attribute "VALUE" "47UF"
					( Origin gFrontEnd )
				)
				( attribute "VER" "1"
					( Origin gFrontEnd )
				)
				( attribute "VOLTAGE" "4V"
					( Units "uVoltage" "V" 1.000000)
					( Origin gFrontEnd )
				)
				( attribute "XY" "(1825,250)"
					( Origin gFrontEnd )
				)
				( attribute "CHIPS_PART_NAME" "CAP_A"
					( Origin gPackager )
				)
				( attribute "CDS_PART_NAME" "CAP_A_0603V-47UF,4V,20%,X5R,60A"
					( Origin gPackager )
				)
				( attribute "GROUP" "PWR_MLCC_CAP"
					( Origin gFrontEnd )
				)
				( attribute "BOM_SS" "E15431-004"
					( Origin gFrontEnd )
				)
				( objectStatus "C3G5" )
			)
			( gate "@baseboard_fab2_lib.baseboard_fab2(sch_1):page225_i289"
				( attribute "CDS_LIB" "dev_discrete"
					( Origin gPackager )
				)
				( attribute "CDS_LOCATION" "C3G6"
					( Origin gPackager )
				)
				( attribute "CDS_SEC" "1"
					( Origin gPackager )
				)
				( attribute "LOCATION" "C3G6"
					( Origin gFrontEnd )
				)
				( attribute "MATERIAL" "X5R"
					( Origin gFrontEnd )
				)
				( attribute "PACK_TYPE" "0603V"
					( Origin gFrontEnd )
				)
				( attribute "PART_NUMBER" "602433-106"
					( Origin gFrontEnd )
				)
				( attribute "PHYS_PAGE" "225"
					( Origin gFrontEnd )
				)
				( attribute "ROT" "0"
					( Origin gFrontEnd )
				)
				( attribute "SEC" "1"
					( Origin gFrontEnd )
				)
				( attribute "SEC_TYPE" "0603V"
					( Origin gFrontEnd )
				)
				( attribute "TOLERANCE" "20%"
					( Origin gFrontEnd )
				)
				( attribute "VALUE" "47UF"
					( Origin gFrontEnd )
				)
				( attribute "VER" "1"
					( Origin gFrontEnd )
				)
				( attribute "VOLTAGE" "4V"
					( Units "uVoltage" "V" 1.000000)
					( Origin gFrontEnd )
				)
				( attribute "XY" "(2100,250)"
					( Origin gFrontEnd )
				)
				( attribute "CHIPS_PART_NAME" "CAP_A"
					( Origin gPackager )
				)
				( attribute "CDS_PART_NAME" "CAP_A_0603V-47UF,4V,20%,X5R,60A"
					( Origin gPackager )
				)
				( attribute "GROUP" "PWR_MLCC_CAP"
					( Origin gFrontEnd )
				)
				( attribute "BOM_SS" "E15431-004"
					( Origin gFrontEnd )
				)
				( objectStatus "C3G6" )
			)
			( gate "@baseboard_fab2_lib.baseboard_fab2(sch_1):page225_i290"
				( attribute "CDS_LIB" "dev_discrete"
					( Origin gPackager )
				)
				( attribute "CDS_LOCATION" "C8U7"
					( Origin gPackager )
				)
				( attribute "CDS_SEC" "1"
					( Origin gPackager )
				)
				( attribute "LOCATION" "C8U7"
					( Origin gFrontEnd )
				)
				( attribute "MATERIAL" "X5R"
					( Origin gFrontEnd )
				)
				( attribute "PACK_TYPE" "0603V"
					( Origin gFrontEnd )
				)
				( attribute "PART_NUMBER" "602433-106"
					( Origin gFrontEnd )
				)
				( attribute "PHYS_PAGE" "225"
					( Origin gFrontEnd )
				)
				( attribute "ROT" "0"
					( Origin gFrontEnd )
				)
				( attribute "SEC" "1"
					( Origin gFrontEnd )
				)
				( attribute "SEC_TYPE" "0603V"
					( Origin gFrontEnd )
				)
				( attribute "TOLERANCE" "20%"
					( Origin gFrontEnd )
				)
				( attribute "VALUE" "47UF"
					( Origin gFrontEnd )
				)
				( attribute "VER" "1"
					( Origin gFrontEnd )
				)
				( attribute "VOLTAGE" "4V"
					( Units "uVoltage" "V" 1.000000)
					( Origin gFrontEnd )
				)
				( attribute "XY" "(-2250,-450)"
					( Origin gFrontEnd )
				)
				( attribute "CHIPS_PART_NAME" "CAP_A"
					( Origin gPackager )
				)
				( attribute "CDS_PART_NAME" "CAP_A_0603V-47UF,4V,20%,X5R,60A"
					( Origin gPackager )
				)
				( attribute "GROUP" "PWR_MLCC_CAP"
					( Origin gFrontEnd )
				)
				( attribute "BOM_SS" "E15431-004"
					( Origin gFrontEnd )
				)
				( objectStatus "C8U7" )
			)
			( gate "@baseboard_fab2_lib.baseboard_fab2(sch_1):page225_i291"
				( attribute "CDS_LIB" "dev_discrete"
					( Origin gPackager )
				)
				( attribute "CDS_LOCATION" "C8U2"
					( Origin gPackager )
				)
				( attribute "CDS_SEC" "1"
					( Origin gPackager )
				)
				( attribute "LOCATION" "C8U2"
					( Origin gFrontEnd )
				)
				( attribute "MATERIAL" "X5R"
					( Origin gFrontEnd )
				)
				( attribute "PACK_TYPE" "0603V"
					( Origin gFrontEnd )
				)
				( attribute "PART_NUMBER" "602433-106"
					( Origin gFrontEnd )
				)
				( attribute "PHYS_PAGE" "225"
					( Origin gFrontEnd )
				)
				( attribute "ROT" "0"
					( Origin gFrontEnd )
				)
				( attribute "SEC" "1"
					( Origin gFrontEnd )
				)
				( attribute "SEC_TYPE" "0603V"
					( Origin gFrontEnd )
				)
				( attribute "TOLERANCE" "20%"
					( Origin gFrontEnd )
				)
				( attribute "VALUE" "47UF"
					( Origin gFrontEnd )
				)
				( attribute "VER" "1"
					( Origin gFrontEnd )
				)
				( attribute "VOLTAGE" "4V"
					( Units "uVoltage" "V" 1.000000)
					( Origin gFrontEnd )
				)
				( attribute "XY" "(-1950,-450)"
					( Origin gFrontEnd )
				)
				( attribute "CHIPS_PART_NAME" "CAP_A"
					( Origin gPackager )
				)
				( attribute "CDS_PART_NAME" "CAP_A_0603V-47UF,4V,20%,X5R,60A"
					( Origin gPackager )
				)
				( attribute "GROUP" "PWR_MLCC_CAP"
					( Origin gFrontEnd )
				)
				( attribute "BOM_SS" "E15431-004"
					( Origin gFrontEnd )
				)
				( objectStatus "C8U2" )
			)
			( gate "@baseboard_fab2_lib.baseboard_fab2(sch_1):page225_i292"
				( attribute "CDS_LIB" "dev_discrete"
					( Origin gPackager )
				)
				( attribute "CDS_LOCATION" "C7U2"
					( Origin gPackager )
				)
				( attribute "CDS_SEC" "1"
					( Origin gPackager )
				)
				( attribute "LOCATION" "C7U2"
					( Origin gFrontEnd )
				)
				( attribute "MATERIAL" "X5R"
					( Origin gFrontEnd )
				)
				( attribute "PACK_TYPE" "0603V"
					( Origin gFrontEnd )
				)
				( attribute "PART_NUMBER" "602433-106"
					( Origin gFrontEnd )
				)
				( attribute "PHYS_PAGE" "225"
					( Origin gFrontEnd )
				)
				( attribute "ROT" "0"
					( Origin gFrontEnd )
				)
				( attribute "SEC" "1"
					( Origin gFrontEnd )
				)
				( attribute "SEC_TYPE" "0603V"
					( Origin gFrontEnd )
				)
				( attribute "TOLERANCE" "20%"
					( Origin gFrontEnd )
				)
				( attribute "VALUE" "47UF"
					( Origin gFrontEnd )
				)
				( attribute "VER" "1"
					( Origin gFrontEnd )
				)
				( attribute "VOLTAGE" "4V"
					( Units "uVoltage" "V" 1.000000)
					( Origin gFrontEnd )
				)
				( attribute "XY" "(-1650,-450)"
					( Origin gFrontEnd )
				)
				( attribute "CHIPS_PART_NAME" "CAP_A"
					( Origin gPackager )
				)
				( attribute "CDS_PART_NAME" "CAP_A_0603V-47UF,4V,20%,X5R,60A"
					( Origin gPackager )
				)
				( attribute "GROUP" "PWR_MLCC_CAP"
					( Origin gFrontEnd )
				)
				( attribute "BOM_SS" "E15431-004"
					( Origin gFrontEnd )
				)
				( objectStatus "C7U2" )
			)
			( gate "@baseboard_fab2_lib.baseboard_fab2(sch_1):page225_i293"
				( attribute "CDS_LIB" "dev_discrete"
					( Origin gPackager )
				)
				( attribute "CDS_LOCATION" "C7U1"
					( Origin gPackager )
				)
				( attribute "CDS_SEC" "1"
					( Origin gPackager )
				)
				( attribute "LOCATION" "C7U1"
					( Origin gFrontEnd )
				)
				( attribute "MATERIAL" "X5R"
					( Origin gFrontEnd )
				)
				( attribute "PACK_TYPE" "0603V"
					( Origin gFrontEnd )
				)
				( attribute "PART_NUMBER" "602433-106"
					( Origin gFrontEnd )
				)
				( attribute "PHYS_PAGE" "225"
					( Origin gFrontEnd )
				)
				( attribute "ROT" "0"
					( Origin gFrontEnd )
				)
				( attribute "SEC" "1"
					( Origin gFrontEnd )
				)
				( attribute "SEC_TYPE" "0603V"
					( Origin gFrontEnd )
				)
				( attribute "TOLERANCE" "20%"
					( Origin gFrontEnd )
				)
				( attribute "VALUE" "47UF"
					( Origin gFrontEnd )
				)
				( attribute "VER" "1"
					( Origin gFrontEnd )
				)
				( attribute "VOLTAGE" "4V"
					( Units "uVoltage" "V" 1.000000)
					( Origin gFrontEnd )
				)
				( attribute "XY" "(-1375,-450)"
					( Origin gFrontEnd )
				)
				( attribute "CHIPS_PART_NAME" "CAP_A"
					( Origin gPackager )
				)
				( attribute "CDS_PART_NAME" "CAP_A_0603V-47UF,4V,20%,X5R,60A"
					( Origin gPackager )
				)
				( attribute "GROUP" "PWR_MLCC_CAP"
					( Origin gFrontEnd )
				)
				( attribute "BOM_SS" "E15431-004"
					( Origin gFrontEnd )
				)
				( objectStatus "C7U1" )
			)
			( gate "@baseboard_fab2_lib.baseboard_fab2(sch_1):page225_i294"
				( attribute "CDS_LIB" "dev_discrete"
					( Origin gPackager )
				)
				( attribute "CDS_LOCATION" "C8U3"
					( Origin gPackager )
				)
				( attribute "CDS_SEC" "1"
					( Origin gPackager )
				)
				( attribute "LOCATION" "C8U3"
					( Origin gFrontEnd )
				)
				( attribute "MATERIAL" "X5R"
					( Origin gFrontEnd )
				)
				( attribute "PACK_TYPE" "0603V"
					( Origin gFrontEnd )
				)
				( attribute "PART_NUMBER" "602433-106"
					( Origin gFrontEnd )
				)
				( attribute "PHYS_PAGE" "225"
					( Origin gFrontEnd )
				)
				( attribute "ROT" "0"
					( Origin gFrontEnd )
				)
				( attribute "SEC" "1"
					( Origin gFrontEnd )
				)
				( attribute "SEC_TYPE" "0603V"
					( Origin gFrontEnd )
				)
				( attribute "TOLERANCE" "20%"
					( Origin gFrontEnd )
				)
				( attribute "VALUE" "47UF"
					( Origin gFrontEnd )
				)
				( attribute "VER" "1"
					( Origin gFrontEnd )
				)
				( attribute "VOLTAGE" "4V"
					( Units "uVoltage" "V" 1.000000)
					( Origin gFrontEnd )
				)
				( attribute "XY" "(-1100,-450)"
					( Origin gFrontEnd )
				)
				( attribute "CHIPS_PART_NAME" "CAP_A"
					( Origin gPackager )
				)
				( attribute "CDS_PART_NAME" "CAP_A_0603V-47UF,4V,20%,X5R,60A"
					( Origin gPackager )
				)
				( attribute "GROUP" "PWR_MLCC_CAP"
					( Origin gFrontEnd )
				)
				( attribute "BOM_SS" "E15431-004"
					( Origin gFrontEnd )
				)
				( objectStatus "C8U3" )
			)
			( gate "@baseboard_fab2_lib.baseboard_fab2(sch_1):page225_i295"
				( attribute "CDS_LIB" "dev_discrete"
					( Origin gPackager )
				)
				( attribute "CDS_LOCATION" "C7T4"
					( Origin gPackager )
				)
				( attribute "CDS_SEC" "1"
					( Origin gPackager )
				)
				( attribute "LOCATION" "C7T4"
					( Origin gFrontEnd )
				)
				( attribute "MATERIAL" "X5R"
					( Origin gFrontEnd )
				)
				( attribute "PACK_TYPE" "0603V"
					( Origin gFrontEnd )
				)
				( attribute "PART_NUMBER" "602433-106"
					( Origin gFrontEnd )
				)
				( attribute "PHYS_PAGE" "225"
					( Origin gFrontEnd )
				)
				( attribute "ROT" "0"
					( Origin gFrontEnd )
				)
				( attribute "SEC" "1"
					( Origin gFrontEnd )
				)
				( attribute "SEC_TYPE" "0603V"
					( Origin gFrontEnd )
				)
				( attribute "TOLERANCE" "20%"
					( Origin gFrontEnd )
				)
				( attribute "VALUE" "47UF"
					( Origin gFrontEnd )
				)
				( attribute "VER" "1"
					( Origin gFrontEnd )
				)
				( attribute "VOLTAGE" "4V"
					( Units "uVoltage" "V" 1.000000)
					( Origin gFrontEnd )
				)
				( attribute "XY" "(-800,-450)"
					( Origin gFrontEnd )
				)
				( attribute "CHIPS_PART_NAME" "CAP_A"
					( Origin gPackager )
				)
				( attribute "CDS_PART_NAME" "CAP_A_0603V-47UF,4V,20%,X5R,60A"
					( Origin gPackager )
				)
				( attribute "GROUP" "PWR_MLCC_CAP"
					( Origin gFrontEnd )
				)
				( attribute "BOM_SS" "E15431-004"
					( Origin gFrontEnd )
				)
				( objectStatus "C7T4" )
			)
			( gate "@baseboard_fab2_lib.baseboard_fab2(sch_1):page225_i296"
				( attribute "CDS_LIB" "dev_discrete"
					( Origin gPackager )
				)
				( attribute "CDS_LOCATION" "C7T5"
					( Origin gPackager )
				)
				( attribute "CDS_SEC" "1"
					( Origin gPackager )
				)
				( attribute "LOCATION" "C7T5"
					( Origin gFrontEnd )
				)
				( attribute "MATERIAL" "X5R"
					( Origin gFrontEnd )
				)
				( attribute "PACK_TYPE" "0603V"
					( Origin gFrontEnd )
				)
				( attribute "PART_NUMBER" "602433-106"
					( Origin gFrontEnd )
				)
				( attribute "PHYS_PAGE" "225"
					( Origin gFrontEnd )
				)
				( attribute "ROT" "0"
					( Origin gFrontEnd )
				)
				( attribute "SEC" "1"
					( Origin gFrontEnd )
				)
				( attribute "SEC_TYPE" "0603V"
					( Origin gFrontEnd )
				)
				( attribute "TOLERANCE" "20%"
					( Origin gFrontEnd )
				)
				( attribute "VALUE" "47UF"
					( Origin gFrontEnd )
				)
				( attribute "VER" "1"
					( Origin gFrontEnd )
				)
				( attribute "VOLTAGE" "4V"
					( Units "uVoltage" "V" 1.000000)
					( Origin gFrontEnd )
				)
				( attribute "XY" "(-500,-450)"
					( Origin gFrontEnd )
				)
				( attribute "CHIPS_PART_NAME" "CAP_A"
					( Origin gPackager )
				)
				( attribute "CDS_PART_NAME" "CAP_A_0603V-47UF,4V,20%,X5R,60A"
					( Origin gPackager )
				)
				( attribute "GROUP" "PWR_MLCC_CAP"
					( Origin gFrontEnd )
				)
				( attribute "BOM_SS" "E15431-004"
					( Origin gFrontEnd )
				)
				( objectStatus "C7T5" )
			)
			( gate "@baseboard_fab2_lib.baseboard_fab2(sch_1):page225_i297"
				( attribute "CDS_LIB" "dev_discrete"
					( Origin gPackager )
				)
				( attribute "CDS_LOCATION" "C8T5"
					( Origin gPackager )
				)
				( attribute "CDS_SEC" "1"
					( Origin gPackager )
				)
				( attribute "LOCATION" "C8T5"
					( Origin gFrontEnd )
				)
				( attribute "MATERIAL" "X5R"
					( Origin gFrontEnd )
				)
				( attribute "PACK_TYPE" "0603V"
					( Origin gFrontEnd )
				)
				( attribute "PART_NUMBER" "602433-106"
					( Origin gFrontEnd )
				)
				( attribute "PHYS_PAGE" "225"
					( Origin gFrontEnd )
				)
				( attribute "ROT" "0"
					( Origin gFrontEnd )
				)
				( attribute "SEC" "1"
					( Origin gFrontEnd )
				)
				( attribute "SEC_TYPE" "0603V"
					( Origin gFrontEnd )
				)
				( attribute "TOLERANCE" "20%"
					( Origin gFrontEnd )
				)
				( attribute "VALUE" "47UF"
					( Origin gFrontEnd )
				)
				( attribute "VER" "1"
					( Origin gFrontEnd )
				)
				( attribute "VOLTAGE" "4V"
					( Units "uVoltage" "V" 1.000000)
					( Origin gFrontEnd )
				)
				( attribute "XY" "(-225,-450)"
					( Origin gFrontEnd )
				)
				( attribute "CHIPS_PART_NAME" "CAP_A"
					( Origin gPackager )
				)
				( attribute "CDS_PART_NAME" "CAP_A_0603V-47UF,4V,20%,X5R,60A"
					( Origin gPackager )
				)
				( attribute "GROUP" "PWR_MLCC_CAP"
					( Origin gFrontEnd )
				)
				( attribute "BOM_SS" "E15431-004"
					( Origin gFrontEnd )
				)
				( objectStatus "C8T5" )
			)
			( gate "@baseboard_fab2_lib.baseboard_fab2(sch_1):page225_i298"
				( attribute "CDS_LIB" "dev_discrete"
					( Origin gPackager )
				)
				( attribute "CDS_LOCATION" "C8U6"
					( Origin gPackager )
				)
				( attribute "CDS_SEC" "1"
					( Origin gPackager )
				)
				( attribute "LOCATION" "C8U6"
					( Origin gFrontEnd )
				)
				( attribute "MATERIAL" "X5R"
					( Origin gFrontEnd )
				)
				( attribute "PACK_TYPE" "0603V"
					( Origin gFrontEnd )
				)
				( attribute "PART_NUMBER" "602433-106"
					( Origin gFrontEnd )
				)
				( attribute "PHYS_PAGE" "225"
					( Origin gFrontEnd )
				)
				( attribute "ROT" "0"
					( Origin gFrontEnd )
				)
				( attribute "SEC" "1"
					( Origin gFrontEnd )
				)
				( attribute "SEC_TYPE" "0603V"
					( Origin gFrontEnd )
				)
				( attribute "TOLERANCE" "20%"
					( Origin gFrontEnd )
				)
				( attribute "VALUE" "47UF"
					( Origin gFrontEnd )
				)
				( attribute "VER" "1"
					( Origin gFrontEnd )
				)
				( attribute "VOLTAGE" "4V"
					( Units "uVoltage" "V" 1.000000)
					( Origin gFrontEnd )
				)
				( attribute "XY" "(100,-450)"
					( Origin gFrontEnd )
				)
				( attribute "CHIPS_PART_NAME" "CAP_A"
					( Origin gPackager )
				)
				( attribute "CDS_PART_NAME" "CAP_A_0603V-47UF,4V,20%,X5R,60A"
					( Origin gPackager )
				)
				( attribute "GROUP" "PWR_MLCC_CAP"
					( Origin gFrontEnd )
				)
				( attribute "BOM_SS" "E15431-004"
					( Origin gFrontEnd )
				)
				( objectStatus "C8U6" )
			)
			( gate "@baseboard_fab2_lib.baseboard_fab2(sch_1):page225_i299"
				( attribute "CDS_LIB" "dev_discrete"
					( Origin gPackager )
				)
				( attribute "CDS_LOCATION" "C8T6"
					( Origin gPackager )
				)
				( attribute "CDS_SEC" "1"
					( Origin gPackager )
				)
				( attribute "LOCATION" "C8T6"
					( Origin gFrontEnd )
				)
				( attribute "MATERIAL" "X5R"
					( Origin gFrontEnd )
				)
				( attribute "PACK_TYPE" "0603V"
					( Origin gFrontEnd )
				)
				( attribute "PART_NUMBER" "602433-106"
					( Origin gFrontEnd )
				)
				( attribute "PHYS_PAGE" "225"
					( Origin gFrontEnd )
				)
				( attribute "ROT" "0"
					( Origin gFrontEnd )
				)
				( attribute "SEC" "1"
					( Origin gFrontEnd )
				)
				( attribute "SEC_TYPE" "0603V"
					( Origin gFrontEnd )
				)
				( attribute "TOLERANCE" "20%"
					( Origin gFrontEnd )
				)
				( attribute "VALUE" "47UF"
					( Origin gFrontEnd )
				)
				( attribute "VER" "1"
					( Origin gFrontEnd )
				)
				( attribute "VOLTAGE" "4V"
					( Units "uVoltage" "V" 1.000000)
					( Origin gFrontEnd )
				)
				( attribute "XY" "(400,-450)"
					( Origin gFrontEnd )
				)
				( attribute "CHIPS_PART_NAME" "CAP_A"
					( Origin gPackager )
				)
				( attribute "CDS_PART_NAME" "CAP_A_0603V-47UF,4V,20%,X5R,60A"
					( Origin gPackager )
				)
				( attribute "GROUP" "PWR_MLCC_CAP"
					( Origin gFrontEnd )
				)
				( attribute "BOM_SS" "E15431-004"
					( Origin gFrontEnd )
				)
				( objectStatus "C8T6" )
			)
			( gate "@baseboard_fab2_lib.baseboard_fab2(sch_1):page225_i300"
				( attribute "CDS_LIB" "dev_discrete"
					( Origin gPackager )
				)
				( attribute "CDS_LOCATION" "C8T7"
					( Origin gPackager )
				)
				( attribute "CDS_SEC" "1"
					( Origin gPackager )
				)
				( attribute "LOCATION" "C8T7"
					( Origin gFrontEnd )
				)
				( attribute "MATERIAL" "X5R"
					( Origin gFrontEnd )
				)
				( attribute "PACK_TYPE" "0603V"
					( Origin gFrontEnd )
				)
				( attribute "PART_NUMBER" "602433-106"
					( Origin gFrontEnd )
				)
				( attribute "PHYS_PAGE" "225"
					( Origin gFrontEnd )
				)
				( attribute "ROT" "0"
					( Origin gFrontEnd )
				)
				( attribute "SEC" "1"
					( Origin gFrontEnd )
				)
				( attribute "SEC_TYPE" "0603V"
					( Origin gFrontEnd )
				)
				( attribute "TOLERANCE" "20%"
					( Origin gFrontEnd )
				)
				( attribute "VALUE" "47UF"
					( Origin gFrontEnd )
				)
				( attribute "VER" "1"
					( Origin gFrontEnd )
				)
				( attribute "VOLTAGE" "4V"
					( Units "uVoltage" "V" 1.000000)
					( Origin gFrontEnd )
				)
				( attribute "XY" "(700,-450)"
					( Origin gFrontEnd )
				)
				( attribute "CHIPS_PART_NAME" "CAP_A"
					( Origin gPackager )
				)
				( attribute "CDS_PART_NAME" "CAP_A_0603V-47UF,4V,20%,X5R,60A"
					( Origin gPackager )
				)
				( attribute "GROUP" "PWR_MLCC_CAP"
					( Origin gFrontEnd )
				)
				( attribute "BOM_SS" "E15431-004"
					( Origin gFrontEnd )
				)
				( objectStatus "C8T7" )
			)
			( gate "@baseboard_fab2_lib.baseboard_fab2(sch_1):page225_i301"
				( attribute "CDS_LIB" "dev_discrete"
					( Origin gPackager )
				)
				( attribute "CDS_LOCATION" "C8T8"
					( Origin gPackager )
				)
				( attribute "CDS_SEC" "1"
					( Origin gPackager )
				)
				( attribute "LOCATION" "C8T8"
					( Origin gFrontEnd )
				)
				( attribute "MATERIAL" "X5R"
					( Origin gFrontEnd )
				)
				( attribute "PACK_TYPE" "0603V"
					( Origin gFrontEnd )
				)
				( attribute "PART_NUMBER" "602433-106"
					( Origin gFrontEnd )
				)
				( attribute "PHYS_PAGE" "225"
					( Origin gFrontEnd )
				)
				( attribute "ROT" "0"
					( Origin gFrontEnd )
				)
				( attribute "SEC" "1"
					( Origin gFrontEnd )
				)
				( attribute "SEC_TYPE" "0603V"
					( Origin gFrontEnd )
				)
				( attribute "TOLERANCE" "20%"
					( Origin gFrontEnd )
				)
				( attribute "VALUE" "47UF"
					( Origin gFrontEnd )
				)
				( attribute "VER" "1"
					( Origin gFrontEnd )
				)
				( attribute "VOLTAGE" "4V"
					( Units "uVoltage" "V" 1.000000)
					( Origin gFrontEnd )
				)
				( attribute "XY" "(975,-450)"
					( Origin gFrontEnd )
				)
				( attribute "CHIPS_PART_NAME" "CAP_A"
					( Origin gPackager )
				)
				( attribute "CDS_PART_NAME" "CAP_A_0603V-47UF,4V,20%,X5R,60A"
					( Origin gPackager )
				)
				( attribute "GROUP" "PWR_MLCC_CAP"
					( Origin gFrontEnd )
				)
				( attribute "BOM_SS" "E15431-004"
					( Origin gFrontEnd )
				)
				( objectStatus "C8T8" )
			)
			( gate "@baseboard_fab2_lib.baseboard_fab2(sch_1):page225_i302"
				( attribute "CDS_LIB" "dev_discrete"
					( Origin gPackager )
				)
				( attribute "CDS_LOCATION" "C8U5"
					( Origin gPackager )
				)
				( attribute "CDS_SEC" "1"
					( Origin gPackager )
				)
				( attribute "LOCATION" "C8U5"
					( Origin gFrontEnd )
				)
				( attribute "MATERIAL" "X5R"
					( Origin gFrontEnd )
				)
				( attribute "PACK_TYPE" "0603V"
					( Origin gFrontEnd )
				)
				( attribute "PART_NUMBER" "602433-106"
					( Origin gFrontEnd )
				)
				( attribute "PHYS_PAGE" "225"
					( Origin gFrontEnd )
				)
				( attribute "ROT" "0"
					( Origin gFrontEnd )
				)
				( attribute "SEC" "1"
					( Origin gFrontEnd )
				)
				( attribute "SEC_TYPE" "0603V"
					( Origin gFrontEnd )
				)
				( attribute "TOLERANCE" "20%"
					( Origin gFrontEnd )
				)
				( attribute "VALUE" "47UF"
					( Origin gFrontEnd )
				)
				( attribute "VER" "1"
					( Origin gFrontEnd )
				)
				( attribute "VOLTAGE" "4V"
					( Units "uVoltage" "V" 1.000000)
					( Origin gFrontEnd )
				)
				( attribute "XY" "(1250,-450)"
					( Origin gFrontEnd )
				)
				( attribute "CHIPS_PART_NAME" "CAP_A"
					( Origin gPackager )
				)
				( attribute "CDS_PART_NAME" "CAP_A_0603V-47UF,4V,20%,X5R,60A"
					( Origin gPackager )
				)
				( attribute "GROUP" "PWR_MLCC_CAP"
					( Origin gFrontEnd )
				)
				( attribute "BOM_SS" "E15431-004"
					( Origin gFrontEnd )
				)
				( objectStatus "C8U5" )
			)
			( gate "@baseboard_fab2_lib.baseboard_fab2(sch_1):page225_i303"
				( attribute "CDS_LIB" "dev_discrete"
					( Origin gPackager )
				)
				( attribute "CDS_LOCATION" "C8T9"
					( Origin gPackager )
				)
				( attribute "CDS_SEC" "1"
					( Origin gPackager )
				)
				( attribute "LOCATION" "C8T9"
					( Origin gFrontEnd )
				)
				( attribute "MATERIAL" "X5R"
					( Origin gFrontEnd )
				)
				( attribute "PACK_TYPE" "0603V"
					( Origin gFrontEnd )
				)
				( attribute "PART_NUMBER" "602433-106"
					( Origin gFrontEnd )
				)
				( attribute "PHYS_PAGE" "225"
					( Origin gFrontEnd )
				)
				( attribute "ROT" "0"
					( Origin gFrontEnd )
				)
				( attribute "SEC" "1"
					( Origin gFrontEnd )
				)
				( attribute "SEC_TYPE" "0603V"
					( Origin gFrontEnd )
				)
				( attribute "TOLERANCE" "20%"
					( Origin gFrontEnd )
				)
				( attribute "VALUE" "47UF"
					( Origin gFrontEnd )
				)
				( attribute "VER" "1"
					( Origin gFrontEnd )
				)
				( attribute "VOLTAGE" "4V"
					( Units "uVoltage" "V" 1.000000)
					( Origin gFrontEnd )
				)
				( attribute "XY" "(1550,-450)"
					( Origin gFrontEnd )
				)
				( attribute "CHIPS_PART_NAME" "CAP_A"
					( Origin gPackager )
				)
				( attribute "CDS_PART_NAME" "CAP_A_0603V-47UF,4V,20%,X5R,60A"
					( Origin gPackager )
				)
				( attribute "GROUP" "PWR_MLCC_CAP"
					( Origin gFrontEnd )
				)
				( attribute "BOM_SS" "E15431-004"
					( Origin gFrontEnd )
				)
				( objectStatus "C8T9" )
			)
			( gate "@baseboard_fab2_lib.baseboard_fab2(sch_1):page225_i304"
				( attribute "CDS_LIB" "dev_discrete"
					( Origin gPackager )
				)
				( attribute "CDS_LOCATION" "C8T10"
					( Origin gPackager )
				)
				( attribute "CDS_SEC" "1"
					( Origin gPackager )
				)
				( attribute "LOCATION" "C8T10"
					( Origin gFrontEnd )
				)
				( attribute "MATERIAL" "X5R"
					( Origin gFrontEnd )
				)
				( attribute "PACK_TYPE" "0603V"
					( Origin gFrontEnd )
				)
				( attribute "PART_NUMBER" "602433-106"
					( Origin gFrontEnd )
				)
				( attribute "PHYS_PAGE" "225"
					( Origin gFrontEnd )
				)
				( attribute "ROT" "0"
					( Origin gFrontEnd )
				)
				( attribute "SEC" "1"
					( Origin gFrontEnd )
				)
				( attribute "SEC_TYPE" "0603V"
					( Origin gFrontEnd )
				)
				( attribute "TOLERANCE" "20%"
					( Origin gFrontEnd )
				)
				( attribute "VALUE" "47UF"
					( Origin gFrontEnd )
				)
				( attribute "VER" "1"
					( Origin gFrontEnd )
				)
				( attribute "VOLTAGE" "4V"
					( Units "uVoltage" "V" 1.000000)
					( Origin gFrontEnd )
				)
				( attribute "XY" "(1850,-450)"
					( Origin gFrontEnd )
				)
				( attribute "CHIPS_PART_NAME" "CAP_A"
					( Origin gPackager )
				)
				( attribute "CDS_PART_NAME" "CAP_A_0603V-47UF,4V,20%,X5R,60A"
					( Origin gPackager )
				)
				( attribute "GROUP" "PWR_MLCC_CAP"
					( Origin gFrontEnd )
				)
				( attribute "BOM_SS" "E15431-004"
					( Origin gFrontEnd )
				)
				( objectStatus "C8T10" )
			)
			( gate "@baseboard_fab2_lib.baseboard_fab2(sch_1):page225_i305"
				( attribute "CDS_LIB" "dev_discrete"
					( Origin gPackager )
				)
				( attribute "CDS_LOCATION" "C8U4"
					( Origin gPackager )
				)
				( attribute "CDS_SEC" "1"
					( Origin gPackager )
				)
				( attribute "LOCATION" "C8U4"
					( Origin gFrontEnd )
				)
				( attribute "MATERIAL" "X5R"
					( Origin gFrontEnd )
				)
				( attribute "PACK_TYPE" "0603V"
					( Origin gFrontEnd )
				)
				( attribute "PART_NUMBER" "602433-106"
					( Origin gFrontEnd )
				)
				( attribute "PHYS_PAGE" "225"
					( Origin gFrontEnd )
				)
				( attribute "ROT" "0"
					( Origin gFrontEnd )
				)
				( attribute "SEC" "1"
					( Origin gFrontEnd )
				)
				( attribute "SEC_TYPE" "0603V"
					( Origin gFrontEnd )
				)
				( attribute "TOLERANCE" "20%"
					( Origin gFrontEnd )
				)
				( attribute "VALUE" "47UF"
					( Origin gFrontEnd )
				)
				( attribute "VER" "1"
					( Origin gFrontEnd )
				)
				( attribute "VOLTAGE" "4V"
					( Units "uVoltage" "V" 1.000000)
					( Origin gFrontEnd )
				)
				( attribute "XY" "(2125,-450)"
					( Origin gFrontEnd )
				)
				( attribute "CHIPS_PART_NAME" "CAP_A"
					( Origin gPackager )
				)
				( attribute "CDS_PART_NAME" "CAP_A_0603V-47UF,4V,20%,X5R,60A"
					( Origin gPackager )
				)
				( attribute "GROUP" "PWR_MLCC_CAP"
					( Origin gFrontEnd )
				)
				( attribute "BOM_SS" "E15431-004"
					( Origin gFrontEnd )
				)
				( objectStatus "C8U4" )
			)
			( gate "@baseboard_fab2_lib.baseboard_fab2(sch_1):page220_i316"
				( attribute "BOM_COST" "MEM_VRD_PVDDQ_CD"
					( Origin gFrontEnd )
				)
				( attribute "CDS_LIB" "mstr_discrete"
					( Origin gPackager )
				)
				( attribute "CDS_LOCATION" "C5P6"
					( Origin gPackager )
				)
				( attribute "CDS_SEC" "1"
					( Origin gPackager )
				)
				( attribute "LOCATION" "C5P6"
					( Origin gFrontEnd )
				)
				( attribute "MATERIAL" "X5R"
					( Origin gFrontEnd )
				)
				( attribute "NEW_MATERIAL" "X6S"
					( Origin gFrontEnd )
				)
				( attribute "PACK_TYPE" "0805"
					( Origin gFrontEnd )
				)
				( attribute "PART_NUMBER" "602433-112"
					( Origin gFrontEnd )
				)
				( attribute "PHYS_PAGE" "220"
					( Origin gFrontEnd )
				)
				( attribute "ROOM" "VDDQ_ABC_PWR_VR"
					( Origin gFrontEnd )
				)
				( attribute "ROT" "0"
					( Origin gFrontEnd )
				)
				( attribute "SEC" "1"
					( Origin gFrontEnd )
				)
				( attribute "SEC_TYPE" "0805"
					( Origin gFrontEnd )
				)
				( attribute "TOLERANCE" "20%"
					( Origin gFrontEnd )
				)
				( attribute "VALUE" "100UF"
					( Origin gFrontEnd )
				)
				( attribute "VER" "1"
					( Origin gFrontEnd )
				)
				( attribute "VOLTAGE" "4V"
					( Units "uVoltage" "V" 1.000000)
					( Origin gFrontEnd )
				)
				( attribute "XY" "(175,2925)"
					( Origin gFrontEnd )
				)
				( attribute "CHIPS_PART_NAME" "CAP"
					( Origin gPackager )
				)
				( attribute "CDS_PART_NAME" "CAP_0805-100UF,4V,20%,X5R,6024A"
					( Origin gPackager )
				)
				( attribute "GROUP" "PWR_MLCC_CAP"
					( Origin gFrontEnd )
				)
				( attribute "NEW_PN" "078.1071T.M002"
					( Origin gFrontEnd )
				)
				( attribute "BOM_SS" "NOPOP"
					( Origin gFrontEnd )
				)
				( objectStatus "C5P6" )
			)
			( gate "@baseboard_fab2_lib.baseboard_fab2(sch_1):page220_i298"
				( attribute "CDS_LIB" "w_hdl"
					( Origin gPackager )
				)
				( attribute "CDS_LMAN_SYM_OUTLINE" "-50,25,50,-25"
					( Origin gPackager )
				)
				( attribute "CDS_LOCATION" "C7W5"
					( Origin gPackager )
				)
				( attribute "CDS_SEC" "1"
					( Origin gPackager )
				)
				( attribute "LOCATION" "C7W5"
					( Origin gFrontEnd )
				)
				( attribute "PACK_TYPE" "SMD-BCG5"
					( Origin gFrontEnd )
				)
				( attribute "PART_NUMBER" "078.22611.0811"
					( Origin gFrontEnd )
				)
				( attribute "PHYS_PAGE" "220"
					( Origin gFrontEnd )
				)
				( attribute "ROT" "0"
					( Origin gFrontEnd )
				)
				( attribute "SEC" "1"
					( Origin gFrontEnd )
				)
				( attribute "SEC_TYPE" "SMD-BCG5"
					( Origin gFrontEnd )
				)
				( attribute "VALUE" "SC22U16V5MX-4-GP"
					( Origin gFrontEnd )
				)
				( attribute "VER" "1"
					( Origin gFrontEnd )
				)
				( attribute "XY" "(-500,1025)"
					( Origin gFrontEnd )
				)
				( attribute "CHIPS_PART_NAME" "SC22U16V5MX-4-GP"
					( Origin gPackager )
				)
				( attribute "CDS_PART_NAME" "SC22U16V5MX-4-GP_SMD-BCG5-SC22A"
					( Origin gPackager )
				)
				( attribute "ATTRIBUTE" "22UF"
					( Origin gFrontEnd )
				)
				( attribute "PACK_SIZE" "0805"
					( Origin gFrontEnd )
				)
				( attribute "RATED" "16V"
					( Origin gFrontEnd )
				)
				( attribute "TOLERANCE" "20%"
					( Origin gFrontEnd )
				)
				( attribute "TYPE" "X6S"
					( Origin gFrontEnd )
				)
				( objectStatus "C7W5" )
			)
			( gate "@baseboard_fab2_lib.baseboard_fab2(sch_1):page220_i299"
				( attribute "CDS_LIB" "w_hdl"
					( Origin gPackager )
				)
				( attribute "CDS_LMAN_SYM_OUTLINE" "-50,25,50,-25"
					( Origin gPackager )
				)
				( attribute "CDS_LOCATION" "C7W9"
					( Origin gPackager )
				)
				( attribute "CDS_SEC" "1"
					( Origin gPackager )
				)
				( attribute "LOCATION" "C7W9"
					( Origin gFrontEnd )
				)
				( attribute "PACK_TYPE" "SMD-BCG5"
					( Origin gFrontEnd )
				)
				( attribute "PART_NUMBER" "078.22611.0811"
					( Origin gFrontEnd )
				)
				( attribute "PHYS_PAGE" "220"
					( Origin gFrontEnd )
				)
				( attribute "ROT" "0"
					( Origin gFrontEnd )
				)
				( attribute "SEC" "1"
					( Origin gFrontEnd )
				)
				( attribute "SEC_TYPE" "SMD-BCG5"
					( Origin gFrontEnd )
				)
				( attribute "VALUE" "SC22U16V5MX-4-GP"
					( Origin gFrontEnd )
				)
				( attribute "VER" "1"
					( Origin gFrontEnd )
				)
				( attribute "XY" "(700,1025)"
					( Origin gFrontEnd )
				)
				( attribute "CHIPS_PART_NAME" "SC22U16V5MX-4-GP"
					( Origin gPackager )
				)
				( attribute "CDS_PART_NAME" "SC22U16V5MX-4-GP_SMD-BCG5-SC22A"
					( Origin gPackager )
				)
				( attribute "ATTRIBUTE" "22UF"
					( Origin gFrontEnd )
				)
				( attribute "PACK_SIZE" "0805"
					( Origin gFrontEnd )
				)
				( attribute "RATED" "16V"
					( Origin gFrontEnd )
				)
				( attribute "TOLERANCE" "20%"
					( Origin gFrontEnd )
				)
				( attribute "TYPE" "X6S"
					( Origin gFrontEnd )
				)
				( objectStatus "C7W9" )
			)
			( gate "@baseboard_fab2_lib.baseboard_fab2(sch_1):page220_i300"
				( attribute "CDS_LIB" "w_hdl"
					( Origin gPackager )
				)
				( attribute "CDS_LMAN_SYM_OUTLINE" "-50,25,50,-25"
					( Origin gPackager )
				)
				( attribute "CDS_LOCATION" "C7W8"
					( Origin gPackager )
				)
				( attribute "CDS_SEC" "1"
					( Origin gPackager )
				)
				( attribute "LOCATION" "C7W8"
					( Origin gFrontEnd )
				)
				( attribute "PACK_TYPE" "SMD-BCG5"
					( Origin gFrontEnd )
				)
				( attribute "PART_NUMBER" "078.22611.0811"
					( Origin gFrontEnd )
				)
				( attribute "PHYS_PAGE" "220"
					( Origin gFrontEnd )
				)
				( attribute "ROT" "0"
					( Origin gFrontEnd )
				)
				( attribute "SEC" "1"
					( Origin gFrontEnd )
				)
				( attribute "SEC_TYPE" "SMD-BCG5"
					( Origin gFrontEnd )
				)
				( attribute "VALUE" "SC22U16V5MX-4-GP"
					( Origin gFrontEnd )
				)
				( attribute "VER" "1"
					( Origin gFrontEnd )
				)
				( attribute "XY" "(400,1025)"
					( Origin gFrontEnd )
				)
				( attribute "CHIPS_PART_NAME" "SC22U16V5MX-4-GP"
					( Origin gPackager )
				)
				( attribute "CDS_PART_NAME" "SC22U16V5MX-4-GP_SMD-BCG5-SC22A"
					( Origin gPackager )
				)
				( attribute "ATTRIBUTE" "22UF"
					( Origin gFrontEnd )
				)
				( attribute "PACK_SIZE" "0805"
					( Origin gFrontEnd )
				)
				( attribute "RATED" "16V"
					( Origin gFrontEnd )
				)
				( attribute "TOLERANCE" "20%"
					( Origin gFrontEnd )
				)
				( attribute "TYPE" "X6S"
					( Origin gFrontEnd )
				)
				( objectStatus "C7W8" )
			)
			( gate "@baseboard_fab2_lib.baseboard_fab2(sch_1):page220_i301"
				( attribute "CDS_LIB" "w_hdl"
					( Origin gPackager )
				)
				( attribute "CDS_LMAN_SYM_OUTLINE" "-50,25,50,-25"
					( Origin gPackager )
				)
				( attribute "CDS_LOCATION" "C7W7"
					( Origin gPackager )
				)
				( attribute "CDS_SEC" "1"
					( Origin gPackager )
				)
				( attribute "LOCATION" "C7W7"
					( Origin gFrontEnd )
				)
				( attribute "PACK_TYPE" "SMD-BCG5"
					( Origin gFrontEnd )
				)
				( attribute "PART_NUMBER" "078.22611.0811"
					( Origin gFrontEnd )
				)
				( attribute "PHYS_PAGE" "220"
					( Origin gFrontEnd )
				)
				( attribute "ROT" "0"
					( Origin gFrontEnd )
				)
				( attribute "SEC" "1"
					( Origin gFrontEnd )
				)
				( attribute "SEC_TYPE" "SMD-BCG5"
					( Origin gFrontEnd )
				)
				( attribute "VALUE" "SC22U16V5MX-4-GP"
					( Origin gFrontEnd )
				)
				( attribute "VER" "1"
					( Origin gFrontEnd )
				)
				( attribute "XY" "(100,1025)"
					( Origin gFrontEnd )
				)
				( attribute "CHIPS_PART_NAME" "SC22U16V5MX-4-GP"
					( Origin gPackager )
				)
				( attribute "CDS_PART_NAME" "SC22U16V5MX-4-GP_SMD-BCG5-SC22A"
					( Origin gPackager )
				)
				( attribute "ATTRIBUTE" "22UF"
					( Origin gFrontEnd )
				)
				( attribute "PACK_SIZE" "0805"
					( Origin gFrontEnd )
				)
				( attribute "RATED" "16V"
					( Origin gFrontEnd )
				)
				( attribute "TOLERANCE" "20%"
					( Origin gFrontEnd )
				)
				( attribute "TYPE" "X6S"
					( Origin gFrontEnd )
				)
				( objectStatus "C7W7" )
			)
			( gate "@baseboard_fab2_lib.baseboard_fab2(sch_1):page220_i302"
				( attribute "CDS_LIB" "w_hdl"
					( Origin gPackager )
				)
				( attribute "CDS_LMAN_SYM_OUTLINE" "-50,25,50,-25"
					( Origin gPackager )
				)
				( attribute "CDS_LOCATION" "C7W6"
					( Origin gPackager )
				)
				( attribute "CDS_SEC" "1"
					( Origin gPackager )
				)
				( attribute "LOCATION" "C7W6"
					( Origin gFrontEnd )
				)
				( attribute "PACK_TYPE" "SMD-BCG5"
					( Origin gFrontEnd )
				)
				( attribute "PART_NUMBER" "078.22611.0811"
					( Origin gFrontEnd )
				)
				( attribute "PHYS_PAGE" "220"
					( Origin gFrontEnd )
				)
				( attribute "ROT" "0"
					( Origin gFrontEnd )
				)
				( attribute "SEC" "1"
					( Origin gFrontEnd )
				)
				( attribute "SEC_TYPE" "SMD-BCG5"
					( Origin gFrontEnd )
				)
				( attribute "VALUE" "SC22U16V5MX-4-GP"
					( Origin gFrontEnd )
				)
				( attribute "VER" "1"
					( Origin gFrontEnd )
				)
				( attribute "XY" "(-200,1025)"
					( Origin gFrontEnd )
				)
				( attribute "CHIPS_PART_NAME" "SC22U16V5MX-4-GP"
					( Origin gPackager )
				)
				( attribute "CDS_PART_NAME" "SC22U16V5MX-4-GP_SMD-BCG5-SC22A"
					( Origin gPackager )
				)
				( attribute "ATTRIBUTE" "22UF"
					( Origin gFrontEnd )
				)
				( attribute "PACK_SIZE" "0805"
					( Origin gFrontEnd )
				)
				( attribute "RATED" "16V"
					( Origin gFrontEnd )
				)
				( attribute "TOLERANCE" "20%"
					( Origin gFrontEnd )
				)
				( attribute "TYPE" "X6S"
					( Origin gFrontEnd )
				)
				( objectStatus "C7W6" )
			)
			( gate "@baseboard_fab2_lib.baseboard_fab2(sch_1):page220_i303"
				( attribute "CDS_LIB" "w_hdl"
					( Origin gPackager )
				)
				( attribute "CDS_LMAN_SYM_OUTLINE" "-50,25,50,-25"
					( Origin gPackager )
				)
				( attribute "CDS_LOCATION" "C7W13"
					( Origin gPackager )
				)
				( attribute "CDS_SEC" "1"
					( Origin gPackager )
				)
				( attribute "LOCATION" "C7W13"
					( Origin gFrontEnd )
				)
				( attribute "PACK_TYPE" "SMD-BCG5"
					( Origin gFrontEnd )
				)
				( attribute "PART_NUMBER" "078.22611.0811"
					( Origin gFrontEnd )
				)
				( attribute "PHYS_PAGE" "220"
					( Origin gFrontEnd )
				)
				( attribute "ROT" "0"
					( Origin gFrontEnd )
				)
				( attribute "SEC" "1"
					( Origin gFrontEnd )
				)
				( attribute "SEC_TYPE" "SMD-BCG5"
					( Origin gFrontEnd )
				)
				( attribute "VALUE" "SC22U16V5MX-4-GP"
					( Origin gFrontEnd )
				)
				( attribute "VER" "1"
					( Origin gFrontEnd )
				)
				( attribute "XY" "(1900,1025)"
					( Origin gFrontEnd )
				)
				( attribute "CHIPS_PART_NAME" "SC22U16V5MX-4-GP"
					( Origin gPackager )
				)
				( attribute "CDS_PART_NAME" "SC22U16V5MX-4-GP_SMD-BCG5-SC22A"
					( Origin gPackager )
				)
				( attribute "ATTRIBUTE" "22UF"
					( Origin gFrontEnd )
				)
				( attribute "PACK_SIZE" "0805"
					( Origin gFrontEnd )
				)
				( attribute "RATED" "16V"
					( Origin gFrontEnd )
				)
				( attribute "TOLERANCE" "20%"
					( Origin gFrontEnd )
				)
				( attribute "TYPE" "X6S"
					( Origin gFrontEnd )
				)
				( objectStatus "C7W13" )
			)
			( gate "@baseboard_fab2_lib.baseboard_fab2(sch_1):page220_i304"
				( attribute "CDS_LIB" "w_hdl"
					( Origin gPackager )
				)
				( attribute "CDS_LMAN_SYM_OUTLINE" "-50,25,50,-25"
					( Origin gPackager )
				)
				( attribute "CDS_LOCATION" "C7W12"
					( Origin gPackager )
				)
				( attribute "CDS_SEC" "1"
					( Origin gPackager )
				)
				( attribute "LOCATION" "C7W12"
					( Origin gFrontEnd )
				)
				( attribute "PACK_TYPE" "SMD-BCG5"
					( Origin gFrontEnd )
				)
				( attribute "PART_NUMBER" "078.22611.0811"
					( Origin gFrontEnd )
				)
				( attribute "PHYS_PAGE" "220"
					( Origin gFrontEnd )
				)
				( attribute "ROT" "0"
					( Origin gFrontEnd )
				)
				( attribute "SEC" "1"
					( Origin gFrontEnd )
				)
				( attribute "SEC_TYPE" "SMD-BCG5"
					( Origin gFrontEnd )
				)
				( attribute "VALUE" "SC22U16V5MX-4-GP"
					( Origin gFrontEnd )
				)
				( attribute "VER" "1"
					( Origin gFrontEnd )
				)
				( attribute "XY" "(1600,1025)"
					( Origin gFrontEnd )
				)
				( attribute "CHIPS_PART_NAME" "SC22U16V5MX-4-GP"
					( Origin gPackager )
				)
				( attribute "CDS_PART_NAME" "SC22U16V5MX-4-GP_SMD-BCG5-SC22A"
					( Origin gPackager )
				)
				( attribute "ATTRIBUTE" "22UF"
					( Origin gFrontEnd )
				)
				( attribute "PACK_SIZE" "0805"
					( Origin gFrontEnd )
				)
				( attribute "RATED" "16V"
					( Origin gFrontEnd )
				)
				( attribute "TOLERANCE" "20%"
					( Origin gFrontEnd )
				)
				( attribute "TYPE" "X6S"
					( Origin gFrontEnd )
				)
				( objectStatus "C7W12" )
			)
			( gate "@baseboard_fab2_lib.baseboard_fab2(sch_1):page220_i305"
				( attribute "CDS_LIB" "w_hdl"
					( Origin gPackager )
				)
				( attribute "CDS_LMAN_SYM_OUTLINE" "-50,25,50,-25"
					( Origin gPackager )
				)
				( attribute "CDS_LOCATION" "C7W11"
					( Origin gPackager )
				)
				( attribute "CDS_SEC" "1"
					( Origin gPackager )
				)
				( attribute "LOCATION" "C7W11"
					( Origin gFrontEnd )
				)
				( attribute "PACK_TYPE" "SMD-BCG5"
					( Origin gFrontEnd )
				)
				( attribute "PART_NUMBER" "078.22611.0811"
					( Origin gFrontEnd )
				)
				( attribute "PHYS_PAGE" "220"
					( Origin gFrontEnd )
				)
				( attribute "ROT" "0"
					( Origin gFrontEnd )
				)
				( attribute "SEC" "1"
					( Origin gFrontEnd )
				)
				( attribute "SEC_TYPE" "SMD-BCG5"
					( Origin gFrontEnd )
				)
				( attribute "VALUE" "SC22U16V5MX-4-GP"
					( Origin gFrontEnd )
				)
				( attribute "VER" "1"
					( Origin gFrontEnd )
				)
				( attribute "XY" "(1300,1025)"
					( Origin gFrontEnd )
				)
				( attribute "CHIPS_PART_NAME" "SC22U16V5MX-4-GP"
					( Origin gPackager )
				)
				( attribute "CDS_PART_NAME" "SC22U16V5MX-4-GP_SMD-BCG5-SC22A"
					( Origin gPackager )
				)
				( attribute "ATTRIBUTE" "22UF"
					( Origin gFrontEnd )
				)
				( attribute "PACK_SIZE" "0805"
					( Origin gFrontEnd )
				)
				( attribute "RATED" "16V"
					( Origin gFrontEnd )
				)
				( attribute "TOLERANCE" "20%"
					( Origin gFrontEnd )
				)
				( attribute "TYPE" "X6S"
					( Origin gFrontEnd )
				)
				( objectStatus "C7W11" )
			)
			( gate "@baseboard_fab2_lib.baseboard_fab2(sch_1):page220_i306"
				( attribute "CDS_LIB" "w_hdl"
					( Origin gPackager )
				)
				( attribute "CDS_LMAN_SYM_OUTLINE" "-50,25,50,-25"
					( Origin gPackager )
				)
				( attribute "CDS_LOCATION" "C7W10"
					( Origin gPackager )
				)
				( attribute "CDS_SEC" "1"
					( Origin gPackager )
				)
				( attribute "LOCATION" "C7W10"
					( Origin gFrontEnd )
				)
				( attribute "PACK_TYPE" "SMD-BCG5"
					( Origin gFrontEnd )
				)
				( attribute "PART_NUMBER" "078.22611.0811"
					( Origin gFrontEnd )
				)
				( attribute "PHYS_PAGE" "220"
					( Origin gFrontEnd )
				)
				( attribute "ROT" "0"
					( Origin gFrontEnd )
				)
				( attribute "SEC" "1"
					( Origin gFrontEnd )
				)
				( attribute "SEC_TYPE" "SMD-BCG5"
					( Origin gFrontEnd )
				)
				( attribute "VALUE" "SC22U16V5MX-4-GP"
					( Origin gFrontEnd )
				)
				( attribute "VER" "1"
					( Origin gFrontEnd )
				)
				( attribute "XY" "(1000,1025)"
					( Origin gFrontEnd )
				)
				( attribute "CHIPS_PART_NAME" "SC22U16V5MX-4-GP"
					( Origin gPackager )
				)
				( attribute "CDS_PART_NAME" "SC22U16V5MX-4-GP_SMD-BCG5-SC22A"
					( Origin gPackager )
				)
				( attribute "ATTRIBUTE" "22UF"
					( Origin gFrontEnd )
				)
				( attribute "PACK_SIZE" "0805"
					( Origin gFrontEnd )
				)
				( attribute "RATED" "16V"
					( Origin gFrontEnd )
				)
				( attribute "TOLERANCE" "20%"
					( Origin gFrontEnd )
				)
				( attribute "TYPE" "X6S"
					( Origin gFrontEnd )
				)
				( objectStatus "C7W10" )
			)
			( gate "@baseboard_fab2_lib.baseboard_fab2(sch_1):page201_i191"
				( attribute "CDS_LIB" "w_hdl"
					( Origin gPackager )
				)
				( attribute "CDS_LMAN_SYM_OUTLINE" "-50,125,50,-125"
					( Origin gPackager )
				)
				( attribute "LOCATION" "J8D4"
					( Origin gFrontEnd )
				)
				( attribute "PACK_TYPE" "CONN-G7"
					( Origin gFrontEnd )
				)
				( attribute "PART_NUMBER" "021.60545.0103"
					( Origin gFrontEnd )
				)
				( attribute "PHYS_PAGE" "201"
					( Origin gFrontEnd )
				)
				( attribute "ROT" "2"
					( Origin gFrontEnd )
				)
				( attribute "SEC" "1"
					( Origin gFrontEnd )
				)
				( attribute "SEC_TYPE" "CONN-G7"
					( Origin gFrontEnd )
				)
				( attribute "VALUE" "PIN-CON3-27-GP"
					( Origin gFrontEnd )
				)
				( attribute "VER" "1"
					( Origin gFrontEnd )
				)
				( attribute "XY" "(-3225,850)"
					( Origin gFrontEnd )
				)
				( attribute "CHIPS_PART_NAME" "PIN-CON3-27-GP"
					( Origin gPackager )
				)
				( attribute "CDS_PART_NAME" "PIN-CON3-27-GP_CONN-G7-PIN-CONA"
					( Origin gPackager )
				)
				( attribute "CDS_LOCATION" "J8D4"
					( Origin gPackager )
				)
				( attribute "CDS_SEC" "1"
					( Origin gPackager )
				)
				( objectStatus "J8D4" )
			)
			( gate "@baseboard_fab2_lib.baseboard_fab2(sch_1):page147_i160"
				( attribute "BOM_COST" "PROC_SIDEBAND"
					( Origin gFrontEnd )
				)
				( attribute "CDS_LIB" "dev_discrete"
					( Origin gPackager )
				)
				( attribute "CDS_LOCATION" "C25W9"
					( Origin gPackager )
				)
				( attribute "CDS_SEC" "1"
					( Origin gPackager )
				)
				( attribute "LOCATION" "C25W9"
					( Origin gFrontEnd )
				)
				( attribute "MATERIAL" "X7R"
					( Origin gFrontEnd )
				)
				( attribute "PACK_TYPE" "0402V"
					( Origin gFrontEnd )
				)
				( attribute "PART_NUMBER" "A36096-030"
					( Origin gFrontEnd )
				)
				( attribute "PHYS_PAGE" "147"
					( Origin gFrontEnd )
				)
				( attribute "ROOM" "PROC_SIDEBAND"
					( Origin gFrontEnd )
				)
				( attribute "ROT" "0"
					( Origin gFrontEnd )
				)
				( attribute "SEC" "1"
					( Origin gFrontEnd )
				)
				( attribute "SEC_TYPE" "0402V"
					( Origin gFrontEnd )
				)
				( attribute "TOLERANCE" "10%"
					( Origin gFrontEnd )
				)
				( attribute "VALUE" "0.1UF"
					( Origin gFrontEnd )
				)
				( attribute "VER" "1"
					( Origin gFrontEnd )
				)
				( attribute "VOLTAGE" "16V"
					( Units "uVoltage" "V" 1.000000)
					( Origin gFrontEnd )
				)
				( attribute "XY" "(1450,2150)"
					( Origin gFrontEnd )
				)
				( attribute "CHIPS_PART_NAME" "CAP_A"
					( Origin gPackager )
				)
				( attribute "CDS_PART_NAME" "CAP_A_0402V-0.1UF,16V,10%,X7R,A"
					( Origin gPackager )
				)
				( objectStatus "C25W9" )
			)
			( gate "@baseboard_fab2_lib.baseboard_fab2(sch_1):page241_i103"
				( attribute "CDS_LIB" "w_hdl"
					( Origin gPackager )
				)
				( attribute "CDS_LMAN_SYM_OUTLINE" "-50,25,50,-25"
					( Origin gPackager )
				)
				( attribute "CDS_LOCATION" "C8E7"
					( Origin gPackager )
				)
				( attribute "CDS_SEC" "1"
					( Origin gPackager )
				)
				( attribute "LOCATION" "C8E7"
					( Origin gFrontEnd )
				)
				( attribute "PACK_TYPE" "SMD-BCG5"
					( Origin gFrontEnd )
				)
				( attribute "PART_NUMBER" "078.22611.0811"
					( Origin gFrontEnd )
				)
				( attribute "PHYS_PAGE" "241"
					( Origin gFrontEnd )
				)
				( attribute "ROT" "0"
					( Origin gFrontEnd )
				)
				( attribute "SEC" "1"
					( Origin gFrontEnd )
				)
				( attribute "SEC_TYPE" "SMD-BCG5"
					( Origin gFrontEnd )
				)
				( attribute "VALUE" "SC22U16V5MX-4-GP"
					( Origin gFrontEnd )
				)
				( attribute "VER" "1"
					( Origin gFrontEnd )
				)
				( attribute "XY" "(3400,3825)"
					( Origin gFrontEnd )
				)
				( attribute "CHIPS_PART_NAME" "SC22U16V5MX-4-GP"
					( Origin gPackager )
				)
				( attribute "CDS_PART_NAME" "SC22U16V5MX-4-GP_SMD-BCG5-SC22A"
					( Origin gPackager )
				)
				( attribute "ATTRIBUTE" "22UF"
					( Origin gFrontEnd )
				)
				( attribute "PACK_SIZE" "0805"
					( Origin gFrontEnd )
				)
				( attribute "RATED" "16V"
					( Origin gFrontEnd )
				)
				( attribute "TOLERANCE" "20%"
					( Origin gFrontEnd )
				)
				( attribute "TYPE" "X6S"
					( Origin gFrontEnd )
				)
				( objectStatus "C8E7" )
			)
			( gate "@baseboard_fab2_lib.baseboard_fab2(sch_1):page241_i104"
				( attribute "CDS_LIB" "w_hdl"
					( Origin gPackager )
				)
				( attribute "CDS_LMAN_SYM_OUTLINE" "-50,25,50,-25"
					( Origin gPackager )
				)
				( attribute "CDS_LOCATION" "C8E9"
					( Origin gPackager )
				)
				( attribute "CDS_SEC" "1"
					( Origin gPackager )
				)
				( attribute "LOCATION" "C8E9"
					( Origin gFrontEnd )
				)
				( attribute "PACK_TYPE" "SMD-BCG5"
					( Origin gFrontEnd )
				)
				( attribute "PART_NUMBER" "078.22611.0811"
					( Origin gFrontEnd )
				)
				( attribute "PHYS_PAGE" "241"
					( Origin gFrontEnd )
				)
				( attribute "ROT" "0"
					( Origin gFrontEnd )
				)
				( attribute "SEC" "1"
					( Origin gFrontEnd )
				)
				( attribute "SEC_TYPE" "SMD-BCG5"
					( Origin gFrontEnd )
				)
				( attribute "VALUE" "SC22U16V5MX-4-GP"
					( Origin gFrontEnd )
				)
				( attribute "VER" "1"
					( Origin gFrontEnd )
				)
				( attribute "XY" "(3800,3825)"
					( Origin gFrontEnd )
				)
				( attribute "CHIPS_PART_NAME" "SC22U16V5MX-4-GP"
					( Origin gPackager )
				)
				( attribute "CDS_PART_NAME" "SC22U16V5MX-4-GP_SMD-BCG5-SC22A"
					( Origin gPackager )
				)
				( attribute "ATTRIBUTE" "22UF"
					( Origin gFrontEnd )
				)
				( attribute "PACK_SIZE" "0805"
					( Origin gFrontEnd )
				)
				( attribute "RATED" "16V"
					( Origin gFrontEnd )
				)
				( attribute "TOLERANCE" "20%"
					( Origin gFrontEnd )
				)
				( attribute "TYPE" "X6S"
					( Origin gFrontEnd )
				)
				( objectStatus "C8E9" )
			)
			( gate "@baseboard_fab2_lib.baseboard_fab2(sch_1):page89_i40"
				( attribute "BOM_COST" "MEM_NV"
					( Origin gFrontEnd )
				)
				( attribute "CDS_LIB" "mstr_discrete"
					( Origin gPackager )
				)
				( attribute "CDS_LOCATION" "R6W29"
					( Origin gPackager )
				)
				( attribute "CDS_SEC" "1"
					( Origin gPackager )
				)
				( attribute "LOCATION" "R6W29"
					( Origin gFrontEnd )
				)
				( attribute "MATERIAL" "CHIP"
					( Origin gFrontEnd )
				)
				( attribute "PACK_TYPE" "0402"
					( Origin gFrontEnd )
				)
				( attribute "PART_NUMBER" "G21796-016"
					( Origin gFrontEnd )
				)
				( attribute "PHYS_PAGE" "89"
					( Origin gFrontEnd )
				)
				( attribute "ROOM" "NV_DIMM"
					( Origin gFrontEnd )
				)
				( attribute "ROT" "0"
					( Origin gFrontEnd )
				)
				( attribute "SEC" "1"
					( Origin gFrontEnd )
				)
				( attribute "SEC_TYPE" "0402"
					( Origin gFrontEnd )
				)
				( attribute "TOLERANCE" "1%"
					( Origin gFrontEnd )
				)
				( attribute "VALUE" "10.0K"
					( Origin gFrontEnd )
				)
				( attribute "VER" "2"
					( Origin gFrontEnd )
				)
				( attribute "WATTAGE" "1/16W"
					( Origin gFrontEnd )
				)
				( attribute "XY" "(-450,2175)"
					( Origin gFrontEnd )
				)
				( attribute "CHIPS_PART_NAME" "RES"
					( Origin gPackager )
				)
				( attribute "CDS_PART_NAME" "RES_0402-10.0K,1%,1/16W,CHIP,GA"
					( Origin gPackager )
				)
				( objectStatus "R6W29" )
			)
			( gate "@baseboard_fab2_lib.baseboard_fab2(sch_1):page89_i45"
				( attribute "BOM_COST" "MEM_NV"
					( Origin gFrontEnd )
				)
				( attribute "CDS_LIB" "mstr_discrete"
					( Origin gPackager )
				)
				( attribute "CDS_LOCATION" "WR8D30"
					( Origin gPackager )
				)
				( attribute "CDS_SEC" "1"
					( Origin gPackager )
				)
				( attribute "LOCATION" "WR8D30"
					( Origin gFrontEnd )
				)
				( attribute "MATERIAL" "CHIP"
					( Origin gFrontEnd )
				)
				( attribute "PACK_TYPE" "0402"
					( Origin gFrontEnd )
				)
				( attribute "PART_NUMBER" "G21796-016"
					( Origin gFrontEnd )
				)
				( attribute "PHYS_PAGE" "89"
					( Origin gFrontEnd )
				)
				( attribute "ROOM" "NV_DIMM"
					( Origin gFrontEnd )
				)
				( attribute "ROT" "0"
					( Origin gFrontEnd )
				)
				( attribute "SEC" "1"
					( Origin gFrontEnd )
				)
				( attribute "SEC_TYPE" "0402"
					( Origin gFrontEnd )
				)
				( attribute "TOLERANCE" "1%"
					( Origin gFrontEnd )
				)
				( attribute "VALUE" "10.0K"
					( Origin gFrontEnd )
				)
				( attribute "VER" "1"
					( Origin gFrontEnd )
				)
				( attribute "WATTAGE" "1/16W"
					( Origin gFrontEnd )
				)
				( attribute "XY" "(1000,2500)"
					( Origin gFrontEnd )
				)
				( attribute "CHIPS_PART_NAME" "RES"
					( Origin gPackager )
				)
				( attribute "CDS_PART_NAME" "RES_0402-10.0K,1%,1/16W,CHIP,GA"
					( Origin gPackager )
				)
				( objectStatus "WR8D30" )
			)
			( gate "@baseboard_fab2_lib.baseboard_fab2(sch_1):page89_i46"
				( attribute "BOM_COST" "MEM_NV"
					( Origin gFrontEnd )
				)
				( attribute "CDS_LIB" "mstr_discrete"
					( Origin gPackager )
				)
				( attribute "CDS_LOCATION" "Q8D1"
					( Origin gPackager )
				)
				( attribute "CDS_SEC" "2"
					( Origin gPackager )
				)
				( attribute "LOCATION" "Q8D1"
					( Origin gFrontEnd )
				)
				( attribute "MATERIAL" "XSTR"
					( Origin gFrontEnd )
				)
				( attribute "PACK_TYPE" "SSOPLF"
					( Origin gFrontEnd )
				)
				( attribute "PART_NUMBER" "C52264-001"
					( Origin gFrontEnd )
				)
				( attribute "PHYS_PAGE" "89"
					( Origin gFrontEnd )
				)
				( attribute "ROOM" "NV_DIMM"
					( Origin gFrontEnd )
				)
				( attribute "ROT" "0"
					( Origin gFrontEnd )
				)
				( attribute "SEC" "2"
					( Origin gFrontEnd )
				)
				( attribute "SEC_TYPE" "SSOPLF"
					( Origin gFrontEnd )
				)
				( attribute "VALUE" "MBT3904"
					( Origin gFrontEnd )
				)
				( attribute "VER" "1"
					( Origin gFrontEnd )
				)
				( attribute "XY" "(2400,4175)"
					( Origin gFrontEnd )
				)
				( attribute "CHIPS_PART_NAME" "NPN_DUAL"
					( Origin gPackager )
				)
				( attribute "CDS_PART_NAME" "NPN_DUAL_SSOPLF-MBT3904,XSTR,CA"
					( Origin gPackager )
				)
				( objectStatus "Q8D1" )
			)
			( gate "@baseboard_fab2_lib.baseboard_fab2(sch_1):page89_i49"
				( attribute "CDS_LIB" "mstr_discrete"
					( Origin gPackager )
				)
				( attribute "CDS_LOCATION" "R8W9"
					( Origin gPackager )
				)
				( attribute "LOCATION" "R8W9"
					( Origin gFrontEnd )
				)
				( attribute "MATERIAL" "CHIP"
					( Origin gFrontEnd )
				)
				( attribute "PACK_TYPE" "0402"
					( Origin gFrontEnd )
				)
				( attribute "PART_NUMBER" "G21796-072"
					( Origin gFrontEnd )
				)
				( attribute "PHYS_PAGE" "89"
					( Origin gFrontEnd )
				)
				( attribute "ROOM" "NVDIMM"
					( Origin gFrontEnd )
				)
				( attribute "ROT" "0"
					( Origin gFrontEnd )
				)
				( attribute "SEC" "1"
					( Origin gFrontEnd )
				)
				( attribute "SEC_TYPE" "0402"
					( Origin gFrontEnd )
				)
				( attribute "TOLERANCE" "1%"
					( Origin gFrontEnd )
				)
				( attribute "VALUE" "4.75K"
					( Origin gFrontEnd )
				)
				( attribute "VER" "2"
					( Origin gFrontEnd )
				)
				( attribute "WATTAGE" "1/16W"
					( Origin gFrontEnd )
				)
				( attribute "XY" "(2200,3250)"
					( Origin gFrontEnd )
				)
				( attribute "CHIPS_PART_NAME" "RES"
					( Origin gPackager )
				)
				( attribute "CDS_PART_NAME" "RES_0402-4.75K,1%,1/16W,CHIP,GA"
					( Origin gPackager )
				)
				( attribute "CDS_SEC" "1"
					( Origin gPackager )
				)
				( objectStatus "R8W9" )
			)
			( gate "@baseboard_fab2_lib.baseboard_fab2(sch_1):page89_i51"
				( attribute "BOM_COST" "MEM_NV"
					( Origin gFrontEnd )
				)
				( attribute "CDS_LIB" "mstr_discrete"
					( Origin gPackager )
				)
				( attribute "CDS_LOCATION" "Q8W1"
					( Origin gPackager )
				)
				( attribute "CDS_SEC" "2"
					( Origin gPackager )
				)
				( attribute "LOCATION" "Q8W1"
					( Origin gFrontEnd )
				)
				( attribute "MATERIAL" "XSTR"
					( Origin gFrontEnd )
				)
				( attribute "PACK_TYPE" "SSOPLF"
					( Origin gFrontEnd )
				)
				( attribute "PART_NUMBER" "C52264-001"
					( Origin gFrontEnd )
				)
				( attribute "PHYS_PAGE" "89"
					( Origin gFrontEnd )
				)
				( attribute "ROOM" "NV_DIMM"
					( Origin gFrontEnd )
				)
				( attribute "ROT" "0"
					( Origin gFrontEnd )
				)
				( attribute "SEC" "2"
					( Origin gFrontEnd )
				)
				( attribute "SEC_TYPE" "SSOPLF"
					( Origin gFrontEnd )
				)
				( attribute "VALUE" "MBT3904"
					( Origin gFrontEnd )
				)
				( attribute "VER" "1"
					( Origin gFrontEnd )
				)
				( attribute "XY" "(2900,2975)"
					( Origin gFrontEnd )
				)
				( attribute "CHIPS_PART_NAME" "NPN_DUAL"
					( Origin gPackager )
				)
				( attribute "CDS_PART_NAME" "NPN_DUAL_SSOPLF-MBT3904,XSTR,CA"
					( Origin gPackager )
				)
				( objectStatus "Q8W1" )
			)
			( gate "@baseboard_fab2_lib.baseboard_fab2(sch_1):page89_i52"
				( attribute "BOM_COST" "MEM_NV"
					( Origin gFrontEnd )
				)
				( attribute "CDS_LIB" "mstr_discrete"
					( Origin gPackager )
				)
				( attribute "CDS_LOCATION" "Q8W1"
					( Origin gPackager )
				)
				( attribute "CDS_SEC" "1"
					( Origin gPackager )
				)
				( attribute "LOCATION" "Q8W1"
					( Origin gFrontEnd )
				)
				( attribute "MATERIAL" "XSTR"
					( Origin gFrontEnd )
				)
				( attribute "PACK_TYPE" "SSOPLF"
					( Origin gFrontEnd )
				)
				( attribute "PART_NUMBER" "C52264-001"
					( Origin gFrontEnd )
				)
				( attribute "PHYS_PAGE" "89"
					( Origin gFrontEnd )
				)
				( attribute "ROOM" "NV_DIMM"
					( Origin gFrontEnd )
				)
				( attribute "ROT" "0"
					( Origin gFrontEnd )
				)
				( attribute "SEC" "1"
					( Origin gFrontEnd )
				)
				( attribute "SEC_TYPE" "SSOPLF"
					( Origin gFrontEnd )
				)
				( attribute "VALUE" "MBT3904"
					( Origin gFrontEnd )
				)
				( attribute "VER" "1"
					( Origin gFrontEnd )
				)
				( attribute "XY" "(2150,2500)"
					( Origin gFrontEnd )
				)
				( attribute "CHIPS_PART_NAME" "NPN_DUAL"
					( Origin gPackager )
				)
				( attribute "CDS_PART_NAME" "NPN_DUAL_SSOPLF-MBT3904,XSTR,CA"
					( Origin gPackager )
				)
				( objectStatus "Q8W1" )
			)
			( gate "@baseboard_fab2_lib.baseboard_fab2(sch_1):page89_i53"
				( attribute "BOM_COST" "PROC_SIDEBAND"
					( Origin gFrontEnd )
				)
				( attribute "CDS_LIB" "mstr_discrete"
					( Origin gPackager )
				)
				( attribute "CDS_LOCATION" "Q1F1"
					( Origin gPackager )
				)
				( attribute "CDS_SEC" "1"
					( Origin gPackager )
				)
				( attribute "LOCATION" "Q1F1"
					( Origin gFrontEnd )
				)
				( attribute "MATERIAL" "IC"
					( Origin gFrontEnd )
				)
				( attribute "PACK_TYPE" "SM"
					( Origin gFrontEnd )
				)
				( attribute "PART_NUMBER" "C52245-001"
					( Origin gFrontEnd )
				)
				( attribute "PHYS_PAGE" "89"
					( Origin gFrontEnd )
				)
				( attribute "ROOM" "PROC_SIDEBAND"
					( Origin gFrontEnd )
				)
				( attribute "ROT" "0"
					( Origin gFrontEnd )
				)
				( attribute "SEC" "1"
					( Origin gFrontEnd )
				)
				( attribute "SEC_TYPE" "SM"
					( Origin gFrontEnd )
				)
				( attribute "VALUE" "MMBT3904"
					( Origin gFrontEnd )
				)
				( attribute "VER" "1"
					( Origin gFrontEnd )
				)
				( attribute "XY" "(-500,2725)"
					( Origin gFrontEnd )
				)
				( attribute "CHIPS_PART_NAME" "NPN"
					( Origin gPackager )
				)
				( attribute "CDS_PART_NAME" "NPN_SM-MMBT3904,IC,C52245-001"
					( Origin gPackager )
				)
				( objectStatus "Q1F1" )
			)
			( gate "@baseboard_fab2_lib.baseboard_fab2(sch_1):page89_i54"
				( attribute "BOM_COST" "DEBUG"
					( Origin gFrontEnd )
				)
				( attribute "CDS_LIB" "mstr_discrete"
					( Origin gPackager )
				)
				( attribute "CDS_LOCATION" "R1W32"
					( Origin gPackager )
				)
				( attribute "CDS_SEC" "1"
					( Origin gPackager )
				)
				( attribute "LOCATION" "R1W32"
					( Origin gFrontEnd )
				)
				( attribute "MATERIAL" "CHIP"
					( Origin gFrontEnd )
				)
				( attribute "PACK_TYPE" "0402"
					( Origin gFrontEnd )
				)
				( attribute "PART_NUMBER" "G21497-028"
					( Origin gFrontEnd )
				)
				( attribute "PHYS_PAGE" "89"
					( Origin gFrontEnd )
				)
				( attribute "ROOM" "UART_MUX"
					( Origin gFrontEnd )
				)
				( attribute "ROT" "0"
					( Origin gFrontEnd )
				)
				( attribute "SEC" "1"
					( Origin gFrontEnd )
				)
				( attribute "SEC_TYPE" "0402"
					( Origin gFrontEnd )
				)
				( attribute "TOLERANCE" "5%"
					( Origin gFrontEnd )
				)
				( attribute "VALUE" "330"
					( Origin gFrontEnd )
				)
				( attribute "VER" "1"
					( Origin gFrontEnd )
				)
				( attribute "WATTAGE" "1/16W"
					( Origin gFrontEnd )
				)
				( attribute "XY" "(-1350,2725)"
					( Origin gFrontEnd )
				)
				( attribute "CHIPS_PART_NAME" "RES"
					( Origin gPackager )
				)
				( attribute "CDS_PART_NAME" "RES_0402-330,5%,1/16W,CHIP,G21A"
					( Origin gPackager )
				)
				( objectStatus "R1W32" )
			)
			( gate "@baseboard_fab2_lib.baseboard_fab2(sch_1):page89_i55"
				( attribute "BOM_COST" "PROC_SIDEBAND"
					( Origin gFrontEnd )
				)
				( attribute "CDS_LIB" "mstr_discrete"
					( Origin gPackager )
				)
				( attribute "CDS_LOCATION" "Q1W6"
					( Origin gPackager )
				)
				( attribute "CDS_SEC" "1"
					( Origin gPackager )
				)
				( attribute "LOCATION" "Q1W6"
					( Origin gFrontEnd )
				)
				( attribute "MATERIAL" "IC"
					( Origin gFrontEnd )
				)
				( attribute "PACK_TYPE" "SM"
					( Origin gFrontEnd )
				)
				( attribute "PART_NUMBER" "C52245-001"
					( Origin gFrontEnd )
				)
				( attribute "PHYS_PAGE" "89"
					( Origin gFrontEnd )
				)
				( attribute "ROOM" "PROC_SIDEBAND"
					( Origin gFrontEnd )
				)
				( attribute "ROT" "0"
					( Origin gFrontEnd )
				)
				( attribute "SEC" "1"
					( Origin gFrontEnd )
				)
				( attribute "SEC_TYPE" "SM"
					( Origin gFrontEnd )
				)
				( attribute "VALUE" "MMBT3904"
					( Origin gFrontEnd )
				)
				( attribute "VER" "1"
					( Origin gFrontEnd )
				)
				( attribute "XY" "(-500,1550)"
					( Origin gFrontEnd )
				)
				( attribute "CHIPS_PART_NAME" "NPN"
					( Origin gPackager )
				)
				( attribute "CDS_PART_NAME" "NPN_SM-MMBT3904,IC,C52245-001"
					( Origin gPackager )
				)
				( objectStatus "Q1W6" )
			)
			( gate "@baseboard_fab2_lib.baseboard_fab2(sch_1):page89_i56"
				( attribute "BOM_COST" "DEBUG"
					( Origin gFrontEnd )
				)
				( attribute "CDS_LIB" "mstr_discrete"
					( Origin gPackager )
				)
				( attribute "CDS_LOCATION" "R1W31"
					( Origin gPackager )
				)
				( attribute "CDS_SEC" "1"
					( Origin gPackager )
				)
				( attribute "LOCATION" "R1W31"
					( Origin gFrontEnd )
				)
				( attribute "MATERIAL" "CHIP"
					( Origin gFrontEnd )
				)
				( attribute "PACK_TYPE" "0402"
					( Origin gFrontEnd )
				)
				( attribute "PART_NUMBER" "G21497-028"
					( Origin gFrontEnd )
				)
				( attribute "PHYS_PAGE" "89"
					( Origin gFrontEnd )
				)
				( attribute "ROOM" "UART_MUX"
					( Origin gFrontEnd )
				)
				( attribute "ROT" "0"
					( Origin gFrontEnd )
				)
				( attribute "SEC" "1"
					( Origin gFrontEnd )
				)
				( attribute "SEC_TYPE" "0402"
					( Origin gFrontEnd )
				)
				( attribute "TOLERANCE" "5%"
					( Origin gFrontEnd )
				)
				( attribute "VALUE" "330"
					( Origin gFrontEnd )
				)
				( attribute "VER" "1"
					( Origin gFrontEnd )
				)
				( attribute "WATTAGE" "1/16W"
					( Origin gFrontEnd )
				)
				( attribute "XY" "(-1350,1550)"
					( Origin gFrontEnd )
				)
				( attribute "CHIPS_PART_NAME" "RES"
					( Origin gPackager )
				)
				( attribute "CDS_PART_NAME" "RES_0402-330,5%,1/16W,CHIP,G21A"
					( Origin gPackager )
				)
				( objectStatus "R1W31" )
			)
			( gate "@baseboard_fab2_lib.baseboard_fab2(sch_1):page253_i35"
				( attribute "CDS_LIB" "w_hdl"
					( Origin gPackager )
				)
				( attribute "CDS_LMAN_SYM_OUTLINE" "-50,25,50,-25"
					( Origin gPackager )
				)
				( attribute "CDS_LOCATION" "C30W3"
					( Origin gPackager )
				)
				( attribute "CDS_SEC" "1"
					( Origin gPackager )
				)
				( attribute "LOCATION" "C30W3"
					( Origin gFrontEnd )
				)
				( attribute "PACK_TYPE" "SMD-BCG5"
					( Origin gFrontEnd )
				)
				( attribute "PART_NUMBER" "078.22611.0811"
					( Origin gFrontEnd )
				)
				( attribute "PHYS_PAGE" "253"
					( Origin gFrontEnd )
				)
				( attribute "ROT" "0"
					( Origin gFrontEnd )
				)
				( attribute "SEC" "1"
					( Origin gFrontEnd )
				)
				( attribute "SEC_TYPE" "SMD-BCG5"
					( Origin gFrontEnd )
				)
				( attribute "VALUE" "SC22U16V5MX-4-GP"
					( Origin gFrontEnd )
				)
				( attribute "VER" "1"
					( Origin gFrontEnd )
				)
				( attribute "XY" "(-4550,4375)"
					( Origin gFrontEnd )
				)
				( attribute "CHIPS_PART_NAME" "SC22U16V5MX-4-GP"
					( Origin gPackager )
				)
				( attribute "CDS_PART_NAME" "SC22U16V5MX-4-GP_SMD-BCG5-SC22A"
					( Origin gPackager )
				)
				( attribute "ATTRIBUTE" "22UF"
					( Origin gFrontEnd )
				)
				( attribute "PACK_SIZE" "0805"
					( Origin gFrontEnd )
				)
				( attribute "RATED" "16V"
					( Origin gFrontEnd )
				)
				( attribute "TOLERANCE" "20%"
					( Origin gFrontEnd )
				)
				( attribute "TYPE" "X6S"
					( Origin gFrontEnd )
				)
				( attribute "GROUP" "NO_KR"
					( Origin gFrontEnd )
				)
				( objectStatus "C30W3" )
			)
			( gate "@baseboard_fab2_lib.baseboard_fab2(sch_1):page253_i36"
				( attribute "CDS_LIB" "w_hdl"
					( Origin gPackager )
				)
				( attribute "CDS_LMAN_SYM_OUTLINE" "-50,25,50,-25"
					( Origin gPackager )
				)
				( attribute "CDS_LOCATION" "C30W4"
					( Origin gPackager )
				)
				( attribute "CDS_SEC" "1"
					( Origin gPackager )
				)
				( attribute "LOCATION" "C30W4"
					( Origin gFrontEnd )
				)
				( attribute "PACK_TYPE" "SMD-BCG5"
					( Origin gFrontEnd )
				)
				( attribute "PART_NUMBER" "078.22611.0811"
					( Origin gFrontEnd )
				)
				( attribute "PHYS_PAGE" "253"
					( Origin gFrontEnd )
				)
				( attribute "ROT" "0"
					( Origin gFrontEnd )
				)
				( attribute "SEC" "1"
					( Origin gFrontEnd )
				)
				( attribute "SEC_TYPE" "SMD-BCG5"
					( Origin gFrontEnd )
				)
				( attribute "VALUE" "SC22U16V5MX-4-GP"
					( Origin gFrontEnd )
				)
				( attribute "VER" "1"
					( Origin gFrontEnd )
				)
				( attribute "XY" "(-4250,4375)"
					( Origin gFrontEnd )
				)
				( attribute "CHIPS_PART_NAME" "SC22U16V5MX-4-GP"
					( Origin gPackager )
				)
				( attribute "CDS_PART_NAME" "SC22U16V5MX-4-GP_SMD-BCG5-SC22A"
					( Origin gPackager )
				)
				( attribute "ATTRIBUTE" "22UF"
					( Origin gFrontEnd )
				)
				( attribute "PACK_SIZE" "0805"
					( Origin gFrontEnd )
				)
				( attribute "RATED" "16V"
					( Origin gFrontEnd )
				)
				( attribute "TOLERANCE" "20%"
					( Origin gFrontEnd )
				)
				( attribute "TYPE" "X6S"
					( Origin gFrontEnd )
				)
				( attribute "GROUP" "NO_KR"
					( Origin gFrontEnd )
				)
				( objectStatus "C30W4" )
			)
			( gate "@baseboard_fab2_lib.baseboard_fab2(sch_1):page253_i37"
				( attribute "CDS_LIB" "w_hdl"
					( Origin gPackager )
				)
				( attribute "CDS_LMAN_SYM_OUTLINE" "-50,25,50,-25"
					( Origin gPackager )
				)
				( attribute "CDS_LOCATION" "C30W6"
					( Origin gPackager )
				)
				( attribute "CDS_SEC" "1"
					( Origin gPackager )
				)
				( attribute "LOCATION" "C30W6"
					( Origin gFrontEnd )
				)
				( attribute "PACK_TYPE" "SMD-BCG5"
					( Origin gFrontEnd )
				)
				( attribute "PART_NUMBER" "078.22611.0811"
					( Origin gFrontEnd )
				)
				( attribute "PHYS_PAGE" "253"
					( Origin gFrontEnd )
				)
				( attribute "ROT" "0"
					( Origin gFrontEnd )
				)
				( attribute "SEC" "1"
					( Origin gFrontEnd )
				)
				( attribute "SEC_TYPE" "SMD-BCG5"
					( Origin gFrontEnd )
				)
				( attribute "VALUE" "SC22U16V5MX-4-GP"
					( Origin gFrontEnd )
				)
				( attribute "VER" "1"
					( Origin gFrontEnd )
				)
				( attribute "XY" "(-3650,4375)"
					( Origin gFrontEnd )
				)
				( attribute "CHIPS_PART_NAME" "SC22U16V5MX-4-GP"
					( Origin gPackager )
				)
				( attribute "CDS_PART_NAME" "SC22U16V5MX-4-GP_SMD-BCG5-SC22A"
					( Origin gPackager )
				)
				( attribute "ATTRIBUTE" "22UF"
					( Origin gFrontEnd )
				)
				( attribute "PACK_SIZE" "0805"
					( Origin gFrontEnd )
				)
				( attribute "RATED" "16V"
					( Origin gFrontEnd )
				)
				( attribute "TOLERANCE" "20%"
					( Origin gFrontEnd )
				)
				( attribute "TYPE" "X6S"
					( Origin gFrontEnd )
				)
				( attribute "GROUP" "NO_KR"
					( Origin gFrontEnd )
				)
				( objectStatus "C30W6" )
			)
			( gate "@baseboard_fab2_lib.baseboard_fab2(sch_1):page253_i38"
				( attribute "CDS_LIB" "w_hdl"
					( Origin gPackager )
				)
				( attribute "CDS_LMAN_SYM_OUTLINE" "-50,25,50,-25"
					( Origin gPackager )
				)
				( attribute "CDS_LOCATION" "C30W5"
					( Origin gPackager )
				)
				( attribute "CDS_SEC" "1"
					( Origin gPackager )
				)
				( attribute "LOCATION" "C30W5"
					( Origin gFrontEnd )
				)
				( attribute "PACK_TYPE" "SMD-BCG5"
					( Origin gFrontEnd )
				)
				( attribute "PART_NUMBER" "078.22611.0811"
					( Origin gFrontEnd )
				)
				( attribute "PHYS_PAGE" "253"
					( Origin gFrontEnd )
				)
				( attribute "ROT" "0"
					( Origin gFrontEnd )
				)
				( attribute "SEC" "1"
					( Origin gFrontEnd )
				)
				( attribute "SEC_TYPE" "SMD-BCG5"
					( Origin gFrontEnd )
				)
				( attribute "VALUE" "SC22U16V5MX-4-GP"
					( Origin gFrontEnd )
				)
				( attribute "VER" "1"
					( Origin gFrontEnd )
				)
				( attribute "XY" "(-3950,4375)"
					( Origin gFrontEnd )
				)
				( attribute "CHIPS_PART_NAME" "SC22U16V5MX-4-GP"
					( Origin gPackager )
				)
				( attribute "CDS_PART_NAME" "SC22U16V5MX-4-GP_SMD-BCG5-SC22A"
					( Origin gPackager )
				)
				( attribute "ATTRIBUTE" "22UF"
					( Origin gFrontEnd )
				)
				( attribute "PACK_SIZE" "0805"
					( Origin gFrontEnd )
				)
				( attribute "RATED" "16V"
					( Origin gFrontEnd )
				)
				( attribute "TOLERANCE" "20%"
					( Origin gFrontEnd )
				)
				( attribute "TYPE" "X6S"
					( Origin gFrontEnd )
				)
				( attribute "GROUP" "NO_KR"
					( Origin gFrontEnd )
				)
				( objectStatus "C30W5" )
			)
			( gate "@baseboard_fab2_lib.baseboard_fab2(sch_1):page253_i40"
				( attribute "CDS_LIB" "w_hdl"
					( Origin gPackager )
				)
				( attribute "CDS_LMAN_SYM_OUTLINE" "-50,25,50,-25"
					( Origin gPackager )
				)
				( attribute "CDS_LOCATION" "C30W9"
					( Origin gPackager )
				)
				( attribute "CDS_SEC" "1"
					( Origin gPackager )
				)
				( attribute "LOCATION" "C30W9"
					( Origin gFrontEnd )
				)
				( attribute "PACK_TYPE" "SMD-BCG5"
					( Origin gFrontEnd )
				)
				( attribute "PART_NUMBER" "078.22611.0811"
					( Origin gFrontEnd )
				)
				( attribute "PHYS_PAGE" "253"
					( Origin gFrontEnd )
				)
				( attribute "ROT" "0"
					( Origin gFrontEnd )
				)
				( attribute "SEC" "1"
					( Origin gFrontEnd )
				)
				( attribute "SEC_TYPE" "SMD-BCG5"
					( Origin gFrontEnd )
				)
				( attribute "VALUE" "SC22U16V5MX-4-GP"
					( Origin gFrontEnd )
				)
				( attribute "VER" "1"
					( Origin gFrontEnd )
				)
				( attribute "XY" "(-2750,4375)"
					( Origin gFrontEnd )
				)
				( attribute "CHIPS_PART_NAME" "SC22U16V5MX-4-GP"
					( Origin gPackager )
				)
				( attribute "CDS_PART_NAME" "SC22U16V5MX-4-GP_SMD-BCG5-SC22A"
					( Origin gPackager )
				)
				( attribute "ATTRIBUTE" "22UF"
					( Origin gFrontEnd )
				)
				( attribute "PACK_SIZE" "0805"
					( Origin gFrontEnd )
				)
				( attribute "RATED" "16V"
					( Origin gFrontEnd )
				)
				( attribute "TOLERANCE" "20%"
					( Origin gFrontEnd )
				)
				( attribute "TYPE" "X6S"
					( Origin gFrontEnd )
				)
				( attribute "GROUP" "NO_KR"
					( Origin gFrontEnd )
				)
				( objectStatus "C30W9" )
			)
			( gate "@baseboard_fab2_lib.baseboard_fab2(sch_1):page253_i41"
				( attribute "CDS_LIB" "w_hdl"
					( Origin gPackager )
				)
				( attribute "CDS_LMAN_SYM_OUTLINE" "-50,25,50,-25"
					( Origin gPackager )
				)
				( attribute "CDS_LOCATION" "C30W8"
					( Origin gPackager )
				)
				( attribute "CDS_SEC" "1"
					( Origin gPackager )
				)
				( attribute "LOCATION" "C30W8"
					( Origin gFrontEnd )
				)
				( attribute "PACK_TYPE" "SMD-BCG5"
					( Origin gFrontEnd )
				)
				( attribute "PART_NUMBER" "078.22611.0811"
					( Origin gFrontEnd )
				)
				( attribute "PHYS_PAGE" "253"
					( Origin gFrontEnd )
				)
				( attribute "ROT" "0"
					( Origin gFrontEnd )
				)
				( attribute "SEC" "1"
					( Origin gFrontEnd )
				)
				( attribute "SEC_TYPE" "SMD-BCG5"
					( Origin gFrontEnd )
				)
				( attribute "VALUE" "SC22U16V5MX-4-GP"
					( Origin gFrontEnd )
				)
				( attribute "VER" "1"
					( Origin gFrontEnd )
				)
				( attribute "XY" "(-3050,4375)"
					( Origin gFrontEnd )
				)
				( attribute "CHIPS_PART_NAME" "SC22U16V5MX-4-GP"
					( Origin gPackager )
				)
				( attribute "CDS_PART_NAME" "SC22U16V5MX-4-GP_SMD-BCG5-SC22A"
					( Origin gPackager )
				)
				( attribute "ATTRIBUTE" "22UF"
					( Origin gFrontEnd )
				)
				( attribute "PACK_SIZE" "0805"
					( Origin gFrontEnd )
				)
				( attribute "RATED" "16V"
					( Origin gFrontEnd )
				)
				( attribute "TOLERANCE" "20%"
					( Origin gFrontEnd )
				)
				( attribute "TYPE" "X6S"
					( Origin gFrontEnd )
				)
				( attribute "GROUP" "NO_KR"
					( Origin gFrontEnd )
				)
				( objectStatus "C30W8" )
			)
			( gate "@baseboard_fab2_lib.baseboard_fab2(sch_1):page253_i42"
				( attribute "CDS_LIB" "w_hdl"
					( Origin gPackager )
				)
				( attribute "CDS_LMAN_SYM_OUTLINE" "-50,25,50,-25"
					( Origin gPackager )
				)
				( attribute "CDS_LOCATION" "C30W7"
					( Origin gPackager )
				)
				( attribute "CDS_SEC" "1"
					( Origin gPackager )
				)
				( attribute "LOCATION" "C30W7"
					( Origin gFrontEnd )
				)
				( attribute "PACK_TYPE" "SMD-BCG5"
					( Origin gFrontEnd )
				)
				( attribute "PART_NUMBER" "078.22611.0811"
					( Origin gFrontEnd )
				)
				( attribute "PHYS_PAGE" "253"
					( Origin gFrontEnd )
				)
				( attribute "ROT" "0"
					( Origin gFrontEnd )
				)
				( attribute "SEC" "1"
					( Origin gFrontEnd )
				)
				( attribute "SEC_TYPE" "SMD-BCG5"
					( Origin gFrontEnd )
				)
				( attribute "VALUE" "SC22U16V5MX-4-GP"
					( Origin gFrontEnd )
				)
				( attribute "VER" "1"
					( Origin gFrontEnd )
				)
				( attribute "XY" "(-3350,4375)"
					( Origin gFrontEnd )
				)
				( attribute "CHIPS_PART_NAME" "SC22U16V5MX-4-GP"
					( Origin gPackager )
				)
				( attribute "CDS_PART_NAME" "SC22U16V5MX-4-GP_SMD-BCG5-SC22A"
					( Origin gPackager )
				)
				( attribute "ATTRIBUTE" "22UF"
					( Origin gFrontEnd )
				)
				( attribute "PACK_SIZE" "0805"
					( Origin gFrontEnd )
				)
				( attribute "RATED" "16V"
					( Origin gFrontEnd )
				)
				( attribute "TOLERANCE" "20%"
					( Origin gFrontEnd )
				)
				( attribute "TYPE" "X6S"
					( Origin gFrontEnd )
				)
				( attribute "GROUP" "NO_KR"
					( Origin gFrontEnd )
				)
				( objectStatus "C30W7" )
			)
			( gate "@baseboard_fab2_lib.baseboard_fab2(sch_1):page213_i103"
				( attribute "CDS_LIB" "mstr_discrete"
					( Origin gPackager )
				)
				( attribute "CDS_LOCATION" "R4E2"
					( Origin gPackager )
				)
				( attribute "CDS_SEC" "1"
					( Origin gPackager )
				)
				( attribute "LOCATION" "R4E2"
					( Origin gFrontEnd )
				)
				( attribute "MATERIAL" "CHIP"
					( Origin gFrontEnd )
				)
				( attribute "PACK_TYPE" "0402"
					( Origin gFrontEnd )
				)
				( attribute "PART_NUMBER" "G21796-043"
					( Origin gFrontEnd )
				)
				( attribute "PHYS_PAGE" "213"
					( Origin gFrontEnd )
				)
				( attribute "ROOM" "PVCCIN_CPU1_VR"
					( Origin gFrontEnd )
				)
				( attribute "ROT" "0"
					( Origin gFrontEnd )
				)
				( attribute "SEC" "1"
					( Origin gFrontEnd )
				)
				( attribute "SEC_TYPE" "0402"
					( Origin gFrontEnd )
				)
				( attribute "TOLERANCE" "1%"
					( Origin gFrontEnd )
				)
				( attribute "VALUE" "3.16K"
					( Origin gFrontEnd )
				)
				( attribute "VER" "2"
					( Origin gFrontEnd )
				)
				( attribute "WATTAGE" "1/16W"
					( Origin gFrontEnd )
				)
				( attribute "XY" "(-525,1175)"
					( Origin gFrontEnd )
				)
				( attribute "CHIPS_PART_NAME" "RES"
					( Origin gPackager )
				)
				( attribute "CDS_PART_NAME" "RES_0402-3.16K,1%,1/16W,CHIP,GA"
					( Origin gPackager )
				)
				( objectStatus "R4E2" )
			)
			( gate "@baseboard_fab2_lib.baseboard_fab2(sch_1):page90_i98"
				( attribute "BOM_COST" "PROC"
					( Origin gFrontEnd )
				)
				( attribute "CDS_LIB" "mstr_discrete"
					( Origin gPackager )
				)
				( attribute "CDS_LOCATION" "R4P1"
					( Origin gPackager )
				)
				( attribute "CDS_SEC" "1"
					( Origin gPackager )
				)
				( attribute "LOCATION" "R4P1"
					( Origin gFrontEnd )
				)
				( attribute "MATERIAL" "EMPTY"
					( Origin gFrontEnd )
				)
				( attribute "PACK_TYPE" "0402"
					( Origin gFrontEnd )
				)
				( attribute "PART_NUMBER" "G21796-294"
					( Origin gFrontEnd )
				)
				( attribute "PHYS_PAGE" "90"
					( Origin gFrontEnd )
				)
				( attribute "ROOM" "PROC_SIDEBAND"
					( Origin gFrontEnd )
				)
				( attribute "ROT" "0"
					( Origin gFrontEnd )
				)
				( attribute "SEC" "1"
					( Origin gFrontEnd )
				)
				( attribute "SEC_TYPE" "0402"
					( Origin gFrontEnd )
				)
				( attribute "TOLERANCE" "1.0%"
					( Origin gFrontEnd )
				)
				( attribute "VALUE" "240"
					( Origin gFrontEnd )
				)
				( attribute "VER" "1"
					( Origin gFrontEnd )
				)
				( attribute "WATTAGE" "1/16W"
					( Origin gFrontEnd )
				)
				( attribute "XY" "(-575,3200)"
					( Origin gFrontEnd )
				)
				( attribute "CHIPS_PART_NAME" "RES"
					( Origin gPackager )
				)
				( attribute "CDS_PART_NAME" "RES_0402-240,1.0%,1/16W,EMPTY,A"
					( Origin gPackager )
				)
				( objectStatus "R4P1" )
			)
			( gate "@baseboard_fab2_lib.baseboard_fab2(sch_1):page90_i99"
				( attribute "BOM_COST" "PROC"
					( Origin gFrontEnd )
				)
				( attribute "CDS_LIB" "mstr_discrete"
					( Origin gPackager )
				)
				( attribute "CDS_LOCATION" "R3D13"
					( Origin gPackager )
				)
				( attribute "CDS_SEC" "1"
					( Origin gPackager )
				)
				( attribute "LOCATION" "R3D13"
					( Origin gFrontEnd )
				)
				( attribute "MATERIAL" "EMPTY"
					( Origin gFrontEnd )
				)
				( attribute "PACK_TYPE" "0402"
					( Origin gFrontEnd )
				)
				( attribute "PART_NUMBER" "G21796-294"
					( Origin gFrontEnd )
				)
				( attribute "PHYS_PAGE" "90"
					( Origin gFrontEnd )
				)
				( attribute "ROOM" "PROC_SIDEBAND"
					( Origin gFrontEnd )
				)
				( attribute "ROT" "0"
					( Origin gFrontEnd )
				)
				( attribute "SEC" "1"
					( Origin gFrontEnd )
				)
				( attribute "SEC_TYPE" "0402"
					( Origin gFrontEnd )
				)
				( attribute "TOLERANCE" "1.0%"
					( Origin gFrontEnd )
				)
				( attribute "VALUE" "240"
					( Origin gFrontEnd )
				)
				( attribute "VER" "1"
					( Origin gFrontEnd )
				)
				( attribute "WATTAGE" "1/16W"
					( Origin gFrontEnd )
				)
				( attribute "XY" "(-425,1050)"
					( Origin gFrontEnd )
				)
				( attribute "CHIPS_PART_NAME" "RES"
					( Origin gPackager )
				)
				( attribute "CDS_PART_NAME" "RES_0402-240,1.0%,1/16W,EMPTY,A"
					( Origin gPackager )
				)
				( objectStatus "R3D13" )
			)
			( gate "@baseboard_fab2_lib.baseboard_fab2(sch_1):page164_i48"
				( attribute "BOM_COST" "SM_CONTROLLER"
					( Origin gFrontEnd )
				)
				( attribute "CDS_LIB" "mstr_discrete"
					( Origin gPackager )
				)
				( attribute "CDS_LOCATION" "R1U15"
					( Origin gPackager )
				)
				( attribute "CDS_SEC" "1"
					( Origin gPackager )
				)
				( attribute "LOCATION" "R1U15"
					( Origin gFrontEnd )
				)
				( attribute "MATERIAL" "CHIP"
					( Origin gFrontEnd )
				)
				( attribute "PACK_TYPE" "0402"
					( Origin gFrontEnd )
				)
				( attribute "PART_NUMBER" "G21796-026"
					( Origin gFrontEnd )
				)
				( attribute "PHYS_PAGE" "164"
					( Origin gFrontEnd )
				)
				( attribute "ROOM" "BMC_MISC"
					( Origin gFrontEnd )
				)
				( attribute "ROT" "0"
					( Origin gFrontEnd )
				)
				( attribute "SEC" "1"
					( Origin gFrontEnd )
				)
				( attribute "SEC_TYPE" "0402"
					( Origin gFrontEnd )
				)
				( attribute "TOLERANCE" "1%"
					( Origin gFrontEnd )
				)
				( attribute "VALUE" "1.00K"
					( Origin gFrontEnd )
				)
				( attribute "VER" "2"
					( Origin gFrontEnd )
				)
				( attribute "WATTAGE" "1/16W"
					( Origin gFrontEnd )
				)
				( attribute "XY" "(-6325,3350)"
					( Origin gFrontEnd )
				)
				( attribute "CHIPS_PART_NAME" "RES"
					( Origin gPackager )
				)
				( attribute "CDS_PART_NAME" "RES_0402-1.00K,1%,1/16W,CHIP,GA"
					( Origin gPackager )
				)
				( attribute "GROUP" "PD_SKU_ID3"
					( Origin gFrontEnd )
				)
				( objectStatus "R1U15" )
			)
			( gate "@baseboard_fab2_lib.baseboard_fab2(sch_1):page90_i101"
				( attribute "BOM_COST" "PROC"
					( Origin gFrontEnd )
				)
				( attribute "CDS_LIB" "mstr_discrete"
					( Origin gPackager )
				)
				( attribute "CDS_LOCATION" "R6D6"
					( Origin gPackager )
				)
				( attribute "CDS_SEC" "1"
					( Origin gPackager )
				)
				( attribute "LOCATION" "R6D6"
					( Origin gFrontEnd )
				)
				( attribute "MATERIAL" "EMPTY"
					( Origin gFrontEnd )
				)
				( attribute "PACK_TYPE" "0402"
					( Origin gFrontEnd )
				)
				( attribute "PART_NUMBER" "G21796-294"
					( Origin gFrontEnd )
				)
				( attribute "PHYS_PAGE" "90"
					( Origin gFrontEnd )
				)
				( attribute "ROOM" "PROC_SIDEBAND"
					( Origin gFrontEnd )
				)
				( attribute "ROT" "0"
					( Origin gFrontEnd )
				)
				( attribute "SEC" "1"
					( Origin gFrontEnd )
				)
				( attribute "SEC_TYPE" "0402"
					( Origin gFrontEnd )
				)
				( attribute "TOLERANCE" "1.0%"
					( Origin gFrontEnd )
				)
				( attribute "VALUE" "240"
					( Origin gFrontEnd )
				)
				( attribute "VER" "1"
					( Origin gFrontEnd )
				)
				( attribute "WATTAGE" "1/16W"
					( Origin gFrontEnd )
				)
				( attribute "XY" "(-575,3400)"
					( Origin gFrontEnd )
				)
				( attribute "CHIPS_PART_NAME" "RES"
					( Origin gPackager )
				)
				( attribute "CDS_PART_NAME" "RES_0402-240,1.0%,1/16W,EMPTY,A"
					( Origin gPackager )
				)
				( objectStatus "R6D6" )
			)
			( gate "@baseboard_fab2_lib.baseboard_fab2(sch_1):page90_i102"
				( attribute "BOM_COST" "PROC"
					( Origin gFrontEnd )
				)
				( attribute "CDS_LIB" "mstr_discrete"
					( Origin gPackager )
				)
				( attribute "CDS_LOCATION" "R3D12"
					( Origin gPackager )
				)
				( attribute "CDS_SEC" "1"
					( Origin gPackager )
				)
				( attribute "LOCATION" "R3D12"
					( Origin gFrontEnd )
				)
				( attribute "MATERIAL" "EMPTY"
					( Origin gFrontEnd )
				)
				( attribute "PACK_TYPE" "0402"
					( Origin gFrontEnd )
				)
				( attribute "PART_NUMBER" "G21796-294"
					( Origin gFrontEnd )
				)
				( attribute "PHYS_PAGE" "90"
					( Origin gFrontEnd )
				)
				( attribute "ROOM" "PROC_SIDEBAND"
					( Origin gFrontEnd )
				)
				( attribute "ROT" "0"
					( Origin gFrontEnd )
				)
				( attribute "SEC" "1"
					( Origin gFrontEnd )
				)
				( attribute "SEC_TYPE" "0402"
					( Origin gFrontEnd )
				)
				( attribute "TOLERANCE" "1.0%"
					( Origin gFrontEnd )
				)
				( attribute "VALUE" "240"
					( Origin gFrontEnd )
				)
				( attribute "VER" "1"
					( Origin gFrontEnd )
				)
				( attribute "WATTAGE" "1/16W"
					( Origin gFrontEnd )
				)
				( attribute "XY" "(-425,1275)"
					( Origin gFrontEnd )
				)
				( attribute "CHIPS_PART_NAME" "RES"
					( Origin gPackager )
				)
				( attribute "CDS_PART_NAME" "RES_0402-240,1.0%,1/16W,EMPTY,A"
					( Origin gPackager )
				)
				( objectStatus "R3D12" )
			)
			( gate "@baseboard_fab2_lib.baseboard_fab2(sch_1):page125_i89"
				( attribute "BOM_COST" "SB"
					( Origin gFrontEnd )
				)
				( attribute "CDS_LIB" "mstr_discrete"
					( Origin gPackager )
				)
				( attribute "CDS_LOCATION" "R2T1"
					( Origin gPackager )
				)
				( attribute "CDS_SEC" "1"
					( Origin gPackager )
				)
				( attribute "LOCATION" "R2T1"
					( Origin gFrontEnd )
				)
				( attribute "MATERIAL" "EMPTY"
					( Origin gFrontEnd )
				)
				( attribute "PACK_TYPE" "0402"
					( Origin gFrontEnd )
				)
				( attribute "PART_NUMBER" "G21796-026"
					( Origin gFrontEnd )
				)
				( attribute "PHYS_PAGE" "125"
					( Origin gFrontEnd )
				)
				( attribute "ROOM" "SB"
					( Origin gFrontEnd )
				)
				( attribute "ROT" "0"
					( Origin gFrontEnd )
				)
				( attribute "SEC" "1"
					( Origin gFrontEnd )
				)
				( attribute "SEC_TYPE" "0402"
					( Origin gFrontEnd )
				)
				( attribute "TOLERANCE" "1%"
					( Origin gFrontEnd )
				)
				( attribute "VALUE" "1.00K"
					( Origin gFrontEnd )
				)
				( attribute "VER" "2"
					( Origin gFrontEnd )
				)
				( attribute "WATTAGE" "1/16W"
					( Origin gFrontEnd )
				)
				( attribute "XY" "(1850,1475)"
					( Origin gFrontEnd )
				)
				( attribute "CHIPS_PART_NAME" "RES"
					( Origin gPackager )
				)
				( attribute "CDS_PART_NAME" "RES_0402-1.00K,1%,1/16W,EMPTY,A"
					( Origin gPackager )
				)
				( objectStatus "R2T1" )
			)
			( gate "@baseboard_fab2_lib.baseboard_fab2(sch_1):page239_i100"
				( attribute "BOM_COST" "PROC_SIDEBAND"
					( Origin gFrontEnd )
				)
				( attribute "CDS_LIB" "mstr_discrete"
					( Origin gPackager )
				)
				( attribute "CDS_LOCATION" "R9F32"
					( Origin gPackager )
				)
				( attribute "CDS_SEC" "1"
					( Origin gPackager )
				)
				( attribute "LOCATION" "R9F32"
					( Origin gFrontEnd )
				)
				( attribute "MATERIAL" "CHIP"
					( Origin gFrontEnd )
				)
				( attribute "PACK_TYPE" "0402"
					( Origin gFrontEnd )
				)
				( attribute "PART_NUMBER" "G21796-016"
					( Origin gFrontEnd )
				)
				( attribute "PHYS_PAGE" "239"
					( Origin gFrontEnd )
				)
				( attribute "ROOM" "CPU0"
					( Origin gFrontEnd )
				)
				( attribute "ROT" "0"
					( Origin gFrontEnd )
				)
				( attribute "SEC" "1"
					( Origin gFrontEnd )
				)
				( attribute "SEC_TYPE" "0402"
					( Origin gFrontEnd )
				)
				( attribute "TOLERANCE" "1%"
					( Origin gFrontEnd )
				)
				( attribute "VALUE" "10.0K"
					( Origin gFrontEnd )
				)
				( attribute "VER" "2"
					( Origin gFrontEnd )
				)
				( attribute "WATTAGE" "1/16W"
					( Origin gFrontEnd )
				)
				( attribute "XY" "(10350,3075)"
					( Origin gFrontEnd )
				)
				( attribute "CHIPS_PART_NAME" "RES"
					( Origin gPackager )
				)
				( attribute "CDS_PART_NAME" "RES_0402-10.0K,1%,1/16W,CHIP,GA"
					( Origin gPackager )
				)
				( objectStatus "R9F32" )
			)
			( gate "@baseboard_fab2_lib.baseboard_fab2(sch_1):page239_i101"
				( attribute "BOM_COST" "PROC_SIDEBAND"
					( Origin gFrontEnd )
				)
				( attribute "CDS_LIB" "mstr_discrete"
					( Origin gPackager )
				)
				( attribute "CDS_LOCATION" "R9W32"
					( Origin gPackager )
				)
				( attribute "CDS_SEC" "1"
					( Origin gPackager )
				)
				( attribute "LOCATION" "R9W32"
					( Origin gFrontEnd )
				)
				( attribute "MATERIAL" "CHIP"
					( Origin gFrontEnd )
				)
				( attribute "PACK_TYPE" "0402"
					( Origin gFrontEnd )
				)
				( attribute "PART_NUMBER" "G21796-016"
					( Origin gFrontEnd )
				)
				( attribute "PHYS_PAGE" "239"
					( Origin gFrontEnd )
				)
				( attribute "ROOM" "CPU0"
					( Origin gFrontEnd )
				)
				( attribute "ROT" "0"
					( Origin gFrontEnd )
				)
				( attribute "SEC" "1"
					( Origin gFrontEnd )
				)
				( attribute "SEC_TYPE" "0402"
					( Origin gFrontEnd )
				)
				( attribute "TOLERANCE" "1%"
					( Origin gFrontEnd )
				)
				( attribute "VALUE" "10.0K"
					( Origin gFrontEnd )
				)
				( attribute "VER" "2"
					( Origin gFrontEnd )
				)
				( attribute "WATTAGE" "1/16W"
					( Origin gFrontEnd )
				)
				( attribute "XY" "(9925,800)"
					( Origin gFrontEnd )
				)
				( attribute "CHIPS_PART_NAME" "RES"
					( Origin gPackager )
				)
				( attribute "CDS_PART_NAME" "RES_0402-10.0K,1%,1/16W,CHIP,GA"
					( Origin gPackager )
				)
				( objectStatus "R9W32" )
			)
			( gate "@baseboard_fab2_lib.baseboard_fab2(sch_1):page215_i72"
				( attribute "BOM_COST" "SM_CONTROLLER"
					( Origin gFrontEnd )
				)
				( attribute "CDS_LIB" "mstr_discrete"
					( Origin gPackager )
				)
				( attribute "CDS_LOCATION" "R7G8"
					( Origin gPackager )
				)
				( attribute "CDS_SEC" "1"
					( Origin gPackager )
				)
				( attribute "LOCATION" "R7G8"
					( Origin gFrontEnd )
				)
				( attribute "MATERIAL" "CHIP"
					( Origin gFrontEnd )
				)
				( attribute "PACK_TYPE" "0402"
					( Origin gFrontEnd )
				)
				( attribute "PART_NUMBER" "G21796-311"
					( Origin gFrontEnd )
				)
				( attribute "PHYS_PAGE" "215"
					( Origin gFrontEnd )
				)
				( attribute "ROOM" "SMBUS"
					( Origin gFrontEnd )
				)
				( attribute "ROT" "0"
					( Origin gFrontEnd )
				)
				( attribute "SEC" "1"
					( Origin gFrontEnd )
				)
				( attribute "SEC_TYPE" "0402"
					( Origin gFrontEnd )
				)
				( attribute "SKU" "B"
					( Origin gFrontEnd )
				)
				( attribute "TOLERANCE" "1.0%"
					( Origin gFrontEnd )
				)
				( attribute "VALUE" "2.26K"
					( Origin gFrontEnd )
				)
				( attribute "VER" "2"
					( Origin gFrontEnd )
				)
				( attribute "WATTAGE" "1/16W"
					( Origin gFrontEnd )
				)
				( attribute "XY" "(1050,-50)"
					( Origin gFrontEnd )
				)
				( attribute "CHIPS_PART_NAME" "RES"
					( Origin gPackager )
				)
				( attribute "CDS_PART_NAME" "RES_0402-2.26K,1.0%,1/16W,CHIPA"
					( Origin gPackager )
				)
				( attribute "POP" "NOPOP"
					( Origin gFrontEnd )
				)
				( objectStatus "R7G8" )
			)
			( gate "@baseboard_fab2_lib.baseboard_fab2(sch_1):page235_i253"
				( attribute "CDS_LIB" "mstr_discrete"
					( Origin gPackager )
				)
				( attribute "LOCATION" "R2L26"
					( Origin gFrontEnd )
				)
				( attribute "MATERIAL" "CHIP"
					( Origin gFrontEnd )
				)
				( attribute "PACK_TYPE" "0402"
					( Origin gFrontEnd )
				)
				( attribute "PART_NUMBER" "G21796-010"
					( Origin gFrontEnd )
				)
				( attribute "PHYS_PAGE" "235"
					( Origin gFrontEnd )
				)
				( attribute "ROOM" "SB"
					( Origin gFrontEnd )
				)
				( attribute "ROT" "0"
					( Origin gFrontEnd )
				)
				( attribute "SEC" "1"
					( Origin gFrontEnd )
				)
				( attribute "SEC_TYPE" "0402"
					( Origin gFrontEnd )
				)
				( attribute "TOLERANCE" "1%"
					( Origin gFrontEnd )
				)
				( attribute "VALUE" "100.0K"
					( Origin gFrontEnd )
				)
				( attribute "VER" "2"
					( Origin gFrontEnd )
				)
				( attribute "WATTAGE" "1/16W"
					( Origin gFrontEnd )
				)
				( attribute "XY" "(-7350,4950)"
					( Origin gFrontEnd )
				)
				( attribute "CHIPS_PART_NAME" "RES"
					( Origin gPackager )
				)
				( attribute "CDS_PART_NAME" "RES_0402-100.0K,1%,1/16W,CHIP,A"
					( Origin gPackager )
				)
				( attribute "CDS_LOCATION" "R2L26"
					( Origin gPackager )
				)
				( attribute "CDS_SEC" "1"
					( Origin gPackager )
				)
				( objectStatus "R2L26" )
			)
			( gate "@baseboard_fab2_lib.baseboard_fab2(sch_1):page231_i230"
				( attribute "BOM_COST" "IO_SLOT"
					( Origin gFrontEnd )
				)
				( attribute "CDS_LIB" "mstr_discrete"
					( Origin gPackager )
				)
				( attribute "CDS_LOCATION" "R7F11"
					( Origin gPackager )
				)
				( attribute "CDS_SEC" "1"
					( Origin gPackager )
				)
				( attribute "LOCATION" "R7F11"
					( Origin gFrontEnd )
				)
				( attribute "MATERIAL" "CHIP"
					( Origin gFrontEnd )
				)
				( attribute "PACK_TYPE" "0402"
					( Origin gFrontEnd )
				)
				( attribute "PART_NUMBER" "G21796-161"
					( Origin gFrontEnd )
				)
				( attribute "PHYS_PAGE" "231"
					( Origin gFrontEnd )
				)
				( attribute "ROOM" "IO_SLOT"
					( Origin gFrontEnd )
				)
				( attribute "ROT" "0"
					( Origin gFrontEnd )
				)
				( attribute "SEC" "1"
					( Origin gFrontEnd )
				)
				( attribute "SEC_TYPE" "0402"
					( Origin gFrontEnd )
				)
				( attribute "TOLERANCE" "1%"
					( Origin gFrontEnd )
				)
				( attribute "VALUE" "6.19K"
					( Origin gFrontEnd )
				)
				( attribute "VER" "2"
					( Origin gFrontEnd )
				)
				( attribute "WATTAGE" "1/16W"
					( Origin gFrontEnd )
				)
				( attribute "XY" "(-1000,1550)"
					( Origin gFrontEnd )
				)
				( attribute "CHIPS_PART_NAME" "RES"
					( Origin gPackager )
				)
				( attribute "CDS_PART_NAME" "RES_0402-6.19K,1%,1/16W,CHIP,GA"
					( Origin gPackager )
				)
				( objectStatus "R7F11" )
			)
			( gate "@baseboard_fab2_lib.baseboard_fab2(sch_1):page176_i148"
				( attribute "BOM_COST" "SB"
					( Origin gFrontEnd )
				)
				( attribute "CDS_LIB" "mstr_ttl"
					( Origin gPackager )
				)
				( attribute "CDS_LOCATION" "U6W5"
					( Origin gPackager )
				)
				( attribute "CDS_SEC" "1"
					( Origin gPackager )
				)
				( attribute "LOCATION" "U6W5"
					( Origin gFrontEnd )
				)
				( attribute "MATERIAL" "IC"
					( Origin gFrontEnd )
				)
				( attribute "PACK_TYPE" "SOT"
					( Origin gFrontEnd )
				)
				( attribute "PART_NUMBER" "A79322-001"
					( Origin gFrontEnd )
				)
				( attribute "PHYS_PAGE" "176"
					( Origin gFrontEnd )
				)
				( attribute "ROOM" "SB"
					( Origin gFrontEnd )
				)
				( attribute "ROT" "6"
					( Origin gFrontEnd )
				)
				( attribute "SEC" "1"
					( Origin gFrontEnd )
				)
				( attribute "SEC_TYPE" "SOT"
					( Origin gFrontEnd )
				)
				( attribute "VALUE" "74HC1G126"
					( Origin gFrontEnd )
				)
				( attribute "VER" "1"
					( Origin gFrontEnd )
				)
				( attribute "XY" "(-1550,3150)"
					( Origin gFrontEnd )
				)
				( attribute "CHIPS_PART_NAME" "TTL1G126_A"
					( Origin gPackager )
				)
				( attribute "CDS_PART_NAME" "TTL1G126_A_SOT-74HC1G126,IC,A7B"
					( Origin gPackager )
				)
				( objectStatus "U6W5" )
			)
			( gate "@baseboard_fab2_lib.baseboard_fab2(sch_1):page150_i240"
				( attribute "BOM_COST" "NT_GBE_BASE"
					( Origin gFrontEnd )
				)
				( attribute "CDS_LIB" "mstr_discrete"
					( Origin gPackager )
				)
				( attribute "CDS_LOCATION" "R25W156"
					( Origin gPackager )
				)
				( attribute "CDS_SEC" "1"
					( Origin gPackager )
				)
				( attribute "LOCATION" "R25W156"
					( Origin gFrontEnd )
				)
				( attribute "MATERIAL" "EMPTY"
					( Origin gFrontEnd )
				)
				( attribute "PACK_TYPE" "0402"
					( Origin gFrontEnd )
				)
				( attribute "PART_NUMBER" "G21796-027"
					( Origin gFrontEnd )
				)
				( attribute "PHYS_PAGE" "150"
					( Origin gFrontEnd )
				)
				( attribute "ROOM" "NIC_SPRV"
					( Origin gFrontEnd )
				)
				( attribute "ROT" "1"
					( Origin gFrontEnd )
				)
				( attribute "SEC" "1"
					( Origin gFrontEnd )
				)
				( attribute "SEC_TYPE" "0402"
					( Origin gFrontEnd )
				)
				( attribute "TOLERANCE" "1%"
					( Origin gFrontEnd )
				)
				( attribute "VALUE" "3.32K"
					( Origin gFrontEnd )
				)
				( attribute "VER" "2"
					( Origin gFrontEnd )
				)
				( attribute "WATTAGE" "1/16W"
					( Origin gFrontEnd )
				)
				( attribute "XY" "(-600,-650)"
					( Origin gFrontEnd )
				)
				( attribute "CHIPS_PART_NAME" "RES"
					( Origin gPackager )
				)
				( attribute "CDS_PART_NAME" "RES_0402-3.32K,1%,1/16W,EMPTY,A"
					( Origin gPackager )
				)
				( objectStatus "R25W156" )
			)
			( gate "@baseboard_fab2_lib.baseboard_fab2(sch_1):page137_i149"
				( attribute "BOM_COST" "SM_THERM"
					( Origin gFrontEnd )
				)
				( attribute "CDS_LIB" "mstr_discrete"
					( Origin gPackager )
				)
				( attribute "CDS_LOCATION" "R6W1"
					( Origin gPackager )
				)
				( attribute "CDS_SEC" "1"
					( Origin gPackager )
				)
				( attribute "LOCATION" "R6W1"
					( Origin gFrontEnd )
				)
				( attribute "MATERIAL" "CHIP"
					( Origin gFrontEnd )
				)
				( attribute "PACK_TYPE" "0402"
					( Origin gFrontEnd )
				)
				( attribute "PART_NUMBER" "G21796-072"
					( Origin gFrontEnd )
				)
				( attribute "PHYS_PAGE" "137"
					( Origin gFrontEnd )
				)
				( attribute "ROOM" "CPU_FANS"
					( Origin gFrontEnd )
				)
				( attribute "ROT" "0"
					( Origin gFrontEnd )
				)
				( attribute "SEC" "1"
					( Origin gFrontEnd )
				)
				( attribute "SEC_TYPE" "0402"
					( Origin gFrontEnd )
				)
				( attribute "TOLERANCE" "1%"
					( Origin gFrontEnd )
				)
				( attribute "VALUE" "4.75K"
					( Origin gFrontEnd )
				)
				( attribute "VER" "2"
					( Origin gFrontEnd )
				)
				( attribute "WATTAGE" "1/16W"
					( Origin gFrontEnd )
				)
				( attribute "XY" "(-4500,3975)"
					( Origin gFrontEnd )
				)
				( attribute "CHIPS_PART_NAME" "RES"
					( Origin gPackager )
				)
				( attribute "CDS_PART_NAME" "RES_0402-4.75K,1%,1/16W,CHIP,GA"
					( Origin gPackager )
				)
				( objectStatus "R6W1" )
			)
			( gate "@baseboard_fab2_lib.baseboard_fab2(sch_1):page176_i142"
				( attribute "BOM_COST" "PROC_SIDEBAND"
					( Origin gFrontEnd )
				)
				( attribute "CDS_LIB" "mstr_discrete"
					( Origin gPackager )
				)
				( attribute "CDS_LOCATION" "R1W33"
					( Origin gPackager )
				)
				( attribute "CDS_SEC" "1"
					( Origin gPackager )
				)
				( attribute "LOCATION" "R1W33"
					( Origin gFrontEnd )
				)
				( attribute "MATERIAL" "CHIP"
					( Origin gFrontEnd )
				)
				( attribute "PACK_TYPE" "0402"
					( Origin gFrontEnd )
				)
				( attribute "PART_NUMBER" "G21497-005"
					( Origin gFrontEnd )
				)
				( attribute "PHYS_PAGE" "176"
					( Origin gFrontEnd )
				)
				( attribute "ROOM" "CPU0"
					( Origin gFrontEnd )
				)
				( attribute "ROT" "0"
					( Origin gFrontEnd )
				)
				( attribute "SEC" "1"
					( Origin gFrontEnd )
				)
				( attribute "SEC_TYPE" "0402"
					( Origin gFrontEnd )
				)
				( attribute "TOLERANCE" "5%"
					( Origin gFrontEnd )
				)
				( attribute "VALUE" "0.0"
					( Origin gFrontEnd )
				)
				( attribute "VER" "1"
					( Origin gFrontEnd )
				)
				( attribute "WATTAGE" "1/16W"
					( Origin gFrontEnd )
				)
				( attribute "XY" "(-1350,3900)"
					( Origin gFrontEnd )
				)
				( attribute "CHIPS_PART_NAME" "RES"
					( Origin gPackager )
				)
				( attribute "CDS_PART_NAME" "RES_0402-0.0,5%,1/16W,CHIP,G21A"
					( Origin gPackager )
				)
				( objectStatus "R1W33" )
			)
			( gate "@baseboard_fab2_lib.baseboard_fab2(sch_1):page176_i143"
				( attribute "BOM_COST" "PROC_SIDEBAND"
					( Origin gFrontEnd )
				)
				( attribute "CDS_LIB" "mstr_discrete"
					( Origin gPackager )
				)
				( attribute "CDS_LOCATION" "R1W34"
					( Origin gPackager )
				)
				( attribute "CDS_SEC" "1"
					( Origin gPackager )
				)
				( attribute "LOCATION" "R1W34"
					( Origin gFrontEnd )
				)
				( attribute "MATERIAL" "CHIP"
					( Origin gFrontEnd )
				)
				( attribute "PACK_TYPE" "0402"
					( Origin gFrontEnd )
				)
				( attribute "PART_NUMBER" "G21497-005"
					( Origin gFrontEnd )
				)
				( attribute "PHYS_PAGE" "176"
					( Origin gFrontEnd )
				)
				( attribute "ROOM" "CPU0"
					( Origin gFrontEnd )
				)
				( attribute "ROT" "0"
					( Origin gFrontEnd )
				)
				( attribute "SEC" "1"
					( Origin gFrontEnd )
				)
				( attribute "SEC_TYPE" "0402"
					( Origin gFrontEnd )
				)
				( attribute "TOLERANCE" "5%"
					( Origin gFrontEnd )
				)
				( attribute "VALUE" "0.0"
					( Origin gFrontEnd )
				)
				( attribute "VER" "1"
					( Origin gFrontEnd )
				)
				( attribute "WATTAGE" "1/16W"
					( Origin gFrontEnd )
				)
				( attribute "XY" "(-1350,3850)"
					( Origin gFrontEnd )
				)
				( attribute "CHIPS_PART_NAME" "RES"
					( Origin gPackager )
				)
				( attribute "CDS_PART_NAME" "RES_0402-0.0,5%,1/16W,CHIP,G21A"
					( Origin gPackager )
				)
				( objectStatus "R1W34" )
			)
			( gate "@baseboard_fab2_lib.baseboard_fab2(sch_1):page176_i146"
				( attribute "BOM_COST" "SB"
					( Origin gFrontEnd )
				)
				( attribute "CDS_LIB" "mstr_ttl"
					( Origin gPackager )
				)
				( attribute "CDS_LOCATION" "U6W4"
					( Origin gPackager )
				)
				( attribute "CDS_SEC" "1"
					( Origin gPackager )
				)
				( attribute "LOCATION" "U6W4"
					( Origin gFrontEnd )
				)
				( attribute "MATERIAL" "IC"
					( Origin gFrontEnd )
				)
				( attribute "PACK_TYPE" "SOT"
					( Origin gFrontEnd )
				)
				( attribute "PART_NUMBER" "A79322-001"
					( Origin gFrontEnd )
				)
				( attribute "PHYS_PAGE" "176"
					( Origin gFrontEnd )
				)
				( attribute "ROOM" "SB"
					( Origin gFrontEnd )
				)
				( attribute "ROT" "6"
					( Origin gFrontEnd )
				)
				( attribute "SEC" "1"
					( Origin gFrontEnd )
				)
				( attribute "SEC_TYPE" "SOT"
					( Origin gFrontEnd )
				)
				( attribute "VALUE" "74HC1G126"
					( Origin gFrontEnd )
				)
				( attribute "VER" "1"
					( Origin gFrontEnd )
				)
				( attribute "XY" "(-2500,1400)"
					( Origin gFrontEnd )
				)
				( attribute "CHIPS_PART_NAME" "TTL1G126_A"
					( Origin gPackager )
				)
				( attribute "CDS_PART_NAME" "TTL1G126_A_SOT-74HC1G126,IC,A7B"
					( Origin gPackager )
				)
				( objectStatus "U6W4" )
			)
			( gate "@baseboard_fab2_lib.baseboard_fab2(sch_1):page176_i147"
				( attribute "BOM_COST" "PROC_SOCKET"
					( Origin gFrontEnd )
				)
				( attribute "CDS_LIB" "mstr_discrete"
					( Origin gPackager )
				)
				( attribute "CDS_LOCATION" "R6W30"
					( Origin gPackager )
				)
				( attribute "CDS_SEC" "1"
					( Origin gPackager )
				)
				( attribute "LOCATION" "R6W30"
					( Origin gFrontEnd )
				)
				( attribute "MATERIAL" "CHIP"
					( Origin gFrontEnd )
				)
				( attribute "PACK_TYPE" "0603"
					( Origin gFrontEnd )
				)
				( attribute "PART_NUMBER" "G22026-050"
					( Origin gFrontEnd )
				)
				( attribute "PHYS_PAGE" "176"
					( Origin gFrontEnd )
				)
				( attribute "ROOM" "CPU0"
					( Origin gFrontEnd )
				)
				( attribute "ROT" "0"
					( Origin gFrontEnd )
				)
				( attribute "SEC" "1"
					( Origin gFrontEnd )
				)
				( attribute "SEC_TYPE" "0603"
					( Origin gFrontEnd )
				)
				( attribute "TOLERANCE" "1%"
					( Origin gFrontEnd )
				)
				( attribute "VALUE" "100.0K"
					( Origin gFrontEnd )
				)
				( attribute "VER" "2"
					( Origin gFrontEnd )
				)
				( attribute "WATTAGE" "1/10W"
					( Origin gFrontEnd )
				)
				( attribute "XY" "(-1550,1600)"
					( Origin gFrontEnd )
				)
				( attribute "CHIPS_PART_NAME" "RES"
					( Origin gPackager )
				)
				( attribute "CDS_PART_NAME" "RES_0603-100.0K,1%,1/10W,CHIP,A"
					( Origin gPackager )
				)
				( objectStatus "R6W30" )
			)
			( gate "@baseboard_fab2_lib.baseboard_fab2(sch_1):page176_i157"
				( attribute "BOM_COST" "SB"
					( Origin gFrontEnd )
				)
				( attribute "CDS_LIB" "mstr_ttl"
					( Origin gPackager )
				)
				( attribute "CDS_LOCATION" "U6W6"
					( Origin gPackager )
				)
				( attribute "CDS_SEC" "1"
					( Origin gPackager )
				)
				( attribute "LOCATION" "U6W6"
					( Origin gFrontEnd )
				)
				( attribute "MATERIAL" "IC"
					( Origin gFrontEnd )
				)
				( attribute "PACK_TYPE" "SOT"
					( Origin gFrontEnd )
				)
				( attribute "PART_NUMBER" "A79322-001"
					( Origin gFrontEnd )
				)
				( attribute "PHYS_PAGE" "176"
					( Origin gFrontEnd )
				)
				( attribute "ROOM" "SB"
					( Origin gFrontEnd )
				)
				( attribute "ROT" "6"
					( Origin gFrontEnd )
				)
				( attribute "SEC" "1"
					( Origin gFrontEnd )
				)
				( attribute "SEC_TYPE" "SOT"
					( Origin gFrontEnd )
				)
				( attribute "VALUE" "74HC1G126"
					( Origin gFrontEnd )
				)
				( attribute "VER" "1"
					( Origin gFrontEnd )
				)
				( attribute "XY" "(-1550,2600)"
					( Origin gFrontEnd )
				)
				( attribute "CHIPS_PART_NAME" "TTL1G126_A"
					( Origin gPackager )
				)
				( attribute "CDS_PART_NAME" "TTL1G126_A_SOT-74HC1G126,IC,A7B"
					( Origin gPackager )
				)
				( objectStatus "U6W6" )
			)
			( gate "@baseboard_fab2_lib.baseboard_fab2(sch_1):page176_i152"
				( attribute "CHIPS_PART_NAME" "TTL1G07_A"
					( Origin gPackager )
				)
			)
			( gate "@baseboard_fab2_lib.baseboard_fab2(sch_1):page222_i41"
				( attribute "CDS_LIB" "dev_discrete"
					( Origin gPackager )
				)
				( attribute "CDS_LOCATION" "C5M13"
					( Origin gPackager )
				)
				( attribute "CDS_SEC" "1"
					( Origin gPackager )
				)
				( attribute "LOCATION" "C5M13"
					( Origin gFrontEnd )
				)
				( attribute "MATERIAL" "X5R"
					( Origin gFrontEnd )
				)
				( attribute "PACK_TYPE" "0603V"
					( Origin gFrontEnd )
				)
				( attribute "PART_NUMBER" "602433-106"
					( Origin gFrontEnd )
				)
				( attribute "PHYS_PAGE" "222"
					( Origin gFrontEnd )
				)
				( attribute "ROT" "0"
					( Origin gFrontEnd )
				)
				( attribute "SEC" "1"
					( Origin gFrontEnd )
				)
				( attribute "SEC_TYPE" "0603V"
					( Origin gFrontEnd )
				)
				( attribute "TOLERANCE" "20%"
					( Origin gFrontEnd )
				)
				( attribute "VALUE" "47UF"
					( Origin gFrontEnd )
				)
				( attribute "VER" "1"
					( Origin gFrontEnd )
				)
				( attribute "VOLTAGE" "4V"
					( Units "uVoltage" "V" 1.000000)
					( Origin gFrontEnd )
				)
				( attribute "XY" "(3500,2825)"
					( Origin gFrontEnd )
				)
				( attribute "CHIPS_PART_NAME" "CAP_A"
					( Origin gPackager )
				)
				( attribute "CDS_PART_NAME" "CAP_A_0603V-47UF,4V,20%,X5R,60A"
					( Origin gPackager )
				)
				( attribute "GROUP" "PWR_MLCC_CAP"
					( Origin gFrontEnd )
				)
				( objectStatus "C5M13" )
			)
			( gate "@baseboard_fab2_lib.baseboard_fab2(sch_1):page230_i42"
				( attribute "BOM_COST" "MEM_VRD_PVDDQ_CD"
					( Origin gFrontEnd )
				)
				( attribute "CDS_LIB" "mstr_discrete"
					( Origin gPackager )
				)
				( attribute "CDS_LOCATION" "C8L4"
					( Origin gPackager )
				)
				( attribute "CDS_SEC" "1"
					( Origin gPackager )
				)
				( attribute "LOCATION" "C8L4"
					( Origin gFrontEnd )
				)
				( attribute "MATERIAL" "X5R"
					( Origin gFrontEnd )
				)
				( attribute "NEW_MATERIAL" "X6S"
					( Origin gFrontEnd )
				)
				( attribute "PACK_TYPE" "0805"
					( Origin gFrontEnd )
				)
				( attribute "PART_NUMBER" "602433-112"
					( Origin gFrontEnd )
				)
				( attribute "PHYS_PAGE" "230"
					( Origin gFrontEnd )
				)
				( attribute "ROOM" "VDDQ_ABC_PWR_VR"
					( Origin gFrontEnd )
				)
				( attribute "ROT" "0"
					( Origin gFrontEnd )
				)
				( attribute "SEC" "1"
					( Origin gFrontEnd )
				)
				( attribute "SEC_TYPE" "0805"
					( Origin gFrontEnd )
				)
				( attribute "TOLERANCE" "20%"
					( Origin gFrontEnd )
				)
				( attribute "VALUE" "100UF"
					( Origin gFrontEnd )
				)
				( attribute "VER" "1"
					( Origin gFrontEnd )
				)
				( attribute "VOLTAGE" "4V"
					( Units "uVoltage" "V" 1.000000)
					( Origin gFrontEnd )
				)
				( attribute "XY" "(2150,2675)"
					( Origin gFrontEnd )
				)
				( attribute "CHIPS_PART_NAME" "CAP"
					( Origin gPackager )
				)
				( attribute "CDS_PART_NAME" "CAP_0805-100UF,4V,20%,X5R,6024A"
					( Origin gPackager )
				)
				( attribute "GROUP" "PWR_MLCC_CAP"
					( Origin gFrontEnd )
				)
				( attribute "NEW_PN" "078.1071T.M002"
					( Origin gFrontEnd )
				)
				( objectStatus "C8L4" )
			)
			( gate "@baseboard_fab2_lib.baseboard_fab2(sch_1):page155_i198"
				( attribute "BOM_COST" "SB"
					( Origin gFrontEnd )
				)
				( attribute "CDS_LIB" "mstr_discrete"
					( Origin gPackager )
				)
				( attribute "CDS_LOCATION" "R9A5"
					( Origin gPackager )
				)
				( attribute "CDS_SEC" "1"
					( Origin gPackager )
				)
				( attribute "LOCATION" "R9A5"
					( Origin gFrontEnd )
				)
				( attribute "MATERIAL" "CHIP"
					( Origin gFrontEnd )
				)
				( attribute "PACK_TYPE" "0402"
					( Origin gFrontEnd )
				)
				( attribute "PART_NUMBER" "G21796-040"
					( Origin gFrontEnd )
				)
				( attribute "PHYS_PAGE" "155"
					( Origin gFrontEnd )
				)
				( attribute "ROOM" "SB"
					( Origin gFrontEnd )
				)
				( attribute "ROT" "0"
					( Origin gFrontEnd )
				)
				( attribute "SEC" "1"
					( Origin gFrontEnd )
				)
				( attribute "SEC_TYPE" "0402"
					( Origin gFrontEnd )
				)
				( attribute "TOLERANCE" "1%"
					( Origin gFrontEnd )
				)
				( attribute "VALUE" "20.0K"
					( Origin gFrontEnd )
				)
				( attribute "VER" "2"
					( Origin gFrontEnd )
				)
				( attribute "WATTAGE" "1/16W"
					( Origin gFrontEnd )
				)
				( attribute "XY" "(-3350,1050)"
					( Origin gFrontEnd )
				)
				( attribute "CHIPS_PART_NAME" "RES"
					( Origin gPackager )
				)
				( attribute "CDS_PART_NAME" "RES_0402-20.0K,1%,1/16W,CHIP,GA"
					( Origin gPackager )
				)
				( objectStatus "R9A5" )
			)
			( gate "@baseboard_fab2_lib.baseboard_fab2(sch_1):page247_i157"
				( attribute "CDS_LIB" "mstr_discrete"
					( Origin gPackager )
				)
				( attribute "CDS_LOCATION" "CR6W1"
					( Origin gPackager )
				)
				( attribute "CDS_SEC" "1"
					( Origin gPackager )
				)
				( attribute "LOCATION" "CR6W1"
					( Origin gFrontEnd )
				)
				( attribute "MATERIAL" "IC"
					( Origin gFrontEnd )
				)
				( attribute "PACK_TYPE" "SMLF"
					( Origin gFrontEnd )
				)
				( attribute "PART_NUMBER" "C73510-001"
					( Origin gFrontEnd )
				)
				( attribute "PHYS_PAGE" "247"
					( Origin gFrontEnd )
				)
				( attribute "ROT" "6"
					( Origin gFrontEnd )
				)
				( attribute "SEC" "1"
					( Origin gFrontEnd )
				)
				( attribute "SEC_TYPE" "SMLF"
					( Origin gFrontEnd )
				)
				( attribute "VALUE" "BAT54WS"
					( Origin gFrontEnd )
				)
				( attribute "VER" "1"
					( Origin gFrontEnd )
				)
				( attribute "XY" "(-1350,3650)"
					( Origin gFrontEnd )
				)
				( attribute "CHIPS_PART_NAME" "DIODE"
					( Origin gPackager )
				)
				( attribute "CDS_PART_NAME" "DIODE_SMLF-BAT54WS,IC,C73510-0A"
					( Origin gPackager )
				)
				( objectStatus "CR6W1" )
			)
			( gate "@baseboard_fab2_lib.baseboard_fab2(sch_1):page247_i158"
				( attribute "CDS_LIB" "mstr_discrete"
					( Origin gPackager )
				)
				( attribute "CDS_LOCATION" "CR6W2"
					( Origin gPackager )
				)
				( attribute "CDS_SEC" "1"
					( Origin gPackager )
				)
				( attribute "LOCATION" "CR6W2"
					( Origin gFrontEnd )
				)
				( attribute "MATERIAL" "IC"
					( Origin gFrontEnd )
				)
				( attribute "PACK_TYPE" "SMLF"
					( Origin gFrontEnd )
				)
				( attribute "PART_NUMBER" "C73510-001"
					( Origin gFrontEnd )
				)
				( attribute "PHYS_PAGE" "247"
					( Origin gFrontEnd )
				)
				( attribute "ROT" "6"
					( Origin gFrontEnd )
				)
				( attribute "SEC" "1"
					( Origin gFrontEnd )
				)
				( attribute "SEC_TYPE" "SMLF"
					( Origin gFrontEnd )
				)
				( attribute "VALUE" "BAT54WS"
					( Origin gFrontEnd )
				)
				( attribute "VER" "1"
					( Origin gFrontEnd )
				)
				( attribute "XY" "(-1350,3450)"
					( Origin gFrontEnd )
				)
				( attribute "CHIPS_PART_NAME" "DIODE"
					( Origin gPackager )
				)
				( attribute "CDS_PART_NAME" "DIODE_SMLF-BAT54WS,IC,C73510-0A"
					( Origin gPackager )
				)
				( objectStatus "CR6W2" )
			)
			( gate "@baseboard_fab2_lib.baseboard_fab2(sch_1):page176_i156"
				( attribute "BOM_COST" "SB"
					( Origin gFrontEnd )
				)
				( attribute "CDS_LIB" "mstr_discrete"
					( Origin gPackager )
				)
				( attribute "CDS_LOCATION" "R6W38"
					( Origin gPackager )
				)
				( attribute "CDS_SEC" "1"
					( Origin gPackager )
				)
				( attribute "LOCATION" "R6W38"
					( Origin gFrontEnd )
				)
				( attribute "MATERIAL" "CHIP"
					( Origin gFrontEnd )
				)
				( attribute "PACK_TYPE" "0402"
					( Origin gFrontEnd )
				)
				( attribute "PART_NUMBER" "G21796-040"
					( Origin gFrontEnd )
				)
				( attribute "PHYS_PAGE" "176"
					( Origin gFrontEnd )
				)
				( attribute "ROOM" "SB"
					( Origin gFrontEnd )
				)
				( attribute "ROT" "1"
					( Origin gFrontEnd )
				)
				( attribute "SEC" "1"
					( Origin gFrontEnd )
				)
				( attribute "SEC_TYPE" "0402"
					( Origin gFrontEnd )
				)
				( attribute "TOLERANCE" "1%"
					( Origin gFrontEnd )
				)
				( attribute "VALUE" "20.0K"
					( Origin gFrontEnd )
				)
				( attribute "VER" "2"
					( Origin gFrontEnd )
				)
				( attribute "WATTAGE" "1/16W"
					( Origin gFrontEnd )
				)
				( attribute "XY" "(-1250,3525)"
					( Origin gFrontEnd )
				)
				( attribute "CHIPS_PART_NAME" "RES"
					( Origin gPackager )
				)
				( attribute "CDS_PART_NAME" "RES_0402-20.0K,1%,1/16W,CHIP,GA"
					( Origin gPackager )
				)
				( objectStatus "R6W38" )
			)
			( gate "@baseboard_fab2_lib.baseboard_fab2(sch_1):page176_i158"
				( attribute "BOM_COST" "MIO_USB"
					( Origin gFrontEnd )
				)
				( attribute "CDS_LIB" "mstr_discrete"
					( Origin gPackager )
				)
				( attribute "CDS_LOCATION" "R6W39"
					( Origin gPackager )
				)
				( attribute "CDS_SEC" "1"
					( Origin gPackager )
				)
				( attribute "LOCATION" "R6W39"
					( Origin gFrontEnd )
				)
				( attribute "MATERIAL" "CHIP"
					( Origin gFrontEnd )
				)
				( attribute "PACK_TYPE" "0402"
					( Origin gFrontEnd )
				)
				( attribute "PART_NUMBER" "G21796-016"
					( Origin gFrontEnd )
				)
				( attribute "PHYS_PAGE" "176"
					( Origin gFrontEnd )
				)
				( attribute "ROOM" "USB_REAR"
					( Origin gFrontEnd )
				)
				( attribute "ROT" "1"
					( Origin gFrontEnd )
				)
				( attribute "SEC" "1"
					( Origin gFrontEnd )
				)
				( attribute "SEC_TYPE" "0402"
					( Origin gFrontEnd )
				)
				( attribute "TOLERANCE" "1%"
					( Origin gFrontEnd )
				)
				( attribute "VALUE" "10.0K"
					( Origin gFrontEnd )
				)
				( attribute "VER" "2"
					( Origin gFrontEnd )
				)
				( attribute "WATTAGE" "1/16W"
					( Origin gFrontEnd )
				)
				( attribute "XY" "(-1300,2950)"
					( Origin gFrontEnd )
				)
				( attribute "CHIPS_PART_NAME" "RES"
					( Origin gPackager )
				)
				( attribute "CDS_PART_NAME" "RES_0402-10.0K,1%,1/16W,CHIP,GA"
					( Origin gPackager )
				)
				( objectStatus "R6W39" )
			)
			( gate "@baseboard_fab2_lib.baseboard_fab2(sch_1):page92_i106"
				( attribute "CDS_LIB" "mstr_discrete"
					( Origin gPackager )
				)
				( attribute "CDS_LOCATION" "R7W4"
					( Origin gPackager )
				)
				( attribute "CDS_SEC" "1"
					( Origin gPackager )
				)
				( attribute "LOCATION" "R7W4"
					( Origin gFrontEnd )
				)
				( attribute "MATERIAL" "EMPTY"
					( Origin gFrontEnd )
				)
				( attribute "PACK_TYPE" "0402"
					( Origin gFrontEnd )
				)
				( attribute "PART_NUMBER" "G21796-047"
					( Origin gFrontEnd )
				)
				( attribute "PHYS_PAGE" "92"
					( Origin gFrontEnd )
				)
				( attribute "ROOM" "SB"
					( Origin gFrontEnd )
				)
				( attribute "ROT" "0"
					( Origin gFrontEnd )
				)
				( attribute "SEC" "1"
					( Origin gFrontEnd )
				)
				( attribute "SEC_TYPE" "0402"
					( Origin gFrontEnd )
				)
				( attribute "TOLERANCE" "1%"
					( Origin gFrontEnd )
				)
				( attribute "VALUE" "49.9"
					( Origin gFrontEnd )
				)
				( attribute "VER" "2"
					( Origin gFrontEnd )
				)
				( attribute "WATTAGE" "1/16W"
					( Origin gFrontEnd )
				)
				( attribute "XY" "(-100,3050)"
					( Origin gFrontEnd )
				)
				( attribute "CHIPS_PART_NAME" "RES"
					( Origin gPackager )
				)
				( attribute "CDS_PART_NAME" "RES_0402-49.9,1%,1/16W,EMPTY,GA"
					( Origin gPackager )
				)
				( objectStatus "R7W4" )
			)
			( gate "@baseboard_fab2_lib.baseboard_fab2(sch_1):page92_i108"
				( attribute "CDS_LIB" "mstr_discrete"
					( Origin gPackager )
				)
				( attribute "CDS_LOCATION" "R3W10"
					( Origin gPackager )
				)
				( attribute "CDS_SEC" "1"
					( Origin gPackager )
				)
				( attribute "LOCATION" "R3W10"
					( Origin gFrontEnd )
				)
				( attribute "MATERIAL" "EMPTY"
					( Origin gFrontEnd )
				)
				( attribute "PACK_TYPE" "0402"
					( Origin gFrontEnd )
				)
				( attribute "PART_NUMBER" "G21796-047"
					( Origin gFrontEnd )
				)
				( attribute "PHYS_PAGE" "92"
					( Origin gFrontEnd )
				)
				( attribute "ROOM" "SB"
					( Origin gFrontEnd )
				)
				( attribute "ROT" "0"
					( Origin gFrontEnd )
				)
				( attribute "SEC" "1"
					( Origin gFrontEnd )
				)
				( attribute "SEC_TYPE" "0402"
					( Origin gFrontEnd )
				)
				( attribute "TOLERANCE" "1%"
					( Origin gFrontEnd )
				)
				( attribute "VALUE" "49.9"
					( Origin gFrontEnd )
				)
				( attribute "VER" "2"
					( Origin gFrontEnd )
				)
				( attribute "WATTAGE" "1/16W"
					( Origin gFrontEnd )
				)
				( attribute "XY" "(-400,5350)"
					( Origin gFrontEnd )
				)
				( attribute "CHIPS_PART_NAME" "RES"
					( Origin gPackager )
				)
				( attribute "CDS_PART_NAME" "RES_0402-49.9,1%,1/16W,EMPTY,GA"
					( Origin gPackager )
				)
				( objectStatus "R3W10" )
			)
			( gate "@baseboard_fab2_lib.baseboard_fab2(sch_1):page93_i147"
				( attribute "CDS_LIB" "mstr_discrete"
					( Origin gPackager )
				)
				( attribute "CDS_LOCATION" "R2W2"
					( Origin gPackager )
				)
				( attribute "CDS_SEC" "1"
					( Origin gPackager )
				)
				( attribute "LOCATION" "R2W2"
					( Origin gFrontEnd )
				)
				( attribute "MATERIAL" "EMPTY"
					( Origin gFrontEnd )
				)
				( attribute "PACK_TYPE" "0402"
					( Origin gFrontEnd )
				)
				( attribute "PART_NUMBER" "G21796-047"
					( Origin gFrontEnd )
				)
				( attribute "PHYS_PAGE" "93"
					( Origin gFrontEnd )
				)
				( attribute "ROOM" "SB"
					( Origin gFrontEnd )
				)
				( attribute "ROT" "0"
					( Origin gFrontEnd )
				)
				( attribute "SEC" "1"
					( Origin gFrontEnd )
				)
				( attribute "SEC_TYPE" "0402"
					( Origin gFrontEnd )
				)
				( attribute "TOLERANCE" "1%"
					( Origin gFrontEnd )
				)
				( attribute "VALUE" "49.9"
					( Origin gFrontEnd )
				)
				( attribute "VER" "2"
					( Origin gFrontEnd )
				)
				( attribute "WATTAGE" "1/16W"
					( Origin gFrontEnd )
				)
				( attribute "XY" "(1750,1100)"
					( Origin gFrontEnd )
				)
				( attribute "CHIPS_PART_NAME" "RES"
					( Origin gPackager )
				)
				( attribute "CDS_PART_NAME" "RES_0402-49.9,1%,1/16W,EMPTY,GA"
					( Origin gPackager )
				)
				( objectStatus "R2W2" )
			)
			( gate "@baseboard_fab2_lib.baseboard_fab2(sch_1):page152_i105"
				( attribute "CDS_LIB" "mstr_discrete"
					( Origin gPackager )
				)
				( attribute "CDS_LOCATION" "R1W35"
					( Origin gPackager )
				)
				( attribute "CDS_SEC" "1"
					( Origin gPackager )
				)
				( attribute "LOCATION" "R1W35"
					( Origin gFrontEnd )
				)
				( attribute "MATERIAL" "EMPTY"
					( Origin gFrontEnd )
				)
				( attribute "PACK_TYPE" "0402"
					( Origin gFrontEnd )
				)
				( attribute "PART_NUMBER" "G21796-047"
					( Origin gFrontEnd )
				)
				( attribute "PHYS_PAGE" "152"
					( Origin gFrontEnd )
				)
				( attribute "ROOM" "SB"
					( Origin gFrontEnd )
				)
				( attribute "ROT" "0"
					( Origin gFrontEnd )
				)
				( attribute "SEC" "1"
					( Origin gFrontEnd )
				)
				( attribute "SEC_TYPE" "0402"
					( Origin gFrontEnd )
				)
				( attribute "TOLERANCE" "1%"
					( Origin gFrontEnd )
				)
				( attribute "VALUE" "49.9"
					( Origin gFrontEnd )
				)
				( attribute "VER" "2"
					( Origin gFrontEnd )
				)
				( attribute "WATTAGE" "1/16W"
					( Origin gFrontEnd )
				)
				( attribute "XY" "(-3100,2075)"
					( Origin gFrontEnd )
				)
				( attribute "CHIPS_PART_NAME" "RES"
					( Origin gPackager )
				)
				( attribute "CDS_PART_NAME" "RES_0402-49.9,1%,1/16W,EMPTY,GA"
					( Origin gPackager )
				)
				( objectStatus "R1W35" )
			)
			( gate "@baseboard_fab2_lib.baseboard_fab2(sch_1):page176_i160"
				( attribute "BOM_COST" "SM_CONTROLLER"
					( Origin gFrontEnd )
				)
				( attribute "CDS_LIB" "mstr_discrete"
					( Origin gPackager )
				)
				( attribute "CDS_LOCATION" "R6W37"
					( Origin gPackager )
				)
				( attribute "CDS_SEC" "1"
					( Origin gPackager )
				)
				( attribute "LOCATION" "R6W37"
					( Origin gFrontEnd )
				)
				( attribute "MATERIAL" "CHIP"
					( Origin gFrontEnd )
				)
				( attribute "PACK_TYPE" "0402"
					( Origin gFrontEnd )
				)
				( attribute "PART_NUMBER" "G21796-066"
					( Origin gFrontEnd )
				)
				( attribute "PHYS_PAGE" "176"
					( Origin gFrontEnd )
				)
				( attribute "ROOM" "MEM"
					( Origin gFrontEnd )
				)
				( attribute "ROT" "0"
					( Origin gFrontEnd )
				)
				( attribute "SEC" "1"
					( Origin gPackager )
				)
				( attribute "TOLERANCE" "1%"
					( Origin gFrontEnd )
				)
				( attribute "VALUE" "10.0"
					( Origin gFrontEnd )
				)
				( attribute "VER" "1"
					( Origin gFrontEnd )
				)
				( attribute "WATTAGE" "1/16W"
					( Origin gFrontEnd )
				)
				( attribute "XY" "(-700,3150)"
					( Origin gFrontEnd )
				)
				( attribute "CHIPS_PART_NAME" "RES"
					( Origin gPackager )
				)
				( attribute "CDS_PART_NAME" "RES_0402-10.0,1%,1/16W,CHIP,G2A"
					( Origin gPackager )
				)
				( objectStatus "R6W37" )
			)
			( gate "@baseboard_fab2_lib.baseboard_fab2(sch_1):page176_i161"
				( attribute "BOM_COST" "SM_CONTROLLER"
					( Origin gFrontEnd )
				)
				( attribute "CDS_LIB" "mstr_discrete"
					( Origin gPackager )
				)
				( attribute "CDS_LOCATION" "R6W36"
					( Origin gPackager )
				)
				( attribute "CDS_SEC" "1"
					( Origin gPackager )
				)
				( attribute "LOCATION" "R6W36"
					( Origin gFrontEnd )
				)
				( attribute "MATERIAL" "CHIP"
					( Origin gFrontEnd )
				)
				( attribute "PACK_TYPE" "0402"
					( Origin gFrontEnd )
				)
				( attribute "PART_NUMBER" "G21796-066"
					( Origin gFrontEnd )
				)
				( attribute "PHYS_PAGE" "176"
					( Origin gFrontEnd )
				)
				( attribute "ROOM" "MEM"
					( Origin gFrontEnd )
				)
				( attribute "ROT" "0"
					( Origin gFrontEnd )
				)
				( attribute "SEC" "1"
					( Origin gPackager )
				)
				( attribute "TOLERANCE" "1%"
					( Origin gFrontEnd )
				)
				( attribute "VALUE" "10.0"
					( Origin gFrontEnd )
				)
				( attribute "VER" "1"
					( Origin gFrontEnd )
				)
				( attribute "WATTAGE" "1/16W"
					( Origin gFrontEnd )
				)
				( attribute "XY" "(-725,2600)"
					( Origin gFrontEnd )
				)
				( attribute "CHIPS_PART_NAME" "RES"
					( Origin gPackager )
				)
				( attribute "CDS_PART_NAME" "RES_0402-10.0,1%,1/16W,CHIP,G2A"
					( Origin gPackager )
				)
				( objectStatus "R6W36" )
			)
			( gate "@baseboard_fab2_lib.baseboard_fab2(sch_1):page222_i44"
				( attribute "BOM_COST" "MEM_VRD_PVDDQ_CD"
					( Origin gFrontEnd )
				)
				( attribute "CDS_LIB" "mstr_discrete"
					( Origin gPackager )
				)
				( attribute "CDS_LOCATION" "C5L5"
					( Origin gPackager )
				)
				( attribute "CDS_SEC" "1"
					( Origin gPackager )
				)
				( attribute "LOCATION" "C5L5"
					( Origin gFrontEnd )
				)
				( attribute "MATERIAL" "X5R"
					( Origin gFrontEnd )
				)
				( attribute "NEW_MATERIAL" "X6S"
					( Origin gFrontEnd )
				)
				( attribute "PACK_TYPE" "0805"
					( Origin gFrontEnd )
				)
				( attribute "PART_NUMBER" "602433-112"
					( Origin gFrontEnd )
				)
				( attribute "PHYS_PAGE" "222"
					( Origin gFrontEnd )
				)
				( attribute "ROOM" "VDDQ_ABC_PWR_VR"
					( Origin gFrontEnd )
				)
				( attribute "ROT" "0"
					( Origin gFrontEnd )
				)
				( attribute "SEC" "1"
					( Origin gFrontEnd )
				)
				( attribute "SEC_TYPE" "0805"
					( Origin gFrontEnd )
				)
				( attribute "TOLERANCE" "20%"
					( Origin gFrontEnd )
				)
				( attribute "VALUE" "100UF"
					( Origin gFrontEnd )
				)
				( attribute "VER" "1"
					( Origin gFrontEnd )
				)
				( attribute "VOLTAGE" "4V"
					( Units "uVoltage" "V" 1.000000)
					( Origin gFrontEnd )
				)
				( attribute "XY" "(3100,2825)"
					( Origin gFrontEnd )
				)
				( attribute "CHIPS_PART_NAME" "CAP"
					( Origin gPackager )
				)
				( attribute "CDS_PART_NAME" "CAP_0805-100UF,4V,20%,X5R,6024A"
					( Origin gPackager )
				)
				( attribute "GROUP" "PWR_MLCC_CAP"
					( Origin gFrontEnd )
				)
				( attribute "NEW_PN" "078.1071T.M002"
					( Origin gFrontEnd )
				)
				( objectStatus "C5L5" )
			)
			( gate "@baseboard_fab2_lib.baseboard_fab2(sch_1):page176_i163"
				( attribute "BOM_COST" "SM_CONTROLLER"
					( Origin gFrontEnd )
				)
				( attribute "CDS_LIB" "dev_discrete"
					( Origin gPackager )
				)
				( attribute "CDS_LOCATION" "C1W18"
					( Origin gPackager )
				)
				( attribute "CDS_SEC" "1"
					( Origin gPackager )
				)
				( attribute "CD_SEC" "1"
					( Origin gFrontEnd )
				)
				( attribute "LOCATION" "C1W18"
					( Origin gFrontEnd )
				)
				( attribute "MATERIAL" "X7R"
					( Origin gFrontEnd )
				)
				( attribute "PACK_TYPE" "0402V"
					( Origin gFrontEnd )
				)
				( attribute "PART_NUMBER" "A36096-030"
					( Origin gFrontEnd )
				)
				( attribute "PHYS_PAGE" "176"
					( Origin gFrontEnd )
				)
				( attribute "ROOM" "MEM"
					( Origin gFrontEnd )
				)
				( attribute "ROT" "0"
					( Origin gFrontEnd )
				)
				( attribute "SEC" "1"
					( Origin gPackager )
				)
				( attribute "SIGNAL_MODEL" "DEFAULT_CAPACITOR_100000pF_2_1"
					( Origin gFrontEnd )
				)
				( attribute "TOLERANCE" "10%"
					( Origin gFrontEnd )
				)
				( attribute "VALUE" "0.1UF"
					( Origin gFrontEnd )
				)
				( attribute "VER" "1"
					( Origin gFrontEnd )
				)
				( attribute "VOLTAGE" "16V"
					( Units "uVoltage" "V" 1.000000)
					( Origin gFrontEnd )
				)
				( attribute "XY" "(-4175,1650)"
					( Origin gFrontEnd )
				)
				( attribute "CHIPS_PART_NAME" "CAP_A"
					( Origin gPackager )
				)
				( attribute "CDS_PART_NAME" "CAP_A_0402V-0.1UF,16V,10%,X7R,A"
					( Origin gPackager )
				)
				( objectStatus "C1W18" )
			)
			( gate "@baseboard_fab2_lib.baseboard_fab2(sch_1):page176_i166"
				( attribute "BOM_COST" "SM_CONTROLLER"
					( Origin gFrontEnd )
				)
				( attribute "CDS_LIB" "dev_discrete"
					( Origin gPackager )
				)
				( attribute "CDS_LOCATION" "C1W19"
					( Origin gPackager )
				)
				( attribute "CDS_SEC" "1"
					( Origin gPackager )
				)
				( attribute "CD_SEC" "1"
					( Origin gFrontEnd )
				)
				( attribute "LOCATION" "C1W19"
					( Origin gFrontEnd )
				)
				( attribute "MATERIAL" "X7R"
					( Origin gFrontEnd )
				)
				( attribute "PACK_TYPE" "0402V"
					( Origin gFrontEnd )
				)
				( attribute "PART_NUMBER" "A36096-030"
					( Origin gFrontEnd )
				)
				( attribute "PHYS_PAGE" "176"
					( Origin gFrontEnd )
				)
				( attribute "ROOM" "MEM"
					( Origin gFrontEnd )
				)
				( attribute "ROT" "0"
					( Origin gFrontEnd )
				)
				( attribute "SEC" "1"
					( Origin gPackager )
				)
				( attribute "SIGNAL_MODEL" "DEFAULT_CAPACITOR_100000pF_2_1"
					( Origin gFrontEnd )
				)
				( attribute "TOLERANCE" "10%"
					( Origin gFrontEnd )
				)
				( attribute "VALUE" "0.1UF"
					( Origin gFrontEnd )
				)
				( attribute "VER" "1"
					( Origin gFrontEnd )
				)
				( attribute "VOLTAGE" "16V"
					( Units "uVoltage" "V" 1.000000)
					( Origin gFrontEnd )
				)
				( attribute "XY" "(-3775,1650)"
					( Origin gFrontEnd )
				)
				( attribute "CHIPS_PART_NAME" "CAP_A"
					( Origin gPackager )
				)
				( attribute "CDS_PART_NAME" "CAP_A_0402V-0.1UF,16V,10%,X7R,A"
					( Origin gPackager )
				)
				( objectStatus "C1W19" )
			)
			( gate "@baseboard_fab2_lib.baseboard_fab2(sch_1):page176_i172"
				( attribute "CDS_LIB" "mstr_discrete"
					( Origin gPackager )
				)
				( attribute "CDS_LOCATION" "R1W36"
					( Origin gPackager )
				)
				( attribute "CDS_SEC" "1"
					( Origin gPackager )
				)
				( attribute "LOCATION" "R1W36"
					( Origin gFrontEnd )
				)
				( attribute "MATERIAL" "CHIP"
					( Origin gFrontEnd )
				)
				( attribute "PACK_TYPE" "0402"
					( Origin gFrontEnd )
				)
				( attribute "PART_NUMBER" "G21796-072"
					( Origin gFrontEnd )
				)
				( attribute "PHYS_PAGE" "176"
					( Origin gFrontEnd )
				)
				( attribute "ROT" "5"
					( Origin gFrontEnd )
				)
				( attribute "SEC" "1"
					( Origin gFrontEnd )
				)
				( attribute "SEC_TYPE" "0402"
					( Origin gFrontEnd )
				)
				( attribute "TOLERANCE" "1%"
					( Origin gFrontEnd )
				)
				( attribute "VALUE" "4.75K"
					( Origin gFrontEnd )
				)
				( attribute "VER" "1"
					( Origin gFrontEnd )
				)
				( attribute "WATTAGE" "1/16W"
					( Origin gFrontEnd )
				)
				( attribute "XY" "(-6100,2250)"
					( Origin gFrontEnd )
				)
				( attribute "CHIPS_PART_NAME" "RES"
					( Origin gPackager )
				)
				( attribute "CDS_PART_NAME" "RES_0402-4.75K,1%,1/16W,CHIP,GA"
					( Origin gPackager )
				)
				( objectStatus "R1W36" )
			)
			( gate "@baseboard_fab2_lib.baseboard_fab2(sch_1):page176_i173"
				( attribute "CDS_LIB" "mstr_discrete"
					( Origin gPackager )
				)
				( attribute "CDS_LOCATION" "R1W37"
					( Origin gPackager )
				)
				( attribute "CDS_SEC" "1"
					( Origin gPackager )
				)
				( attribute "LOCATION" "R1W37"
					( Origin gFrontEnd )
				)
				( attribute "MATERIAL" "CHIP"
					( Origin gFrontEnd )
				)
				( attribute "PACK_TYPE" "0402"
					( Origin gFrontEnd )
				)
				( attribute "PART_NUMBER" "G21796-072"
					( Origin gFrontEnd )
				)
				( attribute "PHYS_PAGE" "176"
					( Origin gFrontEnd )
				)
				( attribute "ROT" "5"
					( Origin gFrontEnd )
				)
				( attribute "SEC" "1"
					( Origin gFrontEnd )
				)
				( attribute "SEC_TYPE" "0402"
					( Origin gFrontEnd )
				)
				( attribute "TOLERANCE" "1%"
					( Origin gFrontEnd )
				)
				( attribute "VALUE" "4.75K"
					( Origin gFrontEnd )
				)
				( attribute "VER" "1"
					( Origin gFrontEnd )
				)
				( attribute "WATTAGE" "1/16W"
					( Origin gFrontEnd )
				)
				( attribute "XY" "(-5800,2250)"
					( Origin gFrontEnd )
				)
				( attribute "CHIPS_PART_NAME" "RES"
					( Origin gPackager )
				)
				( attribute "CDS_PART_NAME" "RES_0402-4.75K,1%,1/16W,CHIP,GA"
					( Origin gPackager )
				)
				( objectStatus "R1W37" )
			)
			( gate "@baseboard_fab2_lib.baseboard_fab2(sch_1):page142_i34"
				( attribute "CDS_LIB" "w_hdl"
					( Origin gPackager )
				)
				( attribute "CDS_LMAN_SYM_OUTLINE" "-50,75,50,-75"
					( Origin gPackager )
				)
				( attribute "LOCATION" "R8E36"
					( Origin gFrontEnd )
				)
				( attribute "PACK_TYPE" "SMD-RG1"
					( Origin gFrontEnd )
				)
				( attribute "PART_NUMBER" "64.21515.6DL"
					( Origin gFrontEnd )
				)
				( attribute "PHYS_PAGE" "142"
					( Origin gFrontEnd )
				)
				( attribute "ROT" "0"
					( Origin gFrontEnd )
				)
				( attribute "VALUE" "2K15R2F-1-GP"
					( Origin gFrontEnd )
				)
				( attribute "VER" "1"
					( Origin gFrontEnd )
				)
				( attribute "XY" "(-4800,3525)"
					( Origin gFrontEnd )
				)
				( attribute "CHIPS_PART_NAME" "2K15R2F-1-GP"
					( Origin gPackager )
				)
				( attribute "CDS_PART_NAME" "2K15R2F-1-GP_SMD-RG1-2K15R2F-1A"
					( Origin gPackager )
				)
				( attribute "ATTRIBUTE" "2.15K OHM"
					( Origin gFrontEnd )
				)
				( attribute "PACK_SIZE" "0402"
					( Origin gFrontEnd )
				)
				( attribute "RATED" "1/16W"
					( Origin gFrontEnd )
				)
				( attribute "TOLERANCE" "1%"
					( Origin gFrontEnd )
				)
				( attribute "SEC" "1"
					( Origin gFrontEnd )
				)
				( attribute "SEC_TYPE" "SMD-RG1"
					( Origin gFrontEnd )
				)
				( attribute "CDS_LOCATION" "R8E36"
					( Origin gPackager )
				)
				( attribute "CDS_SEC" "1"
					( Origin gPackager )
				)
				( objectStatus "R8E36" )
			)
			( gate "@baseboard_fab2_lib.baseboard_fab2(sch_1):page142_i35"
				( attribute "CDS_LIB" "w_hdl"
					( Origin gPackager )
				)
				( attribute "CDS_LMAN_SYM_OUTLINE" "-50,75,50,-75"
					( Origin gPackager )
				)
				( attribute "LOCATION" "R8E30"
					( Origin gFrontEnd )
				)
				( attribute "PACK_TYPE" "SMD-RG1"
					( Origin gFrontEnd )
				)
				( attribute "PART_NUMBER" "64.21515.6DL"
					( Origin gFrontEnd )
				)
				( attribute "PHYS_PAGE" "142"
					( Origin gFrontEnd )
				)
				( attribute "ROT" "0"
					( Origin gFrontEnd )
				)
				( attribute "VALUE" "2K15R2F-1-GP"
					( Origin gFrontEnd )
				)
				( attribute "VER" "1"
					( Origin gFrontEnd )
				)
				( attribute "XY" "(-3800,3525)"
					( Origin gFrontEnd )
				)
				( attribute "CHIPS_PART_NAME" "2K15R2F-1-GP"
					( Origin gPackager )
				)
				( attribute "CDS_PART_NAME" "2K15R2F-1-GP_SMD-RG1-2K15R2F-1A"
					( Origin gPackager )
				)
				( attribute "SEC" "1"
					( Origin gFrontEnd )
				)
				( attribute "ATTRIBUTE" "2.15K OHM"
					( Origin gFrontEnd )
				)
				( attribute "PACK_SIZE" "0402"
					( Origin gFrontEnd )
				)
				( attribute "RATED" "1/16W"
					( Origin gFrontEnd )
				)
				( attribute "TOLERANCE" "1%"
					( Origin gFrontEnd )
				)
				( attribute "SEC_TYPE" "SMD-RG1"
					( Origin gFrontEnd )
				)
				( attribute "CDS_LOCATION" "R8E30"
					( Origin gPackager )
				)
				( attribute "CDS_SEC" "1"
					( Origin gPackager )
				)
				( objectStatus "R8E30" )
			)
			( gate "@baseboard_fab2_lib.baseboard_fab2(sch_1):page176_i176"
				( attribute "BOM_COST" "PROC_SIDEBAND"
					( Origin gFrontEnd )
				)
				( attribute "CDS_LIB" "mstr_discrete"
					( Origin gPackager )
				)
				( attribute "CDS_LOCATION" "R1W38"
					( Origin gPackager )
				)
				( attribute "CDS_SEC" "1"
					( Origin gPackager )
				)
				( attribute "LOCATION" "R1W38"
					( Origin gFrontEnd )
				)
				( attribute "MATERIAL" "CHIP"
					( Origin gFrontEnd )
				)
				( attribute "PACK_TYPE" "0402"
					( Origin gFrontEnd )
				)
				( attribute "PART_NUMBER" "G21497-005"
					( Origin gFrontEnd )
				)
				( attribute "PHYS_PAGE" "176"
					( Origin gFrontEnd )
				)
				( attribute "POP" "NOPOP"
					( Origin gFrontEnd )
				)
				( attribute "ROOM" "CPU0"
					( Origin gFrontEnd )
				)
				( attribute "ROT" "0"
					( Origin gFrontEnd )
				)
				( attribute "SEC" "1"
					( Origin gFrontEnd )
				)
				( attribute "SEC_TYPE" "0402"
					( Origin gFrontEnd )
				)
				( attribute "TOLERANCE" "5%"
					( Origin gFrontEnd )
				)
				( attribute "VALUE" "0.0"
					( Origin gFrontEnd )
				)
				( attribute "VER" "1"
					( Origin gFrontEnd )
				)
				( attribute "WATTAGE" "1/16W"
					( Origin gFrontEnd )
				)
				( attribute "XY" "(-5950,1600)"
					( Origin gFrontEnd )
				)
				( attribute "CHIPS_PART_NAME" "RES"
					( Origin gPackager )
				)
				( attribute "CDS_PART_NAME" "RES_0402-0.0,5%,1/16W,CHIP,G21A"
					( Origin gPackager )
				)
				( objectStatus "R1W38" )
			)
			( gate "@baseboard_fab2_lib.baseboard_fab2(sch_1):page200_i250"
				( attribute "ATTRIBUTE" "232KOHM"
					( Origin gFrontEnd )
				)
				( attribute "CDS_LIB" "w_hdl"
					( Origin gPackager )
				)
				( attribute "CDS_LMAN_SYM_OUTLINE" "-50,75,50,-75"
					( Origin gPackager )
				)
				( attribute "LOCATION" "R6W3"
					( Origin gFrontEnd )
				)
				( attribute "PACK_TYPE" "SMD-RG1"
					( Origin gFrontEnd )
				)
				( attribute "PART_NUMBER" "64.23235.L0L"
					( Origin gFrontEnd )
				)
				( attribute "PHYS_PAGE" "200"
					( Origin gFrontEnd )
				)
				( attribute "RATED" "1/16W"
					( Origin gFrontEnd )
				)
				( attribute "ROT" "1"
					( Origin gFrontEnd )
				)
				( attribute "SEC" "1"
					( Origin gFrontEnd )
				)
				( attribute "SEC_TYPE" "SMD-RG1"
					( Origin gFrontEnd )
				)
				( attribute "TOLERANCE" "1%"
					( Origin gFrontEnd )
				)
				( attribute "VALUE" "232KR2F-2-GP"
					( Origin gFrontEnd )
				)
				( attribute "VER" "1"
					( Origin gFrontEnd )
				)
				( attribute "XY" "(-800,1950)"
					( Origin gFrontEnd )
				)
				( attribute "CHIPS_PART_NAME" "232KR2F-2-GP"
					( Origin gPackager )
				)
				( attribute "CDS_PART_NAME" "232KR2F-2-GP_SMD-RG1-232KR2F-2A"
					( Origin gPackager )
				)
				( attribute "PACK_SIZE" "0402"
					( Origin gFrontEnd )
				)
				( attribute "CDS_LOCATION" "R6W3"
					( Origin gPackager )
				)
				( attribute "CDS_SEC" "1"
					( Origin gPackager )
				)
				( objectStatus "R6W3" )
			)
			( gate "@baseboard_fab2_lib.baseboard_fab2(sch_1):page151_i220"
				( attribute "CDS_LIB" "mstr_discrete"
					( Origin gPackager )
				)
				( attribute "CDS_LOCATION" "C1W20"
					( Origin gPackager )
				)
				( attribute "LOCATION" "C1W20"
					( Origin gFrontEnd )
				)
				( attribute "MATERIAL" "X7R"
					( Origin gFrontEnd )
				)
				( attribute "PACK_TYPE" "0402"
					( Origin gFrontEnd )
				)
				( attribute "PART_NUMBER" "A36096-155"
					( Origin gFrontEnd )
				)
				( attribute "PHYS_PAGE" "151"
					( Origin gFrontEnd )
				)
				( attribute "ROOM" "OCP_STEERING"
					( Origin gFrontEnd )
				)
				( attribute "ROT" "2"
					( Origin gFrontEnd )
				)
				( attribute "SEC" "1"
					( Origin gFrontEnd )
				)
				( attribute "SEC_TYPE" "0402"
					( Origin gFrontEnd )
				)
				( attribute "TOLERANCE" "10%"
					( Origin gFrontEnd )
				)
				( attribute "VALUE" "0.22UF"
					( Origin gFrontEnd )
				)
				( attribute "VER" "1"
					( Origin gFrontEnd )
				)
				( attribute "VOLTAGE" "16V"
					( Units "uVoltage" "V" 1.000000)
					( Origin gFrontEnd )
				)
				( attribute "XY" "(1950,-1900)"
					( Origin gFrontEnd )
				)
				( attribute "CHIPS_PART_NAME" "CAP"
					( Origin gPackager )
				)
				( attribute "CDS_PART_NAME" "CAP_0402-0.22UF,16V,10%,X7R,A3A"
					( Origin gPackager )
				)
				( attribute "CDS_SEC" "1"
					( Origin gPackager )
				)
				( objectStatus "C1W20" )
			)
			( gate "@baseboard_fab2_lib.baseboard_fab2(sch_1):page240_i193"
				( attribute "CDS_LIB" "w_hdl"
					( Origin gPackager )
				)
				( attribute "CDS_LMAN_SYM_OUTLINE" "-50,100,50,-100"
					( Origin gPackager )
				)
				( attribute "LOCATION" "FB9E1"
					( Origin gFrontEnd )
				)
				( attribute "PACK_TYPE" "DISCRET-GB1"
					( Origin gFrontEnd )
				)
				( attribute "PART_NUMBER" "068.00007.0011"
					( Origin gFrontEnd )
				)
				( attribute "PHYS_PAGE" "240"
					( Origin gFrontEnd )
				)
				( attribute "ROT" "1"
					( Origin gFrontEnd )
				)
				( attribute "SEC" "1"
					( Origin gFrontEnd )
				)
				( attribute "SEC_TYPE" "DISCRET-GB1"
					( Origin gFrontEnd )
				)
				( attribute "VALUE" "BLM31SN500SN1L-GP"
					( Origin gFrontEnd )
				)
				( attribute "VER" "1"
					( Origin gFrontEnd )
				)
				( attribute "XY" "(6100,4500)"
					( Origin gFrontEnd )
				)
				( attribute "CHIPS_PART_NAME" "BLM31SN500SN1L-GP"
					( Origin gPackager )
				)
				( attribute "CDS_PART_NAME" "BLM31SN500SN1L-GP_DISCRET-GB1-A"
					( Origin gPackager )
				)
				( attribute "CDS_LOCATION" "FB9E1"
					( Origin gPackager )
				)
				( attribute "CDS_SEC" "1"
					( Origin gPackager )
				)
				( attribute "ATTRIBUTE" "50OHM@100MHZ"
					( Origin gFrontEnd )
				)
				( attribute "PACK_SIZE" "DCR=1.6MOHM"
					( Origin gFrontEnd )
				)
				( attribute "RATED" "1MA"
					( Origin gFrontEnd )
				)
				( objectStatus "FB9E1" )
			)
			( gate "@baseboard_fab2_lib.baseboard_fab2(sch_1):page155_i201"
				( attribute "BOM_COST" "PROC_SIDEBAND"
					( Origin gFrontEnd )
				)
				( attribute "CDS_LIB" "mstr_discrete"
					( Origin gPackager )
				)
				( attribute "CDS_LOCATION" "R6W40"
					( Origin gPackager )
				)
				( attribute "CDS_SEC" "1"
					( Origin gPackager )
				)
				( attribute "LOCATION" "R6W40"
					( Origin gFrontEnd )
				)
				( attribute "MATERIAL" "CHIP"
					( Origin gFrontEnd )
				)
				( attribute "PACK_TYPE" "0402"
					( Origin gFrontEnd )
				)
				( attribute "PART_NUMBER" "G21796-016"
					( Origin gFrontEnd )
				)
				( attribute "PHYS_PAGE" "155"
					( Origin gFrontEnd )
				)
				( attribute "ROOM" "CPU0"
					( Origin gFrontEnd )
				)
				( attribute "ROT" "0"
					( Origin gFrontEnd )
				)
				( attribute "SEC" "1"
					( Origin gFrontEnd )
				)
				( attribute "SEC_TYPE" "0402"
					( Origin gFrontEnd )
				)
				( attribute "TOLERANCE" "1%"
					( Origin gFrontEnd )
				)
				( attribute "VALUE" "10.0K"
					( Origin gFrontEnd )
				)
				( attribute "VER" "2"
					( Origin gFrontEnd )
				)
				( attribute "WATTAGE" "1/16W"
					( Origin gFrontEnd )
				)
				( attribute "XY" "(-2700,1700)"
					( Origin gFrontEnd )
				)
				( attribute "CHIPS_PART_NAME" "RES"
					( Origin gPackager )
				)
				( attribute "CDS_PART_NAME" "RES_0402-10.0K,1%,1/16W,CHIP,GA"
					( Origin gPackager )
				)
				( objectStatus "R6W40" )
			)
			( gate "@baseboard_fab2_lib.baseboard_fab2(sch_1):page151_i222"
				( attribute "CDS_LIB" "mstr_discrete"
					( Origin gPackager )
				)
				( attribute "LOCATION" "R25W30"
					( Origin gFrontEnd )
				)
				( attribute "MATERIAL" "CHIP"
					( Origin gFrontEnd )
				)
				( attribute "PACK_TYPE" "0402"
					( Origin gFrontEnd )
				)
				( attribute "PART_NUMBER" "G21796-344"
					( Origin gFrontEnd )
				)
				( attribute "PHYS_PAGE" "151"
					( Origin gFrontEnd )
				)
				( attribute "ROT" "1"
					( Origin gFrontEnd )
				)
				( attribute "SEC" "1"
					( Origin gFrontEnd )
				)
				( attribute "SEC_TYPE" "0402"
					( Origin gFrontEnd )
				)
				( attribute "TOLERANCE" "1%"
					( Origin gFrontEnd )
				)
				( attribute "VALUE" "2.7K"
					( Origin gFrontEnd )
				)
				( attribute "VER" "2"
					( Origin gFrontEnd )
				)
				( attribute "WATTAGE" "1/16W"
					( Origin gFrontEnd )
				)
				( attribute "XY" "(-975,1525)"
					( Origin gFrontEnd )
				)
				( attribute "CHIPS_PART_NAME" "RES"
					( Origin gPackager )
				)
				( attribute "CDS_PART_NAME" "RES_0402-2.7K,1%,1/16W,CHIP,G2A"
					( Origin gPackager )
				)
				( attribute "CDS_LOCATION" "R25W30"
					( Origin gPackager )
				)
				( attribute "CDS_SEC" "1"
					( Origin gPackager )
				)
				( objectStatus "R25W30" )
			)
			( gate "@baseboard_fab2_lib.baseboard_fab2(sch_1):page199_i137"
				( attribute "CDS_LIB" "mstr_discrete"
					( Origin gPackager )
				)
				( attribute "CDS_LOCATION" "R1D29"
					( Origin gPackager )
				)
				( attribute "CDS_SEC" "1"
					( Origin gPackager )
				)
				( attribute "LOCATION" "R1D29"
					( Origin gFrontEnd )
				)
				( attribute "MATERIAL" "CHIP"
					( Origin gFrontEnd )
				)
				( attribute "PACK_TYPE" "0402"
					( Origin gFrontEnd )
				)
				( attribute "PART_NUMBER" "G21796-072"
					( Origin gFrontEnd )
				)
				( attribute "PHYS_PAGE" "199"
					( Origin gFrontEnd )
				)
				( attribute "ROOM" "CPU0"
					( Origin gFrontEnd )
				)
				( attribute "ROT" "0"
					( Origin gFrontEnd )
				)
				( attribute "SEC" "1"
					( Origin gFrontEnd )
				)
				( attribute "SEC_TYPE" "0402"
					( Origin gFrontEnd )
				)
				( attribute "TOLERANCE" "1%"
					( Origin gFrontEnd )
				)
				( attribute "VALUE" "4.75K"
					( Origin gFrontEnd )
				)
				( attribute "VER" "2"
					( Origin gFrontEnd )
				)
				( attribute "WATTAGE" "1/16W"
					( Origin gFrontEnd )
				)
				( attribute "XY" "(-8000,2950)"
					( Origin gFrontEnd )
				)
				( attribute "CHIPS_PART_NAME" "RES"
					( Origin gPackager )
				)
				( attribute "CDS_PART_NAME" "RES_0402-4.75K,1%,1/16W,CHIP,GA"
					( Origin gPackager )
				)
				( attribute "POP" "NOPOP"
					( Origin gFrontEnd )
				)
				( objectStatus "R1D29" )
			)
			( gate "@baseboard_fab2_lib.baseboard_fab2(sch_1):page164_i101"
				( attribute "BOM_COST" "SM_CONTROLLER"
					( Origin gFrontEnd )
				)
				( attribute "CDS_LIB" "mstr_discrete"
					( Origin gPackager )
				)
				( attribute "CDS_LOCATION" "R1T10"
					( Origin gPackager )
				)
				( attribute "CDS_SEC" "1"
					( Origin gPackager )
				)
				( attribute "LOCATION" "R1T10"
					( Origin gFrontEnd )
				)
				( attribute "MATERIAL" "CHIP"
					( Origin gFrontEnd )
				)
				( attribute "PACK_TYPE" "0402"
					( Origin gFrontEnd )
				)
				( attribute "PART_NUMBER" "G21796-026"
					( Origin gFrontEnd )
				)
				( attribute "PHYS_PAGE" "164"
					( Origin gFrontEnd )
				)
				( attribute "POP" "NOPOP"
					( Origin gFrontEnd )
				)
				( attribute "ROOM" "BMC_MISC"
					( Origin gFrontEnd )
				)
				( attribute "ROT" "0"
					( Origin gFrontEnd )
				)
				( attribute "SEC" "1"
					( Origin gFrontEnd )
				)
				( attribute "SEC_TYPE" "0402"
					( Origin gFrontEnd )
				)
				( attribute "TOLERANCE" "1%"
					( Origin gFrontEnd )
				)
				( attribute "VALUE" "1.00K"
					( Origin gFrontEnd )
				)
				( attribute "VER" "2"
					( Origin gFrontEnd )
				)
				( attribute "WATTAGE" "1/16W"
					( Origin gFrontEnd )
				)
				( attribute "XY" "(-6250,925)"
					( Origin gFrontEnd )
				)
				( attribute "CHIPS_PART_NAME" "RES"
					( Origin gPackager )
				)
				( attribute "CDS_PART_NAME" "RES_0402-1.00K,1%,1/16W,CHIP,GA"
					( Origin gPackager )
				)
				( objectStatus "R1T10" )
			)
			( gate "@baseboard_fab2_lib.baseboard_fab2(sch_1):page164_i51"
				( attribute "BOM_COST" "SM_CONTROLLER"
					( Origin gFrontEnd )
				)
				( attribute "CDS_LIB" "mstr_discrete"
					( Origin gPackager )
				)
				( attribute "CDS_LOCATION" "R1T6"
					( Origin gPackager )
				)
				( attribute "CDS_SEC" "1"
					( Origin gPackager )
				)
				( attribute "LOCATION" "R1T6"
					( Origin gFrontEnd )
				)
				( attribute "MATERIAL" "CHIP"
					( Origin gFrontEnd )
				)
				( attribute "PACK_TYPE" "0402"
					( Origin gFrontEnd )
				)
				( attribute "PART_NUMBER" "G21796-344"
					( Origin gFrontEnd )
				)
				( attribute "PHYS_PAGE" "164"
					( Origin gFrontEnd )
				)
				( attribute "ROOM" "BMC_MISC"
					( Origin gFrontEnd )
				)
				( attribute "ROT" "0"
					( Origin gFrontEnd )
				)
				( attribute "SEC" "1"
					( Origin gFrontEnd )
				)
				( attribute "SEC_TYPE" "0402"
					( Origin gFrontEnd )
				)
				( attribute "TOLERANCE" "1%"
					( Origin gFrontEnd )
				)
				( attribute "VALUE" "2.7K"
					( Origin gFrontEnd )
				)
				( attribute "VER" "1"
					( Origin gFrontEnd )
				)
				( attribute "WATTAGE" "1/16W"
					( Origin gFrontEnd )
				)
				( attribute "XY" "(-7400,1400)"
					( Origin gFrontEnd )
				)
				( attribute "CHIPS_PART_NAME" "RES"
					( Origin gPackager )
				)
				( attribute "CDS_PART_NAME" "RES_0402-2.7K,1%,1/16W,CHIP,G2A"
					( Origin gPackager )
				)
				( objectStatus "R1T6" )
			)
			( gate "@baseboard_fab2_lib.baseboard_fab2(sch_1):page164_i53"
				( attribute "BOM_COST" "SM_CONTROLLER"
					( Origin gFrontEnd )
				)
				( attribute "CDS_LIB" "mstr_discrete"
					( Origin gPackager )
				)
				( attribute "CDS_LOCATION" "R1T12"
					( Origin gPackager )
				)
				( attribute "CDS_SEC" "1"
					( Origin gPackager )
				)
				( attribute "LOCATION" "R1T12"
					( Origin gFrontEnd )
				)
				( attribute "MATERIAL" "CHIP"
					( Origin gFrontEnd )
				)
				( attribute "PACK_TYPE" "0402"
					( Origin gFrontEnd )
				)
				( attribute "PART_NUMBER" "G21796-026"
					( Origin gFrontEnd )
				)
				( attribute "PHYS_PAGE" "164"
					( Origin gFrontEnd )
				)
				( attribute "POP" "NOPOP"
					( Origin gFrontEnd )
				)
				( attribute "ROOM" "BMC_MISC"
					( Origin gFrontEnd )
				)
				( attribute "ROT" "0"
					( Origin gFrontEnd )
				)
				( attribute "SEC" "1"
					( Origin gFrontEnd )
				)
				( attribute "SEC_TYPE" "0402"
					( Origin gFrontEnd )
				)
				( attribute "TOLERANCE" "1%"
					( Origin gFrontEnd )
				)
				( attribute "VALUE" "1.00K"
					( Origin gFrontEnd )
				)
				( attribute "VER" "2"
					( Origin gFrontEnd )
				)
				( attribute "WATTAGE" "1/16W"
					( Origin gFrontEnd )
				)
				( attribute "XY" "(-6550,925)"
					( Origin gFrontEnd )
				)
				( attribute "CHIPS_PART_NAME" "RES"
					( Origin gPackager )
				)
				( attribute "CDS_PART_NAME" "RES_0402-1.00K,1%,1/16W,CHIP,GA"
					( Origin gPackager )
				)
				( objectStatus "R1T12" )
			)
			( gate "@baseboard_fab2_lib.baseboard_fab2(sch_1):page211_i102"
				( attribute "CDS_LIB" "mstr_discrete"
					( Origin gPackager )
				)
				( attribute "CDS_LOCATION" "R3N22"
					( Origin gPackager )
				)
				( attribute "CDS_SEC" "1"
					( Origin gPackager )
				)
				( attribute "LOCATION" "R3N22"
					( Origin gFrontEnd )
				)
				( attribute "MATERIAL" "CHIP"
					( Origin gFrontEnd )
				)
				( attribute "PACK_TYPE" "0402"
					( Origin gFrontEnd )
				)
				( attribute "PART_NUMBER" "G21796-082"
					( Origin gFrontEnd )
				)
				( attribute "PHYS_PAGE" "211"
					( Origin gFrontEnd )
				)
				( attribute "ROOM" "PVCCIN_CPU0_VR"
					( Origin gFrontEnd )
				)
				( attribute "ROT" "0"
					( Origin gFrontEnd )
				)
				( attribute "SEC" "1"
					( Origin gFrontEnd )
				)
				( attribute "SEC_TYPE" "0402"
					( Origin gFrontEnd )
				)
				( attribute "TOLERANCE" "1%"
					( Origin gFrontEnd )
				)
				( attribute "VALUE" "4.02K"
					( Origin gFrontEnd )
				)
				( attribute "VER" "2"
					( Origin gFrontEnd )
				)
				( attribute "WATTAGE" "1/16W"
					( Origin gFrontEnd )
				)
				( attribute "XY" "(-575,1200)"
					( Origin gFrontEnd )
				)
				( attribute "CHIPS_PART_NAME" "RES"
					( Origin gPackager )
				)
				( attribute "CDS_PART_NAME" "RES_0402-4.02K,1%,1/16W,CHIP,GA"
					( Origin gPackager )
				)
				( objectStatus "R3N22" )
			)
			( gate "@baseboard_fab2_lib.baseboard_fab2(sch_1):page213_i104"
				( attribute "CDS_LIB" "mstr_discrete"
					( Origin gPackager )
				)
				( attribute "CDS_LOCATION" "R4D64"
					( Origin gPackager )
				)
				( attribute "CDS_SEC" "1"
					( Origin gPackager )
				)
				( attribute "LOCATION" "R4D64"
					( Origin gFrontEnd )
				)
				( attribute "MATERIAL" "CHIP"
					( Origin gFrontEnd )
				)
				( attribute "PACK_TYPE" "0402"
					( Origin gFrontEnd )
				)
				( attribute "PART_NUMBER" "G21796-043"
					( Origin gFrontEnd )
				)
				( attribute "PHYS_PAGE" "213"
					( Origin gFrontEnd )
				)
				( attribute "ROOM" "PVCCIN_CPU1_VR"
					( Origin gFrontEnd )
				)
				( attribute "ROT" "0"
					( Origin gFrontEnd )
				)
				( attribute "SEC" "1"
					( Origin gFrontEnd )
				)
				( attribute "SEC_TYPE" "0402"
					( Origin gFrontEnd )
				)
				( attribute "TOLERANCE" "1%"
					( Origin gFrontEnd )
				)
				( attribute "VALUE" "3.16K"
					( Origin gFrontEnd )
				)
				( attribute "VER" "2"
					( Origin gFrontEnd )
				)
				( attribute "WATTAGE" "1/16W"
					( Origin gFrontEnd )
				)
				( attribute "XY" "(-850,1175)"
					( Origin gFrontEnd )
				)
				( attribute "CHIPS_PART_NAME" "RES"
					( Origin gPackager )
				)
				( attribute "CDS_PART_NAME" "RES_0402-3.16K,1%,1/16W,CHIP,GA"
					( Origin gPackager )
				)
				( objectStatus "R4D64" )
			)
			( gate "@baseboard_fab2_lib.baseboard_fab2(sch_1):page239_i102"
				( attribute "ATTRIBUTE" "21.5KOHM"
					( Origin gFrontEnd )
				)
				( attribute "CDS_LIB" "w_hdl"
					( Origin gPackager )
				)
				( attribute "CDS_LMAN_SYM_OUTLINE" "-50,75,50,-75"
					( Origin gPackager )
				)
				( attribute "LOCATION" "R9W31"
					( Origin gFrontEnd )
				)
				( attribute "PACK_TYPE" "RCL_GP"
					( Origin gFrontEnd )
				)
				( attribute "PART_NUMBER" "64.21525.6DL"
					( Origin gFrontEnd )
				)
				( attribute "PHYS_PAGE" "239"
					( Origin gFrontEnd )
				)
				( attribute "RATED" "1/16W"
					( Origin gFrontEnd )
				)
				( attribute "ROT" "0"
					( Origin gFrontEnd )
				)
				( attribute "SEC" "1"
					( Origin gFrontEnd )
				)
				( attribute "SEC_TYPE" "RCL_GP"
					( Origin gFrontEnd )
				)
				( attribute "TOLERANCE" "1%"
					( Origin gFrontEnd )
				)
				( attribute "VALUE" "21K5R2F-GP"
					( Origin gFrontEnd )
				)
				( attribute "VER" "1"
					( Origin gFrontEnd )
				)
				( attribute "XY" "(9925,1325)"
					( Origin gFrontEnd )
				)
				( attribute "CHIPS_PART_NAME" "21K5R2F-GP"
					( Origin gPackager )
				)
				( attribute "CDS_PART_NAME" "21K5R2F-GP_RCL_GP-21K5R2F-GP,6A"
					( Origin gPackager )
				)
				( attribute "PACK_SIZE" "0402"
					( Origin gFrontEnd )
				)
				( attribute "CDS_LOCATION" "R9W31"
					( Origin gPackager )
				)
				( attribute "CDS_SEC" "1"
					( Origin gPackager )
				)
				( objectStatus "R9W31" )
			)
			( gate "@baseboard_fab2_lib.baseboard_fab2(sch_1):page151_i224"
				( attribute "ATTRIBUTE" "120OHM"
					( Origin gFrontEnd )
				)
				( attribute "CDS_LIB" "w_hdl"
					( Origin gPackager )
				)
				( attribute "CDS_LMAN_SYM_OUTLINE" "-50,75,50,-75"
					( Origin gPackager )
				)
				( attribute "LOCATION" "R25W28"
					( Origin gFrontEnd )
				)
				( attribute "PACK_TYPE" "RCL_GP"
					( Origin gFrontEnd )
				)
				( attribute "PART_NUMBER" "64.12005.6DL"
					( Origin gFrontEnd )
				)
				( attribute "PHYS_PAGE" "151"
					( Origin gFrontEnd )
				)
				( attribute "RATED" "1/16W"
					( Origin gFrontEnd )
				)
				( attribute "ROT" "1"
					( Origin gFrontEnd )
				)
				( attribute "TOLERANCE" "1%"
					( Origin gFrontEnd )
				)
				( attribute "VALUE" "120R2F-GP"
					( Origin gFrontEnd )
				)
				( attribute "VER" "1"
					( Origin gFrontEnd )
				)
				( attribute "XY" "(-950,1625)"
					( Origin gFrontEnd )
				)
				( attribute "CHIPS_PART_NAME" "120R2F-GP"
					( Origin gPackager )
				)
				( attribute "CDS_PART_NAME" "120R2F-GP_RCL_GP-120R2F-GP,64.A"
					( Origin gPackager )
				)
				( attribute "SEC" "1"
					( Origin gFrontEnd )
				)
				( attribute "SEC_TYPE" "RCL_GP"
					( Origin gFrontEnd )
				)
				( attribute "PACK_SIZE" "0402"
					( Origin gFrontEnd )
				)
				( attribute "CDS_LOCATION" "R25W28"
					( Origin gPackager )
				)
				( attribute "CDS_SEC" "1"
					( Origin gPackager )
				)
				( objectStatus "R25W28" )
			)
			( gate "@baseboard_fab2_lib.baseboard_fab2(sch_1):page151_i225"
				( attribute "ATTRIBUTE" "120OHM"
					( Origin gFrontEnd )
				)
				( attribute "CDS_LIB" "w_hdl"
					( Origin gPackager )
				)
				( attribute "CDS_LMAN_SYM_OUTLINE" "-50,75,50,-75"
					( Origin gPackager )
				)
				( attribute "LOCATION" "R25W29"
					( Origin gFrontEnd )
				)
				( attribute "PACK_TYPE" "RCL_GP"
					( Origin gFrontEnd )
				)
				( attribute "PART_NUMBER" "64.12005.6DL"
					( Origin gFrontEnd )
				)
				( attribute "PHYS_PAGE" "151"
					( Origin gFrontEnd )
				)
				( attribute "POP" "NOPOP"
					( Origin gFrontEnd )
				)
				( attribute "RATED" "1/16W"
					( Origin gFrontEnd )
				)
				( attribute "ROT" "1"
					( Origin gFrontEnd )
				)
				( attribute "TOLERANCE" "1%"
					( Origin gFrontEnd )
				)
				( attribute "VALUE" "120R2F-GP"
					( Origin gFrontEnd )
				)
				( attribute "VER" "1"
					( Origin gFrontEnd )
				)
				( attribute "XY" "(-950,1575)"
					( Origin gFrontEnd )
				)
				( attribute "CHIPS_PART_NAME" "120R2F-GP"
					( Origin gPackager )
				)
				( attribute "CDS_PART_NAME" "120R2F-GP_RCL_GP-120R2F-GP,64.A"
					( Origin gPackager )
				)
				( attribute "SEC" "1"
					( Origin gFrontEnd )
				)
				( attribute "SEC_TYPE" "RCL_GP"
					( Origin gFrontEnd )
				)
				( attribute "PACK_SIZE" "0402"
					( Origin gFrontEnd )
				)
				( attribute "CDS_LOCATION" "R25W29"
					( Origin gPackager )
				)
				( attribute "CDS_SEC" "1"
					( Origin gPackager )
				)
				( objectStatus "R25W29" )
			)
			( gate "@baseboard_fab2_lib.baseboard_fab2(sch_1):page151_i229"
				( attribute "ATTRIBUTE" "120OHM"
					( Origin gFrontEnd )
				)
				( attribute "CDS_LIB" "w_hdl"
					( Origin gPackager )
				)
				( attribute "CDS_LMAN_SYM_OUTLINE" "-50,75,50,-75"
					( Origin gPackager )
				)
				( attribute "LOCATION" "R25W34"
					( Origin gFrontEnd )
				)
				( attribute "PACK_TYPE" "RCL_GP"
					( Origin gFrontEnd )
				)
				( attribute "PART_NUMBER" "64.12005.6DL"
					( Origin gFrontEnd )
				)
				( attribute "PHYS_PAGE" "151"
					( Origin gFrontEnd )
				)
				( attribute "RATED" "1/16W"
					( Origin gFrontEnd )
				)
				( attribute "ROT" "1"
					( Origin gFrontEnd )
				)
				( attribute "SEC" "1"
					( Origin gFrontEnd )
				)
				( attribute "SEC_TYPE" "RCL_GP"
					( Origin gFrontEnd )
				)
				( attribute "TOLERANCE" "1%"
					( Origin gFrontEnd )
				)
				( attribute "VALUE" "120R2F-GP"
					( Origin gFrontEnd )
				)
				( attribute "VER" "1"
					( Origin gFrontEnd )
				)
				( attribute "XY" "(-950,1325)"
					( Origin gFrontEnd )
				)
				( attribute "CHIPS_PART_NAME" "120R2F-GP"
					( Origin gPackager )
				)
				( attribute "CDS_PART_NAME" "120R2F-GP_RCL_GP-120R2F-GP,64.A"
					( Origin gPackager )
				)
				( attribute "PACK_SIZE" "0402"
					( Origin gFrontEnd )
				)
				( attribute "CDS_LOCATION" "R25W34"
					( Origin gPackager )
				)
				( attribute "CDS_SEC" "1"
					( Origin gPackager )
				)
				( objectStatus "R25W34" )
			)
			( gate "@baseboard_fab2_lib.baseboard_fab2(sch_1):page151_i230"
				( attribute "ATTRIBUTE" "120OHM"
					( Origin gFrontEnd )
				)
				( attribute "CDS_LIB" "w_hdl"
					( Origin gPackager )
				)
				( attribute "CDS_LMAN_SYM_OUTLINE" "-50,75,50,-75"
					( Origin gPackager )
				)
				( attribute "LOCATION" "R25W35"
					( Origin gFrontEnd )
				)
				( attribute "PACK_TYPE" "RCL_GP"
					( Origin gFrontEnd )
				)
				( attribute "PART_NUMBER" "64.12005.6DL"
					( Origin gFrontEnd )
				)
				( attribute "PHYS_PAGE" "151"
					( Origin gFrontEnd )
				)
				( attribute "RATED" "1/16W"
					( Origin gFrontEnd )
				)
				( attribute "ROT" "1"
					( Origin gFrontEnd )
				)
				( attribute "SEC" "1"
					( Origin gFrontEnd )
				)
				( attribute "SEC_TYPE" "RCL_GP"
					( Origin gFrontEnd )
				)
				( attribute "TOLERANCE" "1%"
					( Origin gFrontEnd )
				)
				( attribute "VALUE" "120R2F-GP"
					( Origin gFrontEnd )
				)
				( attribute "VER" "1"
					( Origin gFrontEnd )
				)
				( attribute "XY" "(-950,1275)"
					( Origin gFrontEnd )
				)
				( attribute "CHIPS_PART_NAME" "120R2F-GP"
					( Origin gPackager )
				)
				( attribute "CDS_PART_NAME" "120R2F-GP_RCL_GP-120R2F-GP,64.A"
					( Origin gPackager )
				)
				( attribute "PACK_SIZE" "0402"
					( Origin gFrontEnd )
				)
				( attribute "CDS_LOCATION" "R25W35"
					( Origin gPackager )
				)
				( attribute "CDS_SEC" "1"
					( Origin gPackager )
				)
				( objectStatus "R25W35" )
			)
			( gate "@baseboard_fab2_lib.baseboard_fab2(sch_1):page151_i231"
				( attribute "ATTRIBUTE" "120OHM"
					( Origin gFrontEnd )
				)
				( attribute "CDS_LIB" "w_hdl"
					( Origin gPackager )
				)
				( attribute "CDS_LMAN_SYM_OUTLINE" "-50,75,50,-75"
					( Origin gPackager )
				)
				( attribute "LOCATION" "R25W36"
					( Origin gFrontEnd )
				)
				( attribute "PACK_TYPE" "RCL_GP"
					( Origin gFrontEnd )
				)
				( attribute "PART_NUMBER" "64.12005.6DL"
					( Origin gFrontEnd )
				)
				( attribute "PHYS_PAGE" "151"
					( Origin gFrontEnd )
				)
				( attribute "RATED" "1/16W"
					( Origin gFrontEnd )
				)
				( attribute "ROT" "1"
					( Origin gFrontEnd )
				)
				( attribute "SEC" "1"
					( Origin gFrontEnd )
				)
				( attribute "SEC_TYPE" "RCL_GP"
					( Origin gFrontEnd )
				)
				( attribute "TOLERANCE" "1%"
					( Origin gFrontEnd )
				)
				( attribute "VALUE" "120R2F-GP"
					( Origin gFrontEnd )
				)
				( attribute "VER" "1"
					( Origin gFrontEnd )
				)
				( attribute "XY" "(-950,1225)"
					( Origin gFrontEnd )
				)
				( attribute "CHIPS_PART_NAME" "120R2F-GP"
					( Origin gPackager )
				)
				( attribute "CDS_PART_NAME" "120R2F-GP_RCL_GP-120R2F-GP,64.A"
					( Origin gPackager )
				)
				( attribute "PACK_SIZE" "0402"
					( Origin gFrontEnd )
				)
				( attribute "CDS_LOCATION" "R25W36"
					( Origin gPackager )
				)
				( attribute "CDS_SEC" "1"
					( Origin gPackager )
				)
				( objectStatus "R25W36" )
			)
			( gate "@baseboard_fab2_lib.baseboard_fab2(sch_1):page151_i232"
				( attribute "ATTRIBUTE" "120OHM"
					( Origin gFrontEnd )
				)
				( attribute "CDS_LIB" "w_hdl"
					( Origin gPackager )
				)
				( attribute "CDS_LMAN_SYM_OUTLINE" "-50,75,50,-75"
					( Origin gPackager )
				)
				( attribute "LOCATION" "R25W37"
					( Origin gFrontEnd )
				)
				( attribute "PACK_TYPE" "RCL_GP"
					( Origin gFrontEnd )
				)
				( attribute "PART_NUMBER" "64.12005.6DL"
					( Origin gFrontEnd )
				)
				( attribute "PHYS_PAGE" "151"
					( Origin gFrontEnd )
				)
				( attribute "RATED" "1/16W"
					( Origin gFrontEnd )
				)
				( attribute "ROT" "1"
					( Origin gFrontEnd )
				)
				( attribute "SEC" "1"
					( Origin gFrontEnd )
				)
				( attribute "SEC_TYPE" "RCL_GP"
					( Origin gFrontEnd )
				)
				( attribute "TOLERANCE" "1%"
					( Origin gFrontEnd )
				)
				( attribute "VALUE" "120R2F-GP"
					( Origin gFrontEnd )
				)
				( attribute "VER" "1"
					( Origin gFrontEnd )
				)
				( attribute "XY" "(-950,1175)"
					( Origin gFrontEnd )
				)
				( attribute "CHIPS_PART_NAME" "120R2F-GP"
					( Origin gPackager )
				)
				( attribute "CDS_PART_NAME" "120R2F-GP_RCL_GP-120R2F-GP,64.A"
					( Origin gPackager )
				)
				( attribute "PACK_SIZE" "0402"
					( Origin gFrontEnd )
				)
				( attribute "CDS_LOCATION" "R25W37"
					( Origin gPackager )
				)
				( attribute "CDS_SEC" "1"
					( Origin gPackager )
				)
				( objectStatus "R25W37" )
			)
			( gate "@baseboard_fab2_lib.baseboard_fab2(sch_1):page151_i233"
				( attribute "ATTRIBUTE" "120OHM"
					( Origin gFrontEnd )
				)
				( attribute "CDS_LIB" "w_hdl"
					( Origin gPackager )
				)
				( attribute "CDS_LMAN_SYM_OUTLINE" "-50,75,50,-75"
					( Origin gPackager )
				)
				( attribute "LOCATION" "R25W38"
					( Origin gFrontEnd )
				)
				( attribute "PACK_TYPE" "RCL_GP"
					( Origin gFrontEnd )
				)
				( attribute "PART_NUMBER" "64.12005.6DL"
					( Origin gFrontEnd )
				)
				( attribute "PHYS_PAGE" "151"
					( Origin gFrontEnd )
				)
				( attribute "RATED" "1/16W"
					( Origin gFrontEnd )
				)
				( attribute "ROT" "1"
					( Origin gFrontEnd )
				)
				( attribute "SEC" "1"
					( Origin gFrontEnd )
				)
				( attribute "SEC_TYPE" "RCL_GP"
					( Origin gFrontEnd )
				)
				( attribute "TOLERANCE" "1%"
					( Origin gFrontEnd )
				)
				( attribute "VALUE" "120R2F-GP"
					( Origin gFrontEnd )
				)
				( attribute "VER" "1"
					( Origin gFrontEnd )
				)
				( attribute "XY" "(-950,1125)"
					( Origin gFrontEnd )
				)
				( attribute "CHIPS_PART_NAME" "120R2F-GP"
					( Origin gPackager )
				)
				( attribute "CDS_PART_NAME" "120R2F-GP_RCL_GP-120R2F-GP,64.A"
					( Origin gPackager )
				)
				( attribute "PACK_SIZE" "0402"
					( Origin gFrontEnd )
				)
				( attribute "CDS_LOCATION" "R25W38"
					( Origin gPackager )
				)
				( attribute "CDS_SEC" "1"
					( Origin gPackager )
				)
				( objectStatus "R25W38" )
			)
			( gate "@baseboard_fab2_lib.baseboard_fab2(sch_1):page151_i234"
				( attribute "ATTRIBUTE" "120OHM"
					( Origin gFrontEnd )
				)
				( attribute "CDS_LIB" "w_hdl"
					( Origin gPackager )
				)
				( attribute "CDS_LMAN_SYM_OUTLINE" "-50,75,50,-75"
					( Origin gPackager )
				)
				( attribute "LOCATION" "R25W39"
					( Origin gFrontEnd )
				)
				( attribute "PACK_TYPE" "RCL_GP"
					( Origin gFrontEnd )
				)
				( attribute "PART_NUMBER" "64.12005.6DL"
					( Origin gFrontEnd )
				)
				( attribute "PHYS_PAGE" "151"
					( Origin gFrontEnd )
				)
				( attribute "RATED" "1/16W"
					( Origin gFrontEnd )
				)
				( attribute "ROT" "1"
					( Origin gFrontEnd )
				)
				( attribute "SEC" "1"
					( Origin gFrontEnd )
				)
				( attribute "SEC_TYPE" "RCL_GP"
					( Origin gFrontEnd )
				)
				( attribute "TOLERANCE" "1%"
					( Origin gFrontEnd )
				)
				( attribute "VALUE" "120R2F-GP"
					( Origin gFrontEnd )
				)
				( attribute "VER" "1"
					( Origin gFrontEnd )
				)
				( attribute "XY" "(-950,1075)"
					( Origin gFrontEnd )
				)
				( attribute "CHIPS_PART_NAME" "120R2F-GP"
					( Origin gPackager )
				)
				( attribute "CDS_PART_NAME" "120R2F-GP_RCL_GP-120R2F-GP,64.A"
					( Origin gPackager )
				)
				( attribute "PACK_SIZE" "0402"
					( Origin gFrontEnd )
				)
				( attribute "CDS_LOCATION" "R25W39"
					( Origin gPackager )
				)
				( attribute "CDS_SEC" "1"
					( Origin gPackager )
				)
				( objectStatus "R25W39" )
			)
			( gate "@baseboard_fab2_lib.baseboard_fab2(sch_1):page151_i235"
				( attribute "ATTRIBUTE" "120OHM"
					( Origin gFrontEnd )
				)
				( attribute "CDS_LIB" "w_hdl"
					( Origin gPackager )
				)
				( attribute "CDS_LMAN_SYM_OUTLINE" "-50,75,50,-75"
					( Origin gPackager )
				)
				( attribute "LOCATION" "R25W41"
					( Origin gFrontEnd )
				)
				( attribute "PACK_TYPE" "RCL_GP"
					( Origin gFrontEnd )
				)
				( attribute "PART_NUMBER" "64.12005.6DL"
					( Origin gFrontEnd )
				)
				( attribute "PHYS_PAGE" "151"
					( Origin gFrontEnd )
				)
				( attribute "RATED" "1/16W"
					( Origin gFrontEnd )
				)
				( attribute "ROT" "1"
					( Origin gFrontEnd )
				)
				( attribute "SEC" "1"
					( Origin gFrontEnd )
				)
				( attribute "SEC_TYPE" "RCL_GP"
					( Origin gFrontEnd )
				)
				( attribute "TOLERANCE" "1%"
					( Origin gFrontEnd )
				)
				( attribute "VALUE" "120R2F-GP"
					( Origin gFrontEnd )
				)
				( attribute "VER" "1"
					( Origin gFrontEnd )
				)
				( attribute "XY" "(-950,975)"
					( Origin gFrontEnd )
				)
				( attribute "CHIPS_PART_NAME" "120R2F-GP"
					( Origin gPackager )
				)
				( attribute "CDS_PART_NAME" "120R2F-GP_RCL_GP-120R2F-GP,64.A"
					( Origin gPackager )
				)
				( attribute "PACK_SIZE" "0402"
					( Origin gFrontEnd )
				)
				( attribute "CDS_LOCATION" "R25W41"
					( Origin gPackager )
				)
				( attribute "CDS_SEC" "1"
					( Origin gPackager )
				)
				( objectStatus "R25W41" )
			)
			( gate "@baseboard_fab2_lib.baseboard_fab2(sch_1):page151_i236"
				( attribute "ATTRIBUTE" "120OHM"
					( Origin gFrontEnd )
				)
				( attribute "CDS_LIB" "w_hdl"
					( Origin gPackager )
				)
				( attribute "CDS_LMAN_SYM_OUTLINE" "-50,75,50,-75"
					( Origin gPackager )
				)
				( attribute "LOCATION" "R25W42"
					( Origin gFrontEnd )
				)
				( attribute "PACK_TYPE" "RCL_GP"
					( Origin gFrontEnd )
				)
				( attribute "PART_NUMBER" "64.12005.6DL"
					( Origin gFrontEnd )
				)
				( attribute "PHYS_PAGE" "151"
					( Origin gFrontEnd )
				)
				( attribute "RATED" "1/16W"
					( Origin gFrontEnd )
				)
				( attribute "ROT" "1"
					( Origin gFrontEnd )
				)
				( attribute "SEC" "1"
					( Origin gFrontEnd )
				)
				( attribute "SEC_TYPE" "RCL_GP"
					( Origin gFrontEnd )
				)
				( attribute "TOLERANCE" "1%"
					( Origin gFrontEnd )
				)
				( attribute "VALUE" "120R2F-GP"
					( Origin gFrontEnd )
				)
				( attribute "VER" "1"
					( Origin gFrontEnd )
				)
				( attribute "XY" "(-950,925)"
					( Origin gFrontEnd )
				)
				( attribute "CHIPS_PART_NAME" "120R2F-GP"
					( Origin gPackager )
				)
				( attribute "CDS_PART_NAME" "120R2F-GP_RCL_GP-120R2F-GP,64.A"
					( Origin gPackager )
				)
				( attribute "PACK_SIZE" "0402"
					( Origin gFrontEnd )
				)
				( attribute "CDS_LOCATION" "R25W42"
					( Origin gPackager )
				)
				( attribute "CDS_SEC" "1"
					( Origin gPackager )
				)
				( objectStatus "R25W42" )
			)
			( gate "@baseboard_fab2_lib.baseboard_fab2(sch_1):page151_i237"
				( attribute "ATTRIBUTE" "120OHM"
					( Origin gFrontEnd )
				)
				( attribute "CDS_LIB" "w_hdl"
					( Origin gPackager )
				)
				( attribute "CDS_LMAN_SYM_OUTLINE" "-50,75,50,-75"
					( Origin gPackager )
				)
				( attribute "LOCATION" "R25W44"
					( Origin gFrontEnd )
				)
				( attribute "PACK_TYPE" "RCL_GP"
					( Origin gFrontEnd )
				)
				( attribute "PART_NUMBER" "64.12005.6DL"
					( Origin gFrontEnd )
				)
				( attribute "PHYS_PAGE" "151"
					( Origin gFrontEnd )
				)
				( attribute "RATED" "1/16W"
					( Origin gFrontEnd )
				)
				( attribute "ROT" "1"
					( Origin gFrontEnd )
				)
				( attribute "SEC" "1"
					( Origin gFrontEnd )
				)
				( attribute "SEC_TYPE" "RCL_GP"
					( Origin gFrontEnd )
				)
				( attribute "TOLERANCE" "1%"
					( Origin gFrontEnd )
				)
				( attribute "VALUE" "120R2F-GP"
					( Origin gFrontEnd )
				)
				( attribute "VER" "1"
					( Origin gFrontEnd )
				)
				( attribute "XY" "(-950,825)"
					( Origin gFrontEnd )
				)
				( attribute "CHIPS_PART_NAME" "120R2F-GP"
					( Origin gPackager )
				)
				( attribute "CDS_PART_NAME" "120R2F-GP_RCL_GP-120R2F-GP,64.A"
					( Origin gPackager )
				)
				( attribute "PACK_SIZE" "0402"
					( Origin gFrontEnd )
				)
				( attribute "CDS_LOCATION" "R25W44"
					( Origin gPackager )
				)
				( attribute "CDS_SEC" "1"
					( Origin gPackager )
				)
				( objectStatus "R25W44" )
			)
			( gate "@baseboard_fab2_lib.baseboard_fab2(sch_1):page151_i238"
				( attribute "ATTRIBUTE" "120OHM"
					( Origin gFrontEnd )
				)
				( attribute "CDS_LIB" "w_hdl"
					( Origin gPackager )
				)
				( attribute "CDS_LMAN_SYM_OUTLINE" "-50,75,50,-75"
					( Origin gPackager )
				)
				( attribute "LOCATION" "R25W43"
					( Origin gFrontEnd )
				)
				( attribute "PACK_TYPE" "RCL_GP"
					( Origin gFrontEnd )
				)
				( attribute "PART_NUMBER" "64.12005.6DL"
					( Origin gFrontEnd )
				)
				( attribute "PHYS_PAGE" "151"
					( Origin gFrontEnd )
				)
				( attribute "RATED" "1/16W"
					( Origin gFrontEnd )
				)
				( attribute "ROT" "1"
					( Origin gFrontEnd )
				)
				( attribute "SEC" "1"
					( Origin gFrontEnd )
				)
				( attribute "SEC_TYPE" "RCL_GP"
					( Origin gFrontEnd )
				)
				( attribute "TOLERANCE" "1%"
					( Origin gFrontEnd )
				)
				( attribute "VALUE" "120R2F-GP"
					( Origin gFrontEnd )
				)
				( attribute "VER" "1"
					( Origin gFrontEnd )
				)
				( attribute "XY" "(-950,875)"
					( Origin gFrontEnd )
				)
				( attribute "CHIPS_PART_NAME" "120R2F-GP"
					( Origin gPackager )
				)
				( attribute "CDS_PART_NAME" "120R2F-GP_RCL_GP-120R2F-GP,64.A"
					( Origin gPackager )
				)
				( attribute "PACK_SIZE" "0402"
					( Origin gFrontEnd )
				)
				( attribute "CDS_LOCATION" "R25W43"
					( Origin gPackager )
				)
				( attribute "CDS_SEC" "1"
					( Origin gPackager )
				)
				( objectStatus "R25W43" )
			)
			( gate "@baseboard_fab2_lib.baseboard_fab2(sch_1):page151_i239"
				( attribute "ATTRIBUTE" "120OHM"
					( Origin gFrontEnd )
				)
				( attribute "CDS_LIB" "w_hdl"
					( Origin gPackager )
				)
				( attribute "CDS_LMAN_SYM_OUTLINE" "-50,75,50,-75"
					( Origin gPackager )
				)
				( attribute "LOCATION" "R25W47"
					( Origin gFrontEnd )
				)
				( attribute "PACK_TYPE" "RCL_GP"
					( Origin gFrontEnd )
				)
				( attribute "PART_NUMBER" "64.12005.6DL"
					( Origin gFrontEnd )
				)
				( attribute "PHYS_PAGE" "151"
					( Origin gFrontEnd )
				)
				( attribute "RATED" "1/16W"
					( Origin gFrontEnd )
				)
				( attribute "ROT" "1"
					( Origin gFrontEnd )
				)
				( attribute "SEC" "1"
					( Origin gFrontEnd )
				)
				( attribute "SEC_TYPE" "RCL_GP"
					( Origin gFrontEnd )
				)
				( attribute "TOLERANCE" "1%"
					( Origin gFrontEnd )
				)
				( attribute "VALUE" "120R2F-GP"
					( Origin gFrontEnd )
				)
				( attribute "VER" "1"
					( Origin gFrontEnd )
				)
				( attribute "XY" "(-950,675)"
					( Origin gFrontEnd )
				)
				( attribute "CHIPS_PART_NAME" "120R2F-GP"
					( Origin gPackager )
				)
				( attribute "CDS_PART_NAME" "120R2F-GP_RCL_GP-120R2F-GP,64.A"
					( Origin gPackager )
				)
				( attribute "PACK_SIZE" "0402"
					( Origin gFrontEnd )
				)
				( attribute "CDS_LOCATION" "R25W47"
					( Origin gPackager )
				)
				( attribute "CDS_SEC" "1"
					( Origin gPackager )
				)
				( objectStatus "R25W47" )
			)
			( gate "@baseboard_fab2_lib.baseboard_fab2(sch_1):page151_i240"
				( attribute "ATTRIBUTE" "120OHM"
					( Origin gFrontEnd )
				)
				( attribute "CDS_LIB" "w_hdl"
					( Origin gPackager )
				)
				( attribute "CDS_LMAN_SYM_OUTLINE" "-50,75,50,-75"
					( Origin gPackager )
				)
				( attribute "LOCATION" "R25W48"
					( Origin gFrontEnd )
				)
				( attribute "PACK_TYPE" "RCL_GP"
					( Origin gFrontEnd )
				)
				( attribute "PART_NUMBER" "64.12005.6DL"
					( Origin gFrontEnd )
				)
				( attribute "PHYS_PAGE" "151"
					( Origin gFrontEnd )
				)
				( attribute "RATED" "1/16W"
					( Origin gFrontEnd )
				)
				( attribute "ROT" "1"
					( Origin gFrontEnd )
				)
				( attribute "SEC" "1"
					( Origin gFrontEnd )
				)
				( attribute "SEC_TYPE" "RCL_GP"
					( Origin gFrontEnd )
				)
				( attribute "TOLERANCE" "1%"
					( Origin gFrontEnd )
				)
				( attribute "VALUE" "120R2F-GP"
					( Origin gFrontEnd )
				)
				( attribute "VER" "1"
					( Origin gFrontEnd )
				)
				( attribute "XY" "(-950,625)"
					( Origin gFrontEnd )
				)
				( attribute "CHIPS_PART_NAME" "120R2F-GP"
					( Origin gPackager )
				)
				( attribute "CDS_PART_NAME" "120R2F-GP_RCL_GP-120R2F-GP,64.A"
					( Origin gPackager )
				)
				( attribute "PACK_SIZE" "0402"
					( Origin gFrontEnd )
				)
				( attribute "CDS_LOCATION" "R25W48"
					( Origin gPackager )
				)
				( attribute "CDS_SEC" "1"
					( Origin gPackager )
				)
				( objectStatus "R25W48" )
			)
			( gate "@baseboard_fab2_lib.baseboard_fab2(sch_1):page151_i241"
				( attribute "ATTRIBUTE" "120OHM"
					( Origin gFrontEnd )
				)
				( attribute "CDS_LIB" "w_hdl"
					( Origin gPackager )
				)
				( attribute "CDS_LMAN_SYM_OUTLINE" "-50,75,50,-75"
					( Origin gPackager )
				)
				( attribute "LOCATION" "R25W46"
					( Origin gFrontEnd )
				)
				( attribute "PACK_TYPE" "RCL_GP"
					( Origin gFrontEnd )
				)
				( attribute "PART_NUMBER" "64.12005.6DL"
					( Origin gFrontEnd )
				)
				( attribute "PHYS_PAGE" "151"
					( Origin gFrontEnd )
				)
				( attribute "RATED" "1/16W"
					( Origin gFrontEnd )
				)
				( attribute "ROT" "1"
					( Origin gFrontEnd )
				)
				( attribute "SEC" "1"
					( Origin gFrontEnd )
				)
				( attribute "SEC_TYPE" "RCL_GP"
					( Origin gFrontEnd )
				)
				( attribute "TOLERANCE" "1%"
					( Origin gFrontEnd )
				)
				( attribute "VALUE" "120R2F-GP"
					( Origin gFrontEnd )
				)
				( attribute "VER" "1"
					( Origin gFrontEnd )
				)
				( attribute "XY" "(-950,725)"
					( Origin gFrontEnd )
				)
				( attribute "CHIPS_PART_NAME" "120R2F-GP"
					( Origin gPackager )
				)
				( attribute "CDS_PART_NAME" "120R2F-GP_RCL_GP-120R2F-GP,64.A"
					( Origin gPackager )
				)
				( attribute "PACK_SIZE" "0402"
					( Origin gFrontEnd )
				)
				( attribute "CDS_LOCATION" "R25W46"
					( Origin gPackager )
				)
				( attribute "CDS_SEC" "1"
					( Origin gPackager )
				)
				( objectStatus "R25W46" )
			)
			( gate "@baseboard_fab2_lib.baseboard_fab2(sch_1):page151_i242"
				( attribute "ATTRIBUTE" "120OHM"
					( Origin gFrontEnd )
				)
				( attribute "CDS_LIB" "w_hdl"
					( Origin gPackager )
				)
				( attribute "CDS_LMAN_SYM_OUTLINE" "-50,75,50,-75"
					( Origin gPackager )
				)
				( attribute "LOCATION" "R25W45"
					( Origin gFrontEnd )
				)
				( attribute "PACK_TYPE" "RCL_GP"
					( Origin gFrontEnd )
				)
				( attribute "PART_NUMBER" "64.12005.6DL"
					( Origin gFrontEnd )
				)
				( attribute "PHYS_PAGE" "151"
					( Origin gFrontEnd )
				)
				( attribute "RATED" "1/16W"
					( Origin gFrontEnd )
				)
				( attribute "ROT" "1"
					( Origin gFrontEnd )
				)
				( attribute "SEC" "1"
					( Origin gFrontEnd )
				)
				( attribute "SEC_TYPE" "RCL_GP"
					( Origin gFrontEnd )
				)
				( attribute "TOLERANCE" "1%"
					( Origin gFrontEnd )
				)
				( attribute "VALUE" "120R2F-GP"
					( Origin gFrontEnd )
				)
				( attribute "VER" "1"
					( Origin gFrontEnd )
				)
				( attribute "XY" "(-950,775)"
					( Origin gFrontEnd )
				)
				( attribute "CHIPS_PART_NAME" "120R2F-GP"
					( Origin gPackager )
				)
				( attribute "CDS_PART_NAME" "120R2F-GP_RCL_GP-120R2F-GP,64.A"
					( Origin gPackager )
				)
				( attribute "PACK_SIZE" "0402"
					( Origin gFrontEnd )
				)
				( attribute "CDS_LOCATION" "R25W45"
					( Origin gPackager )
				)
				( attribute "CDS_SEC" "1"
					( Origin gPackager )
				)
				( objectStatus "R25W45" )
			)
			( gate "@baseboard_fab2_lib.baseboard_fab2(sch_1):page151_i243"
				( attribute "ATTRIBUTE" "120OHM"
					( Origin gFrontEnd )
				)
				( attribute "CDS_LIB" "w_hdl"
					( Origin gPackager )
				)
				( attribute "CDS_LMAN_SYM_OUTLINE" "-50,75,50,-75"
					( Origin gPackager )
				)
				( attribute "LOCATION" "R25W49"
					( Origin gFrontEnd )
				)
				( attribute "PACK_TYPE" "RCL_GP"
					( Origin gFrontEnd )
				)
				( attribute "PART_NUMBER" "64.12005.6DL"
					( Origin gFrontEnd )
				)
				( attribute "PHYS_PAGE" "151"
					( Origin gFrontEnd )
				)
				( attribute "RATED" "1/16W"
					( Origin gFrontEnd )
				)
				( attribute "ROT" "1"
					( Origin gFrontEnd )
				)
				( attribute "SEC" "1"
					( Origin gFrontEnd )
				)
				( attribute "SEC_TYPE" "RCL_GP"
					( Origin gFrontEnd )
				)
				( attribute "TOLERANCE" "1%"
					( Origin gFrontEnd )
				)
				( attribute "VALUE" "120R2F-GP"
					( Origin gFrontEnd )
				)
				( attribute "VER" "1"
					( Origin gFrontEnd )
				)
				( attribute "XY" "(-950,575)"
					( Origin gFrontEnd )
				)
				( attribute "CHIPS_PART_NAME" "120R2F-GP"
					( Origin gPackager )
				)
				( attribute "CDS_PART_NAME" "120R2F-GP_RCL_GP-120R2F-GP,64.A"
					( Origin gPackager )
				)
				( attribute "PACK_SIZE" "0402"
					( Origin gFrontEnd )
				)
				( attribute "CDS_LOCATION" "R25W49"
					( Origin gPackager )
				)
				( attribute "CDS_SEC" "1"
					( Origin gPackager )
				)
				( objectStatus "R25W49" )
			)
			( gate "@baseboard_fab2_lib.baseboard_fab2(sch_1):page151_i244"
				( attribute "ATTRIBUTE" "120OHM"
					( Origin gFrontEnd )
				)
				( attribute "CDS_LIB" "w_hdl"
					( Origin gPackager )
				)
				( attribute "CDS_LMAN_SYM_OUTLINE" "-50,75,50,-75"
					( Origin gPackager )
				)
				( attribute "LOCATION" "R25W50"
					( Origin gFrontEnd )
				)
				( attribute "PACK_TYPE" "RCL_GP"
					( Origin gFrontEnd )
				)
				( attribute "PART_NUMBER" "64.12005.6DL"
					( Origin gFrontEnd )
				)
				( attribute "PHYS_PAGE" "151"
					( Origin gFrontEnd )
				)
				( attribute "RATED" "1/16W"
					( Origin gFrontEnd )
				)
				( attribute "ROT" "1"
					( Origin gFrontEnd )
				)
				( attribute "SEC" "1"
					( Origin gFrontEnd )
				)
				( attribute "SEC_TYPE" "RCL_GP"
					( Origin gFrontEnd )
				)
				( attribute "TOLERANCE" "1%"
					( Origin gFrontEnd )
				)
				( attribute "VALUE" "120R2F-GP"
					( Origin gFrontEnd )
				)
				( attribute "VER" "1"
					( Origin gFrontEnd )
				)
				( attribute "XY" "(-950,525)"
					( Origin gFrontEnd )
				)
				( attribute "CHIPS_PART_NAME" "120R2F-GP"
					( Origin gPackager )
				)
				( attribute "CDS_PART_NAME" "120R2F-GP_RCL_GP-120R2F-GP,64.A"
					( Origin gPackager )
				)
				( attribute "PACK_SIZE" "0402"
					( Origin gFrontEnd )
				)
				( attribute "CDS_LOCATION" "R25W50"
					( Origin gPackager )
				)
				( attribute "CDS_SEC" "1"
					( Origin gPackager )
				)
				( objectStatus "R25W50" )
			)
			( gate "@baseboard_fab2_lib.baseboard_fab2(sch_1):page151_i245"
				( attribute "ATTRIBUTE" "120OHM"
					( Origin gFrontEnd )
				)
				( attribute "CDS_LIB" "w_hdl"
					( Origin gPackager )
				)
				( attribute "CDS_LMAN_SYM_OUTLINE" "-50,75,50,-75"
					( Origin gPackager )
				)
				( attribute "LOCATION" "R25W51"
					( Origin gFrontEnd )
				)
				( attribute "PACK_TYPE" "RCL_GP"
					( Origin gFrontEnd )
				)
				( attribute "PART_NUMBER" "64.12005.6DL"
					( Origin gFrontEnd )
				)
				( attribute "PHYS_PAGE" "151"
					( Origin gFrontEnd )
				)
				( attribute "RATED" "1/16W"
					( Origin gFrontEnd )
				)
				( attribute "ROT" "1"
					( Origin gFrontEnd )
				)
				( attribute "SEC" "1"
					( Origin gFrontEnd )
				)
				( attribute "SEC_TYPE" "RCL_GP"
					( Origin gFrontEnd )
				)
				( attribute "TOLERANCE" "1%"
					( Origin gFrontEnd )
				)
				( attribute "VALUE" "120R2F-GP"
					( Origin gFrontEnd )
				)
				( attribute "VER" "1"
					( Origin gFrontEnd )
				)
				( attribute "XY" "(-950,475)"
					( Origin gFrontEnd )
				)
				( attribute "CHIPS_PART_NAME" "120R2F-GP"
					( Origin gPackager )
				)
				( attribute "CDS_PART_NAME" "120R2F-GP_RCL_GP-120R2F-GP,64.A"
					( Origin gPackager )
				)
				( attribute "PACK_SIZE" "0402"
					( Origin gFrontEnd )
				)
				( attribute "CDS_LOCATION" "R25W51"
					( Origin gPackager )
				)
				( attribute "CDS_SEC" "1"
					( Origin gPackager )
				)
				( objectStatus "R25W51" )
			)
			( gate "@baseboard_fab2_lib.baseboard_fab2(sch_1):page151_i246"
				( attribute "ATTRIBUTE" "120OHM"
					( Origin gFrontEnd )
				)
				( attribute "CDS_LIB" "w_hdl"
					( Origin gPackager )
				)
				( attribute "CDS_LMAN_SYM_OUTLINE" "-50,75,50,-75"
					( Origin gPackager )
				)
				( attribute "LOCATION" "R25W52"
					( Origin gFrontEnd )
				)
				( attribute "PACK_TYPE" "RCL_GP"
					( Origin gFrontEnd )
				)
				( attribute "PART_NUMBER" "64.12005.6DL"
					( Origin gFrontEnd )
				)
				( attribute "PHYS_PAGE" "151"
					( Origin gFrontEnd )
				)
				( attribute "RATED" "1/16W"
					( Origin gFrontEnd )
				)
				( attribute "ROT" "1"
					( Origin gFrontEnd )
				)
				( attribute "SEC" "1"
					( Origin gFrontEnd )
				)
				( attribute "SEC_TYPE" "RCL_GP"
					( Origin gFrontEnd )
				)
				( attribute "TOLERANCE" "1%"
					( Origin gFrontEnd )
				)
				( attribute "VALUE" "120R2F-GP"
					( Origin gFrontEnd )
				)
				( attribute "VER" "1"
					( Origin gFrontEnd )
				)
				( attribute "XY" "(-950,425)"
					( Origin gFrontEnd )
				)
				( attribute "CHIPS_PART_NAME" "120R2F-GP"
					( Origin gPackager )
				)
				( attribute "CDS_PART_NAME" "120R2F-GP_RCL_GP-120R2F-GP,64.A"
					( Origin gPackager )
				)
				( attribute "PACK_SIZE" "0402"
					( Origin gFrontEnd )
				)
				( attribute "CDS_LOCATION" "R25W52"
					( Origin gPackager )
				)
				( attribute "CDS_SEC" "1"
					( Origin gPackager )
				)
				( objectStatus "R25W52" )
			)
			( gate "@baseboard_fab2_lib.baseboard_fab2(sch_1):page151_i247"
				( attribute "ATTRIBUTE" "120OHM"
					( Origin gFrontEnd )
				)
				( attribute "CDS_LIB" "w_hdl"
					( Origin gPackager )
				)
				( attribute "CDS_LMAN_SYM_OUTLINE" "-50,75,50,-75"
					( Origin gPackager )
				)
				( attribute "LOCATION" "R25W40"
					( Origin gFrontEnd )
				)
				( attribute "PACK_TYPE" "RCL_GP"
					( Origin gFrontEnd )
				)
				( attribute "PART_NUMBER" "64.12005.6DL"
					( Origin gFrontEnd )
				)
				( attribute "PHYS_PAGE" "151"
					( Origin gFrontEnd )
				)
				( attribute "RATED" "1/16W"
					( Origin gFrontEnd )
				)
				( attribute "ROT" "1"
					( Origin gFrontEnd )
				)
				( attribute "SEC" "1"
					( Origin gFrontEnd )
				)
				( attribute "SEC_TYPE" "RCL_GP"
					( Origin gFrontEnd )
				)
				( attribute "TOLERANCE" "1%"
					( Origin gFrontEnd )
				)
				( attribute "VALUE" "120R2F-GP"
					( Origin gFrontEnd )
				)
				( attribute "VER" "1"
					( Origin gFrontEnd )
				)
				( attribute "XY" "(-950,1025)"
					( Origin gFrontEnd )
				)
				( attribute "CHIPS_PART_NAME" "120R2F-GP"
					( Origin gPackager )
				)
				( attribute "CDS_PART_NAME" "120R2F-GP_RCL_GP-120R2F-GP,64.A"
					( Origin gPackager )
				)
				( attribute "PACK_SIZE" "0402"
					( Origin gFrontEnd )
				)
				( attribute "CDS_LOCATION" "R25W40"
					( Origin gPackager )
				)
				( attribute "CDS_SEC" "1"
					( Origin gPackager )
				)
				( objectStatus "R25W40" )
			)
			( gate "@baseboard_fab2_lib.baseboard_fab2(sch_1):page151_i270"
				( attribute "ATTRIBUTE" "120OHM"
					( Origin gFrontEnd )
				)
				( attribute "CDS_LIB" "w_hdl"
					( Origin gPackager )
				)
				( attribute "CDS_LMAN_SYM_OUTLINE" "-50,75,50,-75"
					( Origin gPackager )
				)
				( attribute "LOCATION" "R25W22"
					( Origin gFrontEnd )
				)
				( attribute "PACK_TYPE" "RCL_GP"
					( Origin gFrontEnd )
				)
				( attribute "PART_NUMBER" "64.12005.6DL"
					( Origin gFrontEnd )
				)
				( attribute "PHYS_PAGE" "151"
					( Origin gFrontEnd )
				)
				( attribute "RATED" "1/16W"
					( Origin gFrontEnd )
				)
				( attribute "ROT" "1"
					( Origin gFrontEnd )
				)
				( attribute "SEC" "1"
					( Origin gFrontEnd )
				)
				( attribute "SEC_TYPE" "RCL_GP"
					( Origin gFrontEnd )
				)
				( attribute "TOLERANCE" "1%"
					( Origin gFrontEnd )
				)
				( attribute "VALUE" "120R2F-GP"
					( Origin gFrontEnd )
				)
				( attribute "VER" "1"
					( Origin gFrontEnd )
				)
				( attribute "XY" "(-3025,625)"
					( Origin gFrontEnd )
				)
				( attribute "CHIPS_PART_NAME" "120R2F-GP"
					( Origin gPackager )
				)
				( attribute "CDS_PART_NAME" "120R2F-GP_RCL_GP-120R2F-GP,64.A"
					( Origin gPackager )
				)
				( attribute "PACK_SIZE" "0402"
					( Origin gFrontEnd )
				)
				( attribute "CDS_LOCATION" "R25W22"
					( Origin gPackager )
				)
				( attribute "CDS_SEC" "1"
					( Origin gPackager )
				)
				( objectStatus "R25W22" )
			)
			( gate "@baseboard_fab2_lib.baseboard_fab2(sch_1):page151_i271"
				( attribute "ATTRIBUTE" "120OHM"
					( Origin gFrontEnd )
				)
				( attribute "CDS_LIB" "w_hdl"
					( Origin gPackager )
				)
				( attribute "CDS_LMAN_SYM_OUTLINE" "-50,75,50,-75"
					( Origin gPackager )
				)
				( attribute "LOCATION" "R25W21"
					( Origin gFrontEnd )
				)
				( attribute "PACK_TYPE" "RCL_GP"
					( Origin gFrontEnd )
				)
				( attribute "PART_NUMBER" "64.12005.6DL"
					( Origin gFrontEnd )
				)
				( attribute "PHYS_PAGE" "151"
					( Origin gFrontEnd )
				)
				( attribute "RATED" "1/16W"
					( Origin gFrontEnd )
				)
				( attribute "ROT" "1"
					( Origin gFrontEnd )
				)
				( attribute "SEC" "1"
					( Origin gFrontEnd )
				)
				( attribute "SEC_TYPE" "RCL_GP"
					( Origin gFrontEnd )
				)
				( attribute "TOLERANCE" "1%"
					( Origin gFrontEnd )
				)
				( attribute "VALUE" "120R2F-GP"
					( Origin gFrontEnd )
				)
				( attribute "VER" "1"
					( Origin gFrontEnd )
				)
				( attribute "XY" "(-3025,675)"
					( Origin gFrontEnd )
				)
				( attribute "CHIPS_PART_NAME" "120R2F-GP"
					( Origin gPackager )
				)
				( attribute "CDS_PART_NAME" "120R2F-GP_RCL_GP-120R2F-GP,64.A"
					( Origin gPackager )
				)
				( attribute "PACK_SIZE" "0402"
					( Origin gFrontEnd )
				)
				( attribute "CDS_LOCATION" "R25W21"
					( Origin gPackager )
				)
				( attribute "CDS_SEC" "1"
					( Origin gPackager )
				)
				( objectStatus "R25W21" )
			)
			( gate "@baseboard_fab2_lib.baseboard_fab2(sch_1):page151_i274"
				( attribute "ATTRIBUTE" "120OHM"
					( Origin gFrontEnd )
				)
				( attribute "CDS_LIB" "w_hdl"
					( Origin gPackager )
				)
				( attribute "CDS_LMAN_SYM_OUTLINE" "-50,75,50,-75"
					( Origin gPackager )
				)
				( attribute "LOCATION" "R25W26"
					( Origin gFrontEnd )
				)
				( attribute "PACK_TYPE" "RCL_GP"
					( Origin gFrontEnd )
				)
				( attribute "PART_NUMBER" "64.12005.6DL"
					( Origin gFrontEnd )
				)
				( attribute "PHYS_PAGE" "151"
					( Origin gFrontEnd )
				)
				( attribute "RATED" "1/16W"
					( Origin gFrontEnd )
				)
				( attribute "ROT" "1"
					( Origin gFrontEnd )
				)
				( attribute "SEC" "1"
					( Origin gFrontEnd )
				)
				( attribute "SEC_TYPE" "RCL_GP"
					( Origin gFrontEnd )
				)
				( attribute "TOLERANCE" "1%"
					( Origin gFrontEnd )
				)
				( attribute "VALUE" "120R2F-GP"
					( Origin gFrontEnd )
				)
				( attribute "VER" "1"
					( Origin gFrontEnd )
				)
				( attribute "XY" "(-3025,425)"
					( Origin gFrontEnd )
				)
				( attribute "CHIPS_PART_NAME" "120R2F-GP"
					( Origin gPackager )
				)
				( attribute "CDS_PART_NAME" "120R2F-GP_RCL_GP-120R2F-GP,64.A"
					( Origin gPackager )
				)
				( attribute "PACK_SIZE" "0402"
					( Origin gFrontEnd )
				)
				( attribute "CDS_LOCATION" "R25W26"
					( Origin gPackager )
				)
				( attribute "CDS_SEC" "1"
					( Origin gPackager )
				)
				( objectStatus "R25W26" )
			)
			( gate "@baseboard_fab2_lib.baseboard_fab2(sch_1):page151_i275"
				( attribute "ATTRIBUTE" "120OHM"
					( Origin gFrontEnd )
				)
				( attribute "CDS_LIB" "w_hdl"
					( Origin gPackager )
				)
				( attribute "CDS_LMAN_SYM_OUTLINE" "-50,75,50,-75"
					( Origin gPackager )
				)
				( attribute "LOCATION" "R25W25"
					( Origin gFrontEnd )
				)
				( attribute "PACK_TYPE" "RCL_GP"
					( Origin gFrontEnd )
				)
				( attribute "PART_NUMBER" "64.12005.6DL"
					( Origin gFrontEnd )
				)
				( attribute "PHYS_PAGE" "151"
					( Origin gFrontEnd )
				)
				( attribute "RATED" "1/16W"
					( Origin gFrontEnd )
				)
				( attribute "ROT" "1"
					( Origin gFrontEnd )
				)
				( attribute "SEC" "1"
					( Origin gFrontEnd )
				)
				( attribute "SEC_TYPE" "RCL_GP"
					( Origin gFrontEnd )
				)
				( attribute "TOLERANCE" "1%"
					( Origin gFrontEnd )
				)
				( attribute "VALUE" "120R2F-GP"
					( Origin gFrontEnd )
				)
				( attribute "VER" "1"
					( Origin gFrontEnd )
				)
				( attribute "XY" "(-3025,475)"
					( Origin gFrontEnd )
				)
				( attribute "CHIPS_PART_NAME" "120R2F-GP"
					( Origin gPackager )
				)
				( attribute "CDS_PART_NAME" "120R2F-GP_RCL_GP-120R2F-GP,64.A"
					( Origin gPackager )
				)
				( attribute "PACK_SIZE" "0402"
					( Origin gFrontEnd )
				)
				( attribute "CDS_LOCATION" "R25W25"
					( Origin gPackager )
				)
				( attribute "CDS_SEC" "1"
					( Origin gPackager )
				)
				( objectStatus "R25W25" )
			)
			( gate "@baseboard_fab2_lib.baseboard_fab2(sch_1):page226_i73"
				( attribute "CDS_LIB" "mstr_discrete"
					( Origin gPackager )
				)
				( attribute "CDS_LOCATION" "R1B15"
					( Origin gPackager )
				)
				( attribute "CDS_SEC" "1"
					( Origin gPackager )
				)
				( attribute "LOCATION" "R1B15"
					( Origin gFrontEnd )
				)
				( attribute "MATERIAL" "CHIP"
					( Origin gFrontEnd )
				)
				( attribute "PACK_TYPE" "0402"
					( Origin gFrontEnd )
				)
				( attribute "PART_NUMBER" "G21796-043"
					( Origin gFrontEnd )
				)
				( attribute "PHYS_PAGE" "226"
					( Origin gFrontEnd )
				)
				( attribute "ROOM" "PVCCIN_CPU1_VR"
					( Origin gFrontEnd )
				)
				( attribute "ROT" "0"
					( Origin gFrontEnd )
				)
				( attribute "SEC" "1"
					( Origin gFrontEnd )
				)
				( attribute "SEC_TYPE" "0402"
					( Origin gFrontEnd )
				)
				( attribute "TOLERANCE" "1%"
					( Origin gFrontEnd )
				)
				( attribute "VALUE" "3.16K"
					( Origin gFrontEnd )
				)
				( attribute "VER" "2"
					( Origin gFrontEnd )
				)
				( attribute "WATTAGE" "1/16W"
					( Origin gFrontEnd )
				)
				( attribute "XY" "(325,-600)"
					( Origin gFrontEnd )
				)
				( attribute "CHIPS_PART_NAME" "RES"
					( Origin gPackager )
				)
				( attribute "CDS_PART_NAME" "RES_0402-3.16K,1%,1/16W,CHIP,GA"
					( Origin gPackager )
				)
				( objectStatus "R1B15" )
			)
			( gate "@baseboard_fab2_lib.baseboard_fab2(sch_1):page247_i159"
				( attribute "BOM_COST" "SM_THERM"
					( Origin gFrontEnd )
				)
				( attribute "CDS_LIB" "mstr_discrete"
					( Origin gPackager )
				)
				( attribute "CDS_LOCATION" "R6W4"
					( Origin gPackager )
				)
				( attribute "CDS_SEC" "1"
					( Origin gPackager )
				)
				( attribute "LOCATION" "R6W4"
					( Origin gFrontEnd )
				)
				( attribute "MATERIAL" "CHIP"
					( Origin gFrontEnd )
				)
				( attribute "PACK_TYPE" "0402"
					( Origin gFrontEnd )
				)
				( attribute "PART_NUMBER" "G21796-072"
					( Origin gFrontEnd )
				)
				( attribute "PHYS_PAGE" "247"
					( Origin gFrontEnd )
				)
				( attribute "ROOM" "CPU_FANS"
					( Origin gFrontEnd )
				)
				( attribute "ROT" "2"
					( Origin gFrontEnd )
				)
				( attribute "SEC" "1"
					( Origin gFrontEnd )
				)
				( attribute "SEC_TYPE" "0402"
					( Origin gFrontEnd )
				)
				( attribute "TOLERANCE" "1%"
					( Origin gFrontEnd )
				)
				( attribute "VALUE" "4.75K"
					( Origin gFrontEnd )
				)
				( attribute "VER" "2"
					( Origin gFrontEnd )
				)
				( attribute "WATTAGE" "1/16W"
					( Origin gFrontEnd )
				)
				( attribute "XY" "(-6600,4200)"
					( Origin gFrontEnd )
				)
				( attribute "CHIPS_PART_NAME" "RES"
					( Origin gPackager )
				)
				( attribute "CDS_PART_NAME" "RES_0402-4.75K,1%,1/16W,CHIP,GA"
					( Origin gPackager )
				)
				( objectStatus "R6W4" )
			)
			( gate "@baseboard_fab2_lib.baseboard_fab2(sch_1):page247_i160"
				( attribute "BOM_COST" "SM_THERM"
					( Origin gFrontEnd )
				)
				( attribute "CDS_LIB" "mstr_discrete"
					( Origin gPackager )
				)
				( attribute "CDS_LOCATION" "R6W5"
					( Origin gPackager )
				)
				( attribute "CDS_SEC" "1"
					( Origin gPackager )
				)
				( attribute "LOCATION" "R6W5"
					( Origin gFrontEnd )
				)
				( attribute "MATERIAL" "CHIP"
					( Origin gFrontEnd )
				)
				( attribute "PACK_TYPE" "0402"
					( Origin gFrontEnd )
				)
				( attribute "PART_NUMBER" "G21796-072"
					( Origin gFrontEnd )
				)
				( attribute "PHYS_PAGE" "247"
					( Origin gFrontEnd )
				)
				( attribute "ROOM" "CPU_FANS"
					( Origin gFrontEnd )
				)
				( attribute "ROT" "2"
					( Origin gFrontEnd )
				)
				( attribute "SEC" "1"
					( Origin gFrontEnd )
				)
				( attribute "SEC_TYPE" "0402"
					( Origin gFrontEnd )
				)
				( attribute "TOLERANCE" "1%"
					( Origin gFrontEnd )
				)
				( attribute "VALUE" "4.75K"
					( Origin gFrontEnd )
				)
				( attribute "VER" "2"
					( Origin gFrontEnd )
				)
				( attribute "WATTAGE" "1/16W"
					( Origin gFrontEnd )
				)
				( attribute "XY" "(-6250,4200)"
					( Origin gFrontEnd )
				)
				( attribute "CHIPS_PART_NAME" "RES"
					( Origin gPackager )
				)
				( attribute "CDS_PART_NAME" "RES_0402-4.75K,1%,1/16W,CHIP,GA"
					( Origin gPackager )
				)
				( objectStatus "R6W5" )
			)
			( gate "@baseboard_fab2_lib.baseboard_fab2(sch_1):page247_i161"
				( attribute "BOM_COST" "SM_THERM"
					( Origin gFrontEnd )
				)
				( attribute "CDS_LIB" "mstr_discrete"
					( Origin gPackager )
				)
				( attribute "CDS_LOCATION" "R6W6"
					( Origin gPackager )
				)
				( attribute "CDS_SEC" "1"
					( Origin gPackager )
				)
				( attribute "LOCATION" "R6W6"
					( Origin gFrontEnd )
				)
				( attribute "MATERIAL" "CHIP"
					( Origin gFrontEnd )
				)
				( attribute "PACK_TYPE" "0402"
					( Origin gFrontEnd )
				)
				( attribute "PART_NUMBER" "G21796-072"
					( Origin gFrontEnd )
				)
				( attribute "PHYS_PAGE" "247"
					( Origin gFrontEnd )
				)
				( attribute "ROOM" "CPU_FANS"
					( Origin gFrontEnd )
				)
				( attribute "ROT" "2"
					( Origin gFrontEnd )
				)
				( attribute "SEC" "1"
					( Origin gFrontEnd )
				)
				( attribute "SEC_TYPE" "0402"
					( Origin gFrontEnd )
				)
				( attribute "TOLERANCE" "1%"
					( Origin gFrontEnd )
				)
				( attribute "VALUE" "4.75K"
					( Origin gFrontEnd )
				)
				( attribute "VER" "2"
					( Origin gFrontEnd )
				)
				( attribute "WATTAGE" "1/16W"
					( Origin gFrontEnd )
				)
				( attribute "XY" "(-5900,4200)"
					( Origin gFrontEnd )
				)
				( attribute "CHIPS_PART_NAME" "RES"
					( Origin gPackager )
				)
				( attribute "CDS_PART_NAME" "RES_0402-4.75K,1%,1/16W,CHIP,GA"
					( Origin gPackager )
				)
				( objectStatus "R6W6" )
			)
			( gate "@baseboard_fab2_lib.baseboard_fab2(sch_1):page247_i162"
				( attribute "CDS_LIB" "mstr_discrete"
					( Origin gPackager )
				)
				( attribute "CDS_LOCATION" "R6W9"
					( Origin gPackager )
				)
				( attribute "CDS_SEC" "1"
					( Origin gPackager )
				)
				( attribute "LOCATION" "R6W9"
					( Origin gFrontEnd )
				)
				( attribute "MATERIAL" "EMPTY"
					( Origin gFrontEnd )
				)
				( attribute "NO_XNET_CONNECTION" "1"
					( Origin gFrontEnd )
				)
				( attribute "PACK_TYPE" "0402"
					( Origin gFrontEnd )
				)
				( attribute "PART_NUMBER" "G21796-072"
					( Origin gFrontEnd )
				)
				( attribute "PHYS_PAGE" "247"
					( Origin gFrontEnd )
				)
				( attribute "ROOM" "HOT_SWAP"
					( Origin gFrontEnd )
				)
				( attribute "ROT" "0"
					( Origin gFrontEnd )
				)
				( attribute "SEC" "1"
					( Origin gFrontEnd )
				)
				( attribute "SEC_TYPE" "0402"
					( Origin gFrontEnd )
				)
				( attribute "TOLERANCE" "1%"
					( Origin gFrontEnd )
				)
				( attribute "VALUE" "4.75K"
					( Origin gFrontEnd )
				)
				( attribute "VER" "2"
					( Origin gFrontEnd )
				)
				( attribute "WATTAGE" "1/16W"
					( Origin gFrontEnd )
				)
				( attribute "XY" "(-5900,3650)"
					( Origin gFrontEnd )
				)
				( attribute "CHIPS_PART_NAME" "RES"
					( Origin gPackager )
				)
				( attribute "CDS_PART_NAME" "RES_0402-4.75K,1%,1/16W,EMPTY,A"
					( Origin gPackager )
				)
				( objectStatus "R6W9" )
			)
			( gate "@baseboard_fab2_lib.baseboard_fab2(sch_1):page247_i163"
				( attribute "CDS_LIB" "mstr_discrete"
					( Origin gPackager )
				)
				( attribute "CDS_LOCATION" "R6W8"
					( Origin gPackager )
				)
				( attribute "CDS_SEC" "1"
					( Origin gPackager )
				)
				( attribute "LOCATION" "R6W8"
					( Origin gFrontEnd )
				)
				( attribute "MATERIAL" "EMPTY"
					( Origin gFrontEnd )
				)
				( attribute "NO_XNET_CONNECTION" "1"
					( Origin gFrontEnd )
				)
				( attribute "PACK_TYPE" "0402"
					( Origin gFrontEnd )
				)
				( attribute "PART_NUMBER" "G21796-072"
					( Origin gFrontEnd )
				)
				( attribute "PHYS_PAGE" "247"
					( Origin gFrontEnd )
				)
				( attribute "ROOM" "HOT_SWAP"
					( Origin gFrontEnd )
				)
				( attribute "ROT" "0"
					( Origin gFrontEnd )
				)
				( attribute "SEC" "1"
					( Origin gFrontEnd )
				)
				( attribute "SEC_TYPE" "0402"
					( Origin gFrontEnd )
				)
				( attribute "TOLERANCE" "1%"
					( Origin gFrontEnd )
				)
				( attribute "VALUE" "4.75K"
					( Origin gFrontEnd )
				)
				( attribute "VER" "2"
					( Origin gFrontEnd )
				)
				( attribute "WATTAGE" "1/16W"
					( Origin gFrontEnd )
				)
				( attribute "XY" "(-6250,3650)"
					( Origin gFrontEnd )
				)
				( attribute "CHIPS_PART_NAME" "RES"
					( Origin gPackager )
				)
				( attribute "CDS_PART_NAME" "RES_0402-4.75K,1%,1/16W,EMPTY,A"
					( Origin gPackager )
				)
				( objectStatus "R6W8" )
			)
			( gate "@baseboard_fab2_lib.baseboard_fab2(sch_1):page247_i164"
				( attribute "CDS_LIB" "mstr_discrete"
					( Origin gPackager )
				)
				( attribute "CDS_LOCATION" "R6W7"
					( Origin gPackager )
				)
				( attribute "CDS_SEC" "1"
					( Origin gPackager )
				)
				( attribute "LOCATION" "R6W7"
					( Origin gFrontEnd )
				)
				( attribute "MATERIAL" "EMPTY"
					( Origin gFrontEnd )
				)
				( attribute "NO_XNET_CONNECTION" "1"
					( Origin gFrontEnd )
				)
				( attribute "PACK_TYPE" "0402"
					( Origin gFrontEnd )
				)
				( attribute "PART_NUMBER" "G21796-072"
					( Origin gFrontEnd )
				)
				( attribute "PHYS_PAGE" "247"
					( Origin gFrontEnd )
				)
				( attribute "ROOM" "HOT_SWAP"
					( Origin gFrontEnd )
				)
				( attribute "ROT" "0"
					( Origin gFrontEnd )
				)
				( attribute "SEC" "1"
					( Origin gFrontEnd )
				)
				( attribute "SEC_TYPE" "0402"
					( Origin gFrontEnd )
				)
				( attribute "TOLERANCE" "1%"
					( Origin gFrontEnd )
				)
				( attribute "VALUE" "4.75K"
					( Origin gFrontEnd )
				)
				( attribute "VER" "2"
					( Origin gFrontEnd )
				)
				( attribute "WATTAGE" "1/16W"
					( Origin gFrontEnd )
				)
				( attribute "XY" "(-6600,3650)"
					( Origin gFrontEnd )
				)
				( attribute "CHIPS_PART_NAME" "RES"
					( Origin gPackager )
				)
				( attribute "CDS_PART_NAME" "RES_0402-4.75K,1%,1/16W,EMPTY,A"
					( Origin gPackager )
				)
				( objectStatus "R6W7" )
			)
			( gate "@baseboard_fab2_lib.baseboard_fab2(sch_1):page151_i278"
				( attribute "BOM_COST" "PROC_SOCKET"
					( Origin gFrontEnd )
				)
				( attribute "CDS_LIB" "mstr_discrete"
					( Origin gPackager )
				)
				( attribute "CDS_LOCATION" "R1T40"
					( Origin gPackager )
				)
				( attribute "CDS_SEC" "1"
					( Origin gPackager )
				)
				( attribute "LOCATION" "R1T40"
					( Origin gFrontEnd )
				)
				( attribute "MATERIAL" "CHIP"
					( Origin gFrontEnd )
				)
				( attribute "PACK_TYPE" "0402"
					( Origin gFrontEnd )
				)
				( attribute "PART_NUMBER" "G21796-047"
					( Origin gFrontEnd )
				)
				( attribute "PHYS_PAGE" "151"
					( Origin gFrontEnd )
				)
				( attribute "ROOM" "CPU0"
					( Origin gFrontEnd )
				)
				( attribute "ROT" "0"
					( Origin gFrontEnd )
				)
				( attribute "SEC" "1"
					( Origin gFrontEnd )
				)
				( attribute "SEC_TYPE" "0402"
					( Origin gFrontEnd )
				)
				( attribute "TOLERANCE" "1%"
					( Origin gFrontEnd )
				)
				( attribute "VALUE" "49.9"
					( Origin gFrontEnd )
				)
				( attribute "VER" "1"
					( Origin gFrontEnd )
				)
				( attribute "WATTAGE" "1/16W"
					( Origin gFrontEnd )
				)
				( attribute "XY" "(1250,-1550)"
					( Origin gFrontEnd )
				)
				( attribute "CHIPS_PART_NAME" "RES"
					( Origin gPackager )
				)
				( attribute "CDS_PART_NAME" "RES_0402-49.9,1%,1/16W,CHIP,G2A"
					( Origin gPackager )
				)
				( objectStatus "R1T40" )
			)
			( gate "@baseboard_fab2_lib.baseboard_fab2(sch_1):page151_i279"
				( attribute "BOM_COST" "PROC_SOCKET"
					( Origin gFrontEnd )
				)
				( attribute "CDS_LIB" "mstr_discrete"
					( Origin gPackager )
				)
				( attribute "CDS_LOCATION" "R1T28"
					( Origin gPackager )
				)
				( attribute "CDS_SEC" "1"
					( Origin gPackager )
				)
				( attribute "LOCATION" "R1T28"
					( Origin gFrontEnd )
				)
				( attribute "MATERIAL" "CHIP"
					( Origin gFrontEnd )
				)
				( attribute "PACK_TYPE" "0402"
					( Origin gFrontEnd )
				)
				( attribute "PART_NUMBER" "G21796-047"
					( Origin gFrontEnd )
				)
				( attribute "PHYS_PAGE" "151"
					( Origin gFrontEnd )
				)
				( attribute "ROOM" "CPU0"
					( Origin gFrontEnd )
				)
				( attribute "ROT" "0"
					( Origin gFrontEnd )
				)
				( attribute "SEC" "1"
					( Origin gFrontEnd )
				)
				( attribute "SEC_TYPE" "0402"
					( Origin gFrontEnd )
				)
				( attribute "TOLERANCE" "1%"
					( Origin gFrontEnd )
				)
				( attribute "VALUE" "49.9"
					( Origin gFrontEnd )
				)
				( attribute "VER" "1"
					( Origin gFrontEnd )
				)
				( attribute "WATTAGE" "1/16W"
					( Origin gFrontEnd )
				)
				( attribute "XY" "(1250,-1950)"
					( Origin gFrontEnd )
				)
				( attribute "CHIPS_PART_NAME" "RES"
					( Origin gPackager )
				)
				( attribute "CDS_PART_NAME" "RES_0402-49.9,1%,1/16W,CHIP,G2A"
					( Origin gPackager )
				)
				( objectStatus "R1T28" )
			)
			( gate "@baseboard_fab2_lib.baseboard_fab2(sch_1):page240_i195"
				( attribute "CDS_LIB" "mstr_discrete"
					( Origin gPackager )
				)
				( attribute "CDS_LOCATION" "R8F9"
					( Origin gPackager )
				)
				( attribute "CDS_SEC" "1"
					( Origin gPackager )
				)
				( attribute "LOCATION" "R8F9"
					( Origin gFrontEnd )
				)
				( attribute "MATERIAL" "CHIP"
					( Origin gFrontEnd )
				)
				( attribute "PACK_TYPE" "0402"
					( Origin gFrontEnd )
				)
				( attribute "PART_NUMBER" "G21796-048"
					( Origin gFrontEnd )
				)
				( attribute "PHYS_PAGE" "240"
					( Origin gFrontEnd )
				)
				( attribute "ROOM" "V_SUPER"
					( Origin gFrontEnd )
				)
				( attribute "ROT" "0"
					( Origin gFrontEnd )
				)
				( attribute "SEC" "1"
					( Origin gFrontEnd )
				)
				( attribute "SEC_TYPE" "0402"
					( Origin gFrontEnd )
				)
				( attribute "TOLERANCE" "1%"
					( Origin gFrontEnd )
				)
				( attribute "VALUE" "49.9K"
					( Origin gFrontEnd )
				)
				( attribute "VER" "2"
					( Origin gFrontEnd )
				)
				( attribute "WATTAGE" "1/16W"
					( Origin gFrontEnd )
				)
				( attribute "XY" "(6450,1850)"
					( Origin gFrontEnd )
				)
				( attribute "CHIPS_PART_NAME" "RES"
					( Origin gPackager )
				)
				( attribute "CDS_PART_NAME" "RES_0402-49.9K,1%,1/16W,CHIP,GA"
					( Origin gPackager )
				)
				( objectStatus "R8F9" )
			)
			( gate "@baseboard_fab2_lib.baseboard_fab2(sch_1):page224_i160"
				( attribute "ATTRIBUTE" "120NH"
					( Origin gFrontEnd )
				)
				( attribute "BOM_DS" "068.9002N.1021"
					( Origin gFrontEnd )
				)
				( attribute "BOM_SS" "068.1202N.M001"
					( Origin gFrontEnd )
				)
				( attribute "CDS_LIB" "w_hdl"
					( Origin gPackager )
				)
				( attribute "CDS_LMAN_SYM_OUTLINE" "-75,100,75,-100"
					( Origin gPackager )
				)
				( attribute "CDS_LOCATION" "L1G1"
					( Origin gPackager )
				)
				( attribute "CDS_SEC" "1"
					( Origin gPackager )
				)
				( attribute "DS_VALUE" "90NH"
					( Origin gFrontEnd )
				)
				( attribute "LOCATION" "L1G1"
					( Origin gFrontEnd )
				)
				( attribute "NEW_PACK_SIZE" "DCR=0.17MOHM"
					( Origin gFrontEnd )
				)
				( attribute "NEW_RATED" "DS_ISAT=134A@25C"
					( Origin gFrontEnd )
				)
				( attribute "NEW_TYPE" "IRMS=66A@DELTA_T<40C"
					( Origin gFrontEnd )
				)
				( attribute "PACK_SIZE" "DCR=0.17MOHM"
					( Origin gFrontEnd )
				)
				( attribute "PACK_TYPE" "DISCRET-GB2"
					( Origin gFrontEnd )
				)
				( attribute "PART_NUMBER" "068.1202N.M001"
					( Origin gFrontEnd )
				)
				( attribute "PHYS_PAGE" "224"
					( Origin gFrontEnd )
				)
				( attribute "RATED" "ISAT=94A@25C"
					( Origin gFrontEnd )
				)
				( attribute "ROT" "1"
					( Origin gFrontEnd )
				)
				( attribute "SEC" "1"
					( Origin gFrontEnd )
				)
				( attribute "SEC_TYPE" "DISCRET-GB2"
					( Origin gFrontEnd )
				)
				( attribute "SS_ISAT" "94A@25C"
					( Origin gFrontEnd )
				)
				( attribute "SS_VALUE" "120NH"
					( Origin gFrontEnd )
				)
				( attribute "TYPE" "IRMS=66A@DELTA_T<40C"
					( Origin gFrontEnd )
				)
				( attribute "VALUE" "IND-120NH-30-GP"
					( Origin gFrontEnd )
				)
				( attribute "VER" "1"
					( Origin gFrontEnd )
				)
				( attribute "XY" "(3950,1975)"
					( Origin gFrontEnd )
				)
				( attribute "CHIPS_PART_NAME" "IND-120NH-30-GP"
					( Origin gPackager )
				)
				( attribute "CDS_PART_NAME" "IND-120NH-30-GP_DISCRET-GB2-INA"
					( Origin gPackager )
				)
				( objectStatus "L1G1" )
			)
			( gate "@baseboard_fab2_lib.baseboard_fab2(sch_1):page76_i245"
				( attribute "BOM_COST" "MEM_VRD_PVDDQ_CD"
					( Origin gFrontEnd )
				)
				( attribute "CDS_LIB" "mstr_discrete"
					( Origin gPackager )
				)
				( attribute "CDS_LOCATION" "C8W4"
					( Origin gPackager )
				)
				( attribute "CDS_SEC" "1"
					( Origin gPackager )
				)
				( attribute "LOCATION" "C8W4"
					( Origin gFrontEnd )
				)
				( attribute "MATERIAL" "X5R"
					( Origin gFrontEnd )
				)
				( attribute "NEW_MATERIAL" "X6S"
					( Origin gFrontEnd )
				)
				( attribute "PACK_TYPE" "0805"
					( Origin gFrontEnd )
				)
				( attribute "PART_NUMBER" "602433-112"
					( Origin gFrontEnd )
				)
				( attribute "PHYS_PAGE" "76"
					( Origin gFrontEnd )
				)
				( attribute "ROOM" "VDDQ_ABC_PWR_VR"
					( Origin gFrontEnd )
				)
				( attribute "ROT" "0"
					( Origin gFrontEnd )
				)
				( attribute "SEC" "1"
					( Origin gFrontEnd )
				)
				( attribute "SEC_TYPE" "0805"
					( Origin gFrontEnd )
				)
				( attribute "TOLERANCE" "20%"
					( Origin gFrontEnd )
				)
				( attribute "VALUE" "100UF"
					( Origin gFrontEnd )
				)
				( attribute "VER" "1"
					( Origin gFrontEnd )
				)
				( attribute "VOLTAGE" "4V"
					( Units "uVoltage" "V" 1.000000)
					( Origin gFrontEnd )
				)
				( attribute "XY" "(-1200,1300)"
					( Origin gFrontEnd )
				)
				( attribute "CHIPS_PART_NAME" "CAP"
					( Origin gPackager )
				)
				( attribute "CDS_PART_NAME" "CAP_0805-100UF,4V,20%,X5R,6024A"
					( Origin gPackager )
				)
				( attribute "GROUP" "PWR_MLCC_CAP"
					( Origin gFrontEnd )
				)
				( attribute "NEW_PN" "078.1071T.M002"
					( Origin gFrontEnd )
				)
				( objectStatus "C8W4" )
			)
			( gate "@baseboard_fab2_lib.baseboard_fab2(sch_1):page217_i317"
				( attribute "BOM_COST" "MEM_VRD_PVDDQ_CD"
					( Origin gFrontEnd )
				)
				( attribute "CDS_LIB" "mstr_discrete"
					( Origin gPackager )
				)
				( attribute "CDS_LOCATION" "C5U10"
					( Origin gPackager )
				)
				( attribute "CDS_SEC" "1"
					( Origin gPackager )
				)
				( attribute "LOCATION" "C5U10"
					( Origin gFrontEnd )
				)
				( attribute "MATERIAL" "X5R"
					( Origin gFrontEnd )
				)
				( attribute "NEW_MATERIAL" "X6S"
					( Origin gFrontEnd )
				)
				( attribute "PACK_TYPE" "0805"
					( Origin gFrontEnd )
				)
				( attribute "PART_NUMBER" "602433-112"
					( Origin gFrontEnd )
				)
				( attribute "PHYS_PAGE" "217"
					( Origin gFrontEnd )
				)
				( attribute "ROOM" "VDDQ_ABC_PWR_VR"
					( Origin gFrontEnd )
				)
				( attribute "ROT" "0"
					( Origin gFrontEnd )
				)
				( attribute "SEC" "1"
					( Origin gFrontEnd )
				)
				( attribute "SEC_TYPE" "0805"
					( Origin gFrontEnd )
				)
				( attribute "TOLERANCE" "20%"
					( Origin gFrontEnd )
				)
				( attribute "VALUE" "100UF"
					( Origin gFrontEnd )
				)
				( attribute "VER" "1"
					( Origin gFrontEnd )
				)
				( attribute "VOLTAGE" "4V"
					( Units "uVoltage" "V" 1.000000)
					( Origin gFrontEnd )
				)
				( attribute "XY" "(5075,2850)"
					( Origin gFrontEnd )
				)
				( attribute "CHIPS_PART_NAME" "CAP"
					( Origin gPackager )
				)
				( attribute "CDS_PART_NAME" "CAP_0805-100UF,4V,20%,X5R,6024A"
					( Origin gPackager )
				)
				( attribute "GROUP" "PWR_MLCC_CAP"
					( Origin gFrontEnd )
				)
				( attribute "NEW_PN" "078.1071T.M002"
					( Origin gFrontEnd )
				)
				( attribute "BOM_SS" "NOPOP"
					( Origin gFrontEnd )
				)
				( objectStatus "C5U10" )
			)
			( gate "@baseboard_fab2_lib.baseboard_fab2(sch_1):page217_i320"
				( attribute "BOM_COST" "MEM_VRD_PVDDQ_CD"
					( Origin gFrontEnd )
				)
				( attribute "CDS_LIB" "mstr_discrete"
					( Origin gPackager )
				)
				( attribute "LOCATION" "C5U15"
					( Origin gFrontEnd )
				)
				( attribute "MATERIAL" "X5R"
					( Origin gFrontEnd )
				)
				( attribute "NEW_MATERIAL" "X6S"
					( Origin gFrontEnd )
				)
				( attribute "PACK_TYPE" "0805"
					( Origin gFrontEnd )
				)
				( attribute "PART_NUMBER" "602433-112"
					( Origin gFrontEnd )
				)
				( attribute "PHYS_PAGE" "217"
					( Origin gFrontEnd )
				)
				( attribute "ROOM" "VDDQ_ABC_PWR_VR"
					( Origin gFrontEnd )
				)
				( attribute "ROT" "0"
					( Origin gFrontEnd )
				)
				( attribute "SEC" "1"
					( Origin gFrontEnd )
				)
				( attribute "SEC_TYPE" "0805"
					( Origin gFrontEnd )
				)
				( attribute "TOLERANCE" "20%"
					( Origin gFrontEnd )
				)
				( attribute "VALUE" "100UF"
					( Origin gFrontEnd )
				)
				( attribute "VER" "1"
					( Origin gFrontEnd )
				)
				( attribute "VOLTAGE" "4V"
					( Units "uVoltage" "V" 1.000000)
					( Origin gFrontEnd )
				)
				( attribute "XY" "(3975,2850)"
					( Origin gFrontEnd )
				)
				( attribute "CHIPS_PART_NAME" "CAP"
					( Origin gPackager )
				)
				( attribute "CDS_PART_NAME" "CAP_0805-100UF,4V,20%,X5R,6024A"
					( Origin gPackager )
				)
				( attribute "CDS_LOCATION" "C5U15"
					( Origin gPackager )
				)
				( attribute "CDS_SEC" "1"
					( Origin gPackager )
				)
				( attribute "GROUP" "PWR_MLCC_CAP"
					( Origin gFrontEnd )
				)
				( attribute "NEW_PN" "078.1071T.M002"
					( Origin gFrontEnd )
				)
				( attribute "BOM_SS" "NOPOP"
					( Origin gFrontEnd )
				)
				( objectStatus "C5U15" )
			)
			( gate "@baseboard_fab2_lib.baseboard_fab2(sch_1):page217_i327"
				( attribute "BOM_COST" "MEM_VRD_PVDDQ_CD"
					( Origin gFrontEnd )
				)
				( attribute "CDS_LIB" "mstr_discrete"
					( Origin gPackager )
				)
				( attribute "CDS_LOCATION" "C5P38"
					( Origin gPackager )
				)
				( attribute "CDS_SEC" "1"
					( Origin gPackager )
				)
				( attribute "LOCATION" "C5P38"
					( Origin gFrontEnd )
				)
				( attribute "MATERIAL" "X5R"
					( Origin gFrontEnd )
				)
				( attribute "NEW_MATERIAL" "X6S"
					( Origin gFrontEnd )
				)
				( attribute "PACK_TYPE" "0805"
					( Origin gFrontEnd )
				)
				( attribute "PART_NUMBER" "602433-112"
					( Origin gFrontEnd )
				)
				( attribute "PHYS_PAGE" "217"
					( Origin gFrontEnd )
				)
				( attribute "ROOM" "VDDQ_ABC_PWR_VR"
					( Origin gFrontEnd )
				)
				( attribute "ROT" "0"
					( Origin gFrontEnd )
				)
				( attribute "SEC" "1"
					( Origin gFrontEnd )
				)
				( attribute "SEC_TYPE" "0805"
					( Origin gFrontEnd )
				)
				( attribute "TOLERANCE" "20%"
					( Origin gFrontEnd )
				)
				( attribute "VALUE" "100UF"
					( Origin gFrontEnd )
				)
				( attribute "VER" "1"
					( Origin gFrontEnd )
				)
				( attribute "VOLTAGE" "4V"
					( Units "uVoltage" "V" 1.000000)
					( Origin gFrontEnd )
				)
				( attribute "XY" "(-1400,2850)"
					( Origin gFrontEnd )
				)
				( attribute "CHIPS_PART_NAME" "CAP"
					( Origin gPackager )
				)
				( attribute "CDS_PART_NAME" "CAP_0805-100UF,4V,20%,X5R,6024A"
					( Origin gPackager )
				)
				( attribute "GROUP" "PWR_MLCC_CAP"
					( Origin gFrontEnd )
				)
				( attribute "NEW_PN" "078.1071T.M002"
					( Origin gFrontEnd )
				)
				( attribute "BOM_SS" "NOPOP"
					( Origin gFrontEnd )
				)
				( objectStatus "C5P38" )
			)
			( gate "@baseboard_fab2_lib.baseboard_fab2(sch_1):page217_i328"
				( attribute "BOM_COST" "MEM_VRD_PVDDQ_CD"
					( Origin gFrontEnd )
				)
				( attribute "CDS_LIB" "mstr_discrete"
					( Origin gPackager )
				)
				( attribute "LOCATION" "C5P39"
					( Origin gFrontEnd )
				)
				( attribute "MATERIAL" "X5R"
					( Origin gFrontEnd )
				)
				( attribute "NEW_MATERIAL" "X6S"
					( Origin gFrontEnd )
				)
				( attribute "PACK_TYPE" "0805"
					( Origin gFrontEnd )
				)
				( attribute "PART_NUMBER" "602433-112"
					( Origin gFrontEnd )
				)
				( attribute "PHYS_PAGE" "217"
					( Origin gFrontEnd )
				)
				( attribute "ROOM" "VDDQ_ABC_PWR_VR"
					( Origin gFrontEnd )
				)
				( attribute "ROT" "0"
					( Origin gFrontEnd )
				)
				( attribute "SEC" "1"
					( Origin gFrontEnd )
				)
				( attribute "SEC_TYPE" "0805"
					( Origin gFrontEnd )
				)
				( attribute "TOLERANCE" "20%"
					( Origin gFrontEnd )
				)
				( attribute "VALUE" "100UF"
					( Origin gFrontEnd )
				)
				( attribute "VER" "1"
					( Origin gFrontEnd )
				)
				( attribute "VOLTAGE" "4V"
					( Units "uVoltage" "V" 1.000000)
					( Origin gFrontEnd )
				)
				( attribute "XY" "(-1750,2850)"
					( Origin gFrontEnd )
				)
				( attribute "CHIPS_PART_NAME" "CAP"
					( Origin gPackager )
				)
				( attribute "CDS_PART_NAME" "CAP_0805-100UF,4V,20%,X5R,6024A"
					( Origin gPackager )
				)
				( attribute "CDS_LOCATION" "C5P39"
					( Origin gPackager )
				)
				( attribute "CDS_SEC" "1"
					( Origin gPackager )
				)
				( attribute "GROUP" "PWR_MLCC_CAP"
					( Origin gFrontEnd )
				)
				( attribute "NEW_PN" "078.1071T.M002"
					( Origin gFrontEnd )
				)
				( attribute "BOM_SS" "NOPOP"
					( Origin gFrontEnd )
				)
				( objectStatus "C5P39" )
			)
			( gate "@baseboard_fab2_lib.baseboard_fab2(sch_1):page247_i165"
				( attribute "CDS_LIB" "mstr_discrete"
					( Origin gPackager )
				)
				( attribute "CDS_LOCATION" "R6W35"
					( Origin gPackager )
				)
				( attribute "LOCATION" "R6W35"
					( Origin gFrontEnd )
				)
				( attribute "MATERIAL" "CHIP"
					( Origin gFrontEnd )
				)
				( attribute "PACK_TYPE" "0402"
					( Origin gFrontEnd )
				)
				( attribute "PART_NUMBER" "G21796-010"
					( Origin gFrontEnd )
				)
				( attribute "PHYS_PAGE" "247"
					( Origin gFrontEnd )
				)
				( attribute "ROOM" "HOT_SWAP"
					( Origin gFrontEnd )
				)
				( attribute "ROT" "2"
					( Origin gFrontEnd )
				)
				( attribute "SEC" "1"
					( Origin gFrontEnd )
				)
				( attribute "SEC_TYPE" "0402"
					( Origin gFrontEnd )
				)
				( attribute "TOLERANCE" "1%"
					( Origin gFrontEnd )
				)
				( attribute "VALUE" "100.0K"
					( Origin gFrontEnd )
				)
				( attribute "VER" "2"
					( Origin gFrontEnd )
				)
				( attribute "WATTAGE" "1/16W"
					( Origin gFrontEnd )
				)
				( attribute "XY" "(-1750,3750)"
					( Origin gFrontEnd )
				)
				( attribute "CHIPS_PART_NAME" "RES"
					( Origin gPackager )
				)
				( attribute "CDS_PART_NAME" "RES_0402-100.0K,1%,1/16W,CHIP,A"
					( Origin gPackager )
				)
				( attribute "CDS_SEC" "1"
					( Origin gPackager )
				)
				( objectStatus "R6W35" )
			)
			( gate "@baseboard_fab2_lib.baseboard_fab2(sch_1):page114_i195"
				( attribute "BOM_COST" "SYS_CLOCK"
					( Origin gFrontEnd )
				)
				( attribute "CDS_LIB" "mstr_discrete"
					( Origin gPackager )
				)
				( attribute "CDS_LOCATION" "C7C13"
					( Origin gPackager )
				)
				( attribute "CDS_SEC" "1"
					( Origin gPackager )
				)
				( attribute "LOCATION" "C7C13"
					( Origin gFrontEnd )
				)
				( attribute "MATERIAL" "COG"
					( Origin gFrontEnd )
				)
				( attribute "PACK_TYPE" "0402LF"
					( Origin gFrontEnd )
				)
				( attribute "PART_NUMBER" "A36095-047"
					( Origin gFrontEnd )
				)
				( attribute "PHYS_PAGE" "114"
					( Origin gFrontEnd )
				)
				( attribute "ROOM" "SB"
					( Origin gFrontEnd )
				)
				( attribute "ROT" "0"
					( Origin gFrontEnd )
				)
				( attribute "SEC" "1"
					( Origin gFrontEnd )
				)
				( attribute "SEC_TYPE" "0402LF"
					( Origin gFrontEnd )
				)
				( attribute "TOLERANCE" "5%"
					( Origin gFrontEnd )
				)
				( attribute "VALUE" "15.0PF"
					( Origin gFrontEnd )
				)
				( attribute "VER" "1"
					( Origin gFrontEnd )
				)
				( attribute "VOLTAGE" "50V"
					( Units "uVoltage" "V" 1.000000)
					( Origin gFrontEnd )
				)
				( attribute "XY" "(-275,-225)"
					( Origin gFrontEnd )
				)
				( attribute "CHIPS_PART_NAME" "CAP"
					( Origin gPackager )
				)
				( attribute "CDS_PART_NAME" "CAP_0402LF-15.0PF,50V,5%,COG,AA"
					( Origin gPackager )
				)
				( objectStatus "C7C13" )
			)
			( gate "@baseboard_fab2_lib.baseboard_fab2(sch_1):page114_i196"
				( attribute "BOM_COST" "SYS_CLOCK"
					( Origin gFrontEnd )
				)
				( attribute "CDS_LIB" "mstr_discrete"
					( Origin gPackager )
				)
				( attribute "CDS_LOCATION" "C7C15"
					( Origin gPackager )
				)
				( attribute "CDS_SEC" "1"
					( Origin gPackager )
				)
				( attribute "LOCATION" "C7C15"
					( Origin gFrontEnd )
				)
				( attribute "MATERIAL" "COG"
					( Origin gFrontEnd )
				)
				( attribute "PACK_TYPE" "0402LF"
					( Origin gFrontEnd )
				)
				( attribute "PART_NUMBER" "A36095-047"
					( Origin gFrontEnd )
				)
				( attribute "PHYS_PAGE" "114"
					( Origin gFrontEnd )
				)
				( attribute "ROOM" "SB"
					( Origin gFrontEnd )
				)
				( attribute "ROT" "0"
					( Origin gFrontEnd )
				)
				( attribute "SEC" "1"
					( Origin gFrontEnd )
				)
				( attribute "SEC_TYPE" "0402LF"
					( Origin gFrontEnd )
				)
				( attribute "TOLERANCE" "5%"
					( Origin gFrontEnd )
				)
				( attribute "VALUE" "15.0PF"
					( Origin gFrontEnd )
				)
				( attribute "VER" "1"
					( Origin gFrontEnd )
				)
				( attribute "VOLTAGE" "50V"
					( Units "uVoltage" "V" 1.000000)
					( Origin gFrontEnd )
				)
				( attribute "XY" "(225,-225)"
					( Origin gFrontEnd )
				)
				( attribute "CHIPS_PART_NAME" "CAP"
					( Origin gPackager )
				)
				( attribute "CDS_PART_NAME" "CAP_0402LF-15.0PF,50V,5%,COG,AA"
					( Origin gPackager )
				)
				( objectStatus "C7C15" )
			)
			( gate "@baseboard_fab2_lib.baseboard_fab2(sch_1):page42_i214"
				( attribute "BOM_COST" "PROC_SOCKET"
					( Origin gFrontEnd )
				)
				( attribute "CDS_LIB" "mstr_discrete"
					( Origin gPackager )
				)
				( attribute "CDS_LOCATION" "C5P8"
					( Origin gPackager )
				)
				( attribute "CDS_SEC" "1"
					( Origin gPackager )
				)
				( attribute "LOCATION" "C5P8"
					( Origin gFrontEnd )
				)
				( attribute "MATERIAL" "X6S"
					( Origin gFrontEnd )
				)
				( attribute "PACK_TYPE" "0805LF"
					( Origin gFrontEnd )
				)
				( attribute "PART_NUMBER" "C95333-002"
					( Origin gFrontEnd )
				)
				( attribute "PHYS_PAGE" "42"
					( Origin gFrontEnd )
				)
				( attribute "ROOM" "PVCCIN_CPU0_DECAP_VR"
					( Origin gFrontEnd )
				)
				( attribute "ROT" "0"
					( Origin gFrontEnd )
				)
				( attribute "SEC" "1"
					( Origin gPackager )
				)
				( attribute "TOLERANCE" "20%"
					( Origin gFrontEnd )
				)
				( attribute "VALUE" "22UF"
					( Origin gFrontEnd )
				)
				( attribute "VER" "1"
					( Origin gFrontEnd )
				)
				( attribute "VOLTAGE" "4V"
					( Units "uVoltage" "V" 1.000000)
					( Origin gFrontEnd )
				)
				( attribute "XY" "(-4150,950)"
					( Origin gFrontEnd )
				)
				( attribute "CHIPS_PART_NAME" "CAP"
					( Origin gPackager )
				)
				( attribute "CDS_PART_NAME" "CAP_0805LF-22UF,4V,20%,X6S,C95A"
					( Origin gPackager )
				)
				( attribute "GROUP" "PWR_MLCC_CAP"
					( Origin gFrontEnd )
				)
				( objectStatus "C5P8" )
			)
			( gate "@baseboard_fab2_lib.baseboard_fab2(sch_1):page76_i247"
				( attribute "BOM_COST" "PROC_SOCKET"
					( Origin gFrontEnd )
				)
				( attribute "CDS_LIB" "mstr_discrete"
					( Origin gPackager )
				)
				( attribute "CDS_LOCATION" "C8P6"
					( Origin gPackager )
				)
				( attribute "CDS_SEC" "1"
					( Origin gPackager )
				)
				( attribute "LOCATION" "C8P6"
					( Origin gFrontEnd )
				)
				( attribute "MATERIAL" "X6S"
					( Origin gFrontEnd )
				)
				( attribute "PACK_TYPE" "0805LF"
					( Origin gFrontEnd )
				)
				( attribute "PART_NUMBER" "C95333-002"
					( Origin gFrontEnd )
				)
				( attribute "PHYS_PAGE" "76"
					( Origin gFrontEnd )
				)
				( attribute "ROOM" "PVCCIN_CPU0_DECAP_VR"
					( Origin gFrontEnd )
				)
				( attribute "ROT" "0"
					( Origin gFrontEnd )
				)
				( attribute "SEC" "1"
					( Origin gPackager )
				)
				( attribute "TOLERANCE" "20%"
					( Origin gFrontEnd )
				)
				( attribute "VALUE" "22UF"
					( Origin gFrontEnd )
				)
				( attribute "VER" "1"
					( Origin gFrontEnd )
				)
				( attribute "VOLTAGE" "4V"
					( Units "uVoltage" "V" 1.000000)
					( Origin gFrontEnd )
				)
				( attribute "XY" "(-4250,1150)"
					( Origin gFrontEnd )
				)
				( attribute "CHIPS_PART_NAME" "CAP"
					( Origin gPackager )
				)
				( attribute "CDS_PART_NAME" "CAP_0805LF-22UF,4V,20%,X6S,C95A"
					( Origin gPackager )
				)
				( attribute "GROUP" "PWR_MLCC_CAP"
					( Origin gFrontEnd )
				)
				( objectStatus "C8P6" )
			)
			( gate "@baseboard_fab2_lib.baseboard_fab2(sch_1):page76_i248"
				( attribute "BOM_COST" "PROC_SOCKET"
					( Origin gFrontEnd )
				)
				( attribute "CDS_LIB" "mstr_discrete"
					( Origin gPackager )
				)
				( attribute "CDS_LOCATION" "C8P7"
					( Origin gPackager )
				)
				( attribute "CDS_SEC" "1"
					( Origin gPackager )
				)
				( attribute "LOCATION" "C8P7"
					( Origin gFrontEnd )
				)
				( attribute "MATERIAL" "X6S"
					( Origin gFrontEnd )
				)
				( attribute "PACK_TYPE" "0805LF"
					( Origin gFrontEnd )
				)
				( attribute "PART_NUMBER" "C95333-002"
					( Origin gFrontEnd )
				)
				( attribute "PHYS_PAGE" "76"
					( Origin gFrontEnd )
				)
				( attribute "ROOM" "PVCCIN_CPU0_DECAP_VR"
					( Origin gFrontEnd )
				)
				( attribute "ROT" "0"
					( Origin gFrontEnd )
				)
				( attribute "SEC" "1"
					( Origin gPackager )
				)
				( attribute "TOLERANCE" "20%"
					( Origin gFrontEnd )
				)
				( attribute "VALUE" "22UF"
					( Origin gFrontEnd )
				)
				( attribute "VER" "1"
					( Origin gFrontEnd )
				)
				( attribute "VOLTAGE" "4V"
					( Units "uVoltage" "V" 1.000000)
					( Origin gFrontEnd )
				)
				( attribute "XY" "(-3950,1150)"
					( Origin gFrontEnd )
				)
				( attribute "CHIPS_PART_NAME" "CAP"
					( Origin gPackager )
				)
				( attribute "CDS_PART_NAME" "CAP_0805LF-22UF,4V,20%,X6S,C95A"
					( Origin gPackager )
				)
				( attribute "GROUP" "PWR_MLCC_CAP"
					( Origin gFrontEnd )
				)
				( objectStatus "C8P7" )
			)
			( gate "@baseboard_fab2_lib.baseboard_fab2(sch_1):page76_i252"
				( attribute "BOM_COST" "PROC"
					( Origin gFrontEnd )
				)
				( attribute "CDS_LIB" "mstr_discrete"
					( Origin gPackager )
				)
				( attribute "CDS_LOCATION" "C8P17"
					( Origin gPackager )
				)
				( attribute "LOCATION" "C8P17"
					( Origin gFrontEnd )
				)
				( attribute "MATERIAL" "X6S"
					( Origin gFrontEnd )
				)
				( attribute "PACK_TYPE" "0805"
					( Origin gFrontEnd )
				)
				( attribute "PART_NUMBER" "C95333-006"
					( Origin gFrontEnd )
				)
				( attribute "PHYS_PAGE" "76"
					( Origin gFrontEnd )
				)
				( attribute "ROOM" "PVCCIN_CPU1_DECAP_VR"
					( Origin gFrontEnd )
				)
				( attribute "ROT" "0"
					( Origin gFrontEnd )
				)
				( attribute "SEC" "1"
					( Origin gFrontEnd )
				)
				( attribute "SEC_TYPE" "0805"
					( Origin gFrontEnd )
				)
				( attribute "TOLERANCE" "20%"
					( Origin gFrontEnd )
				)
				( attribute "VALUE" "47UF"
					( Origin gFrontEnd )
				)
				( attribute "VER" "1"
					( Origin gFrontEnd )
				)
				( attribute "VOLTAGE" "4V"
					( Units "uVoltage" "V" 1.000000)
					( Origin gFrontEnd )
				)
				( attribute "XY" "(-6550,800)"
					( Origin gFrontEnd )
				)
				( attribute "CHIPS_PART_NAME" "CAP"
					( Origin gPackager )
				)
				( attribute "CDS_PART_NAME" "CAP_0805-47UF,4V,20%,X6S,C9533A"
					( Origin gPackager )
				)
				( attribute "GROUP" "PWR_MLCC_CAP"
					( Origin gFrontEnd )
				)
				( attribute "CDS_SEC" "1"
					( Origin gPackager )
				)
				( objectStatus "C8P17" )
			)
			( gate "@baseboard_fab2_lib.baseboard_fab2(sch_1):page147_i164"
				( attribute "CDS_LIB" "mstr_discrete"
					( Origin gPackager )
				)
				( attribute "CDS_LOCATION" "R25W157"
					( Origin gPackager )
				)
				( attribute "CDS_SEC" "1"
					( Origin gPackager )
				)
				( attribute "LOCATION" "R25W157"
					( Origin gFrontEnd )
				)
				( attribute "MATERIAL" "CHIP"
					( Origin gFrontEnd )
				)
				( attribute "PACK_TYPE" "0402"
					( Origin gFrontEnd )
				)
				( attribute "PART_NUMBER" "G21796-010"
					( Origin gFrontEnd )
				)
				( attribute "PHYS_PAGE" "147"
					( Origin gFrontEnd )
				)
				( attribute "ROT" "0"
					( Origin gFrontEnd )
				)
				( attribute "SEC" "1"
					( Origin gFrontEnd )
				)
				( attribute "SEC_TYPE" "0402"
					( Origin gFrontEnd )
				)
				( attribute "TOLERANCE" "1%"
					( Origin gFrontEnd )
				)
				( attribute "VALUE" "100.0K"
					( Origin gFrontEnd )
				)
				( attribute "VER" "2"
					( Origin gFrontEnd )
				)
				( attribute "WATTAGE" "1/16W"
					( Origin gFrontEnd )
				)
				( attribute "XY" "(-4750,1300)"
					( Origin gFrontEnd )
				)
				( attribute "CHIPS_PART_NAME" "RES"
					( Origin gPackager )
				)
				( attribute "CDS_PART_NAME" "RES_0402-100.0K,1%,1/16W,CHIP,A"
					( Origin gPackager )
				)
				( objectStatus "R25W157" )
			)
			( gate "@baseboard_fab2_lib.baseboard_fab2(sch_1):page185_i183"
				( attribute "CDS_LIB" "mstr_discrete"
					( Origin gPackager )
				)
				( attribute "CDS_LOCATION" "R32W10"
					( Origin gPackager )
				)
				( attribute "CDS_SEC" "1"
					( Origin gPackager )
				)
				( attribute "LOCATION" "R32W10"
					( Origin gFrontEnd )
				)
				( attribute "MATERIAL" "CHIP"
					( Origin gFrontEnd )
				)
				( attribute "PACK_TYPE" "0402"
					( Origin gFrontEnd )
				)
				( attribute "PART_NUMBER" "G21497-005"
					( Origin gFrontEnd )
				)
				( attribute "PHYS_PAGE" "185"
					( Origin gFrontEnd )
				)
				( attribute "ROOM" "IO_SLOT"
					( Origin gFrontEnd )
				)
				( attribute "ROT" "0"
					( Origin gFrontEnd )
				)
				( attribute "SEC" "1"
					( Origin gFrontEnd )
				)
				( attribute "SEC_TYPE" "0402"
					( Origin gFrontEnd )
				)
				( attribute "TOLERANCE" "5%"
					( Origin gFrontEnd )
				)
				( attribute "VALUE" "0.0"
					( Origin gFrontEnd )
				)
				( attribute "VER" "1"
					( Origin gFrontEnd )
				)
				( attribute "WATTAGE" "1/16W"
					( Origin gFrontEnd )
				)
				( attribute "XY" "(-2850,2925)"
					( Origin gFrontEnd )
				)
				( attribute "CHIPS_PART_NAME" "RES"
					( Origin gPackager )
				)
				( attribute "CDS_PART_NAME" "RES_0402-0.0,5%,1/16W,CHIP,G21A"
					( Origin gPackager )
				)
				( objectStatus "R32W10" )
			)
			( gate "@baseboard_fab2_lib.baseboard_fab2(sch_1):page185_i184"
				( attribute "CDS_LIB" "mstr_discrete"
					( Origin gPackager )
				)
				( attribute "CDS_LOCATION" "R32W11"
					( Origin gPackager )
				)
				( attribute "CDS_SEC" "1"
					( Origin gPackager )
				)
				( attribute "LOCATION" "R32W11"
					( Origin gFrontEnd )
				)
				( attribute "MATERIAL" "CHIP"
					( Origin gFrontEnd )
				)
				( attribute "PACK_TYPE" "0402"
					( Origin gFrontEnd )
				)
				( attribute "PART_NUMBER" "G21497-005"
					( Origin gFrontEnd )
				)
				( attribute "PHYS_PAGE" "185"
					( Origin gFrontEnd )
				)
				( attribute "ROOM" "IO_SLOT"
					( Origin gFrontEnd )
				)
				( attribute "ROT" "0"
					( Origin gFrontEnd )
				)
				( attribute "SEC" "1"
					( Origin gFrontEnd )
				)
				( attribute "SEC_TYPE" "0402"
					( Origin gFrontEnd )
				)
				( attribute "TOLERANCE" "5%"
					( Origin gFrontEnd )
				)
				( attribute "VALUE" "0.0"
					( Origin gFrontEnd )
				)
				( attribute "VER" "1"
					( Origin gFrontEnd )
				)
				( attribute "WATTAGE" "1/16W"
					( Origin gFrontEnd )
				)
				( attribute "XY" "(-2625,2875)"
					( Origin gFrontEnd )
				)
				( attribute "CHIPS_PART_NAME" "RES"
					( Origin gPackager )
				)
				( attribute "CDS_PART_NAME" "RES_0402-0.0,5%,1/16W,CHIP,G21A"
					( Origin gPackager )
				)
				( objectStatus "R32W11" )
			)
			( gate "@baseboard_fab2_lib.baseboard_fab2(sch_1):page185_i187"
				( attribute "CDS_LIB" "mstr_discrete"
					( Origin gPackager )
				)
				( attribute "CDS_LOCATION" "R32W12"
					( Origin gPackager )
				)
				( attribute "CDS_SEC" "1"
					( Origin gPackager )
				)
				( attribute "LOCATION" "R32W12"
					( Origin gFrontEnd )
				)
				( attribute "MATERIAL" "CHIP"
					( Origin gFrontEnd )
				)
				( attribute "PACK_TYPE" "0402"
					( Origin gFrontEnd )
				)
				( attribute "PART_NUMBER" "G21497-005"
					( Origin gFrontEnd )
				)
				( attribute "PHYS_PAGE" "185"
					( Origin gFrontEnd )
				)
				( attribute "ROOM" "IO_SLOT"
					( Origin gFrontEnd )
				)
				( attribute "ROT" "0"
					( Origin gFrontEnd )
				)
				( attribute "SEC" "1"
					( Origin gFrontEnd )
				)
				( attribute "SEC_TYPE" "0402"
					( Origin gFrontEnd )
				)
				( attribute "TOLERANCE" "5%"
					( Origin gFrontEnd )
				)
				( attribute "VALUE" "0.0"
					( Origin gFrontEnd )
				)
				( attribute "VER" "1"
					( Origin gFrontEnd )
				)
				( attribute "WATTAGE" "1/16W"
					( Origin gFrontEnd )
				)
				( attribute "XY" "(-2675,3700)"
					( Origin gFrontEnd )
				)
				( attribute "CHIPS_PART_NAME" "RES"
					( Origin gPackager )
				)
				( attribute "CDS_PART_NAME" "RES_0402-0.0,5%,1/16W,CHIP,G21A"
					( Origin gPackager )
				)
				( objectStatus "R32W12" )
			)
			( gate "@baseboard_fab2_lib.baseboard_fab2(sch_1):page185_i188"
				( attribute "CDS_LIB" "dev_discrete"
					( Origin gPackager )
				)
				( attribute "CDS_LOCATION" "C32W1"
					( Origin gPackager )
				)
				( attribute "CDS_SEC" "1"
					( Origin gPackager )
				)
				( attribute "LOCATION" "C32W1"
					( Origin gFrontEnd )
				)
				( attribute "MATERIAL" "X7R"
					( Origin gFrontEnd )
				)
				( attribute "PACK_TYPE" "0402V"
					( Origin gFrontEnd )
				)
				( attribute "PART_NUMBER" "A36096-030"
					( Origin gFrontEnd )
				)
				( attribute "PHYS_PAGE" "185"
					( Origin gFrontEnd )
				)
				( attribute "ROOM" "SMB_PE_HP_CPU1"
					( Origin gFrontEnd )
				)
				( attribute "ROT" "0"
					( Origin gFrontEnd )
				)
				( attribute "SEC" "1"
					( Origin gFrontEnd )
				)
				( attribute "SEC_TYPE" "0402V"
					( Origin gFrontEnd )
				)
				( attribute "TOLERANCE" "10%"
					( Origin gFrontEnd )
				)
				( attribute "VALUE" "0.1UF"
					( Origin gFrontEnd )
				)
				( attribute "VER" "1"
					( Origin gFrontEnd )
				)
				( attribute "VOLTAGE" "16V"
					( Units "uVoltage" "V" 1.000000)
					( Origin gFrontEnd )
				)
				( attribute "XY" "(-2450,3200)"
					( Origin gFrontEnd )
				)
				( attribute "CHIPS_PART_NAME" "CAP_A"
					( Origin gPackager )
				)
				( attribute "CDS_PART_NAME" "CAP_A_0402V-0.1UF,16V,10%,X7R,A"
					( Origin gPackager )
				)
				( objectStatus "C32W1" )
			)
			( gate "@baseboard_fab2_lib.baseboard_fab2(sch_1):page185_i190"
				( attribute "CDS_LIB" "dev_discrete"
					( Origin gPackager )
				)
				( attribute "CDS_LOCATION" "C32W3"
					( Origin gPackager )
				)
				( attribute "CDS_SEC" "1"
					( Origin gPackager )
				)
				( attribute "LOCATION" "C32W3"
					( Origin gFrontEnd )
				)
				( attribute "MATERIAL" "X7R"
					( Origin gFrontEnd )
				)
				( attribute "PACK_TYPE" "0402V"
					( Origin gFrontEnd )
				)
				( attribute "PART_NUMBER" "A36096-030"
					( Origin gFrontEnd )
				)
				( attribute "PHYS_PAGE" "185"
					( Origin gFrontEnd )
				)
				( attribute "ROOM" "SMB_PE_HP_CPU1"
					( Origin gFrontEnd )
				)
				( attribute "ROT" "0"
					( Origin gFrontEnd )
				)
				( attribute "SEC" "1"
					( Origin gFrontEnd )
				)
				( attribute "SEC_TYPE" "0402V"
					( Origin gFrontEnd )
				)
				( attribute "TOLERANCE" "10%"
					( Origin gFrontEnd )
				)
				( attribute "VALUE" "0.1UF"
					( Origin gFrontEnd )
				)
				( attribute "VER" "1"
					( Origin gFrontEnd )
				)
				( attribute "VOLTAGE" "16V"
					( Units "uVoltage" "V" 1.000000)
					( Origin gFrontEnd )
				)
				( attribute "XY" "(-2450,3975)"
					( Origin gFrontEnd )
				)
				( attribute "CHIPS_PART_NAME" "CAP_A"
					( Origin gPackager )
				)
				( attribute "CDS_PART_NAME" "CAP_A_0402V-0.1UF,16V,10%,X7R,A"
					( Origin gPackager )
				)
				( objectStatus "C32W3" )
			)
			( gate "@baseboard_fab2_lib.baseboard_fab2(sch_1):page185_i191"
				( attribute "CDS_LIB" "w_hdl"
					( Origin gPackager )
				)
				( attribute "CDS_LMAN_SYM_OUTLINE" "-175,175,175,-175"
					( Origin gPackager )
				)
				( attribute "CDS_LOCATION" "U32W1"
					( Origin gPackager )
				)
				( attribute "CDS_SEC" "1"
					( Origin gPackager )
				)
				( attribute "LOCATION" "U32W1"
					( Origin gFrontEnd )
				)
				( attribute "PACK_TYPE" "DISCRET-G8"
					( Origin gFrontEnd )
				)
				( attribute "PART_NUMBER" "071.09517.0009"
					( Origin gFrontEnd )
				)
				( attribute "PHYS_PAGE" "185"
					( Origin gFrontEnd )
				)
				( attribute "ROT" "0"
					( Origin gFrontEnd )
				)
				( attribute "SEC" "1"
					( Origin gFrontEnd )
				)
				( attribute "SEC_TYPE" "DISCRET-G8"
					( Origin gFrontEnd )
				)
				( attribute "VALUE" "TCA9517DGKR-GP"
					( Origin gFrontEnd )
				)
				( attribute "VER" "1"
					( Origin gFrontEnd )
				)
				( attribute "XY" "(-1725,2900)"
					( Origin gFrontEnd )
				)
				( attribute "CHIPS_PART_NAME" "TCA9517DGKR-GP"
					( Origin gPackager )
				)
				( attribute "CDS_PART_NAME" "TCA9517DGKR-GP_DISCRET-G8-TCA9A"
					( Origin gPackager )
				)
				( objectStatus "U32W1" )
			)
			( gate "@baseboard_fab2_lib.baseboard_fab2(sch_1):page185_i193"
				( attribute "CDS_LIB" "dev_discrete"
					( Origin gPackager )
				)
				( attribute "CDS_LOCATION" "C32W2"
					( Origin gPackager )
				)
				( attribute "CDS_SEC" "1"
					( Origin gPackager )
				)
				( attribute "LOCATION" "C32W2"
					( Origin gFrontEnd )
				)
				( attribute "MATERIAL" "X7R"
					( Origin gFrontEnd )
				)
				( attribute "PACK_TYPE" "0402V"
					( Origin gFrontEnd )
				)
				( attribute "PART_NUMBER" "A36096-030"
					( Origin gFrontEnd )
				)
				( attribute "PHYS_PAGE" "185"
					( Origin gFrontEnd )
				)
				( attribute "ROOM" "SMB_PE_HP_CPU1"
					( Origin gFrontEnd )
				)
				( attribute "ROT" "0"
					( Origin gFrontEnd )
				)
				( attribute "SEC" "1"
					( Origin gFrontEnd )
				)
				( attribute "SEC_TYPE" "0402V"
					( Origin gFrontEnd )
				)
				( attribute "TOLERANCE" "10%"
					( Origin gFrontEnd )
				)
				( attribute "VALUE" "0.1UF"
					( Origin gFrontEnd )
				)
				( attribute "VER" "1"
					( Origin gFrontEnd )
				)
				( attribute "VOLTAGE" "16V"
					( Units "uVoltage" "V" 1.000000)
					( Origin gFrontEnd )
				)
				( attribute "XY" "(-1150,3200)"
					( Origin gFrontEnd )
				)
				( attribute "CHIPS_PART_NAME" "CAP_A"
					( Origin gPackager )
				)
				( attribute "CDS_PART_NAME" "CAP_A_0402V-0.1UF,16V,10%,X7R,A"
					( Origin gPackager )
				)
				( objectStatus "C32W2" )
			)
			( gate "@baseboard_fab2_lib.baseboard_fab2(sch_1):page185_i196"
				( attribute "CDS_LIB" "dev_discrete"
					( Origin gPackager )
				)
				( attribute "CDS_LOCATION" "C32W4"
					( Origin gPackager )
				)
				( attribute "CDS_SEC" "1"
					( Origin gPackager )
				)
				( attribute "LOCATION" "C32W4"
					( Origin gFrontEnd )
				)
				( attribute "MATERIAL" "X7R"
					( Origin gFrontEnd )
				)
				( attribute "PACK_TYPE" "0402V"
					( Origin gFrontEnd )
				)
				( attribute "PART_NUMBER" "A36096-030"
					( Origin gFrontEnd )
				)
				( attribute "PHYS_PAGE" "185"
					( Origin gFrontEnd )
				)
				( attribute "ROOM" "SMB_PE_HP_CPU1"
					( Origin gFrontEnd )
				)
				( attribute "ROT" "0"
					( Origin gFrontEnd )
				)
				( attribute "SEC" "1"
					( Origin gFrontEnd )
				)
				( attribute "SEC_TYPE" "0402V"
					( Origin gFrontEnd )
				)
				( attribute "TOLERANCE" "10%"
					( Origin gFrontEnd )
				)
				( attribute "VALUE" "0.1UF"
					( Origin gFrontEnd )
				)
				( attribute "VER" "1"
					( Origin gFrontEnd )
				)
				( attribute "VOLTAGE" "16V"
					( Units "uVoltage" "V" 1.000000)
					( Origin gFrontEnd )
				)
				( attribute "XY" "(-1200,4000)"
					( Origin gFrontEnd )
				)
				( attribute "CHIPS_PART_NAME" "CAP_A"
					( Origin gPackager )
				)
				( attribute "CDS_PART_NAME" "CAP_A_0402V-0.1UF,16V,10%,X7R,A"
					( Origin gPackager )
				)
				( objectStatus "C32W4" )
			)
			( gate "@baseboard_fab2_lib.baseboard_fab2(sch_1):page185_i200"
				( attribute "BOM_COST" "PROC_SIDEBAND"
					( Origin gFrontEnd )
				)
				( attribute "CDS_LIB" "mstr_discrete"
					( Origin gPackager )
				)
				( attribute "CDS_LOCATION" "R32W9"
					( Origin gPackager )
				)
				( attribute "CDS_SEC" "1"
					( Origin gPackager )
				)
				( attribute "LOCATION" "R32W9"
					( Origin gFrontEnd )
				)
				( attribute "MATERIAL" "CHIP"
					( Origin gFrontEnd )
				)
				( attribute "PACK_TYPE" "0402"
					( Origin gFrontEnd )
				)
				( attribute "PART_NUMBER" "G21796-016"
					( Origin gFrontEnd )
				)
				( attribute "PHYS_PAGE" "185"
					( Origin gFrontEnd )
				)
				( attribute "POP" "NOPOP"
					( Origin gFrontEnd )
				)
				( attribute "ROOM" "CPU0"
					( Origin gFrontEnd )
				)
				( attribute "ROT" "0"
					( Origin gFrontEnd )
				)
				( attribute "SEC" "1"
					( Origin gFrontEnd )
				)
				( attribute "SEC_TYPE" "0402"
					( Origin gFrontEnd )
				)
				( attribute "TOLERANCE" "1%"
					( Origin gFrontEnd )
				)
				( attribute "VALUE" "10.0K"
					( Origin gFrontEnd )
				)
				( attribute "VER" "2"
					( Origin gFrontEnd )
				)
				( attribute "WATTAGE" "1/16W"
					( Origin gFrontEnd )
				)
				( attribute "XY" "(-850,3450)"
					( Origin gFrontEnd )
				)
				( attribute "CHIPS_PART_NAME" "RES"
					( Origin gPackager )
				)
				( attribute "CDS_PART_NAME" "RES_0402-10.0K,1%,1/16W,CHIP,GA"
					( Origin gPackager )
				)
				( objectStatus "R32W9" )
			)
			( gate "@baseboard_fab2_lib.baseboard_fab2(sch_1):page185_i204"
				( attribute "CDS_LIB" "w_hdl"
					( Origin gPackager )
				)
				( attribute "CDS_LMAN_SYM_OUTLINE" "-175,175,175,-175"
					( Origin gPackager )
				)
				( attribute "CDS_LOCATION" "U32W2"
					( Origin gPackager )
				)
				( attribute "CDS_SEC" "1"
					( Origin gPackager )
				)
				( attribute "LOCATION" "U32W2"
					( Origin gFrontEnd )
				)
				( attribute "PACK_TYPE" "DISCRET-G8"
					( Origin gFrontEnd )
				)
				( attribute "PART_NUMBER" "071.09517.0009"
					( Origin gFrontEnd )
				)
				( attribute "PHYS_PAGE" "185"
					( Origin gFrontEnd )
				)
				( attribute "ROT" "0"
					( Origin gFrontEnd )
				)
				( attribute "SEC" "1"
					( Origin gFrontEnd )
				)
				( attribute "SEC_TYPE" "DISCRET-G8"
					( Origin gFrontEnd )
				)
				( attribute "VALUE" "TCA9517DGKR-GP"
					( Origin gFrontEnd )
				)
				( attribute "VER" "1"
					( Origin gFrontEnd )
				)
				( attribute "XY" "(-1725,3675)"
					( Origin gFrontEnd )
				)
				( attribute "CHIPS_PART_NAME" "TCA9517DGKR-GP"
					( Origin gPackager )
				)
				( attribute "CDS_PART_NAME" "TCA9517DGKR-GP_DISCRET-G8-TCA9A"
					( Origin gPackager )
				)
				( objectStatus "U32W2" )
			)
			( gate "@baseboard_fab2_lib.baseboard_fab2(sch_1):page185_i206"
				( attribute "CDS_LIB" "mstr_discrete"
					( Origin gPackager )
				)
				( attribute "CDS_LOCATION" "R32W3"
					( Origin gPackager )
				)
				( attribute "CDS_SEC" "1"
					( Origin gPackager )
				)
				( attribute "LOCATION" "R32W3"
					( Origin gFrontEnd )
				)
				( attribute "MATERIAL" "CHIP"
					( Origin gFrontEnd )
				)
				( attribute "PACK_TYPE" "0402"
					( Origin gFrontEnd )
				)
				( attribute "PART_NUMBER" "G21497-013"
					( Origin gFrontEnd )
				)
				( attribute "PHYS_PAGE" "185"
					( Origin gFrontEnd )
				)
				( attribute "ROT" "5"
					( Origin gFrontEnd )
				)
				( attribute "SEC" "1"
					( Origin gFrontEnd )
				)
				( attribute "SEC_TYPE" "0402"
					( Origin gFrontEnd )
				)
				( attribute "TOLERANCE" "5%"
					( Origin gFrontEnd )
				)
				( attribute "VALUE" "3.3K"
					( Origin gFrontEnd )
				)
				( attribute "VER" "1"
					( Origin gFrontEnd )
				)
				( attribute "WATTAGE" "1/16W"
					( Origin gFrontEnd )
				)
				( attribute "XY" "(-7800,1350)"
					( Origin gFrontEnd )
				)
				( attribute "CHIPS_PART_NAME" "RES"
					( Origin gPackager )
				)
				( attribute "CDS_PART_NAME" "RES_0402-3.3K,5%,1/16W,CHIP,G2A"
					( Origin gPackager )
				)
				( objectStatus "R32W3" )
			)
			( gate "@baseboard_fab2_lib.baseboard_fab2(sch_1):page185_i207"
				( attribute "CDS_LIB" "mstr_discrete"
					( Origin gPackager )
				)
				( attribute "CDS_LOCATION" "R32W2"
					( Origin gPackager )
				)
				( attribute "CDS_SEC" "1"
					( Origin gPackager )
				)
				( attribute "LOCATION" "R32W2"
					( Origin gFrontEnd )
				)
				( attribute "MATERIAL" "CHIP"
					( Origin gFrontEnd )
				)
				( attribute "PACK_TYPE" "0402"
					( Origin gFrontEnd )
				)
				( attribute "PART_NUMBER" "G21796-003"
					( Origin gFrontEnd )
				)
				( attribute "PHYS_PAGE" "185"
					( Origin gFrontEnd )
				)
				( attribute "ROOM" "PVCCIN_CPU0_VR"
					( Origin gFrontEnd )
				)
				( attribute "ROT" "0"
					( Origin gFrontEnd )
				)
				( attribute "SEC" "1"
					( Origin gFrontEnd )
				)
				( attribute "SEC_TYPE" "0402"
					( Origin gFrontEnd )
				)
				( attribute "TOLERANCE" "1%"
					( Origin gFrontEnd )
				)
				( attribute "VALUE" "1.5K"
					( Origin gFrontEnd )
				)
				( attribute "VER" "2"
					( Origin gFrontEnd )
				)
				( attribute "WATTAGE" "1/16W"
					( Origin gFrontEnd )
				)
				( attribute "XY" "(-7800,1650)"
					( Origin gFrontEnd )
				)
				( attribute "CHIPS_PART_NAME" "RES"
					( Origin gPackager )
				)
				( attribute "CDS_PART_NAME" "RES_0402-1.5K,1%,1/16W,CHIP,G2A"
					( Origin gPackager )
				)
				( objectStatus "R32W2" )
			)
			( gate "@baseboard_fab2_lib.baseboard_fab2(sch_1):page185_i208"
				( attribute "CDS_LIB" "mstr_discrete"
					( Origin gPackager )
				)
				( attribute "CDS_LOCATION" "R32W1"
					( Origin gPackager )
				)
				( attribute "CDS_SEC" "1"
					( Origin gPackager )
				)
				( attribute "LOCATION" "R32W1"
					( Origin gFrontEnd )
				)
				( attribute "MATERIAL" "CHIP"
					( Origin gFrontEnd )
				)
				( attribute "PACK_TYPE" "0402"
					( Origin gFrontEnd )
				)
				( attribute "PART_NUMBER" "G21796-082"
					( Origin gFrontEnd )
				)
				( attribute "PHYS_PAGE" "185"
					( Origin gFrontEnd )
				)
				( attribute "ROOM" "PVCCIN_CPU1_VR"
					( Origin gFrontEnd )
				)
				( attribute "ROT" "0"
					( Origin gFrontEnd )
				)
				( attribute "SEC" "1"
					( Origin gFrontEnd )
				)
				( attribute "SEC_TYPE" "0402"
					( Origin gFrontEnd )
				)
				( attribute "TOLERANCE" "1%"
					( Origin gFrontEnd )
				)
				( attribute "VALUE" "4.02K"
					( Origin gFrontEnd )
				)
				( attribute "VER" "2"
					( Origin gFrontEnd )
				)
				( attribute "WATTAGE" "1/16W"
					( Origin gFrontEnd )
				)
				( attribute "XY" "(-7800,1950)"
					( Origin gFrontEnd )
				)
				( attribute "CHIPS_PART_NAME" "RES"
					( Origin gPackager )
				)
				( attribute "CDS_PART_NAME" "RES_0402-4.02K,1%,1/16W,CHIP,GA"
					( Origin gPackager )
				)
				( objectStatus "R32W1" )
			)
			( gate "@baseboard_fab2_lib.baseboard_fab2(sch_1):page185_i211"
				( attribute "CDS_LIB" "mstr_discrete"
					( Origin gPackager )
				)
				( attribute "CDS_LOCATION" "R32W4"
					( Origin gPackager )
				)
				( attribute "CDS_SEC" "1"
					( Origin gPackager )
				)
				( attribute "LOCATION" "R32W4"
					( Origin gFrontEnd )
				)
				( attribute "MATERIAL" "CHIP"
					( Origin gFrontEnd )
				)
				( attribute "PACK_TYPE" "0402"
					( Origin gFrontEnd )
				)
				( attribute "PART_NUMBER" "G21796-048"
					( Origin gFrontEnd )
				)
				( attribute "PHYS_PAGE" "185"
					( Origin gFrontEnd )
				)
				( attribute "POP" "NOPOP"
					( Origin gFrontEnd )
				)
				( attribute "ROOM" "V_SUPER"
					( Origin gFrontEnd )
				)
				( attribute "ROT" "0"
					( Origin gFrontEnd )
				)
				( attribute "SEC" "1"
					( Origin gFrontEnd )
				)
				( attribute "SEC_TYPE" "0402"
					( Origin gFrontEnd )
				)
				( attribute "TOLERANCE" "1%"
					( Origin gFrontEnd )
				)
				( attribute "VALUE" "49.9K"
					( Origin gFrontEnd )
				)
				( attribute "VER" "2"
					( Origin gFrontEnd )
				)
				( attribute "WATTAGE" "1/16W"
					( Origin gFrontEnd )
				)
				( attribute "XY" "(-7900,900)"
					( Origin gFrontEnd )
				)
				( attribute "CHIPS_PART_NAME" "RES"
					( Origin gPackager )
				)
				( attribute "CDS_PART_NAME" "RES_0402-49.9K,1%,1/16W,CHIP,GA"
					( Origin gPackager )
				)
				( objectStatus "R32W4" )
			)
			( gate "@baseboard_fab2_lib.baseboard_fab2(sch_1):page185_i213"
				( attribute "CDS_LIB" "w_hdl"
					( Origin gPackager )
				)
				( attribute "CDS_LMAN_SYM_OUTLINE" "-200,150,200,-150"
					( Origin gPackager )
				)
				( attribute "CDS_LOCATION" "VR32W1"
					( Origin gPackager )
				)
				( attribute "CDS_SEC" "1"
					( Origin gPackager )
				)
				( attribute "LOCATION" "VR32W1"
					( Origin gFrontEnd )
				)
				( attribute "PACK_TYPE" "DISCRET-G5"
					( Origin gFrontEnd )
				)
				( attribute "PART_NUMBER" "74.MV431.031"
					( Origin gFrontEnd )
				)
				( attribute "PHYS_PAGE" "185"
					( Origin gFrontEnd )
				)
				( attribute "ROT" "0"
					( Origin gFrontEnd )
				)
				( attribute "SEC" "1"
					( Origin gFrontEnd )
				)
				( attribute "SEC_TYPE" "DISCRET-G5"
					( Origin gFrontEnd )
				)
				( attribute "VALUE" "LMV431AIMFX-GP"
					( Origin gFrontEnd )
				)
				( attribute "VER" "1"
					( Origin gFrontEnd )
				)
				( attribute "XY" "(-6900,1400)"
					( Origin gFrontEnd )
				)
				( attribute "CHIPS_PART_NAME" "LMV431AIMFX-GP"
					( Origin gPackager )
				)
				( attribute "CDS_PART_NAME" "LMV431AIMFX-GP_DISCRET-G5-LMV4A"
					( Origin gPackager )
				)
				( objectStatus "VR32W1" )
			)
			( gate "@baseboard_fab2_lib.baseboard_fab2(sch_1):page185_i214"
				( attribute "BOM_COST" "SM_CONTROLLER"
					( Origin gFrontEnd )
				)
				( attribute "CDS_LIB" "mstr_discrete"
					( Origin gPackager )
				)
				( attribute "CDS_LOCATION" "R32W6"
					( Origin gPackager )
				)
				( attribute "CDS_SEC" "1"
					( Origin gPackager )
				)
				( attribute "LOCATION" "R32W6"
					( Origin gFrontEnd )
				)
				( attribute "MATERIAL" "CHIP"
					( Origin gFrontEnd )
				)
				( attribute "PACK_TYPE" "0402"
					( Origin gFrontEnd )
				)
				( attribute "PART_NUMBER" "G21796-001"
					( Origin gFrontEnd )
				)
				( attribute "PHYS_PAGE" "185"
					( Origin gFrontEnd )
				)
				( attribute "ROOM" "SMBUS"
					( Origin gFrontEnd )
				)
				( attribute "ROT" "0"
					( Origin gFrontEnd )
				)
				( attribute "SEC" "1"
					( Origin gFrontEnd )
				)
				( attribute "SEC_TYPE" "0402"
					( Origin gFrontEnd )
				)
				( attribute "TOLERANCE" "1%"
					( Origin gFrontEnd )
				)
				( attribute "VALUE" "2.0K"
					( Origin gFrontEnd )
				)
				( attribute "VER" "2"
					( Origin gFrontEnd )
				)
				( attribute "WATTAGE" "1/16W"
					( Origin gFrontEnd )
				)
				( attribute "XY" "(-5450,1150)"
					( Origin gFrontEnd )
				)
				( attribute "CHIPS_PART_NAME" "RES"
					( Origin gPackager )
				)
				( attribute "CDS_PART_NAME" "RES_0402-2.0K,1%,1/16W,CHIP,G2A"
					( Origin gPackager )
				)
				( objectStatus "R32W6" )
			)
			( gate "@baseboard_fab2_lib.baseboard_fab2(sch_1):page185_i215"
				( attribute "BOM_COST" "SM_CONTROLLER"
					( Origin gFrontEnd )
				)
				( attribute "CDS_LIB" "mstr_discrete"
					( Origin gPackager )
				)
				( attribute "CDS_LOCATION" "R32W7"
					( Origin gPackager )
				)
				( attribute "CDS_SEC" "1"
					( Origin gPackager )
				)
				( attribute "LOCATION" "R32W7"
					( Origin gFrontEnd )
				)
				( attribute "MATERIAL" "CHIP"
					( Origin gFrontEnd )
				)
				( attribute "PACK_TYPE" "0402"
					( Origin gFrontEnd )
				)
				( attribute "PART_NUMBER" "G21796-001"
					( Origin gFrontEnd )
				)
				( attribute "PHYS_PAGE" "185"
					( Origin gFrontEnd )
				)
				( attribute "ROOM" "SMBUS"
					( Origin gFrontEnd )
				)
				( attribute "ROT" "0"
					( Origin gFrontEnd )
				)
				( attribute "SEC" "1"
					( Origin gFrontEnd )
				)
				( attribute "SEC_TYPE" "0402"
					( Origin gFrontEnd )
				)
				( attribute "TOLERANCE" "1%"
					( Origin gFrontEnd )
				)
				( attribute "VALUE" "2.0K"
					( Origin gFrontEnd )
				)
				( attribute "VER" "2"
					( Origin gFrontEnd )
				)
				( attribute "WATTAGE" "1/16W"
					( Origin gFrontEnd )
				)
				( attribute "XY" "(-5150,1150)"
					( Origin gFrontEnd )
				)
				( attribute "CHIPS_PART_NAME" "RES"
					( Origin gPackager )
				)
				( attribute "CDS_PART_NAME" "RES_0402-2.0K,1%,1/16W,CHIP,G2A"
					( Origin gPackager )
				)
				( objectStatus "R32W7" )
			)
			( gate "@baseboard_fab2_lib.baseboard_fab2(sch_1):page185_i216"
				( attribute "BOM_COST" "SM_CONTROLLER"
					( Origin gFrontEnd )
				)
				( attribute "CDS_LIB" "mstr_discrete"
					( Origin gPackager )
				)
				( attribute "CDS_LOCATION" "R32W5"
					( Origin gPackager )
				)
				( attribute "CDS_SEC" "1"
					( Origin gPackager )
				)
				( attribute "LOCATION" "R32W5"
					( Origin gFrontEnd )
				)
				( attribute "MATERIAL" "CHIP"
					( Origin gFrontEnd )
				)
				( attribute "PACK_TYPE" "0402"
					( Origin gFrontEnd )
				)
				( attribute "PART_NUMBER" "G21796-001"
					( Origin gFrontEnd )
				)
				( attribute "PHYS_PAGE" "185"
					( Origin gFrontEnd )
				)
				( attribute "ROOM" "SMBUS"
					( Origin gFrontEnd )
				)
				( attribute "ROT" "0"
					( Origin gFrontEnd )
				)
				( attribute "SEC" "1"
					( Origin gFrontEnd )
				)
				( attribute "SEC_TYPE" "0402"
					( Origin gFrontEnd )
				)
				( attribute "TOLERANCE" "1%"
					( Origin gFrontEnd )
				)
				( attribute "VALUE" "2.0K"
					( Origin gFrontEnd )
				)
				( attribute "VER" "2"
					( Origin gFrontEnd )
				)
				( attribute "WATTAGE" "1/16W"
					( Origin gFrontEnd )
				)
				( attribute "XY" "(-5750,1150)"
					( Origin gFrontEnd )
				)
				( attribute "CHIPS_PART_NAME" "RES"
					( Origin gPackager )
				)
				( attribute "CDS_PART_NAME" "RES_0402-2.0K,1%,1/16W,CHIP,G2A"
					( Origin gPackager )
				)
				( objectStatus "R32W5" )
			)
			( gate "@baseboard_fab2_lib.baseboard_fab2(sch_1):page249_i52"
				( attribute "ATTRIBUTE" "1UF"
					( Origin gFrontEnd )
				)
				( attribute "CDS_LIB" "w_hdl"
					( Origin gPackager )
				)
				( attribute "CDS_LMAN_SYM_OUTLINE" "-50,25,50,-25"
					( Origin gPackager )
				)
				( attribute "CDS_LOCATION" "C8W1"
					( Origin gPackager )
				)
				( attribute "CDS_SEC" "1"
					( Origin gPackager )
				)
				( attribute "LOCATION" "C8W1"
					( Origin gFrontEnd )
				)
				( attribute "PACK_SIZE" "0603"
					( Origin gFrontEnd )
				)
				( attribute "PACK_TYPE" "SMD-BCG"
					( Origin gFrontEnd )
				)
				( attribute "PART_NUMBER" "78.10521.5BL"
					( Origin gFrontEnd )
				)
				( attribute "PHYS_PAGE" "249"
					( Origin gFrontEnd )
				)
				( attribute "RATED" "16V"
					( Origin gFrontEnd )
				)
				( attribute "ROT" "1"
					( Origin gFrontEnd )
				)
				( attribute "SEC" "1"
					( Origin gPackager )
				)
				( attribute "TOLERANCE" "10%"
					( Origin gFrontEnd )
				)
				( attribute "TYPE" "X5R"
					( Origin gFrontEnd )
				)
				( attribute "VALUE" "SC1U16V3KX-2GP"
					( Origin gFrontEnd )
				)
				( attribute "VER" "1"
					( Origin gFrontEnd )
				)
				( attribute "XY" "(-6625,2150)"
					( Origin gFrontEnd )
				)
				( attribute "CHIPS_PART_NAME" "SC1U16V3KX-2GP"
					( Origin gPackager )
				)
				( attribute "CDS_PART_NAME" "SC1U16V3KX-2GP_SMD-BCG-SC1U16VA"
					( Origin gPackager )
				)
				( objectStatus "C8W1" )
			)
			( gate "@baseboard_fab2_lib.baseboard_fab2(sch_1):page197_i117"
				( attribute "ATTRIBUTE" "665K OHM"
					( Origin gFrontEnd )
				)
				( attribute "CDS_LIB" "w_hdl"
					( Origin gPackager )
				)
				( attribute "CDS_LMAN_SYM_OUTLINE" "-50,75,50,-75"
					( Origin gPackager )
				)
				( attribute "CDS_LOCATION" "R12W2"
					( Origin gPackager )
				)
				( attribute "CDS_SEC" "1"
					( Origin gPackager )
				)
				( attribute "CONFIG" "064.1003F.M001"
					( Origin gFrontEnd )
				)
				( attribute "LOCATION" "R12W2"
					( Origin gFrontEnd )
				)
				( attribute "NEW_VALUE" "100K OHM"
					( Origin gFrontEnd )
				)
				( attribute "PACK_SIZE" "AT0805"
					( Origin gFrontEnd )
				)
				( attribute "PACK_TYPE" "SMD-RG3"
					( Origin gFrontEnd )
				)
				( attribute "PART_NUMBER" "064.6653F.M001"
					( Origin gFrontEnd )
				)
				( attribute "PHYS_PAGE" "197"
					( Origin gFrontEnd )
				)
				( attribute "RATED" "1/8W"
					( Origin gFrontEnd )
				)
				( attribute "ROT" "0"
					( Origin gFrontEnd )
				)
				( attribute "SEC" "1"
					( Origin gPackager )
				)
				( attribute "TOLERANCE" "0.1%"
					( Origin gFrontEnd )
				)
				( attribute "VALUE" "665KR5B-1-GP"
					( Origin gFrontEnd )
				)
				( attribute "VER" "1"
					( Origin gFrontEnd )
				)
				( attribute "XY" "(-4025,4125)"
					( Origin gFrontEnd )
				)
				( attribute "CHIPS_PART_NAME" "665KR5B-1-GP"
					( Origin gPackager )
				)
				( attribute "CDS_PART_NAME" "665KR5B-1-GP_SMD-RG3-665KR5B-1A"
					( Origin gPackager )
				)
				( objectStatus "R12W2" )
			)
			( gate "@baseboard_fab2_lib.baseboard_fab2(sch_1):page197_i119"
				( attribute "ATTRIBUTE" "665K OHM"
					( Origin gFrontEnd )
				)
				( attribute "CDS_LIB" "w_hdl"
					( Origin gPackager )
				)
				( attribute "CDS_LMAN_SYM_OUTLINE" "-50,75,50,-75"
					( Origin gPackager )
				)
				( attribute "CDS_LOCATION" "R12W12"
					( Origin gPackager )
				)
				( attribute "CDS_SEC" "1"
					( Origin gPackager )
				)
				( attribute "CONFIG" "064.1003F.M001"
					( Origin gFrontEnd )
				)
				( attribute "LOCATION" "R12W12"
					( Origin gFrontEnd )
				)
				( attribute "NEW_VALUE" "100K OHM"
					( Origin gFrontEnd )
				)
				( attribute "PACK_SIZE" "AT0805"
					( Origin gFrontEnd )
				)
				( attribute "PACK_TYPE" "SMD-RG3"
					( Origin gFrontEnd )
				)
				( attribute "PART_NUMBER" "064.6653F.M001"
					( Origin gFrontEnd )
				)
				( attribute "PHYS_PAGE" "197"
					( Origin gFrontEnd )
				)
				( attribute "RATED" "1/8W"
					( Origin gFrontEnd )
				)
				( attribute "ROT" "0"
					( Origin gFrontEnd )
				)
				( attribute "SEC" "1"
					( Origin gPackager )
				)
				( attribute "TOLERANCE" "0.1%"
					( Origin gFrontEnd )
				)
				( attribute "VALUE" "665KR5B-1-GP"
					( Origin gFrontEnd )
				)
				( attribute "VER" "1"
					( Origin gFrontEnd )
				)
				( attribute "XY" "(-1475,4125)"
					( Origin gFrontEnd )
				)
				( attribute "CHIPS_PART_NAME" "665KR5B-1-GP"
					( Origin gPackager )
				)
				( attribute "CDS_PART_NAME" "665KR5B-1-GP_SMD-RG3-665KR5B-1A"
					( Origin gPackager )
				)
				( objectStatus "R12W12" )
			)
			( gate "@baseboard_fab2_lib.baseboard_fab2(sch_1):page197_i120"
				( attribute "ATTRIBUTE" "665K OHM"
					( Origin gFrontEnd )
				)
				( attribute "CDS_LIB" "w_hdl"
					( Origin gPackager )
				)
				( attribute "CDS_LMAN_SYM_OUTLINE" "-50,75,50,-75"
					( Origin gPackager )
				)
				( attribute "CDS_LOCATION" "R12W6"
					( Origin gPackager )
				)
				( attribute "CDS_SEC" "1"
					( Origin gPackager )
				)
				( attribute "CONFIG" "064.1003F.M001"
					( Origin gFrontEnd )
				)
				( attribute "LOCATION" "R12W6"
					( Origin gFrontEnd )
				)
				( attribute "NEW_VALUE" "100K OHM"
					( Origin gFrontEnd )
				)
				( attribute "PACK_SIZE" "AT0805"
					( Origin gFrontEnd )
				)
				( attribute "PACK_TYPE" "SMD-RG3"
					( Origin gFrontEnd )
				)
				( attribute "PART_NUMBER" "064.6653F.M001"
					( Origin gFrontEnd )
				)
				( attribute "PHYS_PAGE" "197"
					( Origin gFrontEnd )
				)
				( attribute "RATED" "1/8W"
					( Origin gFrontEnd )
				)
				( attribute "ROT" "0"
					( Origin gFrontEnd )
				)
				( attribute "SEC" "1"
					( Origin gPackager )
				)
				( attribute "TOLERANCE" "0.1%"
					( Origin gFrontEnd )
				)
				( attribute "VALUE" "665KR5B-1-GP"
					( Origin gFrontEnd )
				)
				( attribute "VER" "1"
					( Origin gFrontEnd )
				)
				( attribute "XY" "(-4475,2025)"
					( Origin gFrontEnd )
				)
				( attribute "CHIPS_PART_NAME" "665KR5B-1-GP"
					( Origin gPackager )
				)
				( attribute "CDS_PART_NAME" "665KR5B-1-GP_SMD-RG3-665KR5B-1A"
					( Origin gPackager )
				)
				( objectStatus "R12W6" )
			)
			( gate "@baseboard_fab2_lib.baseboard_fab2(sch_1):page197_i121"
				( attribute "ATTRIBUTE" "665K OHM"
					( Origin gFrontEnd )
				)
				( attribute "CDS_LIB" "w_hdl"
					( Origin gPackager )
				)
				( attribute "CDS_LMAN_SYM_OUTLINE" "-50,75,50,-75"
					( Origin gPackager )
				)
				( attribute "CDS_LOCATION" "R12W7"
					( Origin gPackager )
				)
				( attribute "CDS_SEC" "1"
					( Origin gPackager )
				)
				( attribute "CONFIG" "064.1003F.M001"
					( Origin gFrontEnd )
				)
				( attribute "LOCATION" "R12W7"
					( Origin gFrontEnd )
				)
				( attribute "NEW_VALUE" "100K OHM"
					( Origin gFrontEnd )
				)
				( attribute "PACK_SIZE" "AT0805"
					( Origin gFrontEnd )
				)
				( attribute "PACK_TYPE" "SMD-RG3"
					( Origin gFrontEnd )
				)
				( attribute "PART_NUMBER" "064.6653F.M001"
					( Origin gFrontEnd )
				)
				( attribute "PHYS_PAGE" "197"
					( Origin gFrontEnd )
				)
				( attribute "RATED" "1/8W"
					( Origin gFrontEnd )
				)
				( attribute "ROT" "0"
					( Origin gFrontEnd )
				)
				( attribute "SEC" "1"
					( Origin gPackager )
				)
				( attribute "TOLERANCE" "0.1%"
					( Origin gFrontEnd )
				)
				( attribute "VALUE" "665KR5B-1-GP"
					( Origin gFrontEnd )
				)
				( attribute "VER" "1"
					( Origin gFrontEnd )
				)
				( attribute "XY" "(-4025,2025)"
					( Origin gFrontEnd )
				)
				( attribute "CHIPS_PART_NAME" "665KR5B-1-GP"
					( Origin gPackager )
				)
				( attribute "CDS_PART_NAME" "665KR5B-1-GP_SMD-RG3-665KR5B-1A"
					( Origin gPackager )
				)
				( objectStatus "R12W7" )
			)
			( gate "@baseboard_fab2_lib.baseboard_fab2(sch_1):page197_i122"
				( attribute "ATTRIBUTE" "665K OHM"
					( Origin gFrontEnd )
				)
				( attribute "CDS_LIB" "w_hdl"
					( Origin gPackager )
				)
				( attribute "CDS_LMAN_SYM_OUTLINE" "-50,75,50,-75"
					( Origin gPackager )
				)
				( attribute "CDS_LOCATION" "R12W16"
					( Origin gPackager )
				)
				( attribute "CDS_SEC" "1"
					( Origin gPackager )
				)
				( attribute "CONFIG" "064.1003F.M001"
					( Origin gFrontEnd )
				)
				( attribute "LOCATION" "R12W16"
					( Origin gFrontEnd )
				)
				( attribute "NEW_VALUE" "100K OHM"
					( Origin gFrontEnd )
				)
				( attribute "PACK_SIZE" "AT0805"
					( Origin gFrontEnd )
				)
				( attribute "PACK_TYPE" "SMD-RG3"
					( Origin gFrontEnd )
				)
				( attribute "PART_NUMBER" "064.6653F.M001"
					( Origin gFrontEnd )
				)
				( attribute "PHYS_PAGE" "197"
					( Origin gFrontEnd )
				)
				( attribute "RATED" "1/8W"
					( Origin gFrontEnd )
				)
				( attribute "ROT" "0"
					( Origin gFrontEnd )
				)
				( attribute "SEC" "1"
					( Origin gPackager )
				)
				( attribute "TOLERANCE" "0.1%"
					( Origin gFrontEnd )
				)
				( attribute "VALUE" "665KR5B-1-GP"
					( Origin gFrontEnd )
				)
				( attribute "VER" "1"
					( Origin gFrontEnd )
				)
				( attribute "XY" "(-1925,2025)"
					( Origin gFrontEnd )
				)
				( attribute "CHIPS_PART_NAME" "665KR5B-1-GP"
					( Origin gPackager )
				)
				( attribute "CDS_PART_NAME" "665KR5B-1-GP_SMD-RG3-665KR5B-1A"
					( Origin gPackager )
				)
				( objectStatus "R12W16" )
			)
			( gate "@baseboard_fab2_lib.baseboard_fab2(sch_1):page197_i123"
				( attribute "ATTRIBUTE" "665K OHM"
					( Origin gFrontEnd )
				)
				( attribute "CDS_LIB" "w_hdl"
					( Origin gPackager )
				)
				( attribute "CDS_LMAN_SYM_OUTLINE" "-50,75,50,-75"
					( Origin gPackager )
				)
				( attribute "CDS_LOCATION" "R12W17"
					( Origin gPackager )
				)
				( attribute "CDS_SEC" "1"
					( Origin gPackager )
				)
				( attribute "CONFIG" "064.1003F.M001"
					( Origin gFrontEnd )
				)
				( attribute "LOCATION" "R12W17"
					( Origin gFrontEnd )
				)
				( attribute "NEW_VALUE" "100K OHM"
					( Origin gFrontEnd )
				)
				( attribute "PACK_SIZE" "AT0805"
					( Origin gFrontEnd )
				)
				( attribute "PACK_TYPE" "SMD-RG3"
					( Origin gFrontEnd )
				)
				( attribute "PART_NUMBER" "064.6653F.M001"
					( Origin gFrontEnd )
				)
				( attribute "PHYS_PAGE" "197"
					( Origin gFrontEnd )
				)
				( attribute "RATED" "1/8W"
					( Origin gFrontEnd )
				)
				( attribute "ROT" "0"
					( Origin gFrontEnd )
				)
				( attribute "SEC" "1"
					( Origin gPackager )
				)
				( attribute "TOLERANCE" "0.1%"
					( Origin gFrontEnd )
				)
				( attribute "VALUE" "665KR5B-1-GP"
					( Origin gFrontEnd )
				)
				( attribute "VER" "1"
					( Origin gFrontEnd )
				)
				( attribute "XY" "(-1475,2025)"
					( Origin gFrontEnd )
				)
				( attribute "CHIPS_PART_NAME" "665KR5B-1-GP"
					( Origin gPackager )
				)
				( attribute "CDS_PART_NAME" "665KR5B-1-GP_SMD-RG3-665KR5B-1A"
					( Origin gPackager )
				)
				( objectStatus "R12W17" )
			)
			( gate "@baseboard_fab2_lib.baseboard_fab2(sch_1):page249_i49"
				( attribute "CDS_LIB" "mstr_discrete"
					( Origin gPackager )
				)
				( attribute "CDS_LOCATION" "Q9W3"
					( Origin gPackager )
				)
				( attribute "CDS_SEC" "1"
					( Origin gPackager )
				)
				( attribute "LOCATION" "Q9W3"
					( Origin gFrontEnd )
				)
				( attribute "MATERIAL" "IC"
					( Origin gFrontEnd )
				)
				( attribute "PACK_TYPE" "SM"
					( Origin gFrontEnd )
				)
				( attribute "PART_NUMBER" "C52245-001"
					( Origin gFrontEnd )
				)
				( attribute "PHYS_PAGE" "249"
					( Origin gFrontEnd )
				)
				( attribute "ROOM" "SB"
					( Origin gFrontEnd )
				)
				( attribute "ROT" "0"
					( Origin gFrontEnd )
				)
				( attribute "SEC" "1"
					( Origin gFrontEnd )
				)
				( attribute "SEC_TYPE" "SM"
					( Origin gFrontEnd )
				)
				( attribute "VALUE" "MMBT3904"
					( Origin gFrontEnd )
				)
				( attribute "VER" "1"
					( Origin gFrontEnd )
				)
				( attribute "XY" "(-2350,4100)"
					( Origin gFrontEnd )
				)
				( attribute "CHIPS_PART_NAME" "NPN"
					( Origin gPackager )
				)
				( attribute "CDS_PART_NAME" "NPN_SM-MMBT3904,IC,C52245-001"
					( Origin gPackager )
				)
				( objectStatus "Q9W3" )
			)
			( gate "@baseboard_fab2_lib.baseboard_fab2(sch_1):page139_i250"
				( attribute "BOM_COST" "SYS_CLOCK"
					( Origin gFrontEnd )
				)
				( attribute "CDS_LIB" "mstr_discrete"
					( Origin gPackager )
				)
				( attribute "CDS_LOCATION" "C9E8"
					( Origin gPackager )
				)
				( attribute "LOCATION" "C9E8"
					( Origin gFrontEnd )
				)
				( attribute "MATERIAL" "COG"
					( Origin gFrontEnd )
				)
				( attribute "PACK_TYPE" "0402LF"
					( Origin gFrontEnd )
				)
				( attribute "PART_NUMBER" "A36095-047"
					( Origin gFrontEnd )
				)
				( attribute "PHYS_PAGE" "139"
					( Origin gFrontEnd )
				)
				( attribute "ROOM" "SB"
					( Origin gFrontEnd )
				)
				( attribute "ROT" "0"
					( Origin gFrontEnd )
				)
				( attribute "SEC" "1"
					( Origin gFrontEnd )
				)
				( attribute "SEC_TYPE" "0402LF"
					( Origin gFrontEnd )
				)
				( attribute "TOLERANCE" "5%"
					( Origin gFrontEnd )
				)
				( attribute "VALUE" "15.0PF"
					( Origin gFrontEnd )
				)
				( attribute "VER" "1"
					( Origin gFrontEnd )
				)
				( attribute "VOLTAGE" "50V"
					( Units "uVoltage" "V" 1.000000)
					( Origin gFrontEnd )
				)
				( attribute "XY" "(-7325,1200)"
					( Origin gFrontEnd )
				)
				( attribute "CHIPS_PART_NAME" "CAP"
					( Origin gPackager )
				)
				( attribute "CDS_PART_NAME" "CAP_0402LF-15.0PF,50V,5%,COG,AA"
					( Origin gPackager )
				)
				( attribute "CDS_SEC" "1"
					( Origin gPackager )
				)
				( attribute "GROUP" "NI_I210&RJ45"
					( Origin gFrontEnd )
				)
				( objectStatus "C9E8" )
			)
			( gate "@baseboard_fab2_lib.baseboard_fab2(sch_1):page139_i252"
				( attribute "BOM_COST" "NT_GBE_BASE"
					( Origin gFrontEnd )
				)
				( attribute "CDS_LIB" "mstr_discrete"
					( Origin gPackager )
				)
				( attribute "CDS_LOCATION" "R9W36"
					( Origin gPackager )
				)
				( attribute "CDS_SEC" "1"
					( Origin gPackager )
				)
				( attribute "LOCATION" "R9W36"
					( Origin gFrontEnd )
				)
				( attribute "MATERIAL" "CHIP"
					( Origin gFrontEnd )
				)
				( attribute "PACK_TYPE" "0402"
					( Origin gFrontEnd )
				)
				( attribute "PART_NUMBER" "G21796-016"
					( Origin gFrontEnd )
				)
				( attribute "PHYS_PAGE" "139"
					( Origin gFrontEnd )
				)
				( attribute "ROOM" "NIC_SPRV"
					( Origin gFrontEnd )
				)
				( attribute "ROT" "0"
					( Origin gFrontEnd )
				)
				( attribute "SEC" "1"
					( Origin gFrontEnd )
				)
				( attribute "SEC_TYPE" "0402"
					( Origin gFrontEnd )
				)
				( attribute "TOLERANCE" "1%"
					( Origin gFrontEnd )
				)
				( attribute "VALUE" "10.0K"
					( Origin gFrontEnd )
				)
				( attribute "VER" "2"
					( Origin gFrontEnd )
				)
				( attribute "WATTAGE" "1/16W"
					( Origin gFrontEnd )
				)
				( attribute "XY" "(-6950,3275)"
					( Origin gFrontEnd )
				)
				( attribute "CHIPS_PART_NAME" "RES"
					( Origin gPackager )
				)
				( attribute "CDS_PART_NAME" "RES_0402-10.0K,1%,1/16W,CHIP,GA"
					( Origin gPackager )
				)
				( attribute "GROUP" "NI_I210&RJ45"
					( Origin gFrontEnd )
				)
				( objectStatus "R9W36" )
			)
			( gate "@baseboard_fab2_lib.baseboard_fab2(sch_1):page167_i93"
				( attribute "CDS_LIB" "w_hdl"
					( Origin gPackager )
				)
				( attribute "CDS_LMAN_SYM_OUTLINE" "-50,50,50,-50"
					( Origin gPackager )
				)
				( attribute "LOCATION" "Q9B1"
					( Origin gFrontEnd )
				)
				( attribute "PACK_TYPE" "DISCRET-GB1"
					( Origin gFrontEnd )
				)
				( attribute "PART_NUMBER" "006.02907.001A"
					( Origin gFrontEnd )
				)
				( attribute "PHYS_PAGE" "167"
					( Origin gFrontEnd )
				)
				( attribute "ROT" "4"
					( Origin gFrontEnd )
				)
				( attribute "SEC" "1"
					( Origin gFrontEnd )
				)
				( attribute "SEC_TYPE" "DISCRET-GB1"
					( Origin gFrontEnd )
				)
				( attribute "VALUE" "2SB2907A-B0-00001-GP"
					( Origin gFrontEnd )
				)
				( attribute "VER" "1"
					( Origin gFrontEnd )
				)
				( attribute "XY" "(-5925,4600)"
					( Origin gFrontEnd )
				)
				( attribute "CHIPS_PART_NAME" "2SB2907A-B0-00001-GP"
					( Origin gPackager )
				)
				( attribute "CDS_PART_NAME" "2SB2907A-B0-00001-GP_DISCRET-GA"
					( Origin gPackager )
				)
				( attribute "CDS_LOCATION" "Q9B1"
					( Origin gPackager )
				)
				( attribute "CDS_SEC" "1"
					( Origin gPackager )
				)
				( objectStatus "Q9B1" )
			)
			( gate "@baseboard_fab2_lib.baseboard_fab2(sch_1):page167_i94"
				( attribute "CDS_LIB" "w_hdl"
					( Origin gPackager )
				)
				( attribute "CDS_LMAN_SYM_OUTLINE" "-50,50,50,-50"
					( Origin gPackager )
				)
				( attribute "LOCATION" "Q1E1"
					( Origin gFrontEnd )
				)
				( attribute "PACK_TYPE" "DISCRET-GB1"
					( Origin gFrontEnd )
				)
				( attribute "PART_NUMBER" "006.02907.001A"
					( Origin gFrontEnd )
				)
				( attribute "PHYS_PAGE" "167"
					( Origin gFrontEnd )
				)
				( attribute "ROT" "4"
					( Origin gFrontEnd )
				)
				( attribute "SEC" "1"
					( Origin gFrontEnd )
				)
				( attribute "SEC_TYPE" "DISCRET-GB1"
					( Origin gFrontEnd )
				)
				( attribute "VALUE" "2SB2907A-B0-00001-GP"
					( Origin gFrontEnd )
				)
				( attribute "VER" "1"
					( Origin gFrontEnd )
				)
				( attribute "XY" "(-5700,3150)"
					( Origin gFrontEnd )
				)
				( attribute "CHIPS_PART_NAME" "2SB2907A-B0-00001-GP"
					( Origin gPackager )
				)
				( attribute "CDS_PART_NAME" "2SB2907A-B0-00001-GP_DISCRET-GA"
					( Origin gPackager )
				)
				( attribute "CDS_LOCATION" "Q1E1"
					( Origin gPackager )
				)
				( attribute "CDS_SEC" "1"
					( Origin gPackager )
				)
				( objectStatus "Q1E1" )
			)
			( gate "@baseboard_fab2_lib.baseboard_fab2(sch_1):page249_i56"
				( attribute "CDS_LIB" "mstr_discrete"
					( Origin gPackager )
				)
				( attribute "CDS_LOCATION" "R3W2"
					( Origin gPackager )
				)
				( attribute "CDS_SEC" "1"
					( Origin gPackager )
				)
				( attribute "LOCATION" "R3W2"
					( Origin gFrontEnd )
				)
				( attribute "MATERIAL" "CHIP"
					( Origin gFrontEnd )
				)
				( attribute "PACK_TYPE" "0402"
					( Origin gFrontEnd )
				)
				( attribute "PART_NUMBER" "G21796-010"
					( Origin gFrontEnd )
				)
				( attribute "PHYS_PAGE" "249"
					( Origin gFrontEnd )
				)
				( attribute "ROOM" "SB"
					( Origin gFrontEnd )
				)
				( attribute "ROT" "0"
					( Origin gFrontEnd )
				)
				( attribute "SEC" "1"
					( Origin gPackager )
				)
				( attribute "TOLERANCE" "1%"
					( Origin gFrontEnd )
				)
				( attribute "VALUE" "100.0K"
					( Origin gFrontEnd )
				)
				( attribute "VER" "2"
					( Origin gFrontEnd )
				)
				( attribute "WATTAGE" "1/16W"
					( Origin gFrontEnd )
				)
				( attribute "XY" "(-6350,1950)"
					( Origin gFrontEnd )
				)
				( attribute "CHIPS_PART_NAME" "RES"
					( Origin gPackager )
				)
				( attribute "CDS_PART_NAME" "RES_0402-100.0K,1%,1/16W,CHIP,A"
					( Origin gPackager )
				)
				( objectStatus "R3W2" )
			)
			( gate "@baseboard_fab2_lib.baseboard_fab2(sch_1):page201_i192"
				( attribute "BOM_COST" "SM_THERM"
					( Origin gFrontEnd )
				)
				( attribute "CDS_LIB" "dev_discrete"
					( Origin gPackager )
				)
				( attribute "CDS_LOCATION" "C4D20"
					( Origin gPackager )
				)
				( attribute "CDS_SEC" "1"
					( Origin gPackager )
				)
				( attribute "LOCATION" "C4D20"
					( Origin gFrontEnd )
				)
				( attribute "MATERIAL" "X7R"
					( Origin gFrontEnd )
				)
				( attribute "PACK_TYPE" "0402V"
					( Origin gFrontEnd )
				)
				( attribute "PART_NUMBER" "A36096-030"
					( Origin gFrontEnd )
				)
				( attribute "PHYS_PAGE" "201"
					( Origin gFrontEnd )
				)
				( attribute "ROOM" "CPU_FANS"
					( Origin gFrontEnd )
				)
				( attribute "ROT" "0"
					( Origin gFrontEnd )
				)
				( attribute "SEC" "1"
					( Origin gFrontEnd )
				)
				( attribute "SEC_TYPE" "0402V"
					( Origin gFrontEnd )
				)
				( attribute "TOLERANCE" "10%"
					( Origin gFrontEnd )
				)
				( attribute "VALUE" "0.1UF"
					( Origin gFrontEnd )
				)
				( attribute "VER" "1"
					( Origin gFrontEnd )
				)
				( attribute "VOLTAGE" "16V"
					( Units "uVoltage" "V" 1.000000)
					( Origin gFrontEnd )
				)
				( attribute "XY" "(-6600,4200)"
					( Origin gFrontEnd )
				)
				( attribute "CHIPS_PART_NAME" "CAP_A"
					( Origin gPackager )
				)
				( attribute "CDS_PART_NAME" "CAP_A_0402V-0.1UF,16V,10%,X7R,A"
					( Origin gPackager )
				)
				( objectStatus "C4D20" )
			)
			( gate "@baseboard_fab2_lib.baseboard_fab2(sch_1):page249_i55"
				( attribute "CDS_LIB" "mstr_discrete"
					( Origin gPackager )
				)
				( attribute "CDS_LOCATION" "CR3W1"
					( Origin gPackager )
				)
				( attribute "CDS_SEC" "1"
					( Origin gPackager )
				)
				( attribute "LOCATION" "CR3W1"
					( Origin gFrontEnd )
				)
				( attribute "MATERIAL" "IC"
					( Origin gFrontEnd )
				)
				( attribute "PACK_TYPE" "SMLF"
					( Origin gFrontEnd )
				)
				( attribute "PART_NUMBER" "C73510-001"
					( Origin gFrontEnd )
				)
				( attribute "PHYS_PAGE" "249"
					( Origin gFrontEnd )
				)
				( attribute "ROT" "6"
					( Origin gFrontEnd )
				)
				( attribute "SEC" "1"
					( Origin gFrontEnd )
				)
				( attribute "SEC_TYPE" "SMLF"
					( Origin gFrontEnd )
				)
				( attribute "VALUE" "BAT54WS"
					( Origin gFrontEnd )
				)
				( attribute "VER" "1"
					( Origin gFrontEnd )
				)
				( attribute "XY" "(-7050,2150)"
					( Origin gFrontEnd )
				)
				( attribute "CHIPS_PART_NAME" "DIODE"
					( Origin gPackager )
				)
				( attribute "CDS_PART_NAME" "DIODE_SMLF-BAT54WS,IC,C73510-0A"
					( Origin gPackager )
				)
				( objectStatus "CR3W1" )
			)
			( gate "@baseboard_fab2_lib.baseboard_fab2(sch_1):page249_i58"
				( attribute "BOM_COST" "PROC_SIDEBAND"
					( Origin gFrontEnd )
				)
				( attribute "CDS_LIB" "mstr_discrete"
					( Origin gPackager )
				)
				( attribute "CDS_LOCATION" "R3W5"
					( Origin gPackager )
				)
				( attribute "CDS_SEC" "1"
					( Origin gPackager )
				)
				( attribute "LOCATION" "R3W5"
					( Origin gFrontEnd )
				)
				( attribute "MATERIAL" "CHIP"
					( Origin gFrontEnd )
				)
				( attribute "PACK_TYPE" "0402"
					( Origin gFrontEnd )
				)
				( attribute "PART_NUMBER" "G21796-016"
					( Origin gFrontEnd )
				)
				( attribute "PHYS_PAGE" "249"
					( Origin gFrontEnd )
				)
				( attribute "ROOM" "CPU0"
					( Origin gFrontEnd )
				)
				( attribute "ROT" "0"
					( Origin gFrontEnd )
				)
				( attribute "SEC" "1"
					( Origin gFrontEnd )
				)
				( attribute "SEC_TYPE" "0402"
					( Origin gFrontEnd )
				)
				( attribute "TOLERANCE" "1%"
					( Origin gFrontEnd )
				)
				( attribute "VALUE" "10.0K"
					( Origin gFrontEnd )
				)
				( attribute "VER" "2"
					( Origin gFrontEnd )
				)
				( attribute "WATTAGE" "1/16W"
					( Origin gFrontEnd )
				)
				( attribute "XY" "(-3200,4350)"
					( Origin gFrontEnd )
				)
				( attribute "CHIPS_PART_NAME" "RES"
					( Origin gPackager )
				)
				( attribute "CDS_PART_NAME" "RES_0402-10.0K,1%,1/16W,CHIP,GA"
					( Origin gPackager )
				)
				( objectStatus "R3W5" )
			)
			( gate "@baseboard_fab2_lib.baseboard_fab2(sch_1):page42_i217"
				( attribute "BOM_COST" "PROC_SOCKET"
					( Origin gFrontEnd )
				)
				( attribute "CDS_LIB" "dev_discrete"
					( Origin gPackager )
				)
				( attribute "CDS_LOCATION" "C5W1"
					( Origin gPackager )
				)
				( attribute "LOCATION" "C5W1"
					( Origin gFrontEnd )
				)
				( attribute "MATERIAL" "X6S"
					( Origin gFrontEnd )
				)
				( attribute "PACK_TYPE" "0603V"
					( Origin gFrontEnd )
				)
				( attribute "PART_NUMBER" "E15431-004"
					( Origin gFrontEnd )
				)
				( attribute "PHYS_PAGE" "42"
					( Origin gFrontEnd )
				)
				( attribute "ROOM" "PVCCIN_CPU0_DECAP_VR"
					( Origin gFrontEnd )
				)
				( attribute "ROT" "0"
					( Origin gFrontEnd )
				)
				( attribute "SEC" "1"
					( Origin gFrontEnd )
				)
				( attribute "TOLERANCE" "20%"
					( Origin gFrontEnd )
				)
				( attribute "VALUE" "22.0UF"
					( Origin gFrontEnd )
				)
				( attribute "VER" "1"
					( Origin gFrontEnd )
				)
				( attribute "VOLTAGE" "4V"
					( Units "uVoltage" "V" 1.000000)
					( Origin gFrontEnd )
				)
				( attribute "XY" "(-800,3150)"
					( Origin gFrontEnd )
				)
				( attribute "CHIPS_PART_NAME" "CAP_A"
					( Origin gPackager )
				)
				( attribute "CDS_PART_NAME" "CAP_A_0603V-22.0UF,4V,20%,X6S,A"
					( Origin gPackager )
				)
				( attribute "SEC_TYPE" "0603V"
					( Origin gFrontEnd )
				)
				( attribute "CDS_SEC" "1"
					( Origin gPackager )
				)
				( attribute "GROUP" "PWR_MCP_CAP"
					( Origin gFrontEnd )
				)
				( objectStatus "C5W1" )
			)
			( gate "@baseboard_fab2_lib.baseboard_fab2(sch_1):page42_i218"
				( attribute "BOM_COST" "PROC_SOCKET"
					( Origin gFrontEnd )
				)
				( attribute "CDS_LIB" "dev_discrete"
					( Origin gPackager )
				)
				( attribute "CDS_LOCATION" "C5W2"
					( Origin gPackager )
				)
				( attribute "LOCATION" "C5W2"
					( Origin gFrontEnd )
				)
				( attribute "MATERIAL" "X6S"
					( Origin gFrontEnd )
				)
				( attribute "PACK_TYPE" "0603V"
					( Origin gFrontEnd )
				)
				( attribute "PART_NUMBER" "E15431-004"
					( Origin gFrontEnd )
				)
				( attribute "PHYS_PAGE" "42"
					( Origin gFrontEnd )
				)
				( attribute "ROOM" "PVCCIN_CPU0_DECAP_VR"
					( Origin gFrontEnd )
				)
				( attribute "ROT" "0"
					( Origin gFrontEnd )
				)
				( attribute "SEC" "1"
					( Origin gFrontEnd )
				)
				( attribute "TOLERANCE" "20%"
					( Origin gFrontEnd )
				)
				( attribute "VALUE" "22.0UF"
					( Origin gFrontEnd )
				)
				( attribute "VER" "1"
					( Origin gFrontEnd )
				)
				( attribute "VOLTAGE" "4V"
					( Units "uVoltage" "V" 1.000000)
					( Origin gFrontEnd )
				)
				( attribute "XY" "(-550,3150)"
					( Origin gFrontEnd )
				)
				( attribute "CHIPS_PART_NAME" "CAP_A"
					( Origin gPackager )
				)
				( attribute "CDS_PART_NAME" "CAP_A_0603V-22.0UF,4V,20%,X6S,A"
					( Origin gPackager )
				)
				( attribute "SEC_TYPE" "0603V"
					( Origin gFrontEnd )
				)
				( attribute "CDS_SEC" "1"
					( Origin gPackager )
				)
				( attribute "GROUP" "PWR_MCP_CAP"
					( Origin gFrontEnd )
				)
				( objectStatus "C5W2" )
			)
			( gate "@baseboard_fab2_lib.baseboard_fab2(sch_1):page76_i254"
				( attribute "BOM_COST" "PROC_SOCKET"
					( Origin gFrontEnd )
				)
				( attribute "CDS_LIB" "dev_discrete"
					( Origin gPackager )
				)
				( attribute "CDS_LOCATION" "C3W4"
					( Origin gPackager )
				)
				( attribute "LOCATION" "C3W4"
					( Origin gFrontEnd )
				)
				( attribute "MATERIAL" "X6S"
					( Origin gFrontEnd )
				)
				( attribute "PACK_TYPE" "0603V"
					( Origin gFrontEnd )
				)
				( attribute "PART_NUMBER" "E15431-004"
					( Origin gFrontEnd )
				)
				( attribute "PHYS_PAGE" "76"
					( Origin gFrontEnd )
				)
				( attribute "ROOM" "PVCCIN_CPU0_DECAP_VR"
					( Origin gFrontEnd )
				)
				( attribute "ROT" "0"
					( Origin gFrontEnd )
				)
				( attribute "SEC" "1"
					( Origin gFrontEnd )
				)
				( attribute "TOLERANCE" "20%"
					( Origin gFrontEnd )
				)
				( attribute "VALUE" "22.0UF"
					( Origin gFrontEnd )
				)
				( attribute "VER" "1"
					( Origin gFrontEnd )
				)
				( attribute "VOLTAGE" "4V"
					( Units "uVoltage" "V" 1.000000)
					( Origin gFrontEnd )
				)
				( attribute "XY" "(-1100,3050)"
					( Origin gFrontEnd )
				)
				( attribute "CHIPS_PART_NAME" "CAP_A"
					( Origin gPackager )
				)
				( attribute "CDS_PART_NAME" "CAP_A_0603V-22.0UF,4V,20%,X6S,A"
					( Origin gPackager )
				)
				( attribute "SEC_TYPE" "0603V"
					( Origin gFrontEnd )
				)
				( attribute "CDS_SEC" "1"
					( Origin gPackager )
				)
				( attribute "GROUP" "PWR_MCP_CAP"
					( Origin gFrontEnd )
				)
				( objectStatus "C3W4" )
			)
			( gate "@baseboard_fab2_lib.baseboard_fab2(sch_1):page76_i256"
				( attribute "BOM_COST" "PROC_SOCKET"
					( Origin gFrontEnd )
				)
				( attribute "CDS_LIB" "dev_discrete"
					( Origin gPackager )
				)
				( attribute "CDS_LOCATION" "C3W3"
					( Origin gPackager )
				)
				( attribute "LOCATION" "C3W3"
					( Origin gFrontEnd )
				)
				( attribute "MATERIAL" "X6S"
					( Origin gFrontEnd )
				)
				( attribute "PACK_TYPE" "0603V"
					( Origin gFrontEnd )
				)
				( attribute "PART_NUMBER" "E15431-004"
					( Origin gFrontEnd )
				)
				( attribute "PHYS_PAGE" "76"
					( Origin gFrontEnd )
				)
				( attribute "ROOM" "PVCCIN_CPU0_DECAP_VR"
					( Origin gFrontEnd )
				)
				( attribute "ROT" "0"
					( Origin gFrontEnd )
				)
				( attribute "SEC" "1"
					( Origin gFrontEnd )
				)
				( attribute "TOLERANCE" "20%"
					( Origin gFrontEnd )
				)
				( attribute "VALUE" "22.0UF"
					( Origin gFrontEnd )
				)
				( attribute "VER" "1"
					( Origin gFrontEnd )
				)
				( attribute "VOLTAGE" "4V"
					( Units "uVoltage" "V" 1.000000)
					( Origin gFrontEnd )
				)
				( attribute "XY" "(-1400,3050)"
					( Origin gFrontEnd )
				)
				( attribute "CHIPS_PART_NAME" "CAP_A"
					( Origin gPackager )
				)
				( attribute "CDS_PART_NAME" "CAP_A_0603V-22.0UF,4V,20%,X6S,A"
					( Origin gPackager )
				)
				( attribute "SEC_TYPE" "0603V"
					( Origin gFrontEnd )
				)
				( attribute "CDS_SEC" "1"
					( Origin gPackager )
				)
				( attribute "GROUP" "PWR_MCP_CAP"
					( Origin gFrontEnd )
				)
				( objectStatus "C3W3" )
			)
			( gate "@baseboard_fab2_lib.baseboard_fab2(sch_1):page215_i74"
				( attribute "BOM_COST" "PROC_SIDEBAND"
					( Origin gFrontEnd )
				)
				( attribute "CDS_LIB" "mstr_discrete"
					( Origin gPackager )
				)
				( attribute "CDS_LOCATION" "R12W25"
					( Origin gPackager )
				)
				( attribute "CDS_SEC" "1"
					( Origin gPackager )
				)
				( attribute "LOCATION" "R12W25"
					( Origin gFrontEnd )
				)
				( attribute "MATERIAL" "CHIP"
					( Origin gFrontEnd )
				)
				( attribute "PACK_TYPE" "0402"
					( Origin gFrontEnd )
				)
				( attribute "PART_NUMBER" "G21497-005"
					( Origin gFrontEnd )
				)
				( attribute "PHYS_PAGE" "215"
					( Origin gFrontEnd )
				)
				( attribute "ROOM" "CPU0"
					( Origin gFrontEnd )
				)
				( attribute "ROT" "0"
					( Origin gFrontEnd )
				)
				( attribute "SEC" "1"
					( Origin gFrontEnd )
				)
				( attribute "SEC_TYPE" "0402"
					( Origin gFrontEnd )
				)
				( attribute "TOLERANCE" "5%"
					( Origin gFrontEnd )
				)
				( attribute "VALUE" "0.0"
					( Origin gFrontEnd )
				)
				( attribute "VER" "1"
					( Origin gFrontEnd )
				)
				( attribute "WATTAGE" "1/16W"
					( Origin gFrontEnd )
				)
				( attribute "XY" "(4000,1700)"
					( Origin gFrontEnd )
				)
				( attribute "CHIPS_PART_NAME" "RES"
					( Origin gPackager )
				)
				( attribute "CDS_PART_NAME" "RES_0402-0.0,5%,1/16W,CHIP,G21A"
					( Origin gPackager )
				)
				( objectStatus "R12W25" )
			)
			( gate "@baseboard_fab2_lib.baseboard_fab2(sch_1):page119_i223"
				( attribute "BOM_COST" "PROC_SIDEBAND"
					( Origin gFrontEnd )
				)
				( attribute "CDS_LIB" "mstr_discrete"
					( Origin gPackager )
				)
				( attribute "CDS_LOCATION" "R2W3"
					( Origin gPackager )
				)
				( attribute "CDS_SEC" "1"
					( Origin gPackager )
				)
				( attribute "LOCATION" "R2W3"
					( Origin gFrontEnd )
				)
				( attribute "MATERIAL" "CHIP"
					( Origin gFrontEnd )
				)
				( attribute "PACK_TYPE" "0402"
					( Origin gFrontEnd )
				)
				( attribute "PART_NUMBER" "G21497-005"
					( Origin gFrontEnd )
				)
				( attribute "PHYS_PAGE" "119"
					( Origin gFrontEnd )
				)
				( attribute "ROOM" "CPU0"
					( Origin gFrontEnd )
				)
				( attribute "ROT" "0"
					( Origin gFrontEnd )
				)
				( attribute "SEC" "1"
					( Origin gFrontEnd )
				)
				( attribute "SEC_TYPE" "0402"
					( Origin gFrontEnd )
				)
				( attribute "TOLERANCE" "5%"
					( Origin gFrontEnd )
				)
				( attribute "VALUE" "0.0"
					( Origin gFrontEnd )
				)
				( attribute "VER" "1"
					( Origin gFrontEnd )
				)
				( attribute "WATTAGE" "1/16W"
					( Origin gFrontEnd )
				)
				( attribute "XY" "(-1200,4150)"
					( Origin gFrontEnd )
				)
				( attribute "CHIPS_PART_NAME" "RES"
					( Origin gPackager )
				)
				( attribute "CDS_PART_NAME" "RES_0402-0.0,5%,1/16W,CHIP,G21A"
					( Origin gPackager )
				)
				( objectStatus "R2W3" )
			)
			( gate "@baseboard_fab2_lib.baseboard_fab2(sch_1):page119_i224"
				( attribute "BOM_COST" "PROC_SIDEBAND"
					( Origin gFrontEnd )
				)
				( attribute "CDS_LIB" "mstr_discrete"
					( Origin gPackager )
				)
				( attribute "CDS_LOCATION" "R2W4"
					( Origin gPackager )
				)
				( attribute "CDS_SEC" "1"
					( Origin gPackager )
				)
				( attribute "LOCATION" "R2W4"
					( Origin gFrontEnd )
				)
				( attribute "MATERIAL" "CHIP"
					( Origin gFrontEnd )
				)
				( attribute "PACK_TYPE" "0402"
					( Origin gFrontEnd )
				)
				( attribute "PART_NUMBER" "G21497-005"
					( Origin gFrontEnd )
				)
				( attribute "PHYS_PAGE" "119"
					( Origin gFrontEnd )
				)
				( attribute "ROOM" "CPU0"
					( Origin gFrontEnd )
				)
				( attribute "ROT" "0"
					( Origin gFrontEnd )
				)
				( attribute "SEC" "1"
					( Origin gFrontEnd )
				)
				( attribute "SEC_TYPE" "0402"
					( Origin gFrontEnd )
				)
				( attribute "TOLERANCE" "5%"
					( Origin gFrontEnd )
				)
				( attribute "VALUE" "0.0"
					( Origin gFrontEnd )
				)
				( attribute "VER" "1"
					( Origin gFrontEnd )
				)
				( attribute "WATTAGE" "1/16W"
					( Origin gFrontEnd )
				)
				( attribute "XY" "(-6925,2550)"
					( Origin gFrontEnd )
				)
				( attribute "CHIPS_PART_NAME" "RES"
					( Origin gPackager )
				)
				( attribute "CDS_PART_NAME" "RES_0402-0.0,5%,1/16W,CHIP,G21A"
					( Origin gPackager )
				)
				( attribute "POP" "NOPOP"
					( Origin gFrontEnd )
				)
				( objectStatus "R2W4" )
			)
			( gate "@baseboard_fab2_lib.baseboard_fab2(sch_1):page145_i176"
				( attribute "BOM_COST" "PROC_SIDEBAND"
					( Origin gFrontEnd )
				)
				( attribute "CDS_LIB" "mstr_discrete"
					( Origin gPackager )
				)
				( attribute "CDS_LOCATION" "R2W5"
					( Origin gPackager )
				)
				( attribute "CDS_SEC" "1"
					( Origin gPackager )
				)
				( attribute "LOCATION" "R2W5"
					( Origin gFrontEnd )
				)
				( attribute "MATERIAL" "CHIP"
					( Origin gFrontEnd )
				)
				( attribute "PACK_TYPE" "0402"
					( Origin gFrontEnd )
				)
				( attribute "PART_NUMBER" "G21497-005"
					( Origin gFrontEnd )
				)
				( attribute "PHYS_PAGE" "145"
					( Origin gFrontEnd )
				)
				( attribute "ROOM" "CPU0"
					( Origin gFrontEnd )
				)
				( attribute "ROT" "0"
					( Origin gFrontEnd )
				)
				( attribute "SEC" "1"
					( Origin gFrontEnd )
				)
				( attribute "SEC_TYPE" "0402"
					( Origin gFrontEnd )
				)
				( attribute "TOLERANCE" "5%"
					( Origin gFrontEnd )
				)
				( attribute "VALUE" "0.0"
					( Origin gFrontEnd )
				)
				( attribute "VER" "1"
					( Origin gFrontEnd )
				)
				( attribute "WATTAGE" "1/16W"
					( Origin gFrontEnd )
				)
				( attribute "XY" "(-1500,-1850)"
					( Origin gFrontEnd )
				)
				( attribute "CHIPS_PART_NAME" "RES"
					( Origin gPackager )
				)
				( attribute "CDS_PART_NAME" "RES_0402-0.0,5%,1/16W,CHIP,G21A"
					( Origin gPackager )
				)
				( objectStatus "R2W5" )
			)
			( gate "@baseboard_fab2_lib.baseboard_fab2(sch_1):page269_i76"
				( attribute "BOM_COST" "SB"
					( Origin gFrontEnd )
				)
				( attribute "CDS_LIB" "mstr_ttl"
					( Origin gPackager )
				)
				( attribute "CDS_LOCATION" "U25W19"
					( Origin gPackager )
				)
				( attribute "LOCATION" "U25W19"
					( Origin gFrontEnd )
				)
				( attribute "MATERIAL" "IC"
					( Origin gFrontEnd )
				)
				( attribute "PACK_TYPE" "SOT"
					( Origin gFrontEnd )
				)
				( attribute "PART_NUMBER" "A79322-001"
					( Origin gFrontEnd )
				)
				( attribute "PHYS_PAGE" "254"
					( Origin gFrontEnd )
				)
				( attribute "ROOM" "SB"
					( Origin gFrontEnd )
				)
				( attribute "ROT" "6"
					( Origin gFrontEnd )
				)
				( attribute "SEC" "1"
					( Origin gFrontEnd )
				)
				( attribute "SEC_TYPE" "SOT"
					( Origin gFrontEnd )
				)
				( attribute "VALUE" "74HC1G126"
					( Origin gFrontEnd )
				)
				( attribute "VER" "1"
					( Origin gFrontEnd )
				)
				( attribute "XY" "(-7850,4750)"
					( Origin gFrontEnd )
				)
				( attribute "CHIPS_PART_NAME" "TTL1G126_A"
					( Origin gPackager )
				)
				( attribute "CDS_PART_NAME" "TTL1G126_A_SOT-74HC1G126,IC,A7B"
					( Origin gPackager )
				)
				( attribute "CDS_SEC" "1"
					( Origin gPackager )
				)
				( objectStatus "U25W19" )
			)
			( gate "@baseboard_fab2_lib.baseboard_fab2(sch_1):page269_i4"
				( attribute "BOM_COST" "PROC_SIDEBAND"
					( Origin gFrontEnd )
				)
				( attribute "CDS_LIB" "mstr_discrete"
					( Origin gPackager )
				)
				( attribute "CDS_LOCATION" "R25W174"
					( Origin gPackager )
				)
				( attribute "CDS_SEC" "1"
					( Origin gPackager )
				)
				( attribute "LOCATION" "R25W174"
					( Origin gFrontEnd )
				)
				( attribute "MATERIAL" "CHIP"
					( Origin gFrontEnd )
				)
				( attribute "PACK_TYPE" "0402"
					( Origin gFrontEnd )
				)
				( attribute "PART_NUMBER" "G21796-016"
					( Origin gFrontEnd )
				)
				( attribute "PHYS_PAGE" "254"
					( Origin gFrontEnd )
				)
				( attribute "ROOM" "CPU0"
					( Origin gFrontEnd )
				)
				( attribute "ROT" "0"
					( Origin gFrontEnd )
				)
				( attribute "SEC" "1"
					( Origin gFrontEnd )
				)
				( attribute "SEC_TYPE" "0402"
					( Origin gFrontEnd )
				)
				( attribute "TOLERANCE" "1%"
					( Origin gFrontEnd )
				)
				( attribute "VALUE" "10.0K"
					( Origin gFrontEnd )
				)
				( attribute "VER" "2"
					( Origin gFrontEnd )
				)
				( attribute "WATTAGE" "1/16W"
					( Origin gFrontEnd )
				)
				( attribute "XY" "(-6400,3850)"
					( Origin gFrontEnd )
				)
				( attribute "CHIPS_PART_NAME" "RES"
					( Origin gPackager )
				)
				( attribute "CDS_PART_NAME" "RES_0402-10.0K,1%,1/16W,CHIP,GA"
					( Origin gPackager )
				)
				( objectStatus "R25W174" )
			)
			( gate "@baseboard_fab2_lib.baseboard_fab2(sch_1):page168_i46"
				( attribute "BOM_COST" "DEBUG"
					( Origin gFrontEnd )
				)
				( attribute "CDS_LIB" "mstr_discrete"
					( Origin gPackager )
				)
				( attribute "CDS_LOCATION" "R6W16"
					( Origin gPackager )
				)
				( attribute "CDS_SEC" "1"
					( Origin gPackager )
				)
				( attribute "LOCATION" "R6W16"
					( Origin gFrontEnd )
				)
				( attribute "MATERIAL" "CHIP"
					( Origin gFrontEnd )
				)
				( attribute "PACK_TYPE" "0402"
					( Origin gFrontEnd )
				)
				( attribute "PART_NUMBER" "G21796-026"
					( Origin gFrontEnd )
				)
				( attribute "PHYS_PAGE" "168"
					( Origin gFrontEnd )
				)
				( attribute "ROOM" "UART_MUX"
					( Origin gFrontEnd )
				)
				( attribute "ROT" "0"
					( Origin gFrontEnd )
				)
				( attribute "SEC" "1"
					( Origin gFrontEnd )
				)
				( attribute "SEC_TYPE" "0402"
					( Origin gFrontEnd )
				)
				( attribute "TOLERANCE" "1%"
					( Origin gFrontEnd )
				)
				( attribute "VALUE" "1.00K"
					( Origin gFrontEnd )
				)
				( attribute "VER" "2"
					( Origin gFrontEnd )
				)
				( attribute "WATTAGE" "1/16W"
					( Origin gFrontEnd )
				)
				( attribute "XY" "(-3950,2100)"
					( Origin gFrontEnd )
				)
				( attribute "CHIPS_PART_NAME" "RES"
					( Origin gPackager )
				)
				( attribute "CDS_PART_NAME" "RES_0402-1.00K,1%,1/16W,CHIP,GA"
					( Origin gPackager )
				)
				( objectStatus "R6W16" )
			)
			( gate "@baseboard_fab2_lib.baseboard_fab2(sch_1):page269_i10"
				( attribute "BOM_COST" "PROC_SIDEBAND"
					( Origin gFrontEnd )
				)
				( attribute "CDS_LIB" "mstr_discrete"
					( Origin gPackager )
				)
				( attribute "CDS_LOCATION" "R25W167"
					( Origin gPackager )
				)
				( attribute "CDS_SEC" "1"
					( Origin gPackager )
				)
				( attribute "LOCATION" "R25W167"
					( Origin gFrontEnd )
				)
				( attribute "MATERIAL" "CHIP"
					( Origin gFrontEnd )
				)
				( attribute "PACK_TYPE" "0402"
					( Origin gFrontEnd )
				)
				( attribute "PART_NUMBER" "G21796-026"
					( Origin gFrontEnd )
				)
				( attribute "PHYS_PAGE" "254"
					( Origin gFrontEnd )
				)
				( attribute "ROOM" "PROC_RSTS_PGOODS"
					( Origin gFrontEnd )
				)
				( attribute "ROT" "1"
					( Origin gFrontEnd )
				)
				( attribute "SEC" "1"
					( Origin gPackager )
				)
				( attribute "TOLERANCE" "1%"
					( Origin gFrontEnd )
				)
				( attribute "VALUE" "1.00K"
					( Origin gFrontEnd )
				)
				( attribute "VER" "2"
					( Origin gFrontEnd )
				)
				( attribute "WATTAGE" "1/16W"
					( Origin gFrontEnd )
				)
				( attribute "XY" "(-6100,2900)"
					( Origin gFrontEnd )
				)
				( attribute "CHIPS_PART_NAME" "RES"
					( Origin gPackager )
				)
				( attribute "CDS_PART_NAME" "RES_0402-1.00K,1%,1/16W,CHIP,GA"
					( Origin gPackager )
				)
				( objectStatus "R25W167" )
			)
			( gate "@baseboard_fab2_lib.baseboard_fab2(sch_1):page269_i11"
				( attribute "BOM_COST" "PROC_SIDEBAND"
					( Origin gFrontEnd )
				)
				( attribute "CDS_LIB" "mstr_discrete"
					( Origin gPackager )
				)
				( attribute "CDS_LOCATION" "R25W168"
					( Origin gPackager )
				)
				( attribute "CDS_SEC" "1"
					( Origin gPackager )
				)
				( attribute "LOCATION" "R25W168"
					( Origin gFrontEnd )
				)
				( attribute "MATERIAL" "CHIP"
					( Origin gFrontEnd )
				)
				( attribute "PACK_TYPE" "0402"
					( Origin gFrontEnd )
				)
				( attribute "PART_NUMBER" "G21796-026"
					( Origin gFrontEnd )
				)
				( attribute "PHYS_PAGE" "254"
					( Origin gFrontEnd )
				)
				( attribute "ROOM" "PROC_RSTS_PGOODS"
					( Origin gFrontEnd )
				)
				( attribute "ROT" "1"
					( Origin gFrontEnd )
				)
				( attribute "SEC" "1"
					( Origin gPackager )
				)
				( attribute "TOLERANCE" "1%"
					( Origin gFrontEnd )
				)
				( attribute "VALUE" "1.00K"
					( Origin gFrontEnd )
				)
				( attribute "VER" "2"
					( Origin gFrontEnd )
				)
				( attribute "WATTAGE" "1/16W"
					( Origin gFrontEnd )
				)
				( attribute "XY" "(-4750,3500)"
					( Origin gFrontEnd )
				)
				( attribute "CHIPS_PART_NAME" "RES"
					( Origin gPackager )
				)
				( attribute "CDS_PART_NAME" "RES_0402-1.00K,1%,1/16W,CHIP,GA"
					( Origin gPackager )
				)
				( objectStatus "R25W168" )
			)
			( gate "@baseboard_fab2_lib.baseboard_fab2(sch_1):page269_i12"
				( attribute "BOM_COST" "PROC_SIDEBAND"
					( Origin gFrontEnd )
				)
				( attribute "CDS_LIB" "mstr_discrete"
					( Origin gPackager )
				)
				( attribute "CDS_LOCATION" "R25W169"
					( Origin gPackager )
				)
				( attribute "CDS_SEC" "1"
					( Origin gPackager )
				)
				( attribute "LOCATION" "R25W169"
					( Origin gFrontEnd )
				)
				( attribute "MATERIAL" "CHIP"
					( Origin gFrontEnd )
				)
				( attribute "PACK_TYPE" "0402"
					( Origin gFrontEnd )
				)
				( attribute "PART_NUMBER" "G21796-026"
					( Origin gFrontEnd )
				)
				( attribute "PHYS_PAGE" "254"
					( Origin gFrontEnd )
				)
				( attribute "ROOM" "PROC_RSTS_PGOODS"
					( Origin gFrontEnd )
				)
				( attribute "ROT" "1"
					( Origin gFrontEnd )
				)
				( attribute "SEC" "1"
					( Origin gPackager )
				)
				( attribute "TOLERANCE" "1%"
					( Origin gFrontEnd )
				)
				( attribute "VALUE" "1.00K"
					( Origin gFrontEnd )
				)
				( attribute "VER" "2"
					( Origin gFrontEnd )
				)
				( attribute "WATTAGE" "1/16W"
					( Origin gFrontEnd )
				)
				( attribute "XY" "(-4750,3700)"
					( Origin gFrontEnd )
				)
				( attribute "CHIPS_PART_NAME" "RES"
					( Origin gPackager )
				)
				( attribute "CDS_PART_NAME" "RES_0402-1.00K,1%,1/16W,CHIP,GA"
					( Origin gPackager )
				)
				( objectStatus "R25W169" )
			)
			( gate "@baseboard_fab2_lib.baseboard_fab2(sch_1):page269_i13"
				( attribute "BOM_COST" "PROC_SIDEBAND"
					( Origin gFrontEnd )
				)
				( attribute "CDS_LIB" "mstr_discrete"
					( Origin gPackager )
				)
				( attribute "CDS_LOCATION" "R25W170"
					( Origin gPackager )
				)
				( attribute "CDS_SEC" "1"
					( Origin gPackager )
				)
				( attribute "LOCATION" "R25W170"
					( Origin gFrontEnd )
				)
				( attribute "MATERIAL" "CHIP"
					( Origin gFrontEnd )
				)
				( attribute "PACK_TYPE" "0402"
					( Origin gFrontEnd )
				)
				( attribute "PART_NUMBER" "G21796-026"
					( Origin gFrontEnd )
				)
				( attribute "PHYS_PAGE" "254"
					( Origin gFrontEnd )
				)
				( attribute "ROOM" "PROC_RSTS_PGOODS"
					( Origin gFrontEnd )
				)
				( attribute "ROT" "1"
					( Origin gFrontEnd )
				)
				( attribute "SEC" "1"
					( Origin gPackager )
				)
				( attribute "TOLERANCE" "1%"
					( Origin gFrontEnd )
				)
				( attribute "VALUE" "1.00K"
					( Origin gFrontEnd )
				)
				( attribute "VER" "2"
					( Origin gFrontEnd )
				)
				( attribute "WATTAGE" "1/16W"
					( Origin gFrontEnd )
				)
				( attribute "XY" "(-4750,3900)"
					( Origin gFrontEnd )
				)
				( attribute "CHIPS_PART_NAME" "RES"
					( Origin gPackager )
				)
				( attribute "CDS_PART_NAME" "RES_0402-1.00K,1%,1/16W,CHIP,GA"
					( Origin gPackager )
				)
				( objectStatus "R25W170" )
			)
			( gate "@baseboard_fab2_lib.baseboard_fab2(sch_1):page269_i18"
				( attribute "BOM_COST" "PROC_SIDEBAND"
					( Origin gFrontEnd )
				)
				( attribute "CDS_LIB" "mstr_discrete"
					( Origin gPackager )
				)
				( attribute "CDS_LOCATION" "R25W177"
					( Origin gPackager )
				)
				( attribute "CDS_SEC" "1"
					( Origin gPackager )
				)
				( attribute "LOCATION" "R25W177"
					( Origin gFrontEnd )
				)
				( attribute "MATERIAL" "CHIP"
					( Origin gFrontEnd )
				)
				( attribute "PACK_TYPE" "0402"
					( Origin gFrontEnd )
				)
				( attribute "PART_NUMBER" "G21796-026"
					( Origin gFrontEnd )
				)
				( attribute "PHYS_PAGE" "254"
					( Origin gFrontEnd )
				)
				( attribute "ROOM" "PROC_RSTS_PGOODS"
					( Origin gFrontEnd )
				)
				( attribute "ROT" "0"
					( Origin gFrontEnd )
				)
				( attribute "SEC" "1"
					( Origin gPackager )
				)
				( attribute "TOLERANCE" "1%"
					( Origin gFrontEnd )
				)
				( attribute "VALUE" "1.00K"
					( Origin gFrontEnd )
				)
				( attribute "VER" "2"
					( Origin gFrontEnd )
				)
				( attribute "WATTAGE" "1/16W"
					( Origin gFrontEnd )
				)
				( attribute "XY" "(-7650,6050)"
					( Origin gFrontEnd )
				)
				( attribute "CHIPS_PART_NAME" "RES"
					( Origin gPackager )
				)
				( attribute "CDS_PART_NAME" "RES_0402-1.00K,1%,1/16W,CHIP,GA"
					( Origin gPackager )
				)
				( objectStatus "R25W177" )
			)
			( gate "@baseboard_fab2_lib.baseboard_fab2(sch_1):page269_i19"
				( attribute "BOM_COST" "PROC_SIDEBAND"
					( Origin gFrontEnd )
				)
				( attribute "CDS_LIB" "mstr_discrete"
					( Origin gPackager )
				)
				( attribute "CDS_LOCATION" "R25W178"
					( Origin gPackager )
				)
				( attribute "CDS_SEC" "1"
					( Origin gPackager )
				)
				( attribute "LOCATION" "R25W178"
					( Origin gFrontEnd )
				)
				( attribute "MATERIAL" "CHIP"
					( Origin gFrontEnd )
				)
				( attribute "PACK_TYPE" "0402"
					( Origin gFrontEnd )
				)
				( attribute "PART_NUMBER" "G21796-026"
					( Origin gFrontEnd )
				)
				( attribute "PHYS_PAGE" "254"
					( Origin gFrontEnd )
				)
				( attribute "ROOM" "PROC_RSTS_PGOODS"
					( Origin gFrontEnd )
				)
				( attribute "ROT" "0"
					( Origin gFrontEnd )
				)
				( attribute "SEC" "1"
					( Origin gPackager )
				)
				( attribute "TOLERANCE" "1%"
					( Origin gFrontEnd )
				)
				( attribute "VALUE" "1.00K"
					( Origin gFrontEnd )
				)
				( attribute "VER" "2"
					( Origin gFrontEnd )
				)
				( attribute "WATTAGE" "1/16W"
					( Origin gFrontEnd )
				)
				( attribute "XY" "(-7350,6050)"
					( Origin gFrontEnd )
				)
				( attribute "CHIPS_PART_NAME" "RES"
					( Origin gPackager )
				)
				( attribute "CDS_PART_NAME" "RES_0402-1.00K,1%,1/16W,CHIP,GA"
					( Origin gPackager )
				)
				( objectStatus "R25W178" )
			)
			( gate "@baseboard_fab2_lib.baseboard_fab2(sch_1):page269_i20"
				( attribute "BOM_COST" "PROC_SIDEBAND"
					( Origin gFrontEnd )
				)
				( attribute "CDS_LIB" "mstr_discrete"
					( Origin gPackager )
				)
				( attribute "CDS_LOCATION" "R25W160"
					( Origin gPackager )
				)
				( attribute "CDS_SEC" "1"
					( Origin gPackager )
				)
				( attribute "LOCATION" "R25W160"
					( Origin gFrontEnd )
				)
				( attribute "MATERIAL" "CHIP"
					( Origin gFrontEnd )
				)
				( attribute "PACK_TYPE" "0402"
					( Origin gFrontEnd )
				)
				( attribute "PART_NUMBER" "G21796-026"
					( Origin gFrontEnd )
				)
				( attribute "PHYS_PAGE" "254"
					( Origin gFrontEnd )
				)
				( attribute "ROOM" "PROC_RSTS_PGOODS"
					( Origin gFrontEnd )
				)
				( attribute "ROT" "0"
					( Origin gFrontEnd )
				)
				( attribute "SEC" "1"
					( Origin gPackager )
				)
				( attribute "TOLERANCE" "1%"
					( Origin gFrontEnd )
				)
				( attribute "VALUE" "1.00K"
					( Origin gFrontEnd )
				)
				( attribute "VER" "2"
					( Origin gFrontEnd )
				)
				( attribute "WATTAGE" "1/16W"
					( Origin gFrontEnd )
				)
				( attribute "XY" "(-7050,6050)"
					( Origin gFrontEnd )
				)
				( attribute "CHIPS_PART_NAME" "RES"
					( Origin gPackager )
				)
				( attribute "CDS_PART_NAME" "RES_0402-1.00K,1%,1/16W,CHIP,GA"
					( Origin gPackager )
				)
				( objectStatus "R25W160" )
			)
			( gate "@baseboard_fab2_lib.baseboard_fab2(sch_1):page269_i21"
				( attribute "BOM_COST" "PROC_SIDEBAND"
					( Origin gFrontEnd )
				)
				( attribute "CDS_LIB" "mstr_discrete"
					( Origin gPackager )
				)
				( attribute "CDS_LOCATION" "R25W161"
					( Origin gPackager )
				)
				( attribute "CDS_SEC" "1"
					( Origin gPackager )
				)
				( attribute "LOCATION" "R25W161"
					( Origin gFrontEnd )
				)
				( attribute "MATERIAL" "CHIP"
					( Origin gFrontEnd )
				)
				( attribute "PACK_TYPE" "0402"
					( Origin gFrontEnd )
				)
				( attribute "PART_NUMBER" "G21796-026"
					( Origin gFrontEnd )
				)
				( attribute "PHYS_PAGE" "254"
					( Origin gFrontEnd )
				)
				( attribute "ROOM" "PROC_RSTS_PGOODS"
					( Origin gFrontEnd )
				)
				( attribute "ROT" "0"
					( Origin gFrontEnd )
				)
				( attribute "SEC" "1"
					( Origin gPackager )
				)
				( attribute "TOLERANCE" "1%"
					( Origin gFrontEnd )
				)
				( attribute "VALUE" "1.00K"
					( Origin gFrontEnd )
				)
				( attribute "VER" "2"
					( Origin gFrontEnd )
				)
				( attribute "WATTAGE" "1/16W"
					( Origin gFrontEnd )
				)
				( attribute "XY" "(-6750,6050)"
					( Origin gFrontEnd )
				)
				( attribute "CHIPS_PART_NAME" "RES"
					( Origin gPackager )
				)
				( attribute "CDS_PART_NAME" "RES_0402-1.00K,1%,1/16W,CHIP,GA"
					( Origin gPackager )
				)
				( objectStatus "R25W161" )
			)
			( gate "@baseboard_fab2_lib.baseboard_fab2(sch_1):page269_i22"
				( attribute "BOM_COST" "PROC_SIDEBAND"
					( Origin gFrontEnd )
				)
				( attribute "CDS_LIB" "mstr_discrete"
					( Origin gPackager )
				)
				( attribute "CDS_LOCATION" "R25W158"
					( Origin gPackager )
				)
				( attribute "CDS_SEC" "1"
					( Origin gPackager )
				)
				( attribute "LOCATION" "R25W158"
					( Origin gFrontEnd )
				)
				( attribute "MATERIAL" "CHIP"
					( Origin gFrontEnd )
				)
				( attribute "PACK_TYPE" "0402"
					( Origin gFrontEnd )
				)
				( attribute "PART_NUMBER" "G21796-026"
					( Origin gFrontEnd )
				)
				( attribute "PHYS_PAGE" "254"
					( Origin gFrontEnd )
				)
				( attribute "ROOM" "PROC_RSTS_PGOODS"
					( Origin gFrontEnd )
				)
				( attribute "ROT" "0"
					( Origin gFrontEnd )
				)
				( attribute "SEC" "1"
					( Origin gPackager )
				)
				( attribute "TOLERANCE" "1%"
					( Origin gFrontEnd )
				)
				( attribute "VALUE" "1.00K"
					( Origin gFrontEnd )
				)
				( attribute "VER" "2"
					( Origin gFrontEnd )
				)
				( attribute "WATTAGE" "1/16W"
					( Origin gFrontEnd )
				)
				( attribute "XY" "(-6450,6050)"
					( Origin gFrontEnd )
				)
				( attribute "CHIPS_PART_NAME" "RES"
					( Origin gPackager )
				)
				( attribute "CDS_PART_NAME" "RES_0402-1.00K,1%,1/16W,CHIP,GA"
					( Origin gPackager )
				)
				( objectStatus "R25W158" )
			)
			( gate "@baseboard_fab2_lib.baseboard_fab2(sch_1):page269_i24"
				( attribute "BOM_COST" "PROC_SIDEBAND"
					( Origin gFrontEnd )
				)
				( attribute "CDS_LIB" "mstr_discrete"
					( Origin gPackager )
				)
				( attribute "CDS_LOCATION" "R25W159"
					( Origin gPackager )
				)
				( attribute "CDS_SEC" "1"
					( Origin gPackager )
				)
				( attribute "LOCATION" "R25W159"
					( Origin gFrontEnd )
				)
				( attribute "MATERIAL" "CHIP"
					( Origin gFrontEnd )
				)
				( attribute "PACK_TYPE" "0402"
					( Origin gFrontEnd )
				)
				( attribute "PART_NUMBER" "G21796-026"
					( Origin gFrontEnd )
				)
				( attribute "PHYS_PAGE" "254"
					( Origin gFrontEnd )
				)
				( attribute "ROOM" "PROC_RSTS_PGOODS"
					( Origin gFrontEnd )
				)
				( attribute "ROT" "0"
					( Origin gFrontEnd )
				)
				( attribute "SEC" "1"
					( Origin gFrontEnd )
				)
				( attribute "SEC_TYPE" "0402"
					( Origin gFrontEnd )
				)
				( attribute "TOLERANCE" "1%"
					( Origin gFrontEnd )
				)
				( attribute "VALUE" "1.00K"
					( Origin gFrontEnd )
				)
				( attribute "VER" "1"
					( Origin gFrontEnd )
				)
				( attribute "WATTAGE" "1/16W"
					( Origin gFrontEnd )
				)
				( attribute "XY" "(-6050,6000)"
					( Origin gFrontEnd )
				)
				( attribute "CHIPS_PART_NAME" "RES"
					( Origin gPackager )
				)
				( attribute "CDS_PART_NAME" "RES_0402-1.00K,1%,1/16W,CHIP,GA"
					( Origin gPackager )
				)
				( objectStatus "R25W159" )
			)
			( gate "@baseboard_fab2_lib.baseboard_fab2(sch_1):page269_i26"
				( attribute "BOM_COST" "PROC_SIDEBAND"
					( Origin gFrontEnd )
				)
				( attribute "CDS_LIB" "dev_discrete"
					( Origin gPackager )
				)
				( attribute "CDS_LOCATION" "C25W91"
					( Origin gPackager )
				)
				( attribute "CDS_SEC" "1"
					( Origin gPackager )
				)
				( attribute "LOCATION" "C25W91"
					( Origin gFrontEnd )
				)
				( attribute "MATERIAL" "X6S"
					( Origin gFrontEnd )
				)
				( attribute "PACK_TYPE" "0402V"
					( Origin gFrontEnd )
				)
				( attribute "PART_NUMBER" "D97712-004"
					( Origin gFrontEnd )
				)
				( attribute "PHYS_PAGE" "254"
					( Origin gFrontEnd )
				)
				( attribute "ROOM" "PROC_RSTS_PGOODS"
					( Origin gFrontEnd )
				)
				( attribute "ROT" "0"
					( Origin gFrontEnd )
				)
				( attribute "SEC" "1"
					( Origin gFrontEnd )
				)
				( attribute "SEC_TYPE" "0402V"
					( Origin gFrontEnd )
				)
				( attribute "TOLERANCE" "10%"
					( Origin gFrontEnd )
				)
				( attribute "VALUE" "1.0UF"
					( Origin gFrontEnd )
				)
				( attribute "VER" "1"
					( Origin gFrontEnd )
				)
				( attribute "VOLTAGE" "6.3V"
					( Units "uVoltage" "V" 1.000000)
					( Origin gFrontEnd )
				)
				( attribute "XY" "(-5800,6050)"
					( Origin gFrontEnd )
				)
				( attribute "CHIPS_PART_NAME" "CAP_A"
					( Origin gPackager )
				)
				( attribute "CDS_PART_NAME" "CAP_A_0402V-1.0UF,6.3V,10%,X6SA"
					( Origin gPackager )
				)
				( objectStatus "C25W91" )
			)
			( gate "@baseboard_fab2_lib.baseboard_fab2(sch_1):page269_i32"
				( attribute "CDS_LIB" "mstr_discrete"
					( Origin gPackager )
				)
				( attribute "CDS_LOCATION" "C25W94"
					( Origin gPackager )
				)
				( attribute "CDS_SEC" "1"
					( Origin gPackager )
				)
				( attribute "LOCATION" "C25W94"
					( Origin gFrontEnd )
				)
				( attribute "MATERIAL" "X6S"
					( Origin gFrontEnd )
				)
				( attribute "PACK_TYPE" "0402"
					( Origin gFrontEnd )
				)
				( attribute "PART_NUMBER" "D97712-011"
					( Origin gFrontEnd )
				)
				( attribute "PHYS_PAGE" "254"
					( Origin gFrontEnd )
				)
				( attribute "ROOM" "DEBUG"
					( Origin gFrontEnd )
				)
				( attribute "ROT" "0"
					( Origin gFrontEnd )
				)
				( attribute "SEC" "1"
					( Origin gFrontEnd )
				)
				( attribute "SEC_TYPE" "0402"
					( Origin gFrontEnd )
				)
				( attribute "TOLERANCE" "10%"
					( Origin gFrontEnd )
				)
				( attribute "VALUE" "1.0UF"
					( Origin gFrontEnd )
				)
				( attribute "VER" "1"
					( Origin gFrontEnd )
				)
				( attribute "VOLTAGE" "16V"
					( Units "uVoltage" "V" 1.000000)
					( Origin gFrontEnd )
				)
				( attribute "XY" "(-3050,3000)"
					( Origin gFrontEnd )
				)
				( attribute "CHIPS_PART_NAME" "CAP"
					( Origin gPackager )
				)
				( attribute "CDS_PART_NAME" "CAP_0402-1.0UF,16V,10%,X6S,D97A"
					( Origin gPackager )
				)
				( objectStatus "C25W94" )
			)
			( gate "@baseboard_fab2_lib.baseboard_fab2(sch_1):page269_i33"
				( attribute "CDS_LIB" "mstr_ttl"
					( Origin gPackager )
				)
				( attribute "CDS_LOCATION" "U25W12"
					( Origin gPackager )
				)
				( attribute "HAS_FIXED_SIZE" "4"
					( Origin gFrontEnd )
				)
				( attribute "LOCATION" "U25W12"
					( Origin gFrontEnd )
				)
				( attribute "MATERIAL" "IC"
					( Origin gFrontEnd )
				)
				( attribute "PACK_TYPE" "QFNLF"
					( Origin gFrontEnd )
				)
				( attribute "PART_NUMBER" "D18317-001"
					( Origin gFrontEnd )
				)
				( attribute "PHYS_PAGE" "254"
					( Origin gFrontEnd )
				)
				( attribute "ROOM" "DEBUG"
					( Origin gFrontEnd )
				)
				( attribute "ROT" "0"
					( Origin gFrontEnd )
				)
				( attribute "SIZE" "4"
					( Origin gFrontEnd )
				)
				( attribute "VALUE" "74CBTLV3126"
					( Origin gFrontEnd )
				)
				( attribute "VER" "3"
					( Origin gFrontEnd )
				)
				( attribute "XY" "(-3700,3750)"
					( Origin gFrontEnd )
				)
				( attribute "CHIPS_PART_NAME" "TTL3126"
					( Origin gPackager )
				)
				( attribute "CDS_PART_NAME" "TTL3126_QFNLF-74CBTLV3126,IC,DB"
					( Origin gPackager )
				)
				( objectStatus "U25W12" )
			)
			( gate "@baseboard_fab2_lib.baseboard_fab2(sch_1):page269_i49"
				( attribute "BOM_COST" "PROC_SIDEBAND"
					( Origin gFrontEnd )
				)
				( attribute "CDS_LIB" "mstr_digital"
					( Origin gPackager )
				)
				( attribute "CDS_LOCATION" "U25W10"
					( Origin gPackager )
				)
				( attribute "CDS_SEC" "1"
					( Origin gPackager )
				)
				( attribute "LOCATION" "U25W10"
					( Origin gFrontEnd )
				)
				( attribute "MATERIAL" "IC"
					( Origin gFrontEnd )
				)
				( attribute "PACK_TYPE" "SM"
					( Origin gFrontEnd )
				)
				( attribute "PART_NUMBER" "D66151-001"
					( Origin gFrontEnd )
				)
				( attribute "PHYS_PAGE" "254"
					( Origin gFrontEnd )
				)
				( attribute "ROOM" "PROC_RSTS_PGOODS"
					( Origin gFrontEnd )
				)
				( attribute "ROT" "0"
					( Origin gFrontEnd )
				)
				( attribute "SEC" "1"
					( Origin gPackager )
				)
				( attribute "VER" "1"
					( Origin gFrontEnd )
				)
				( attribute "XY" "(-4950,5500)"
					( Origin gFrontEnd )
				)
				( attribute "CHIPS_PART_NAME" "GTL2014"
					( Origin gPackager )
				)
				( attribute "CDS_PART_NAME" "GTL2014_SM-IC,D66151-001"
					( Origin gPackager )
				)
				( objectStatus "U25W10" )
			)
			( gate "@baseboard_fab2_lib.baseboard_fab2(sch_1):page268_i2"
				( attribute "BOM_COST" "PROC_SIDEBAND"
					( Origin gFrontEnd )
				)
				( attribute "CDS_LIB" "mstr_discrete"
					( Origin gPackager )
				)
				( attribute "CDS_LOCATION" "R25W180"
					( Origin gPackager )
				)
				( attribute "CDS_SEC" "1"
					( Origin gPackager )
				)
				( attribute "LOCATION" "R25W180"
					( Origin gFrontEnd )
				)
				( attribute "MATERIAL" "CHIP"
					( Origin gFrontEnd )
				)
				( attribute "PACK_TYPE" "0402"
					( Origin gFrontEnd )
				)
				( attribute "PART_NUMBER" "G21796-026"
					( Origin gFrontEnd )
				)
				( attribute "PHYS_PAGE" "255"
					( Origin gFrontEnd )
				)
				( attribute "ROOM" "PROC_RSTS_PGOODS"
					( Origin gFrontEnd )
				)
				( attribute "ROT" "0"
					( Origin gFrontEnd )
				)
				( attribute "SEC" "1"
					( Origin gPackager )
				)
				( attribute "TOLERANCE" "1%"
					( Origin gFrontEnd )
				)
				( attribute "VALUE" "1.00K"
					( Origin gFrontEnd )
				)
				( attribute "VER" "2"
					( Origin gFrontEnd )
				)
				( attribute "WATTAGE" "1/16W"
					( Origin gFrontEnd )
				)
				( attribute "XY" "(-7100,3350)"
					( Origin gFrontEnd )
				)
				( attribute "CHIPS_PART_NAME" "RES"
					( Origin gPackager )
				)
				( attribute "CDS_PART_NAME" "RES_0402-1.00K,1%,1/16W,CHIP,GA"
					( Origin gPackager )
				)
				( objectStatus "R25W180" )
			)
			( gate "@baseboard_fab2_lib.baseboard_fab2(sch_1):page268_i4"
				( attribute "BOM_COST" "SM_THERM"
					( Origin gFrontEnd )
				)
				( attribute "CDS_LIB" "dev_discrete"
					( Origin gPackager )
				)
				( attribute "CDS_LOCATION" "C25W97"
					( Origin gPackager )
				)
				( attribute "CDS_SEC" "1"
					( Origin gPackager )
				)
				( attribute "LOCATION" "C25W97"
					( Origin gFrontEnd )
				)
				( attribute "MATERIAL" "X7R"
					( Origin gFrontEnd )
				)
				( attribute "PACK_TYPE" "0402V"
					( Origin gFrontEnd )
				)
				( attribute "PART_NUMBER" "A36096-030"
					( Origin gFrontEnd )
				)
				( attribute "PHYS_PAGE" "255"
					( Origin gFrontEnd )
				)
				( attribute "ROOM" "CPU_FANS"
					( Origin gFrontEnd )
				)
				( attribute "ROT" "0"
					( Origin gFrontEnd )
				)
				( attribute "SEC" "1"
					( Origin gFrontEnd )
				)
				( attribute "SEC_TYPE" "0402V"
					( Origin gFrontEnd )
				)
				( attribute "TOLERANCE" "10%"
					( Origin gFrontEnd )
				)
				( attribute "VALUE" "0.1UF"
					( Origin gFrontEnd )
				)
				( attribute "VER" "1"
					( Origin gFrontEnd )
				)
				( attribute "VOLTAGE" "16V"
					( Units "uVoltage" "V" 1.000000)
					( Origin gFrontEnd )
				)
				( attribute "XY" "(-6700,3350)"
					( Origin gFrontEnd )
				)
				( attribute "CHIPS_PART_NAME" "CAP_A"
					( Origin gPackager )
				)
				( attribute "CDS_PART_NAME" "CAP_A_0402V-0.1UF,16V,10%,X7R,A"
					( Origin gPackager )
				)
				( objectStatus "C25W97" )
			)
			( gate "@baseboard_fab2_lib.baseboard_fab2(sch_1):page268_i7"
				( attribute "BOM_COST" "PROC_SIDEBAND"
					( Origin gFrontEnd )
				)
				( attribute "CDS_LIB" "mstr_discrete"
					( Origin gPackager )
				)
				( attribute "CDS_LOCATION" "R25W179"
					( Origin gPackager )
				)
				( attribute "CDS_SEC" "1"
					( Origin gPackager )
				)
				( attribute "LOCATION" "R25W179"
					( Origin gFrontEnd )
				)
				( attribute "MATERIAL" "CHIP"
					( Origin gFrontEnd )
				)
				( attribute "PACK_TYPE" "0402"
					( Origin gFrontEnd )
				)
				( attribute "PART_NUMBER" "G21796-026"
					( Origin gFrontEnd )
				)
				( attribute "PHYS_PAGE" "255"
					( Origin gFrontEnd )
				)
				( attribute "ROOM" "PROC_RSTS_PGOODS"
					( Origin gFrontEnd )
				)
				( attribute "ROT" "0"
					( Origin gFrontEnd )
				)
				( attribute "SEC" "1"
					( Origin gPackager )
				)
				( attribute "TOLERANCE" "1%"
					( Origin gFrontEnd )
				)
				( attribute "VALUE" "1.00K"
					( Origin gFrontEnd )
				)
				( attribute "VER" "2"
					( Origin gFrontEnd )
				)
				( attribute "WATTAGE" "1/16W"
					( Origin gFrontEnd )
				)
				( attribute "XY" "(-7100,4150)"
					( Origin gFrontEnd )
				)
				( attribute "CHIPS_PART_NAME" "RES"
					( Origin gPackager )
				)
				( attribute "CDS_PART_NAME" "RES_0402-1.00K,1%,1/16W,CHIP,GA"
					( Origin gPackager )
				)
				( objectStatus "R25W179" )
			)
			( gate "@baseboard_fab2_lib.baseboard_fab2(sch_1):page268_i9"
				( attribute "BOM_COST" "SM_THERM"
					( Origin gFrontEnd )
				)
				( attribute "CDS_LIB" "dev_discrete"
					( Origin gPackager )
				)
				( attribute "CDS_LOCATION" "C25W96"
					( Origin gPackager )
				)
				( attribute "CDS_SEC" "1"
					( Origin gPackager )
				)
				( attribute "LOCATION" "C25W96"
					( Origin gFrontEnd )
				)
				( attribute "MATERIAL" "X7R"
					( Origin gFrontEnd )
				)
				( attribute "PACK_TYPE" "0402V"
					( Origin gFrontEnd )
				)
				( attribute "PART_NUMBER" "A36096-030"
					( Origin gFrontEnd )
				)
				( attribute "PHYS_PAGE" "255"
					( Origin gFrontEnd )
				)
				( attribute "ROOM" "CPU_FANS"
					( Origin gFrontEnd )
				)
				( attribute "ROT" "0"
					( Origin gFrontEnd )
				)
				( attribute "SEC" "1"
					( Origin gFrontEnd )
				)
				( attribute "SEC_TYPE" "0402V"
					( Origin gFrontEnd )
				)
				( attribute "TOLERANCE" "10%"
					( Origin gFrontEnd )
				)
				( attribute "VALUE" "0.1UF"
					( Origin gFrontEnd )
				)
				( attribute "VER" "1"
					( Origin gFrontEnd )
				)
				( attribute "VOLTAGE" "16V"
					( Units "uVoltage" "V" 1.000000)
					( Origin gFrontEnd )
				)
				( attribute "XY" "(-6700,4150)"
					( Origin gFrontEnd )
				)
				( attribute "CHIPS_PART_NAME" "CAP_A"
					( Origin gPackager )
				)
				( attribute "CDS_PART_NAME" "CAP_A_0402V-0.1UF,16V,10%,X7R,A"
					( Origin gPackager )
				)
				( objectStatus "C25W96" )
			)
			( gate "@baseboard_fab2_lib.baseboard_fab2(sch_1):page268_i12"
				( attribute "BOM_COST" "SM_THERM"
					( Origin gFrontEnd )
				)
				( attribute "CDS_LIB" "mstr_ttl"
					( Origin gPackager )
				)
				( attribute "CDS_LOCATION" "U25W15"
					( Origin gPackager )
				)
				( attribute "CDS_SEC" "1"
					( Origin gPackager )
				)
				( attribute "LOCATION" "U25W15"
					( Origin gFrontEnd )
				)
				( attribute "MATERIAL" "IC"
					( Origin gFrontEnd )
				)
				( attribute "PACK_TYPE" "SOP"
					( Origin gFrontEnd )
				)
				( attribute "PART_NUMBER" "C88419-001"
					( Origin gFrontEnd )
				)
				( attribute "PHYS_PAGE" "255"
					( Origin gFrontEnd )
				)
				( attribute "ROOM" "CPU_FANS"
					( Origin gFrontEnd )
				)
				( attribute "ROT" "0"
					( Origin gFrontEnd )
				)
				( attribute "SEC" "1"
					( Origin gFrontEnd )
				)
				( attribute "SEC_TYPE" "SOP"
					( Origin gFrontEnd )
				)
				( attribute "VALUE" "74LVC1G07"
					( Origin gFrontEnd )
				)
				( attribute "VER" "1"
					( Origin gFrontEnd )
				)
				( attribute "XY" "(-6300,3100)"
					( Origin gFrontEnd )
				)
				( attribute "CHIPS_PART_NAME" "TTL1G07_A"
					( Origin gPackager )
				)
				( attribute "CDS_PART_NAME" "TTL1G07_A_SOP-74LVC1G07,IC,C88B"
					( Origin gPackager )
				)
				( objectStatus "U25W15" )
			)
			( gate "@baseboard_fab2_lib.baseboard_fab2(sch_1):page268_i13"
				( attribute "BOM_COST" "SM_THERM"
					( Origin gFrontEnd )
				)
				( attribute "CDS_LIB" "mstr_ttl"
					( Origin gPackager )
				)
				( attribute "CDS_LOCATION" "U25W14"
					( Origin gPackager )
				)
				( attribute "CDS_SEC" "1"
					( Origin gPackager )
				)
				( attribute "LOCATION" "U25W14"
					( Origin gFrontEnd )
				)
				( attribute "MATERIAL" "IC"
					( Origin gFrontEnd )
				)
				( attribute "PACK_TYPE" "SOP"
					( Origin gFrontEnd )
				)
				( attribute "PART_NUMBER" "C88419-001"
					( Origin gFrontEnd )
				)
				( attribute "PHYS_PAGE" "255"
					( Origin gFrontEnd )
				)
				( attribute "ROOM" "CPU_FANS"
					( Origin gFrontEnd )
				)
				( attribute "ROT" "0"
					( Origin gFrontEnd )
				)
				( attribute "SEC" "1"
					( Origin gFrontEnd )
				)
				( attribute "SEC_TYPE" "SOP"
					( Origin gFrontEnd )
				)
				( attribute "VALUE" "74LVC1G07"
					( Origin gFrontEnd )
				)
				( attribute "VER" "1"
					( Origin gFrontEnd )
				)
				( attribute "XY" "(-6300,3900)"
					( Origin gFrontEnd )
				)
				( attribute "CHIPS_PART_NAME" "TTL1G07_A"
					( Origin gPackager )
				)
				( attribute "CDS_PART_NAME" "TTL1G07_A_SOP-74LVC1G07,IC,C88B"
					( Origin gPackager )
				)
				( objectStatus "U25W14" )
			)
			( gate "@baseboard_fab2_lib.baseboard_fab2(sch_1):page268_i14"
				( attribute "BOM_COST" "PROC_SIDEBAND"
					( Origin gFrontEnd )
				)
				( attribute "CDS_LIB" "mstr_discrete"
					( Origin gPackager )
				)
				( attribute "CDS_LOCATION" "R25W176"
					( Origin gPackager )
				)
				( attribute "CDS_SEC" "1"
					( Origin gPackager )
				)
				( attribute "LOCATION" "R25W176"
					( Origin gFrontEnd )
				)
				( attribute "MATERIAL" "CHIP"
					( Origin gFrontEnd )
				)
				( attribute "PACK_TYPE" "0402"
					( Origin gFrontEnd )
				)
				( attribute "PART_NUMBER" "G21796-026"
					( Origin gFrontEnd )
				)
				( attribute "PHYS_PAGE" "255"
					( Origin gFrontEnd )
				)
				( attribute "ROOM" "PROC_RSTS_PGOODS"
					( Origin gFrontEnd )
				)
				( attribute "ROT" "0"
					( Origin gFrontEnd )
				)
				( attribute "SEC" "1"
					( Origin gPackager )
				)
				( attribute "TOLERANCE" "1%"
					( Origin gFrontEnd )
				)
				( attribute "VALUE" "1.00K"
					( Origin gFrontEnd )
				)
				( attribute "VER" "2"
					( Origin gFrontEnd )
				)
				( attribute "WATTAGE" "1/16W"
					( Origin gFrontEnd )
				)
				( attribute "XY" "(-8450,4950)"
					( Origin gFrontEnd )
				)
				( attribute "CHIPS_PART_NAME" "RES"
					( Origin gPackager )
				)
				( attribute "CDS_PART_NAME" "RES_0402-1.00K,1%,1/16W,CHIP,GA"
					( Origin gPackager )
				)
				( objectStatus "R25W176" )
			)
			( gate "@baseboard_fab2_lib.baseboard_fab2(sch_1):page268_i17"
				( attribute "BOM_COST" "PROC_SIDEBAND"
					( Origin gFrontEnd )
				)
				( attribute "CDS_LIB" "mstr_discrete"
					( Origin gPackager )
				)
				( attribute "CDS_LOCATION" "R25W175"
					( Origin gPackager )
				)
				( attribute "CDS_SEC" "1"
					( Origin gPackager )
				)
				( attribute "LOCATION" "R25W175"
					( Origin gFrontEnd )
				)
				( attribute "MATERIAL" "CHIP"
					( Origin gFrontEnd )
				)
				( attribute "PACK_TYPE" "0402"
					( Origin gFrontEnd )
				)
				( attribute "PART_NUMBER" "G21796-026"
					( Origin gFrontEnd )
				)
				( attribute "PHYS_PAGE" "255"
					( Origin gFrontEnd )
				)
				( attribute "ROOM" "PROC_RSTS_PGOODS"
					( Origin gFrontEnd )
				)
				( attribute "ROT" "0"
					( Origin gFrontEnd )
				)
				( attribute "SEC" "1"
					( Origin gPackager )
				)
				( attribute "TOLERANCE" "1%"
					( Origin gFrontEnd )
				)
				( attribute "VALUE" "1.00K"
					( Origin gFrontEnd )
				)
				( attribute "VER" "2"
					( Origin gFrontEnd )
				)
				( attribute "WATTAGE" "1/16W"
					( Origin gFrontEnd )
				)
				( attribute "XY" "(-8150,4950)"
					( Origin gFrontEnd )
				)
				( attribute "CHIPS_PART_NAME" "RES"
					( Origin gPackager )
				)
				( attribute "CDS_PART_NAME" "RES_0402-1.00K,1%,1/16W,CHIP,GA"
					( Origin gPackager )
				)
				( objectStatus "R25W175" )
			)
			( gate "@baseboard_fab2_lib.baseboard_fab2(sch_1):page268_i23"
				( attribute "BOM_COST" "PROC"
					( Origin gFrontEnd )
				)
				( attribute "CDS_LIB" "mstr_discrete"
					( Origin gPackager )
				)
				( attribute "CDS_LOCATION" "C25W92"
					( Origin gPackager )
				)
				( attribute "CDS_SEC" "1"
					( Origin gPackager )
				)
				( attribute "LOCATION" "C25W92"
					( Origin gFrontEnd )
				)
				( attribute "MATERIAL" "X6S"
					( Origin gFrontEnd )
				)
				( attribute "PACK_TYPE" "0402"
					( Origin gFrontEnd )
				)
				( attribute "PART_NUMBER" "D97712-011"
					( Origin gFrontEnd )
				)
				( attribute "PHYS_PAGE" "255"
					( Origin gFrontEnd )
				)
				( attribute "ROOM" "PROC_SIDEBAND"
					( Origin gFrontEnd )
				)
				( attribute "ROT" "0"
					( Origin gFrontEnd )
				)
				( attribute "SEC" "1"
					( Origin gFrontEnd )
				)
				( attribute "SEC_TYPE" "0402"
					( Origin gFrontEnd )
				)
				( attribute "TOLERANCE" "10%"
					( Origin gFrontEnd )
				)
				( attribute "VALUE" "1.0UF"
					( Origin gFrontEnd )
				)
				( attribute "VER" "1"
					( Origin gFrontEnd )
				)
				( attribute "VOLTAGE" "16V"
					( Units "uVoltage" "V" 1.000000)
					( Origin gFrontEnd )
				)
				( attribute "XY" "(-6550,5800)"
					( Origin gFrontEnd )
				)
				( attribute "CHIPS_PART_NAME" "CAP"
					( Origin gPackager )
				)
				( attribute "CDS_PART_NAME" "CAP_0402-1.0UF,16V,10%,X6S,D97A"
					( Origin gPackager )
				)
				( objectStatus "C25W92" )
			)
			( gate "@baseboard_fab2_lib.baseboard_fab2(sch_1):page268_i26"
				( attribute "BOM_COST" "PROC_SIDEBAND"
					( Origin gFrontEnd )
				)
				( attribute "CDS_LIB" "mstr_discrete"
					( Origin gPackager )
				)
				( attribute "CDS_LOCATION" "R25W166"
					( Origin gPackager )
				)
				( attribute "CDS_SEC" "1"
					( Origin gPackager )
				)
				( attribute "LOCATION" "R25W166"
					( Origin gFrontEnd )
				)
				( attribute "MATERIAL" "CHIP"
					( Origin gFrontEnd )
				)
				( attribute "PACK_TYPE" "0402"
					( Origin gFrontEnd )
				)
				( attribute "PART_NUMBER" "G21796-026"
					( Origin gFrontEnd )
				)
				( attribute "PHYS_PAGE" "255"
					( Origin gFrontEnd )
				)
				( attribute "ROOM" "PROC_SIDEBAND"
					( Origin gFrontEnd )
				)
				( attribute "ROT" "0"
					( Origin gFrontEnd )
				)
				( attribute "SEC" "1"
					( Origin gFrontEnd )
				)
				( attribute "SEC_TYPE" "0402"
					( Origin gFrontEnd )
				)
				( attribute "TOLERANCE" "1%"
					( Origin gFrontEnd )
				)
				( attribute "VALUE" "1.00K"
					( Origin gFrontEnd )
				)
				( attribute "VER" "1"
					( Origin gFrontEnd )
				)
				( attribute "WATTAGE" "1/16W"
					( Origin gFrontEnd )
				)
				( attribute "XY" "(-6000,5450)"
					( Origin gFrontEnd )
				)
				( attribute "CHIPS_PART_NAME" "RES"
					( Origin gPackager )
				)
				( attribute "CDS_PART_NAME" "RES_0402-1.00K,1%,1/16W,CHIP,GA"
					( Origin gPackager )
				)
				( objectStatus "R25W166" )
			)
			( gate "@baseboard_fab2_lib.baseboard_fab2(sch_1):page268_i27"
				( attribute "BOM_COST" "PROC_SIDEBAND"
					( Origin gFrontEnd )
				)
				( attribute "CDS_LIB" "dev_discrete"
					( Origin gPackager )
				)
				( attribute "CDS_LOCATION" "C25W93"
					( Origin gPackager )
				)
				( attribute "CDS_SEC" "1"
					( Origin gPackager )
				)
				( attribute "LOCATION" "C25W93"
					( Origin gFrontEnd )
				)
				( attribute "MATERIAL" "X7R"
					( Origin gFrontEnd )
				)
				( attribute "PACK_TYPE" "0402V"
					( Origin gFrontEnd )
				)
				( attribute "PART_NUMBER" "A36096-030"
					( Origin gFrontEnd )
				)
				( attribute "PHYS_PAGE" "255"
					( Origin gFrontEnd )
				)
				( attribute "ROOM" "PROC_SIDEBAND"
					( Origin gFrontEnd )
				)
				( attribute "ROT" "0"
					( Origin gFrontEnd )
				)
				( attribute "SEC" "1"
					( Origin gFrontEnd )
				)
				( attribute "SEC_TYPE" "0402V"
					( Origin gFrontEnd )
				)
				( attribute "TOLERANCE" "10%"
					( Origin gFrontEnd )
				)
				( attribute "VALUE" "0.1UF"
					( Origin gFrontEnd )
				)
				( attribute "VER" "1"
					( Origin gFrontEnd )
				)
				( attribute "VOLTAGE" "16V"
					( Units "uVoltage" "V" 1.000000)
					( Origin gFrontEnd )
				)
				( attribute "XY" "(-6050,5850)"
					( Origin gFrontEnd )
				)
				( attribute "CHIPS_PART_NAME" "CAP_A"
					( Origin gPackager )
				)
				( attribute "CDS_PART_NAME" "CAP_A_0402V-0.1UF,16V,10%,X7R,A"
					( Origin gPackager )
				)
				( objectStatus "C25W93" )
			)
			( gate "@baseboard_fab2_lib.baseboard_fab2(sch_1):page268_i28"
				( attribute "BOM_COST" "PROC_SIDEBAND"
					( Origin gFrontEnd )
				)
				( attribute "CDS_LIB" "mstr_discrete"
					( Origin gPackager )
				)
				( attribute "CDS_LOCATION" "R25W165"
					( Origin gPackager )
				)
				( attribute "CDS_SEC" "1"
					( Origin gPackager )
				)
				( attribute "LOCATION" "R25W165"
					( Origin gFrontEnd )
				)
				( attribute "MATERIAL" "CHIP"
					( Origin gFrontEnd )
				)
				( attribute "PACK_TYPE" "0402"
					( Origin gFrontEnd )
				)
				( attribute "PART_NUMBER" "G21796-017"
					( Origin gFrontEnd )
				)
				( attribute "PHYS_PAGE" "255"
					( Origin gFrontEnd )
				)
				( attribute "ROOM" "PROC_SIDEBAND"
					( Origin gFrontEnd )
				)
				( attribute "ROT" "0"
					( Origin gFrontEnd )
				)
				( attribute "SEC" "1"
					( Origin gFrontEnd )
				)
				( attribute "SEC_TYPE" "0402"
					( Origin gFrontEnd )
				)
				( attribute "TOLERANCE" "1%"
					( Origin gFrontEnd )
				)
				( attribute "VALUE" "100.0"
					( Origin gFrontEnd )
				)
				( attribute "VER" "2"
					( Origin gFrontEnd )
				)
				( attribute "WATTAGE" "1/16W"
					( Origin gFrontEnd )
				)
				( attribute "XY" "(-5750,5850)"
					( Origin gFrontEnd )
				)
				( attribute "CHIPS_PART_NAME" "RES"
					( Origin gPackager )
				)
				( attribute "CDS_PART_NAME" "RES_0402-100.0,1%,1/16W,CHIP,GA"
					( Origin gPackager )
				)
				( objectStatus "R25W165" )
			)
			( gate "@baseboard_fab2_lib.baseboard_fab2(sch_1):page268_i29"
				( attribute "BOM_COST" "PROC_SIDEBAND"
					( Origin gFrontEnd )
				)
				( attribute "CDS_LIB" "mstr_discrete"
					( Origin gPackager )
				)
				( attribute "CDS_LOCATION" "R25W164"
					( Origin gPackager )
				)
				( attribute "CDS_SEC" "1"
					( Origin gPackager )
				)
				( attribute "LOCATION" "R25W164"
					( Origin gFrontEnd )
				)
				( attribute "MATERIAL" "CHIP"
					( Origin gFrontEnd )
				)
				( attribute "PACK_TYPE" "0402"
					( Origin gFrontEnd )
				)
				( attribute "PART_NUMBER" "G21796-047"
					( Origin gFrontEnd )
				)
				( attribute "PHYS_PAGE" "255"
					( Origin gFrontEnd )
				)
				( attribute "ROOM" "CPU0"
					( Origin gFrontEnd )
				)
				( attribute "ROT" "0"
					( Origin gFrontEnd )
				)
				( attribute "SEC" "1"
					( Origin gFrontEnd )
				)
				( attribute "SEC_TYPE" "0402"
					( Origin gFrontEnd )
				)
				( attribute "TOLERANCE" "1%"
					( Origin gFrontEnd )
				)
				( attribute "VALUE" "49.9"
					( Origin gFrontEnd )
				)
				( attribute "VER" "2"
					( Origin gFrontEnd )
				)
				( attribute "WATTAGE" "1/16W"
					( Origin gFrontEnd )
				)
				( attribute "XY" "(-5750,6250)"
					( Origin gFrontEnd )
				)
				( attribute "CHIPS_PART_NAME" "RES"
					( Origin gPackager )
				)
				( attribute "CDS_PART_NAME" "RES_0402-49.9,1%,1/16W,CHIP,G2A"
					( Origin gPackager )
				)
				( attribute "POP" "NOPOP"
					( Origin gFrontEnd )
				)
				( objectStatus "R25W164" )
			)
			( gate "@baseboard_fab2_lib.baseboard_fab2(sch_1):page268_i33"
				( attribute "BOM_COST" "PROC_SIDEBAND"
					( Origin gFrontEnd )
				)
				( attribute "CDS_LIB" "mstr_digital"
					( Origin gPackager )
				)
				( attribute "CDS_LOCATION" "U25W11"
					( Origin gPackager )
				)
				( attribute "CDS_SEC" "1"
					( Origin gPackager )
				)
				( attribute "LOCATION" "U25W11"
					( Origin gFrontEnd )
				)
				( attribute "MATERIAL" "IC"
					( Origin gFrontEnd )
				)
				( attribute "PACK_TYPE" "SM"
					( Origin gFrontEnd )
				)
				( attribute "PART_NUMBER" "D66151-001"
					( Origin gFrontEnd )
				)
				( attribute "PHYS_PAGE" "255"
					( Origin gFrontEnd )
				)
				( attribute "ROOM" "PROC_SIDEBAND"
					( Origin gFrontEnd )
				)
				( attribute "ROT" "2"
					( Origin gFrontEnd )
				)
				( attribute "SEC" "1"
					( Origin gFrontEnd )
				)
				( attribute "SEC_TYPE" "SM"
					( Origin gFrontEnd )
				)
				( attribute "VER" "1"
					( Origin gFrontEnd )
				)
				( attribute "XY" "(-7200,5300)"
					( Origin gFrontEnd )
				)
				( attribute "CHIPS_PART_NAME" "GTL2014"
					( Origin gPackager )
				)
				( attribute "CDS_PART_NAME" "GTL2014_SM-IC,D66151-001"
					( Origin gPackager )
				)
				( objectStatus "U25W11" )
			)
			( gate "@baseboard_fab2_lib.baseboard_fab2(sch_1):page269_i53"
				( attribute "CDS_LIB" "w_hdl"
					( Origin gPackager )
				)
				( attribute "CDS_LMAN_SYM_OUTLINE" "-225,175,225,-175"
					( Origin gPackager )
				)
				( attribute "LOCATION" "U25W13"
					( Origin gFrontEnd )
				)
				( attribute "PACK_TYPE" "SCRET-GC1"
					( Origin gFrontEnd )
				)
				( attribute "PART_NUMBER" "074.04564.0099"
					( Origin gFrontEnd )
				)
				( attribute "PHYS_PAGE" "254"
					( Origin gFrontEnd )
				)
				( attribute "ROT" "0"
					( Origin gFrontEnd )
				)
				( attribute "SEC" "1"
					( Origin gFrontEnd )
				)
				( attribute "SEC_TYPE" "SCRET-GC1"
					( Origin gFrontEnd )
				)
				( attribute "VALUE" "MAX4564EKA-GP"
					( Origin gFrontEnd )
				)
				( attribute "VER" "1"
					( Origin gFrontEnd )
				)
				( attribute "XY" "(-7075,3625)"
					( Origin gFrontEnd )
				)
				( attribute "CHIPS_PART_NAME" "MAX4564EKA-GP"
					( Origin gPackager )
				)
				( attribute "CDS_PART_NAME" "MAX4564EKA-GP_SCRET-GC1-MAX456A"
					( Origin gPackager )
				)
				( attribute "CDS_LOCATION" "U25W13"
					( Origin gPackager )
				)
				( attribute "CDS_SEC" "1"
					( Origin gPackager )
				)
				( objectStatus "U25W13" )
			)
			( gate "@baseboard_fab2_lib.baseboard_fab2(sch_1):page269_i56"
				( attribute "BOM_COST" "DEBUG"
					( Origin gFrontEnd )
				)
				( attribute "CDS_LIB" "dev_discrete"
					( Origin gPackager )
				)
				( attribute "CDS_LOCATION" "C25W95"
					( Origin gPackager )
				)
				( attribute "CDS_SEC" "1"
					( Origin gPackager )
				)
				( attribute "LOCATION" "C25W95"
					( Origin gFrontEnd )
				)
				( attribute "MATERIAL" "X7R"
					( Origin gFrontEnd )
				)
				( attribute "PACK_TYPE" "0402V"
					( Origin gFrontEnd )
				)
				( attribute "PART_NUMBER" "A36096-030"
					( Origin gFrontEnd )
				)
				( attribute "PHYS_PAGE" "254"
					( Origin gFrontEnd )
				)
				( attribute "ROOM" "UART_MUX"
					( Origin gFrontEnd )
				)
				( attribute "ROT" "0"
					( Origin gFrontEnd )
				)
				( attribute "SEC" "1"
					( Origin gFrontEnd )
				)
				( attribute "SEC_TYPE" "0402V"
					( Origin gFrontEnd )
				)
				( attribute "TOLERANCE" "10%"
					( Origin gFrontEnd )
				)
				( attribute "VALUE" "0.1UF"
					( Origin gFrontEnd )
				)
				( attribute "VER" "1"
					( Origin gFrontEnd )
				)
				( attribute "VOLTAGE" "16V"
					( Units "uVoltage" "V" 1.000000)
					( Origin gFrontEnd )
				)
				( attribute "XY" "(-8700,3850)"
					( Origin gFrontEnd )
				)
				( attribute "CHIPS_PART_NAME" "CAP_A"
					( Origin gPackager )
				)
				( attribute "CDS_PART_NAME" "CAP_A_0402V-0.1UF,16V,10%,X7R,A"
					( Origin gPackager )
				)
				( objectStatus "C25W95" )
			)
			( gate "@baseboard_fab2_lib.baseboard_fab2(sch_1):page164_i93"
				( attribute "BOM_COST" "SM_THERM"
					( Origin gFrontEnd )
				)
				( attribute "CDS_LIB" "mstr_discrete"
					( Origin gPackager )
				)
				( attribute "CDS_LOCATION" "R6W46"
					( Origin gPackager )
				)
				( attribute "CDS_SEC" "1"
					( Origin gPackager )
				)
				( attribute "LOCATION" "R6W46"
					( Origin gFrontEnd )
				)
				( attribute "MATERIAL" "CHIP"
					( Origin gFrontEnd )
				)
				( attribute "PACK_TYPE" "0402"
					( Origin gFrontEnd )
				)
				( attribute "PART_NUMBER" "G21796-072"
					( Origin gFrontEnd )
				)
				( attribute "PHYS_PAGE" "164"
					( Origin gFrontEnd )
				)
				( attribute "ROOM" "CPU_FANS"
					( Origin gFrontEnd )
				)
				( attribute "ROT" "2"
					( Origin gFrontEnd )
				)
				( attribute "SEC" "1"
					( Origin gFrontEnd )
				)
				( attribute "SEC_TYPE" "0402"
					( Origin gFrontEnd )
				)
				( attribute "TOLERANCE" "1%"
					( Origin gFrontEnd )
				)
				( attribute "VALUE" "4.75K"
					( Origin gFrontEnd )
				)
				( attribute "VER" "2"
					( Origin gFrontEnd )
				)
				( attribute "WATTAGE" "1/16W"
					( Origin gFrontEnd )
				)
				( attribute "XY" "(-2000,1800)"
					( Origin gFrontEnd )
				)
				( attribute "CHIPS_PART_NAME" "RES"
					( Origin gPackager )
				)
				( attribute "CDS_PART_NAME" "RES_0402-4.75K,1%,1/16W,CHIP,GA"
					( Origin gPackager )
				)
				( objectStatus "R6W46" )
			)
			( gate "@baseboard_fab2_lib.baseboard_fab2(sch_1):page144_i151"
				( attribute "CDS_LIB" "mstr_discrete"
					( Origin gPackager )
				)
				( attribute "CDS_LOCATION" "R25W182"
					( Origin gPackager )
				)
				( attribute "CDS_SEC" "1"
					( Origin gPackager )
				)
				( attribute "LOCATION" "R25W182"
					( Origin gFrontEnd )
				)
				( attribute "MATERIAL" "CHIP"
					( Origin gFrontEnd )
				)
				( attribute "PACK_TYPE" "0402"
					( Origin gFrontEnd )
				)
				( attribute "PART_NUMBER" "G21497-005"
					( Origin gFrontEnd )
				)
				( attribute "PHYS_PAGE" "144"
					( Origin gFrontEnd )
				)
				( attribute "ROOM" "DEBUG"
					( Origin gFrontEnd )
				)
				( attribute "ROT" "0"
					( Origin gFrontEnd )
				)
				( attribute "SEC" "1"
					( Origin gFrontEnd )
				)
				( attribute "SEC_TYPE" "0402"
					( Origin gFrontEnd )
				)
				( attribute "TOLERANCE" "5%"
					( Origin gFrontEnd )
				)
				( attribute "VALUE" "0.0"
					( Origin gFrontEnd )
				)
				( attribute "VER" "1"
					( Origin gFrontEnd )
				)
				( attribute "WATTAGE" "1/16W"
					( Origin gFrontEnd )
				)
				( attribute "XY" "(-6700,-4050)"
					( Origin gFrontEnd )
				)
				( attribute "CHIPS_PART_NAME" "RES"
					( Origin gPackager )
				)
				( attribute "CDS_PART_NAME" "RES_0402-0.0,5%,1/16W,CHIP,G21A"
					( Origin gPackager )
				)
				( attribute "POP" "NOPOP"
					( Origin gFrontEnd )
				)
				( objectStatus "R25W182" )
			)
			( gate "@baseboard_fab2_lib.baseboard_fab2(sch_1):page147_i173"
				( attribute "CDS_LIB" "mstr_discrete"
					( Origin gPackager )
				)
				( attribute "CDS_LOCATION" "R25W181"
					( Origin gPackager )
				)
				( attribute "CDS_SEC" "1"
					( Origin gPackager )
				)
				( attribute "LOCATION" "R25W181"
					( Origin gFrontEnd )
				)
				( attribute "MATERIAL" "CHIP"
					( Origin gFrontEnd )
				)
				( attribute "PACK_TYPE" "0402"
					( Origin gFrontEnd )
				)
				( attribute "PART_NUMBER" "G21497-005"
					( Origin gFrontEnd )
				)
				( attribute "PHYS_PAGE" "147"
					( Origin gFrontEnd )
				)
				( attribute "ROOM" "DEBUG"
					( Origin gFrontEnd )
				)
				( attribute "ROT" "0"
					( Origin gFrontEnd )
				)
				( attribute "SEC" "1"
					( Origin gFrontEnd )
				)
				( attribute "SEC_TYPE" "0402"
					( Origin gFrontEnd )
				)
				( attribute "TOLERANCE" "5%"
					( Origin gFrontEnd )
				)
				( attribute "VALUE" "0.0"
					( Origin gFrontEnd )
				)
				( attribute "VER" "1"
					( Origin gFrontEnd )
				)
				( attribute "WATTAGE" "1/16W"
					( Origin gFrontEnd )
				)
				( attribute "XY" "(-4150,3100)"
					( Origin gFrontEnd )
				)
				( attribute "CHIPS_PART_NAME" "RES"
					( Origin gPackager )
				)
				( attribute "CDS_PART_NAME" "RES_0402-0.0,5%,1/16W,CHIP,G21A"
					( Origin gPackager )
				)
				( objectStatus "R25W181" )
			)
			( gate "@baseboard_fab2_lib.baseboard_fab2(sch_1):page164_i94"
				( attribute "BOM_COST" "SM_THERM"
					( Origin gFrontEnd )
				)
				( attribute "CDS_LIB" "mstr_discrete"
					( Origin gPackager )
				)
				( attribute "CDS_LOCATION" "R6W45"
					( Origin gPackager )
				)
				( attribute "CDS_SEC" "1"
					( Origin gPackager )
				)
				( attribute "LOCATION" "R6W45"
					( Origin gFrontEnd )
				)
				( attribute "MATERIAL" "CHIP"
					( Origin gFrontEnd )
				)
				( attribute "PACK_TYPE" "0402"
					( Origin gFrontEnd )
				)
				( attribute "PART_NUMBER" "G21796-072"
					( Origin gFrontEnd )
				)
				( attribute "PHYS_PAGE" "164"
					( Origin gFrontEnd )
				)
				( attribute "ROOM" "CPU_FANS"
					( Origin gFrontEnd )
				)
				( attribute "ROT" "2"
					( Origin gFrontEnd )
				)
				( attribute "SEC" "1"
					( Origin gFrontEnd )
				)
				( attribute "SEC_TYPE" "0402"
					( Origin gFrontEnd )
				)
				( attribute "TOLERANCE" "1%"
					( Origin gFrontEnd )
				)
				( attribute "VALUE" "4.75K"
					( Origin gFrontEnd )
				)
				( attribute "VER" "2"
					( Origin gFrontEnd )
				)
				( attribute "WATTAGE" "1/16W"
					( Origin gFrontEnd )
				)
				( attribute "XY" "(-2350,1800)"
					( Origin gFrontEnd )
				)
				( attribute "CHIPS_PART_NAME" "RES"
					( Origin gPackager )
				)
				( attribute "CDS_PART_NAME" "RES_0402-4.75K,1%,1/16W,CHIP,GA"
					( Origin gPackager )
				)
				( objectStatus "R6W45" )
			)
			( gate "@baseboard_fab2_lib.baseboard_fab2(sch_1):page164_i95"
				( attribute "CDS_LIB" "mstr_discrete"
					( Origin gPackager )
				)
				( attribute "CDS_LOCATION" "R6W42"
					( Origin gPackager )
				)
				( attribute "CDS_SEC" "1"
					( Origin gPackager )
				)
				( attribute "LOCATION" "R6W42"
					( Origin gFrontEnd )
				)
				( attribute "MATERIAL" "EMPTY"
					( Origin gFrontEnd )
				)
				( attribute "NO_XNET_CONNECTION" "1"
					( Origin gFrontEnd )
				)
				( attribute "PACK_TYPE" "0402"
					( Origin gFrontEnd )
				)
				( attribute "PART_NUMBER" "G21796-072"
					( Origin gFrontEnd )
				)
				( attribute "PHYS_PAGE" "164"
					( Origin gFrontEnd )
				)
				( attribute "ROOM" "HOT_SWAP"
					( Origin gFrontEnd )
				)
				( attribute "ROT" "0"
					( Origin gFrontEnd )
				)
				( attribute "SEC" "1"
					( Origin gFrontEnd )
				)
				( attribute "SEC_TYPE" "0402"
					( Origin gFrontEnd )
				)
				( attribute "TOLERANCE" "1%"
					( Origin gFrontEnd )
				)
				( attribute "VALUE" "4.75K"
					( Origin gFrontEnd )
				)
				( attribute "VER" "2"
					( Origin gFrontEnd )
				)
				( attribute "WATTAGE" "1/16W"
					( Origin gFrontEnd )
				)
				( attribute "XY" "(-2350,2350)"
					( Origin gFrontEnd )
				)
				( attribute "CHIPS_PART_NAME" "RES"
					( Origin gPackager )
				)
				( attribute "CDS_PART_NAME" "RES_0402-4.75K,1%,1/16W,EMPTY,A"
					( Origin gPackager )
				)
				( objectStatus "R6W42" )
			)
			( gate "@baseboard_fab2_lib.baseboard_fab2(sch_1):page164_i96"
				( attribute "CDS_LIB" "mstr_discrete"
					( Origin gPackager )
				)
				( attribute "CDS_LOCATION" "R6W43"
					( Origin gPackager )
				)
				( attribute "CDS_SEC" "1"
					( Origin gPackager )
				)
				( attribute "LOCATION" "R6W43"
					( Origin gFrontEnd )
				)
				( attribute "MATERIAL" "EMPTY"
					( Origin gFrontEnd )
				)
				( attribute "NO_XNET_CONNECTION" "1"
					( Origin gFrontEnd )
				)
				( attribute "PACK_TYPE" "0402"
					( Origin gFrontEnd )
				)
				( attribute "PART_NUMBER" "G21796-072"
					( Origin gFrontEnd )
				)
				( attribute "PHYS_PAGE" "164"
					( Origin gFrontEnd )
				)
				( attribute "ROOM" "HOT_SWAP"
					( Origin gFrontEnd )
				)
				( attribute "ROT" "0"
					( Origin gFrontEnd )
				)
				( attribute "SEC" "1"
					( Origin gFrontEnd )
				)
				( attribute "SEC_TYPE" "0402"
					( Origin gFrontEnd )
				)
				( attribute "TOLERANCE" "1%"
					( Origin gFrontEnd )
				)
				( attribute "VALUE" "4.75K"
					( Origin gFrontEnd )
				)
				( attribute "VER" "2"
					( Origin gFrontEnd )
				)
				( attribute "WATTAGE" "1/16W"
					( Origin gFrontEnd )
				)
				( attribute "XY" "(-2000,2350)"
					( Origin gFrontEnd )
				)
				( attribute "CHIPS_PART_NAME" "RES"
					( Origin gPackager )
				)
				( attribute "CDS_PART_NAME" "RES_0402-4.75K,1%,1/16W,EMPTY,A"
					( Origin gPackager )
				)
				( objectStatus "R6W43" )
			)
			( gate "@baseboard_fab2_lib.baseboard_fab2(sch_1):page189_i67"
				( attribute "CDS_LIB" "mstr_ttl"
					( Origin gPackager )
				)
				( attribute "HAS_FIXED_SIZE" "4"
					( Origin gFrontEnd )
				)
				( attribute "LOCATION" "U1L10"
					( Origin gFrontEnd )
				)
				( attribute "MATERIAL" "IC"
					( Origin gFrontEnd )
				)
				( attribute "PACK_TYPE" "QFNLF"
					( Origin gFrontEnd )
				)
				( attribute "PART_NUMBER" "D18317-001"
					( Origin gFrontEnd )
				)
				( attribute "PHYS_PAGE" "189"
					( Origin gFrontEnd )
				)
				( attribute "ROOM" "DEBUG"
					( Origin gFrontEnd )
				)
				( attribute "ROT" "0"
					( Origin gFrontEnd )
				)
				( attribute "SIZE" "4"
					( Origin gFrontEnd )
				)
				( attribute "VALUE" "74CBTLV3126"
					( Origin gFrontEnd )
				)
				( attribute "VER" "3"
					( Origin gFrontEnd )
				)
				( attribute "XY" "(800,4300)"
					( Origin gFrontEnd )
				)
				( attribute "CHIPS_PART_NAME" "TTL3126"
					( Origin gPackager )
				)
				( attribute "CDS_PART_NAME" "TTL3126_QFNLF-74CBTLV3126,IC,DB"
					( Origin gPackager )
				)
				( attribute "CDS_LOCATION" "U1L10"
					( Origin gPackager )
				)
				( objectStatus "U1L10" )
			)
			( gate "@baseboard_fab2_lib.baseboard_fab2(sch_1):page189_i69"
				( attribute "CDS_LIB" "mstr_discrete"
					( Origin gPackager )
				)
				( attribute "LOCATION" "C1L119"
					( Origin gFrontEnd )
				)
				( attribute "MATERIAL" "X6S"
					( Origin gFrontEnd )
				)
				( attribute "PACK_TYPE" "0402"
					( Origin gFrontEnd )
				)
				( attribute "PART_NUMBER" "D97712-011"
					( Origin gFrontEnd )
				)
				( attribute "PHYS_PAGE" "189"
					( Origin gFrontEnd )
				)
				( attribute "ROOM" "DEBUG"
					( Origin gFrontEnd )
				)
				( attribute "ROT" "0"
					( Origin gFrontEnd )
				)
				( attribute "TOLERANCE" "10%"
					( Origin gFrontEnd )
				)
				( attribute "VALUE" "1.0UF"
					( Origin gFrontEnd )
				)
				( attribute "VER" "1"
					( Origin gFrontEnd )
				)
				( attribute "VOLTAGE" "16V"
					( Units "uVoltage" "V" 1.000000)
					( Origin gFrontEnd )
				)
				( attribute "XY" "(775,3525)"
					( Origin gFrontEnd )
				)
				( attribute "CHIPS_PART_NAME" "CAP"
					( Origin gPackager )
				)
				( attribute "CDS_PART_NAME" "CAP_0402-1.0UF,16V,10%,X6S,D97A"
					( Origin gPackager )
				)
				( attribute "CDS_LOCATION" "C1L119"
					( Origin gPackager )
				)
				( attribute "CDS_SEC" "1"
					( Origin gPackager )
				)
				( attribute "SEC" "1"
					( Origin gPackager )
				)
				( objectStatus "C1L119" )
			)
			( gate "@baseboard_fab2_lib.baseboard_fab2(sch_1):page189_i76"
				( attribute "BOM_COST" "DEBUG"
					( Origin gFrontEnd )
				)
				( attribute "CDS_LIB" "mstr_discrete"
					( Origin gPackager )
				)
				( attribute "LOCATION" "R7G114"
					( Origin gFrontEnd )
				)
				( attribute "MATERIAL" "CHIP"
					( Origin gFrontEnd )
				)
				( attribute "PACK_TYPE" "0402"
					( Origin gFrontEnd )
				)
				( attribute "PART_NUMBER" "G21497-005"
					( Origin gFrontEnd )
				)
				( attribute "PHYS_PAGE" "189"
					( Origin gFrontEnd )
				)
				( attribute "ROOM" "BMC_DEBUG_HEADER"
					( Origin gFrontEnd )
				)
				( attribute "ROT" "0"
					( Origin gFrontEnd )
				)
				( attribute "TOLERANCE" "5%"
					( Origin gFrontEnd )
				)
				( attribute "VALUE" "0.0"
					( Origin gFrontEnd )
				)
				( attribute "VER" "1"
					( Origin gFrontEnd )
				)
				( attribute "WATTAGE" "1/16W"
					( Origin gFrontEnd )
				)
				( attribute "XY" "(-100,3800)"
					( Origin gFrontEnd )
				)
				( attribute "CHIPS_PART_NAME" "RES"
					( Origin gPackager )
				)
				( attribute "CDS_PART_NAME" "RES_0402-0.0,5%,1/16W,CHIP,G21A"
					( Origin gPackager )
				)
				( attribute "CDS_LOCATION" "R7G114"
					( Origin gPackager )
				)
				( attribute "CDS_SEC" "1"
					( Origin gPackager )
				)
				( attribute "SEC" "1"
					( Origin gPackager )
				)
				( objectStatus "R7G114" )
			)
			( gate "@baseboard_fab2_lib.baseboard_fab2(sch_1):page193_i175"
				( attribute "BOM_COST" "PVMCP_MCP_CPU1_VR"
					( Origin gFrontEnd )
				)
				( attribute "CDS_LIB" "mstr_discrete"
					( Origin gPackager )
				)
				( attribute "LOCATION" "C4E29"
					( Origin gFrontEnd )
				)
				( attribute "MATERIAL" "ALUM"
					( Origin gFrontEnd )
				)
				( attribute "PACK_TYPE" "3018"
					( Origin gFrontEnd )
				)
				( attribute "PART_NUMBER" "699013-049"
					( Origin gFrontEnd )
				)
				( attribute "PHYS_PAGE" "193"
					( Origin gFrontEnd )
				)
				( attribute "ROOM" "PVMCP_MCP_CPU1_VR"
					( Origin gFrontEnd )
				)
				( attribute "ROT" "0"
					( Origin gFrontEnd )
				)
				( attribute "TOLERANCE" "20%"
					( Origin gFrontEnd )
				)
				( attribute "VALUE" "470UF"
					( Origin gFrontEnd )
				)
				( attribute "VER" "1"
					( Origin gFrontEnd )
				)
				( attribute "VOLTAGE" "2.5V"
					( Units "uVoltage" "V" 1.000000)
					( Origin gFrontEnd )
				)
				( attribute "XY" "(-1300,3100)"
					( Origin gFrontEnd )
				)
				( attribute "CHIPS_PART_NAME" "CAPP"
					( Origin gPackager )
				)
				( attribute "CDS_PART_NAME" "CAPP_3018-470UF,2.5V,20%,ALUM,A"
					( Origin gPackager )
				)
				( attribute "CDS_LOCATION" "C4E29"
					( Origin gPackager )
				)
				( attribute "SEC" "1"
					( Origin gFrontEnd )
				)
				( attribute "SEC_TYPE" "3018"
					( Origin gFrontEnd )
				)
				( attribute "GROUP" "PWR_MCP_CAP"
					( Origin gFrontEnd )
				)
				( attribute "CDS_SEC" "1"
					( Origin gPackager )
				)
				( objectStatus "C4E29" )
			)
			( gate "@baseboard_fab2_lib.baseboard_fab2(sch_1):page146_i166"
				( attribute "BOM_COST" "SM_CONTROLLER"
					( Origin gFrontEnd )
				)
				( attribute "CDS_LIB" "mstr_discrete"
					( Origin gPackager )
				)
				( attribute "CDS_LOCATION" "R25W184"
					( Origin gPackager )
				)
				( attribute "CDS_SEC" "1"
					( Origin gPackager )
				)
				( attribute "LOCATION" "R25W184"
					( Origin gFrontEnd )
				)
				( attribute "MATERIAL" "CHIP"
					( Origin gFrontEnd )
				)
				( attribute "PACK_TYPE" "0402"
					( Origin gFrontEnd )
				)
				( attribute "PART_NUMBER" "G21497-005"
					( Origin gFrontEnd )
				)
				( attribute "PHYS_PAGE" "146"
					( Origin gFrontEnd )
				)
				( attribute "ROOM" "BMC"
					( Origin gFrontEnd )
				)
				( attribute "ROT" "0"
					( Origin gFrontEnd )
				)
				( attribute "SEC" "1"
					( Origin gFrontEnd )
				)
				( attribute "SEC_TYPE" "0402"
					( Origin gFrontEnd )
				)
				( attribute "TOLERANCE" "5%"
					( Origin gFrontEnd )
				)
				( attribute "VALUE" "0.0"
					( Origin gFrontEnd )
				)
				( attribute "VER" "1"
					( Origin gFrontEnd )
				)
				( attribute "WATTAGE" "1/16W"
					( Origin gFrontEnd )
				)
				( attribute "XY" "(-1600,1800)"
					( Origin gFrontEnd )
				)
				( attribute "CHIPS_PART_NAME" "RES"
					( Origin gPackager )
				)
				( attribute "CDS_PART_NAME" "RES_0402-0.0,5%,1/16W,CHIP,G21A"
					( Origin gPackager )
				)
				( objectStatus "R25W184" )
			)
			( gate "@baseboard_fab2_lib.baseboard_fab2(sch_1):page133_i371"
				( attribute "CDS_LIB" "mstr_discrete"
					( Origin gPackager )
				)
				( attribute "CDS_LOCATION" "R8E3"
					( Origin gPackager )
				)
				( attribute "CDS_SEC" "1"
					( Origin gPackager )
				)
				( attribute "LOCATION" "R8E3"
					( Origin gFrontEnd )
				)
				( attribute "MATERIAL" "CHIP"
					( Origin gFrontEnd )
				)
				( attribute "PACK_TYPE" "0402"
					( Origin gFrontEnd )
				)
				( attribute "PART_NUMBER" "G21796-072"
					( Origin gFrontEnd )
				)
				( attribute "PHYS_PAGE" "133"
					( Origin gFrontEnd )
				)
				( attribute "ROOM" "SB_PU_PD"
					( Origin gFrontEnd )
				)
				( attribute "ROT" "0"
					( Origin gFrontEnd )
				)
				( attribute "SEC" "1"
					( Origin gFrontEnd )
				)
				( attribute "SEC_TYPE" "0402"
					( Origin gFrontEnd )
				)
				( attribute "TOLERANCE" "1%"
					( Origin gFrontEnd )
				)
				( attribute "VALUE" "4.75K"
					( Origin gFrontEnd )
				)
				( attribute "VER" "1"
					( Origin gFrontEnd )
				)
				( attribute "WATTAGE" "1/16W"
					( Origin gFrontEnd )
				)
				( attribute "XY" "(-4700,3475)"
					( Origin gFrontEnd )
				)
				( attribute "CHIPS_PART_NAME" "RES"
					( Origin gPackager )
				)
				( attribute "CDS_PART_NAME" "RES_0402-4.75K,1%,1/16W,CHIP,GA"
					( Origin gPackager )
				)
				( objectStatus "R8E3" )
			)
			( gate "@baseboard_fab2_lib.baseboard_fab2(sch_1):page42_i221"
				( attribute "BOM_COST" "MEM_VRD_PVDDQ_CD"
					( Origin gFrontEnd )
				)
				( attribute "CDS_LIB" "mstr_discrete"
					( Origin gPackager )
				)
				( attribute "CDS_LOCATION" "C5P30"
					( Origin gPackager )
				)
				( attribute "CDS_SEC" "1"
					( Origin gPackager )
				)
				( attribute "LOCATION" "C5P30"
					( Origin gFrontEnd )
				)
				( attribute "MATERIAL" "X5R"
					( Origin gFrontEnd )
				)
				( attribute "NEW_MATERIAL" "X6S"
					( Origin gFrontEnd )
				)
				( attribute "PACK_TYPE" "0805"
					( Origin gFrontEnd )
				)
				( attribute "PART_NUMBER" "602433-112"
					( Origin gFrontEnd )
				)
				( attribute "PHYS_PAGE" "42"
					( Origin gFrontEnd )
				)
				( attribute "ROOM" "VDDQ_ABC_PWR_VR"
					( Origin gFrontEnd )
				)
				( attribute "ROT" "0"
					( Origin gFrontEnd )
				)
				( attribute "SEC" "1"
					( Origin gFrontEnd )
				)
				( attribute "SEC_TYPE" "0805"
					( Origin gFrontEnd )
				)
				( attribute "TOLERANCE" "20%"
					( Origin gFrontEnd )
				)
				( attribute "VALUE" "100UF"
					( Origin gFrontEnd )
				)
				( attribute "VER" "1"
					( Origin gFrontEnd )
				)
				( attribute "VOLTAGE" "4V"
					( Units "uVoltage" "V" 1.000000)
					( Origin gFrontEnd )
				)
				( attribute "XY" "(-4500,2225)"
					( Origin gFrontEnd )
				)
				( attribute "CHIPS_PART_NAME" "CAP"
					( Origin gPackager )
				)
				( attribute "CDS_PART_NAME" "CAP_0805-100UF,4V,20%,X5R,6024A"
					( Origin gPackager )
				)
				( attribute "NEW_PN" "078.1071T.M002"
					( Origin gFrontEnd )
				)
				( attribute "GROUP" "PWR_MCP_CAP"
					( Origin gFrontEnd )
				)
				( objectStatus "C5P30" )
			)
			( gate "@baseboard_fab2_lib.baseboard_fab2(sch_1):page42_i222"
				( attribute "BOM_COST" "MEM_VRD_PVDDQ_CD"
					( Origin gFrontEnd )
				)
				( attribute "CDS_LIB" "mstr_discrete"
					( Origin gPackager )
				)
				( attribute "CDS_LOCATION" "C5P19"
					( Origin gPackager )
				)
				( attribute "CDS_SEC" "1"
					( Origin gPackager )
				)
				( attribute "LOCATION" "C5P19"
					( Origin gFrontEnd )
				)
				( attribute "MATERIAL" "X5R"
					( Origin gFrontEnd )
				)
				( attribute "NEW_MATERIAL" "X6S"
					( Origin gFrontEnd )
				)
				( attribute "PACK_TYPE" "0805"
					( Origin gFrontEnd )
				)
				( attribute "PART_NUMBER" "602433-112"
					( Origin gFrontEnd )
				)
				( attribute "PHYS_PAGE" "42"
					( Origin gFrontEnd )
				)
				( attribute "ROOM" "VDDQ_ABC_PWR_VR"
					( Origin gFrontEnd )
				)
				( attribute "ROT" "0"
					( Origin gFrontEnd )
				)
				( attribute "SEC" "1"
					( Origin gFrontEnd )
				)
				( attribute "SEC_TYPE" "0805"
					( Origin gFrontEnd )
				)
				( attribute "TOLERANCE" "20%"
					( Origin gFrontEnd )
				)
				( attribute "VALUE" "100UF"
					( Origin gFrontEnd )
				)
				( attribute "VER" "1"
					( Origin gFrontEnd )
				)
				( attribute "VOLTAGE" "4V"
					( Units "uVoltage" "V" 1.000000)
					( Origin gFrontEnd )
				)
				( attribute "XY" "(-4000,2225)"
					( Origin gFrontEnd )
				)
				( attribute "CHIPS_PART_NAME" "CAP"
					( Origin gPackager )
				)
				( attribute "CDS_PART_NAME" "CAP_0805-100UF,4V,20%,X5R,6024A"
					( Origin gPackager )
				)
				( attribute "NEW_PN" "078.1071T.M002"
					( Origin gFrontEnd )
				)
				( attribute "GROUP" "PWR_MCP_CAP"
					( Origin gFrontEnd )
				)
				( objectStatus "C5P19" )
			)
			( gate "@baseboard_fab2_lib.baseboard_fab2(sch_1):page42_i223"
				( attribute "BOM_COST" "MEM_VRD_PVDDQ_CD"
					( Origin gFrontEnd )
				)
				( attribute "CDS_LIB" "mstr_discrete"
					( Origin gPackager )
				)
				( attribute "CDS_LOCATION" "C4P4"
					( Origin gPackager )
				)
				( attribute "CDS_SEC" "1"
					( Origin gPackager )
				)
				( attribute "LOCATION" "C4P4"
					( Origin gFrontEnd )
				)
				( attribute "MATERIAL" "X5R"
					( Origin gFrontEnd )
				)
				( attribute "NEW_MATERIAL" "X6S"
					( Origin gFrontEnd )
				)
				( attribute "PACK_TYPE" "0805"
					( Origin gFrontEnd )
				)
				( attribute "PART_NUMBER" "602433-112"
					( Origin gFrontEnd )
				)
				( attribute "PHYS_PAGE" "42"
					( Origin gFrontEnd )
				)
				( attribute "ROOM" "VDDQ_ABC_PWR_VR"
					( Origin gFrontEnd )
				)
				( attribute "ROT" "0"
					( Origin gFrontEnd )
				)
				( attribute "SEC" "1"
					( Origin gFrontEnd )
				)
				( attribute "SEC_TYPE" "0805"
					( Origin gFrontEnd )
				)
				( attribute "TOLERANCE" "20%"
					( Origin gFrontEnd )
				)
				( attribute "VALUE" "100UF"
					( Origin gFrontEnd )
				)
				( attribute "VER" "1"
					( Origin gFrontEnd )
				)
				( attribute "VOLTAGE" "4V"
					( Units "uVoltage" "V" 1.000000)
					( Origin gFrontEnd )
				)
				( attribute "XY" "(-4250,2225)"
					( Origin gFrontEnd )
				)
				( attribute "CHIPS_PART_NAME" "CAP"
					( Origin gPackager )
				)
				( attribute "CDS_PART_NAME" "CAP_0805-100UF,4V,20%,X5R,6024A"
					( Origin gPackager )
				)
				( attribute "NEW_PN" "078.1071T.M002"
					( Origin gFrontEnd )
				)
				( attribute "GROUP" "PWR_MCP_CAP"
					( Origin gFrontEnd )
				)
				( objectStatus "C4P4" )
			)
			( gate "@baseboard_fab2_lib.baseboard_fab2(sch_1):page42_i224"
				( attribute "BOM_COST" "MEM_VRD_PVDDQ_CD"
					( Origin gFrontEnd )
				)
				( attribute "CDS_LIB" "mstr_discrete"
					( Origin gPackager )
				)
				( attribute "CDS_LOCATION" "C4P7"
					( Origin gPackager )
				)
				( attribute "CDS_SEC" "1"
					( Origin gPackager )
				)
				( attribute "LOCATION" "C4P7"
					( Origin gFrontEnd )
				)
				( attribute "MATERIAL" "X5R"
					( Origin gFrontEnd )
				)
				( attribute "NEW_MATERIAL" "X6S"
					( Origin gFrontEnd )
				)
				( attribute "PACK_TYPE" "0805"
					( Origin gFrontEnd )
				)
				( attribute "PART_NUMBER" "602433-112"
					( Origin gFrontEnd )
				)
				( attribute "PHYS_PAGE" "42"
					( Origin gFrontEnd )
				)
				( attribute "ROOM" "VDDQ_ABC_PWR_VR"
					( Origin gFrontEnd )
				)
				( attribute "ROT" "0"
					( Origin gFrontEnd )
				)
				( attribute "SEC" "1"
					( Origin gFrontEnd )
				)
				( attribute "SEC_TYPE" "0805"
					( Origin gFrontEnd )
				)
				( attribute "TOLERANCE" "20%"
					( Origin gFrontEnd )
				)
				( attribute "VALUE" "100UF"
					( Origin gFrontEnd )
				)
				( attribute "VER" "1"
					( Origin gFrontEnd )
				)
				( attribute "VOLTAGE" "4V"
					( Units "uVoltage" "V" 1.000000)
					( Origin gFrontEnd )
				)
				( attribute "XY" "(-3750,2225)"
					( Origin gFrontEnd )
				)
				( attribute "CHIPS_PART_NAME" "CAP"
					( Origin gPackager )
				)
				( attribute "CDS_PART_NAME" "CAP_0805-100UF,4V,20%,X5R,6024A"
					( Origin gPackager )
				)
				( attribute "NEW_PN" "078.1071T.M002"
					( Origin gFrontEnd )
				)
				( attribute "GROUP" "PWR_MCP_CAP"
					( Origin gFrontEnd )
				)
				( objectStatus "C4P7" )
			)
			( gate "@baseboard_fab2_lib.baseboard_fab2(sch_1):page42_i225"
				( attribute "BOM_COST" "MEM_VRD_PVDDQ_CD"
					( Origin gFrontEnd )
				)
				( attribute "CDS_LIB" "mstr_discrete"
					( Origin gPackager )
				)
				( attribute "CDS_LOCATION" "C4P3"
					( Origin gPackager )
				)
				( attribute "CDS_SEC" "1"
					( Origin gPackager )
				)
				( attribute "LOCATION" "C4P3"
					( Origin gFrontEnd )
				)
				( attribute "MATERIAL" "X5R"
					( Origin gFrontEnd )
				)
				( attribute "NEW_MATERIAL" "X6S"
					( Origin gFrontEnd )
				)
				( attribute "PACK_TYPE" "0805"
					( Origin gFrontEnd )
				)
				( attribute "PART_NUMBER" "602433-112"
					( Origin gFrontEnd )
				)
				( attribute "PHYS_PAGE" "42"
					( Origin gFrontEnd )
				)
				( attribute "ROOM" "VDDQ_ABC_PWR_VR"
					( Origin gFrontEnd )
				)
				( attribute "ROT" "0"
					( Origin gFrontEnd )
				)
				( attribute "SEC" "1"
					( Origin gFrontEnd )
				)
				( attribute "SEC_TYPE" "0805"
					( Origin gFrontEnd )
				)
				( attribute "TOLERANCE" "20%"
					( Origin gFrontEnd )
				)
				( attribute "VALUE" "100UF"
					( Origin gFrontEnd )
				)
				( attribute "VER" "1"
					( Origin gFrontEnd )
				)
				( attribute "VOLTAGE" "4V"
					( Units "uVoltage" "V" 1.000000)
					( Origin gFrontEnd )
				)
				( attribute "XY" "(-3500,2225)"
					( Origin gFrontEnd )
				)
				( attribute "CHIPS_PART_NAME" "CAP"
					( Origin gPackager )
				)
				( attribute "CDS_PART_NAME" "CAP_0805-100UF,4V,20%,X5R,6024A"
					( Origin gPackager )
				)
				( attribute "NEW_PN" "078.1071T.M002"
					( Origin gFrontEnd )
				)
				( attribute "GROUP" "PWR_MCP_CAP"
					( Origin gFrontEnd )
				)
				( objectStatus "C4P3" )
			)
			( gate "@baseboard_fab2_lib.baseboard_fab2(sch_1):page42_i226"
				( attribute "BOM_COST" "MEM_VRD_PVDDQ_CD"
					( Origin gFrontEnd )
				)
				( attribute "CDS_LIB" "mstr_discrete"
					( Origin gPackager )
				)
				( attribute "CDS_LOCATION" "C5P10"
					( Origin gPackager )
				)
				( attribute "CDS_SEC" "1"
					( Origin gPackager )
				)
				( attribute "LOCATION" "C5P10"
					( Origin gFrontEnd )
				)
				( attribute "MATERIAL" "X5R"
					( Origin gFrontEnd )
				)
				( attribute "NEW_MATERIAL" "X6S"
					( Origin gFrontEnd )
				)
				( attribute "PACK_TYPE" "0805"
					( Origin gFrontEnd )
				)
				( attribute "PART_NUMBER" "602433-112"
					( Origin gFrontEnd )
				)
				( attribute "PHYS_PAGE" "42"
					( Origin gFrontEnd )
				)
				( attribute "ROOM" "VDDQ_ABC_PWR_VR"
					( Origin gFrontEnd )
				)
				( attribute "ROT" "0"
					( Origin gFrontEnd )
				)
				( attribute "SEC" "1"
					( Origin gFrontEnd )
				)
				( attribute "SEC_TYPE" "0805"
					( Origin gFrontEnd )
				)
				( attribute "TOLERANCE" "20%"
					( Origin gFrontEnd )
				)
				( attribute "VALUE" "100UF"
					( Origin gFrontEnd )
				)
				( attribute "VER" "1"
					( Origin gFrontEnd )
				)
				( attribute "VOLTAGE" "4V"
					( Units "uVoltage" "V" 1.000000)
					( Origin gFrontEnd )
				)
				( attribute "XY" "(-3250,2225)"
					( Origin gFrontEnd )
				)
				( attribute "CHIPS_PART_NAME" "CAP"
					( Origin gPackager )
				)
				( attribute "CDS_PART_NAME" "CAP_0805-100UF,4V,20%,X5R,6024A"
					( Origin gPackager )
				)
				( attribute "NEW_PN" "078.1071T.M002"
					( Origin gFrontEnd )
				)
				( attribute "GROUP" "PWR_MCP_CAP"
					( Origin gFrontEnd )
				)
				( objectStatus "C5P10" )
			)
			( gate "@baseboard_fab2_lib.baseboard_fab2(sch_1):page42_i227"
				( attribute "BOM_COST" "MEM_VRD_PVDDQ_CD"
					( Origin gFrontEnd )
				)
				( attribute "CDS_LIB" "mstr_discrete"
					( Origin gPackager )
				)
				( attribute "CDS_LOCATION" "C5P11"
					( Origin gPackager )
				)
				( attribute "CDS_SEC" "1"
					( Origin gPackager )
				)
				( attribute "LOCATION" "C5P11"
					( Origin gFrontEnd )
				)
				( attribute "MATERIAL" "X5R"
					( Origin gFrontEnd )
				)
				( attribute "NEW_MATERIAL" "X6S"
					( Origin gFrontEnd )
				)
				( attribute "PACK_TYPE" "0805"
					( Origin gFrontEnd )
				)
				( attribute "PART_NUMBER" "602433-112"
					( Origin gFrontEnd )
				)
				( attribute "PHYS_PAGE" "42"
					( Origin gFrontEnd )
				)
				( attribute "ROOM" "VDDQ_ABC_PWR_VR"
					( Origin gFrontEnd )
				)
				( attribute "ROT" "0"
					( Origin gFrontEnd )
				)
				( attribute "SEC" "1"
					( Origin gFrontEnd )
				)
				( attribute "SEC_TYPE" "0805"
					( Origin gFrontEnd )
				)
				( attribute "TOLERANCE" "20%"
					( Origin gFrontEnd )
				)
				( attribute "VALUE" "100UF"
					( Origin gFrontEnd )
				)
				( attribute "VER" "1"
					( Origin gFrontEnd )
				)
				( attribute "VOLTAGE" "4V"
					( Units "uVoltage" "V" 1.000000)
					( Origin gFrontEnd )
				)
				( attribute "XY" "(-3000,2225)"
					( Origin gFrontEnd )
				)
				( attribute "CHIPS_PART_NAME" "CAP"
					( Origin gPackager )
				)
				( attribute "CDS_PART_NAME" "CAP_0805-100UF,4V,20%,X5R,6024A"
					( Origin gPackager )
				)
				( attribute "NEW_PN" "078.1071T.M002"
					( Origin gFrontEnd )
				)
				( attribute "GROUP" "PWR_MCP_CAP"
					( Origin gFrontEnd )
				)
				( objectStatus "C5P11" )
			)
			( gate "@baseboard_fab2_lib.baseboard_fab2(sch_1):page42_i228"
				( attribute "BOM_COST" "MEM_VRD_PVDDQ_CD"
					( Origin gFrontEnd )
				)
				( attribute "CDS_LIB" "mstr_discrete"
					( Origin gPackager )
				)
				( attribute "CDS_LOCATION" "C5P18"
					( Origin gPackager )
				)
				( attribute "CDS_SEC" "1"
					( Origin gPackager )
				)
				( attribute "LOCATION" "C5P18"
					( Origin gFrontEnd )
				)
				( attribute "MATERIAL" "X5R"
					( Origin gFrontEnd )
				)
				( attribute "NEW_MATERIAL" "X6S"
					( Origin gFrontEnd )
				)
				( attribute "PACK_TYPE" "0805"
					( Origin gFrontEnd )
				)
				( attribute "PART_NUMBER" "602433-112"
					( Origin gFrontEnd )
				)
				( attribute "PHYS_PAGE" "42"
					( Origin gFrontEnd )
				)
				( attribute "ROOM" "VDDQ_ABC_PWR_VR"
					( Origin gFrontEnd )
				)
				( attribute "ROT" "0"
					( Origin gFrontEnd )
				)
				( attribute "SEC" "1"
					( Origin gFrontEnd )
				)
				( attribute "SEC_TYPE" "0805"
					( Origin gFrontEnd )
				)
				( attribute "TOLERANCE" "20%"
					( Origin gFrontEnd )
				)
				( attribute "VALUE" "100UF"
					( Origin gFrontEnd )
				)
				( attribute "VER" "1"
					( Origin gFrontEnd )
				)
				( attribute "VOLTAGE" "4V"
					( Units "uVoltage" "V" 1.000000)
					( Origin gFrontEnd )
				)
				( attribute "XY" "(-2500,2225)"
					( Origin gFrontEnd )
				)
				( attribute "CHIPS_PART_NAME" "CAP"
					( Origin gPackager )
				)
				( attribute "CDS_PART_NAME" "CAP_0805-100UF,4V,20%,X5R,6024A"
					( Origin gPackager )
				)
				( attribute "NEW_PN" "078.1071T.M002"
					( Origin gFrontEnd )
				)
				( attribute "GROUP" "PWR_MCP_CAP"
					( Origin gFrontEnd )
				)
				( objectStatus "C5P18" )
			)
			( gate "@baseboard_fab2_lib.baseboard_fab2(sch_1):page42_i229"
				( attribute "BOM_COST" "MEM_VRD_PVDDQ_CD"
					( Origin gFrontEnd )
				)
				( attribute "CDS_LIB" "mstr_discrete"
					( Origin gPackager )
				)
				( attribute "CDS_LOCATION" "C5P28"
					( Origin gPackager )
				)
				( attribute "CDS_SEC" "1"
					( Origin gPackager )
				)
				( attribute "LOCATION" "C5P28"
					( Origin gFrontEnd )
				)
				( attribute "MATERIAL" "X5R"
					( Origin gFrontEnd )
				)
				( attribute "NEW_MATERIAL" "X6S"
					( Origin gFrontEnd )
				)
				( attribute "PACK_TYPE" "0805"
					( Origin gFrontEnd )
				)
				( attribute "PART_NUMBER" "602433-112"
					( Origin gFrontEnd )
				)
				( attribute "PHYS_PAGE" "42"
					( Origin gFrontEnd )
				)
				( attribute "ROOM" "VDDQ_ABC_PWR_VR"
					( Origin gFrontEnd )
				)
				( attribute "ROT" "0"
					( Origin gFrontEnd )
				)
				( attribute "SEC" "1"
					( Origin gFrontEnd )
				)
				( attribute "SEC_TYPE" "0805"
					( Origin gFrontEnd )
				)
				( attribute "TOLERANCE" "20%"
					( Origin gFrontEnd )
				)
				( attribute "VALUE" "100UF"
					( Origin gFrontEnd )
				)
				( attribute "VER" "1"
					( Origin gFrontEnd )
				)
				( attribute "VOLTAGE" "4V"
					( Units "uVoltage" "V" 1.000000)
					( Origin gFrontEnd )
				)
				( attribute "XY" "(-2750,2225)"
					( Origin gFrontEnd )
				)
				( attribute "CHIPS_PART_NAME" "CAP"
					( Origin gPackager )
				)
				( attribute "CDS_PART_NAME" "CAP_0805-100UF,4V,20%,X5R,6024A"
					( Origin gPackager )
				)
				( attribute "NEW_PN" "078.1071T.M002"
					( Origin gFrontEnd )
				)
				( attribute "GROUP" "PWR_MCP_CAP"
					( Origin gFrontEnd )
				)
				( objectStatus "C5P28" )
			)
			( gate "@baseboard_fab2_lib.baseboard_fab2(sch_1):page42_i230"
				( attribute "BOM_COST" "MEM_VRD_PVDDQ_CD"
					( Origin gFrontEnd )
				)
				( attribute "CDS_LIB" "mstr_discrete"
					( Origin gPackager )
				)
				( attribute "CDS_LOCATION" "C4P2"
					( Origin gPackager )
				)
				( attribute "CDS_SEC" "1"
					( Origin gPackager )
				)
				( attribute "LOCATION" "C4P2"
					( Origin gFrontEnd )
				)
				( attribute "MATERIAL" "X5R"
					( Origin gFrontEnd )
				)
				( attribute "NEW_MATERIAL" "X6S"
					( Origin gFrontEnd )
				)
				( attribute "PACK_TYPE" "0805"
					( Origin gFrontEnd )
				)
				( attribute "PART_NUMBER" "602433-112"
					( Origin gFrontEnd )
				)
				( attribute "PHYS_PAGE" "42"
					( Origin gFrontEnd )
				)
				( attribute "ROOM" "VDDQ_ABC_PWR_VR"
					( Origin gFrontEnd )
				)
				( attribute "ROT" "0"
					( Origin gFrontEnd )
				)
				( attribute "SEC" "1"
					( Origin gFrontEnd )
				)
				( attribute "SEC_TYPE" "0805"
					( Origin gFrontEnd )
				)
				( attribute "TOLERANCE" "20%"
					( Origin gFrontEnd )
				)
				( attribute "VALUE" "100UF"
					( Origin gFrontEnd )
				)
				( attribute "VER" "1"
					( Origin gFrontEnd )
				)
				( attribute "VOLTAGE" "4V"
					( Units "uVoltage" "V" 1.000000)
					( Origin gFrontEnd )
				)
				( attribute "XY" "(-2000,2225)"
					( Origin gFrontEnd )
				)
				( attribute "CHIPS_PART_NAME" "CAP"
					( Origin gPackager )
				)
				( attribute "CDS_PART_NAME" "CAP_0805-100UF,4V,20%,X5R,6024A"
					( Origin gPackager )
				)
				( attribute "NEW_PN" "078.1071T.M002"
					( Origin gFrontEnd )
				)
				( attribute "GROUP" "PWR_MCP_CAP"
					( Origin gFrontEnd )
				)
				( objectStatus "C4P2" )
			)
			( gate "@baseboard_fab2_lib.baseboard_fab2(sch_1):page42_i231"
				( attribute "BOM_COST" "MEM_VRD_PVDDQ_CD"
					( Origin gFrontEnd )
				)
				( attribute "CDS_LIB" "mstr_discrete"
					( Origin gPackager )
				)
				( attribute "CDS_LOCATION" "C5P31"
					( Origin gPackager )
				)
				( attribute "CDS_SEC" "1"
					( Origin gPackager )
				)
				( attribute "LOCATION" "C5P31"
					( Origin gFrontEnd )
				)
				( attribute "MATERIAL" "X5R"
					( Origin gFrontEnd )
				)
				( attribute "NEW_MATERIAL" "X6S"
					( Origin gFrontEnd )
				)
				( attribute "PACK_TYPE" "0805"
					( Origin gFrontEnd )
				)
				( attribute "PART_NUMBER" "602433-112"
					( Origin gFrontEnd )
				)
				( attribute "PHYS_PAGE" "42"
					( Origin gFrontEnd )
				)
				( attribute "ROOM" "VDDQ_ABC_PWR_VR"
					( Origin gFrontEnd )
				)
				( attribute "ROT" "0"
					( Origin gFrontEnd )
				)
				( attribute "SEC" "1"
					( Origin gFrontEnd )
				)
				( attribute "SEC_TYPE" "0805"
					( Origin gFrontEnd )
				)
				( attribute "TOLERANCE" "20%"
					( Origin gFrontEnd )
				)
				( attribute "VALUE" "100UF"
					( Origin gFrontEnd )
				)
				( attribute "VER" "1"
					( Origin gFrontEnd )
				)
				( attribute "VOLTAGE" "4V"
					( Units "uVoltage" "V" 1.000000)
					( Origin gFrontEnd )
				)
				( attribute "XY" "(-2250,2225)"
					( Origin gFrontEnd )
				)
				( attribute "CHIPS_PART_NAME" "CAP"
					( Origin gPackager )
				)
				( attribute "CDS_PART_NAME" "CAP_0805-100UF,4V,20%,X5R,6024A"
					( Origin gPackager )
				)
				( attribute "NEW_PN" "078.1071T.M002"
					( Origin gFrontEnd )
				)
				( attribute "GROUP" "PWR_MCP_CAP"
					( Origin gFrontEnd )
				)
				( objectStatus "C5P31" )
			)
			( gate "@baseboard_fab2_lib.baseboard_fab2(sch_1):page42_i232"
				( attribute "BOM_COST" "MEM_VRD_PVDDQ_CD"
					( Origin gFrontEnd )
				)
				( attribute "CDS_LIB" "mstr_discrete"
					( Origin gPackager )
				)
				( attribute "CDS_LOCATION" "C5P13"
					( Origin gPackager )
				)
				( attribute "CDS_SEC" "1"
					( Origin gPackager )
				)
				( attribute "LOCATION" "C5P13"
					( Origin gFrontEnd )
				)
				( attribute "MATERIAL" "X5R"
					( Origin gFrontEnd )
				)
				( attribute "NEW_MATERIAL" "X6S"
					( Origin gFrontEnd )
				)
				( attribute "PACK_TYPE" "0805"
					( Origin gFrontEnd )
				)
				( attribute "PART_NUMBER" "602433-112"
					( Origin gFrontEnd )
				)
				( attribute "PHYS_PAGE" "42"
					( Origin gFrontEnd )
				)
				( attribute "ROOM" "VDDQ_ABC_PWR_VR"
					( Origin gFrontEnd )
				)
				( attribute "ROT" "0"
					( Origin gFrontEnd )
				)
				( attribute "SEC" "1"
					( Origin gFrontEnd )
				)
				( attribute "SEC_TYPE" "0805"
					( Origin gFrontEnd )
				)
				( attribute "TOLERANCE" "20%"
					( Origin gFrontEnd )
				)
				( attribute "VALUE" "100UF"
					( Origin gFrontEnd )
				)
				( attribute "VER" "1"
					( Origin gFrontEnd )
				)
				( attribute "VOLTAGE" "4V"
					( Units "uVoltage" "V" 1.000000)
					( Origin gFrontEnd )
				)
				( attribute "XY" "(-1500,2225)"
					( Origin gFrontEnd )
				)
				( attribute "CHIPS_PART_NAME" "CAP"
					( Origin gPackager )
				)
				( attribute "CDS_PART_NAME" "CAP_0805-100UF,4V,20%,X5R,6024A"
					( Origin gPackager )
				)
				( attribute "NEW_PN" "078.1071T.M002"
					( Origin gFrontEnd )
				)
				( attribute "GROUP" "PWR_MCP_CAP"
					( Origin gFrontEnd )
				)
				( objectStatus "C5P13" )
			)
			( gate "@baseboard_fab2_lib.baseboard_fab2(sch_1):page42_i233"
				( attribute "BOM_COST" "MEM_VRD_PVDDQ_CD"
					( Origin gFrontEnd )
				)
				( attribute "CDS_LIB" "mstr_discrete"
					( Origin gPackager )
				)
				( attribute "CDS_LOCATION" "C4P5"
					( Origin gPackager )
				)
				( attribute "CDS_SEC" "1"
					( Origin gPackager )
				)
				( attribute "LOCATION" "C4P5"
					( Origin gFrontEnd )
				)
				( attribute "MATERIAL" "X5R"
					( Origin gFrontEnd )
				)
				( attribute "NEW_MATERIAL" "X6S"
					( Origin gFrontEnd )
				)
				( attribute "PACK_TYPE" "0805"
					( Origin gFrontEnd )
				)
				( attribute "PART_NUMBER" "602433-112"
					( Origin gFrontEnd )
				)
				( attribute "PHYS_PAGE" "42"
					( Origin gFrontEnd )
				)
				( attribute "ROOM" "VDDQ_ABC_PWR_VR"
					( Origin gFrontEnd )
				)
				( attribute "ROT" "0"
					( Origin gFrontEnd )
				)
				( attribute "SEC" "1"
					( Origin gFrontEnd )
				)
				( attribute "SEC_TYPE" "0805"
					( Origin gFrontEnd )
				)
				( attribute "TOLERANCE" "20%"
					( Origin gFrontEnd )
				)
				( attribute "VALUE" "100UF"
					( Origin gFrontEnd )
				)
				( attribute "VER" "1"
					( Origin gFrontEnd )
				)
				( attribute "VOLTAGE" "4V"
					( Units "uVoltage" "V" 1.000000)
					( Origin gFrontEnd )
				)
				( attribute "XY" "(-1750,2225)"
					( Origin gFrontEnd )
				)
				( attribute "CHIPS_PART_NAME" "CAP"
					( Origin gPackager )
				)
				( attribute "CDS_PART_NAME" "CAP_0805-100UF,4V,20%,X5R,6024A"
					( Origin gPackager )
				)
				( attribute "NEW_PN" "078.1071T.M002"
					( Origin gFrontEnd )
				)
				( attribute "GROUP" "PWR_MCP_CAP"
					( Origin gFrontEnd )
				)
				( objectStatus "C4P5" )
			)
			( gate "@baseboard_fab2_lib.baseboard_fab2(sch_1):page42_i234"
				( attribute "BOM_COST" "MEM_VRD_PVDDQ_CD"
					( Origin gFrontEnd )
				)
				( attribute "CDS_LIB" "mstr_discrete"
					( Origin gPackager )
				)
				( attribute "CDS_LOCATION" "C5P20"
					( Origin gPackager )
				)
				( attribute "CDS_SEC" "1"
					( Origin gPackager )
				)
				( attribute "LOCATION" "C5P20"
					( Origin gFrontEnd )
				)
				( attribute "MATERIAL" "X5R"
					( Origin gFrontEnd )
				)
				( attribute "NEW_MATERIAL" "X6S"
					( Origin gFrontEnd )
				)
				( attribute "PACK_TYPE" "0805"
					( Origin gFrontEnd )
				)
				( attribute "PART_NUMBER" "602433-112"
					( Origin gFrontEnd )
				)
				( attribute "PHYS_PAGE" "42"
					( Origin gFrontEnd )
				)
				( attribute "ROOM" "VDDQ_ABC_PWR_VR"
					( Origin gFrontEnd )
				)
				( attribute "ROT" "0"
					( Origin gFrontEnd )
				)
				( attribute "SEC" "1"
					( Origin gFrontEnd )
				)
				( attribute "SEC_TYPE" "0805"
					( Origin gFrontEnd )
				)
				( attribute "TOLERANCE" "20%"
					( Origin gFrontEnd )
				)
				( attribute "VALUE" "100UF"
					( Origin gFrontEnd )
				)
				( attribute "VER" "1"
					( Origin gFrontEnd )
				)
				( attribute "VOLTAGE" "4V"
					( Units "uVoltage" "V" 1.000000)
					( Origin gFrontEnd )
				)
				( attribute "XY" "(-1250,2225)"
					( Origin gFrontEnd )
				)
				( attribute "CHIPS_PART_NAME" "CAP"
					( Origin gPackager )
				)
				( attribute "CDS_PART_NAME" "CAP_0805-100UF,4V,20%,X5R,6024A"
					( Origin gPackager )
				)
				( attribute "NEW_PN" "078.1071T.M002"
					( Origin gFrontEnd )
				)
				( attribute "GROUP" "PWR_MCP_CAP"
					( Origin gFrontEnd )
				)
				( objectStatus "C5P20" )
			)
			( gate "@baseboard_fab2_lib.baseboard_fab2(sch_1):page42_i235"
				( attribute "BOM_COST" "MEM_VRD_PVDDQ_CD"
					( Origin gFrontEnd )
				)
				( attribute "CDS_LIB" "mstr_discrete"
					( Origin gPackager )
				)
				( attribute "CDS_LOCATION" "C5P21"
					( Origin gPackager )
				)
				( attribute "CDS_SEC" "1"
					( Origin gPackager )
				)
				( attribute "LOCATION" "C5P21"
					( Origin gFrontEnd )
				)
				( attribute "MATERIAL" "X5R"
					( Origin gFrontEnd )
				)
				( attribute "NEW_MATERIAL" "X6S"
					( Origin gFrontEnd )
				)
				( attribute "PACK_TYPE" "0805"
					( Origin gFrontEnd )
				)
				( attribute "PART_NUMBER" "602433-112"
					( Origin gFrontEnd )
				)
				( attribute "PHYS_PAGE" "42"
					( Origin gFrontEnd )
				)
				( attribute "ROOM" "VDDQ_ABC_PWR_VR"
					( Origin gFrontEnd )
				)
				( attribute "ROT" "0"
					( Origin gFrontEnd )
				)
				( attribute "SEC" "1"
					( Origin gFrontEnd )
				)
				( attribute "SEC_TYPE" "0805"
					( Origin gFrontEnd )
				)
				( attribute "TOLERANCE" "20%"
					( Origin gFrontEnd )
				)
				( attribute "VALUE" "100UF"
					( Origin gFrontEnd )
				)
				( attribute "VER" "1"
					( Origin gFrontEnd )
				)
				( attribute "VOLTAGE" "4V"
					( Units "uVoltage" "V" 1.000000)
					( Origin gFrontEnd )
				)
				( attribute "XY" "(-1000,2225)"
					( Origin gFrontEnd )
				)
				( attribute "CHIPS_PART_NAME" "CAP"
					( Origin gPackager )
				)
				( attribute "CDS_PART_NAME" "CAP_0805-100UF,4V,20%,X5R,6024A"
					( Origin gPackager )
				)
				( attribute "NEW_PN" "078.1071T.M002"
					( Origin gFrontEnd )
				)
				( attribute "GROUP" "PWR_MCP_CAP"
					( Origin gFrontEnd )
				)
				( objectStatus "C5P21" )
			)
			( gate "@baseboard_fab2_lib.baseboard_fab2(sch_1):page42_i236"
				( attribute "BOM_COST" "MEM_VRD_PVDDQ_CD"
					( Origin gFrontEnd )
				)
				( attribute "CDS_LIB" "mstr_discrete"
					( Origin gPackager )
				)
				( attribute "CDS_LOCATION" "C5P12"
					( Origin gPackager )
				)
				( attribute "CDS_SEC" "1"
					( Origin gPackager )
				)
				( attribute "LOCATION" "C5P12"
					( Origin gFrontEnd )
				)
				( attribute "MATERIAL" "X5R"
					( Origin gFrontEnd )
				)
				( attribute "NEW_MATERIAL" "X6S"
					( Origin gFrontEnd )
				)
				( attribute "PACK_TYPE" "0805"
					( Origin gFrontEnd )
				)
				( attribute "PART_NUMBER" "602433-112"
					( Origin gFrontEnd )
				)
				( attribute "PHYS_PAGE" "42"
					( Origin gFrontEnd )
				)
				( attribute "ROOM" "VDDQ_ABC_PWR_VR"
					( Origin gFrontEnd )
				)
				( attribute "ROT" "0"
					( Origin gFrontEnd )
				)
				( attribute "SEC" "1"
					( Origin gFrontEnd )
				)
				( attribute "SEC_TYPE" "0805"
					( Origin gFrontEnd )
				)
				( attribute "TOLERANCE" "20%"
					( Origin gFrontEnd )
				)
				( attribute "VALUE" "100UF"
					( Origin gFrontEnd )
				)
				( attribute "VER" "1"
					( Origin gFrontEnd )
				)
				( attribute "VOLTAGE" "4V"
					( Units "uVoltage" "V" 1.000000)
					( Origin gFrontEnd )
				)
				( attribute "XY" "(-750,2225)"
					( Origin gFrontEnd )
				)
				( attribute "CHIPS_PART_NAME" "CAP"
					( Origin gPackager )
				)
				( attribute "CDS_PART_NAME" "CAP_0805-100UF,4V,20%,X5R,6024A"
					( Origin gPackager )
				)
				( attribute "NEW_PN" "078.1071T.M002"
					( Origin gFrontEnd )
				)
				( attribute "GROUP" "PWR_MCP_CAP"
					( Origin gFrontEnd )
				)
				( objectStatus "C5P12" )
			)
			( gate "@baseboard_fab2_lib.baseboard_fab2(sch_1):page76_i258"
				( attribute "BOM_COST" "MEM_VRD_PVDDQ_CD"
					( Origin gFrontEnd )
				)
				( attribute "CDS_LIB" "mstr_discrete"
					( Origin gPackager )
				)
				( attribute "CDS_LOCATION" "C7P9"
					( Origin gPackager )
				)
				( attribute "CDS_SEC" "1"
					( Origin gPackager )
				)
				( attribute "LOCATION" "C7P9"
					( Origin gFrontEnd )
				)
				( attribute "MATERIAL" "X5R"
					( Origin gFrontEnd )
				)
				( attribute "NEW_MATERIAL" "X6S"
					( Origin gFrontEnd )
				)
				( attribute "PACK_TYPE" "0805"
					( Origin gFrontEnd )
				)
				( attribute "PART_NUMBER" "602433-112"
					( Origin gFrontEnd )
				)
				( attribute "PHYS_PAGE" "76"
					( Origin gFrontEnd )
				)
				( attribute "ROOM" "VDDQ_ABC_PWR_VR"
					( Origin gFrontEnd )
				)
				( attribute "ROT" "0"
					( Origin gFrontEnd )
				)
				( attribute "SEC" "1"
					( Origin gFrontEnd )
				)
				( attribute "SEC_TYPE" "0805"
					( Origin gFrontEnd )
				)
				( attribute "TOLERANCE" "20%"
					( Origin gFrontEnd )
				)
				( attribute "VALUE" "100UF"
					( Origin gFrontEnd )
				)
				( attribute "VER" "1"
					( Origin gFrontEnd )
				)
				( attribute "VOLTAGE" "4V"
					( Units "uVoltage" "V" 1.000000)
					( Origin gFrontEnd )
				)
				( attribute "XY" "(-4600,2200)"
					( Origin gFrontEnd )
				)
				( attribute "CHIPS_PART_NAME" "CAP"
					( Origin gPackager )
				)
				( attribute "CDS_PART_NAME" "CAP_0805-100UF,4V,20%,X5R,6024A"
					( Origin gPackager )
				)
				( attribute "NEW_PN" "078.1071T.M002"
					( Origin gFrontEnd )
				)
				( attribute "GROUP" "PWR_MCP_CAP"
					( Origin gFrontEnd )
				)
				( objectStatus "C7P9" )
			)
			( gate "@baseboard_fab2_lib.baseboard_fab2(sch_1):page76_i259"
				( attribute "BOM_COST" "MEM_VRD_PVDDQ_CD"
					( Origin gFrontEnd )
				)
				( attribute "CDS_LIB" "mstr_discrete"
					( Origin gPackager )
				)
				( attribute "CDS_LOCATION" "C7P5"
					( Origin gPackager )
				)
				( attribute "CDS_SEC" "1"
					( Origin gPackager )
				)
				( attribute "LOCATION" "C7P5"
					( Origin gFrontEnd )
				)
				( attribute "MATERIAL" "X5R"
					( Origin gFrontEnd )
				)
				( attribute "NEW_MATERIAL" "X6S"
					( Origin gFrontEnd )
				)
				( attribute "PACK_TYPE" "0805"
					( Origin gFrontEnd )
				)
				( attribute "PART_NUMBER" "602433-112"
					( Origin gFrontEnd )
				)
				( attribute "PHYS_PAGE" "76"
					( Origin gFrontEnd )
				)
				( attribute "ROOM" "VDDQ_ABC_PWR_VR"
					( Origin gFrontEnd )
				)
				( attribute "ROT" "0"
					( Origin gFrontEnd )
				)
				( attribute "SEC" "1"
					( Origin gFrontEnd )
				)
				( attribute "SEC_TYPE" "0805"
					( Origin gFrontEnd )
				)
				( attribute "TOLERANCE" "20%"
					( Origin gFrontEnd )
				)
				( attribute "VALUE" "100UF"
					( Origin gFrontEnd )
				)
				( attribute "VER" "1"
					( Origin gFrontEnd )
				)
				( attribute "VOLTAGE" "4V"
					( Units "uVoltage" "V" 1.000000)
					( Origin gFrontEnd )
				)
				( attribute "XY" "(-4350,2200)"
					( Origin gFrontEnd )
				)
				( attribute "CHIPS_PART_NAME" "CAP"
					( Origin gPackager )
				)
				( attribute "CDS_PART_NAME" "CAP_0805-100UF,4V,20%,X5R,6024A"
					( Origin gPackager )
				)
				( attribute "NEW_PN" "078.1071T.M002"
					( Origin gFrontEnd )
				)
				( attribute "GROUP" "PWR_MCP_CAP"
					( Origin gFrontEnd )
				)
				( objectStatus "C7P5" )
			)
			( gate "@baseboard_fab2_lib.baseboard_fab2(sch_1):page76_i266"
				( attribute "BOM_COST" "MEM_VRD_PVDDQ_CD"
					( Origin gFrontEnd )
				)
				( attribute "CDS_LIB" "mstr_discrete"
					( Origin gPackager )
				)
				( attribute "CDS_LOCATION" "C7P10"
					( Origin gPackager )
				)
				( attribute "CDS_SEC" "1"
					( Origin gPackager )
				)
				( attribute "LOCATION" "C7P10"
					( Origin gFrontEnd )
				)
				( attribute "MATERIAL" "X5R"
					( Origin gFrontEnd )
				)
				( attribute "NEW_MATERIAL" "X6S"
					( Origin gFrontEnd )
				)
				( attribute "PACK_TYPE" "0805"
					( Origin gFrontEnd )
				)
				( attribute "PART_NUMBER" "602433-112"
					( Origin gFrontEnd )
				)
				( attribute "PHYS_PAGE" "76"
					( Origin gFrontEnd )
				)
				( attribute "ROOM" "VDDQ_ABC_PWR_VR"
					( Origin gFrontEnd )
				)
				( attribute "ROT" "0"
					( Origin gFrontEnd )
				)
				( attribute "SEC" "1"
					( Origin gFrontEnd )
				)
				( attribute "SEC_TYPE" "0805"
					( Origin gFrontEnd )
				)
				( attribute "TOLERANCE" "20%"
					( Origin gFrontEnd )
				)
				( attribute "VALUE" "100UF"
					( Origin gFrontEnd )
				)
				( attribute "VER" "1"
					( Origin gFrontEnd )
				)
				( attribute "VOLTAGE" "4V"
					( Units "uVoltage" "V" 1.000000)
					( Origin gFrontEnd )
				)
				( attribute "XY" "(-2350,2200)"
					( Origin gFrontEnd )
				)
				( attribute "CHIPS_PART_NAME" "CAP"
					( Origin gPackager )
				)
				( attribute "CDS_PART_NAME" "CAP_0805-100UF,4V,20%,X5R,6024A"
					( Origin gPackager )
				)
				( attribute "NEW_PN" "078.1071T.M002"
					( Origin gFrontEnd )
				)
				( attribute "GROUP" "PWR_MCP_CAP"
					( Origin gFrontEnd )
				)
				( objectStatus "C7P10" )
			)
			( gate "@baseboard_fab2_lib.baseboard_fab2(sch_1):page76_i267"
				( attribute "BOM_COST" "MEM_VRD_PVDDQ_CD"
					( Origin gFrontEnd )
				)
				( attribute "CDS_LIB" "mstr_discrete"
					( Origin gPackager )
				)
				( attribute "CDS_LOCATION" "C7P7"
					( Origin gPackager )
				)
				( attribute "CDS_SEC" "1"
					( Origin gPackager )
				)
				( attribute "LOCATION" "C7P7"
					( Origin gFrontEnd )
				)
				( attribute "MATERIAL" "X5R"
					( Origin gFrontEnd )
				)
				( attribute "NEW_MATERIAL" "X6S"
					( Origin gFrontEnd )
				)
				( attribute "PACK_TYPE" "0805"
					( Origin gFrontEnd )
				)
				( attribute "PART_NUMBER" "602433-112"
					( Origin gFrontEnd )
				)
				( attribute "PHYS_PAGE" "76"
					( Origin gFrontEnd )
				)
				( attribute "ROOM" "VDDQ_ABC_PWR_VR"
					( Origin gFrontEnd )
				)
				( attribute "ROT" "0"
					( Origin gFrontEnd )
				)
				( attribute "SEC" "1"
					( Origin gFrontEnd )
				)
				( attribute "SEC_TYPE" "0805"
					( Origin gFrontEnd )
				)
				( attribute "TOLERANCE" "20%"
					( Origin gFrontEnd )
				)
				( attribute "VALUE" "100UF"
					( Origin gFrontEnd )
				)
				( attribute "VER" "1"
					( Origin gFrontEnd )
				)
				( attribute "VOLTAGE" "4V"
					( Units "uVoltage" "V" 1.000000)
					( Origin gFrontEnd )
				)
				( attribute "XY" "(-2600,2200)"
					( Origin gFrontEnd )
				)
				( attribute "CHIPS_PART_NAME" "CAP"
					( Origin gPackager )
				)
				( attribute "CDS_PART_NAME" "CAP_0805-100UF,4V,20%,X5R,6024A"
					( Origin gPackager )
				)
				( attribute "NEW_PN" "078.1071T.M002"
					( Origin gFrontEnd )
				)
				( attribute "GROUP" "PWR_MCP_CAP"
					( Origin gFrontEnd )
				)
				( objectStatus "C7P7" )
			)
			( gate "@baseboard_fab2_lib.baseboard_fab2(sch_1):page76_i272"
				( attribute "BOM_COST" "MEM_VRD_PVDDQ_CD"
					( Origin gFrontEnd )
				)
				( attribute "CDS_LIB" "mstr_discrete"
					( Origin gPackager )
				)
				( attribute "CDS_LOCATION" "C8P14"
					( Origin gPackager )
				)
				( attribute "CDS_SEC" "1"
					( Origin gPackager )
				)
				( attribute "LOCATION" "C8P14"
					( Origin gFrontEnd )
				)
				( attribute "MATERIAL" "X5R"
					( Origin gFrontEnd )
				)
				( attribute "NEW_MATERIAL" "X6S"
					( Origin gFrontEnd )
				)
				( attribute "PACK_TYPE" "0805"
					( Origin gFrontEnd )
				)
				( attribute "PART_NUMBER" "602433-112"
					( Origin gFrontEnd )
				)
				( attribute "PHYS_PAGE" "76"
					( Origin gFrontEnd )
				)
				( attribute "ROOM" "VDDQ_ABC_PWR_VR"
					( Origin gFrontEnd )
				)
				( attribute "ROT" "0"
					( Origin gFrontEnd )
				)
				( attribute "SEC" "1"
					( Origin gFrontEnd )
				)
				( attribute "SEC_TYPE" "0805"
					( Origin gFrontEnd )
				)
				( attribute "TOLERANCE" "20%"
					( Origin gFrontEnd )
				)
				( attribute "VALUE" "100UF"
					( Origin gFrontEnd )
				)
				( attribute "VER" "1"
					( Origin gFrontEnd )
				)
				( attribute "VOLTAGE" "4V"
					( Units "uVoltage" "V" 1.000000)
					( Origin gFrontEnd )
				)
				( attribute "XY" "(-1100,2200)"
					( Origin gFrontEnd )
				)
				( attribute "CHIPS_PART_NAME" "CAP"
					( Origin gPackager )
				)
				( attribute "CDS_PART_NAME" "CAP_0805-100UF,4V,20%,X5R,6024A"
					( Origin gPackager )
				)
				( attribute "NEW_PN" "078.1071T.M002"
					( Origin gFrontEnd )
				)
				( attribute "GROUP" "PWR_MCP_CAP"
					( Origin gFrontEnd )
				)
				( objectStatus "C8P14" )
			)
			( gate "@baseboard_fab2_lib.baseboard_fab2(sch_1):page76_i273"
				( attribute "BOM_COST" "MEM_VRD_PVDDQ_CD"
					( Origin gFrontEnd )
				)
				( attribute "CDS_LIB" "mstr_discrete"
					( Origin gPackager )
				)
				( attribute "CDS_LOCATION" "C8P9"
					( Origin gPackager )
				)
				( attribute "CDS_SEC" "1"
					( Origin gPackager )
				)
				( attribute "LOCATION" "C8P9"
					( Origin gFrontEnd )
				)
				( attribute "MATERIAL" "X5R"
					( Origin gFrontEnd )
				)
				( attribute "NEW_MATERIAL" "X6S"
					( Origin gFrontEnd )
				)
				( attribute "PACK_TYPE" "0805"
					( Origin gFrontEnd )
				)
				( attribute "PART_NUMBER" "602433-112"
					( Origin gFrontEnd )
				)
				( attribute "PHYS_PAGE" "76"
					( Origin gFrontEnd )
				)
				( attribute "ROOM" "VDDQ_ABC_PWR_VR"
					( Origin gFrontEnd )
				)
				( attribute "ROT" "0"
					( Origin gFrontEnd )
				)
				( attribute "SEC" "1"
					( Origin gFrontEnd )
				)
				( attribute "SEC_TYPE" "0805"
					( Origin gFrontEnd )
				)
				( attribute "TOLERANCE" "20%"
					( Origin gFrontEnd )
				)
				( attribute "VALUE" "100UF"
					( Origin gFrontEnd )
				)
				( attribute "VER" "1"
					( Origin gFrontEnd )
				)
				( attribute "VOLTAGE" "4V"
					( Units "uVoltage" "V" 1.000000)
					( Origin gFrontEnd )
				)
				( attribute "XY" "(-850,2200)"
					( Origin gFrontEnd )
				)
				( attribute "CHIPS_PART_NAME" "CAP"
					( Origin gPackager )
				)
				( attribute "CDS_PART_NAME" "CAP_0805-100UF,4V,20%,X5R,6024A"
					( Origin gPackager )
				)
				( attribute "NEW_PN" "078.1071T.M002"
					( Origin gFrontEnd )
				)
				( attribute "GROUP" "PWR_MCP_CAP"
					( Origin gFrontEnd )
				)
				( objectStatus "C8P9" )
			)
			( gate "@baseboard_fab2_lib.baseboard_fab2(sch_1):page76_i274"
				( attribute "BOM_COST" "MEM_VRD_PVDDQ_CD"
					( Origin gFrontEnd )
				)
				( attribute "CDS_LIB" "mstr_discrete"
					( Origin gPackager )
				)
				( attribute "CDS_LOCATION" "C8P8"
					( Origin gPackager )
				)
				( attribute "CDS_SEC" "1"
					( Origin gPackager )
				)
				( attribute "LOCATION" "C8P8"
					( Origin gFrontEnd )
				)
				( attribute "MATERIAL" "X5R"
					( Origin gFrontEnd )
				)
				( attribute "NEW_MATERIAL" "X6S"
					( Origin gFrontEnd )
				)
				( attribute "PACK_TYPE" "0805"
					( Origin gFrontEnd )
				)
				( attribute "PART_NUMBER" "602433-112"
					( Origin gFrontEnd )
				)
				( attribute "PHYS_PAGE" "76"
					( Origin gFrontEnd )
				)
				( attribute "ROOM" "VDDQ_ABC_PWR_VR"
					( Origin gFrontEnd )
				)
				( attribute "ROT" "0"
					( Origin gFrontEnd )
				)
				( attribute "SEC" "1"
					( Origin gFrontEnd )
				)
				( attribute "SEC_TYPE" "0805"
					( Origin gFrontEnd )
				)
				( attribute "TOLERANCE" "20%"
					( Origin gFrontEnd )
				)
				( attribute "VALUE" "100UF"
					( Origin gFrontEnd )
				)
				( attribute "VER" "1"
					( Origin gFrontEnd )
				)
				( attribute "VOLTAGE" "4V"
					( Units "uVoltage" "V" 1.000000)
					( Origin gFrontEnd )
				)
				( attribute "XY" "(-600,2200)"
					( Origin gFrontEnd )
				)
				( attribute "CHIPS_PART_NAME" "CAP"
					( Origin gPackager )
				)
				( attribute "CDS_PART_NAME" "CAP_0805-100UF,4V,20%,X5R,6024A"
					( Origin gPackager )
				)
				( attribute "NEW_PN" "078.1071T.M002"
					( Origin gFrontEnd )
				)
				( attribute "GROUP" "PWR_MCP_CAP"
					( Origin gFrontEnd )
				)
				( objectStatus "C8P8" )
			)
			( gate "@baseboard_fab2_lib.baseboard_fab2(sch_1):page215_i75"
				( attribute "BOM_COST" "SM_CONTROLLER"
					( Origin gFrontEnd )
				)
				( attribute "CDS_LIB" "mstr_discrete"
					( Origin gPackager )
				)
				( attribute "CDS_LOCATION" "R7F36"
					( Origin gPackager )
				)
				( attribute "CDS_SEC" "1"
					( Origin gPackager )
				)
				( attribute "LOCATION" "R7F36"
					( Origin gFrontEnd )
				)
				( attribute "MATERIAL" "CHIP"
					( Origin gFrontEnd )
				)
				( attribute "PACK_TYPE" "0402"
					( Origin gFrontEnd )
				)
				( attribute "PART_NUMBER" "G21796-311"
					( Origin gFrontEnd )
				)
				( attribute "PHYS_PAGE" "215"
					( Origin gFrontEnd )
				)
				( attribute "ROOM" "SMBUS"
					( Origin gFrontEnd )
				)
				( attribute "ROT" "0"
					( Origin gFrontEnd )
				)
				( attribute "SEC" "1"
					( Origin gFrontEnd )
				)
				( attribute "SEC_TYPE" "0402"
					( Origin gFrontEnd )
				)
				( attribute "SKU" "B"
					( Origin gFrontEnd )
				)
				( attribute "TOLERANCE" "1.0%"
					( Origin gFrontEnd )
				)
				( attribute "VALUE" "2.26K"
					( Origin gFrontEnd )
				)
				( attribute "VER" "2"
					( Origin gFrontEnd )
				)
				( attribute "WATTAGE" "1/16W"
					( Origin gFrontEnd )
				)
				( attribute "XY" "(4300,2900)"
					( Origin gFrontEnd )
				)
				( attribute "CHIPS_PART_NAME" "RES"
					( Origin gPackager )
				)
				( attribute "CDS_PART_NAME" "RES_0402-2.26K,1.0%,1/16W,CHIPA"
					( Origin gPackager )
				)
				( objectStatus "R7F36" )
			)
			( gate "@baseboard_fab2_lib.baseboard_fab2(sch_1):page268_i40"
				( attribute "CDS_LIB" "mstr_discrete"
					( Origin gPackager )
				)
				( attribute "CDS_LOCATION" "C25W98"
					( Origin gPackager )
				)
				( attribute "CDS_SEC" "1"
					( Origin gPackager )
				)
				( attribute "LOCATION" "C25W98"
					( Origin gFrontEnd )
				)
				( attribute "MATERIAL" "X6S"
					( Origin gFrontEnd )
				)
				( attribute "PACK_TYPE" "0402"
					( Origin gFrontEnd )
				)
				( attribute "PART_NUMBER" "D97712-011"
					( Origin gFrontEnd )
				)
				( attribute "PHYS_PAGE" "255"
					( Origin gFrontEnd )
				)
				( attribute "ROOM" "DEBUG"
					( Origin gFrontEnd )
				)
				( attribute "ROT" "0"
					( Origin gFrontEnd )
				)
				( attribute "SEC" "1"
					( Origin gFrontEnd )
				)
				( attribute "SEC_TYPE" "0402"
					( Origin gFrontEnd )
				)
				( attribute "TOLERANCE" "10%"
					( Origin gFrontEnd )
				)
				( attribute "VALUE" "1.0UF"
					( Origin gFrontEnd )
				)
				( attribute "VER" "1"
					( Origin gFrontEnd )
				)
				( attribute "VOLTAGE" "16V"
					( Units "uVoltage" "V" 1.000000)
					( Origin gFrontEnd )
				)
				( attribute "XY" "(-2250,4400)"
					( Origin gFrontEnd )
				)
				( attribute "CHIPS_PART_NAME" "CAP"
					( Origin gPackager )
				)
				( attribute "CDS_PART_NAME" "CAP_0402-1.0UF,16V,10%,X6S,D97A"
					( Origin gPackager )
				)
				( objectStatus "C25W98" )
			)
			( gate "@baseboard_fab2_lib.baseboard_fab2(sch_1):page268_i51"
				( attribute "CDS_LIB" "mstr_discrete"
					( Origin gPackager )
				)
				( attribute "CDS_LOCATION" "Q25W5"
					( Origin gPackager )
				)
				( attribute "LOCATION" "Q25W5"
					( Origin gFrontEnd )
				)
				( attribute "MATERIAL" "FET"
					( Origin gFrontEnd )
				)
				( attribute "PACK_TYPE" "SOT23LF"
					( Origin gFrontEnd )
				)
				( attribute "PART_NUMBER" "C79254-001"
					( Origin gFrontEnd )
				)
				( attribute "PHYS_PAGE" "255"
					( Origin gFrontEnd )
				)
				( attribute "ROOM" "HOT_SWAP"
					( Origin gFrontEnd )
				)
				( attribute "ROT" "0"
					( Origin gFrontEnd )
				)
				( attribute "SEC" "1"
					( Origin gFrontEnd )
				)
				( attribute "SEC_TYPE" "SOT23LF"
					( Origin gFrontEnd )
				)
				( attribute "VALUE" "2N7002"
					( Origin gFrontEnd )
				)
				( attribute "VER" "8"
					( Origin gFrontEnd )
				)
				( attribute "XY" "(-3250,3050)"
					( Origin gFrontEnd )
				)
				( attribute "CHIPS_PART_NAME" "FET_N"
					( Origin gPackager )
				)
				( attribute "CDS_PART_NAME" "FET_N_SOT23LF-2N7002,FET,C7925A"
					( Origin gPackager )
				)
				( attribute "CDS_SEC" "1"
					( Origin gPackager )
				)
				( objectStatus "Q25W5" )
			)
			( gate "@baseboard_fab2_lib.baseboard_fab2(sch_1):page268_i54"
				( attribute "BOM_COST" "SM_CONTROLLER"
					( Origin gFrontEnd )
				)
				( attribute "CDS_LIB" "mstr_discrete"
					( Origin gPackager )
				)
				( attribute "CDS_LOCATION" "R25W185"
					( Origin gPackager )
				)
				( attribute "CDS_SEC" "1"
					( Origin gPackager )
				)
				( attribute "LOCATION" "R25W185"
					( Origin gFrontEnd )
				)
				( attribute "MATERIAL" "CHIP"
					( Origin gFrontEnd )
				)
				( attribute "PACK_TYPE" "0402"
					( Origin gFrontEnd )
				)
				( attribute "PART_NUMBER" "G21796-072"
					( Origin gFrontEnd )
				)
				( attribute "PHYS_PAGE" "255"
					( Origin gFrontEnd )
				)
				( attribute "ROOM" "BMC_MISC"
					( Origin gFrontEnd )
				)
				( attribute "ROT" "0"
					( Origin gFrontEnd )
				)
				( attribute "SEC" "1"
					( Origin gFrontEnd )
				)
				( attribute "SEC_TYPE" "0402"
					( Origin gFrontEnd )
				)
				( attribute "TOLERANCE" "1%"
					( Origin gFrontEnd )
				)
				( attribute "VALUE" "4.75K"
					( Origin gFrontEnd )
				)
				( attribute "VER" "2"
					( Origin gFrontEnd )
				)
				( attribute "WATTAGE" "1/16W"
					( Origin gFrontEnd )
				)
				( attribute "XY" "(-3550,3500)"
					( Origin gFrontEnd )
				)
				( attribute "CHIPS_PART_NAME" "RES"
					( Origin gPackager )
				)
				( attribute "CDS_PART_NAME" "RES_0402-4.75K,1%,1/16W,CHIP,GA"
					( Origin gPackager )
				)
				( objectStatus "R25W185" )
			)
			( gate "@baseboard_fab2_lib.baseboard_fab2(sch_1):page189_i77"
				( attribute "BOM_COST" "DEBUG"
					( Origin gFrontEnd )
				)
				( attribute "CDS_LIB" "mstr_discrete"
					( Origin gPackager )
				)
				( attribute "CDS_LOCATION" "R25W186"
					( Origin gPackager )
				)
				( attribute "CDS_SEC" "1"
					( Origin gPackager )
				)
				( attribute "LOCATION" "R25W186"
					( Origin gFrontEnd )
				)
				( attribute "MATERIAL" "CHIP"
					( Origin gFrontEnd )
				)
				( attribute "PACK_TYPE" "0402"
					( Origin gFrontEnd )
				)
				( attribute "PART_NUMBER" "G21497-005"
					( Origin gFrontEnd )
				)
				( attribute "PHYS_PAGE" "189"
					( Origin gFrontEnd )
				)
				( attribute "ROOM" "BMC_DEBUG_HEADER"
					( Origin gFrontEnd )
				)
				( attribute "ROT" "0"
					( Origin gFrontEnd )
				)
				( attribute "SEC" "1"
					( Origin gFrontEnd )
				)
				( attribute "SEC_TYPE" "0402"
					( Origin gFrontEnd )
				)
				( attribute "TOLERANCE" "5%"
					( Origin gFrontEnd )
				)
				( attribute "VALUE" "0.0"
					( Origin gFrontEnd )
				)
				( attribute "VER" "1"
					( Origin gFrontEnd )
				)
				( attribute "WATTAGE" "1/16W"
					( Origin gFrontEnd )
				)
				( attribute "XY" "(-50,1800)"
					( Origin gFrontEnd )
				)
				( attribute "CHIPS_PART_NAME" "RES"
					( Origin gPackager )
				)
				( attribute "CDS_PART_NAME" "RES_0402-0.0,5%,1/16W,CHIP,G21A"
					( Origin gPackager )
				)
				( objectStatus "R25W186" )
			)
			( gate "@baseboard_fab2_lib.baseboard_fab2(sch_1):page153_i187"
				( attribute "CDS_LIB" "mstr_discrete"
					( Origin gPackager )
				)
				( attribute "CDS_LOCATION" "R7W5"
					( Origin gPackager )
				)
				( attribute "CDS_SEC" "1"
					( Origin gPackager )
				)
				( attribute "LOCATION" "R7W5"
					( Origin gFrontEnd )
				)
				( attribute "MATERIAL" "CHIP"
					( Origin gFrontEnd )
				)
				( attribute "PACK_TYPE" "0402"
					( Origin gFrontEnd )
				)
				( attribute "PART_NUMBER" "G21497-005"
					( Origin gFrontEnd )
				)
				( attribute "PHYS_PAGE" "153"
					( Origin gFrontEnd )
				)
				( attribute "ROOM" "MIO_BIOS_MEM"
					( Origin gFrontEnd )
				)
				( attribute "ROT" "0"
					( Origin gFrontEnd )
				)
				( attribute "SEC" "1"
					( Origin gPackager )
				)
				( attribute "TOLERANCE" "5%"
					( Origin gFrontEnd )
				)
				( attribute "VALUE" "0.0"
					( Origin gFrontEnd )
				)
				( attribute "VER" "1"
					( Origin gFrontEnd )
				)
				( attribute "WATTAGE" "1/16W"
					( Origin gFrontEnd )
				)
				( attribute "XY" "(-6550,3625)"
					( Origin gFrontEnd )
				)
				( attribute "CHIPS_PART_NAME" "RES"
					( Origin gPackager )
				)
				( attribute "CDS_PART_NAME" "RES_0402-0.0,5%,1/16W,CHIP,G21A"
					( Origin gPackager )
				)
				( objectStatus "R7W5" )
			)
			( gate "@baseboard_fab2_lib.baseboard_fab2(sch_1):page207_i113"
				( attribute "CDS_LIB" "mstr_discrete"
					( Origin gPackager )
				)
				( attribute "CDS_LOCATION" "EU1D4"
					( Origin gPackager )
				)
				( attribute "CDS_SEC" "1"
					( Origin gPackager )
				)
				( attribute "LOCATION" "EU1D4"
					( Origin gFrontEnd )
				)
				( attribute "MATERIAL" "IC"
					( Origin gFrontEnd )
				)
				( attribute "PACK_TYPE" "SM"
					( Origin gFrontEnd )
				)
				( attribute "PART_NUMBER" "H73688-001"
					( Origin gFrontEnd )
				)
				( attribute "PHYS_PAGE" "207"
					( Origin gFrontEnd )
				)
				( attribute "ROOM" "PVCCIN_CPU1_PWR_VR"
					( Origin gFrontEnd )
				)
				( attribute "ROT" "0"
					( Origin gFrontEnd )
				)
				( attribute "SEC" "1"
					( Origin gFrontEnd )
				)
				( attribute "SEC_TYPE" "SM"
					( Origin gFrontEnd )
				)
				( attribute "VALUE" "IR35411"
					( Origin gFrontEnd )
				)
				( attribute "VER" "1"
					( Origin gFrontEnd )
				)
				( attribute "XY" "(-3150,1250)"
					( Origin gFrontEnd )
				)
				( attribute "CHIPS_PART_NAME" "IR354XX"
					( Origin gPackager )
				)
				( attribute "CDS_PART_NAME" "IR354XX_SM-IR35411,IC,H73688-0A"
					( Origin gPackager )
				)
				( objectStatus "EU1D4" )
			)
			( gate "@baseboard_fab2_lib.baseboard_fab2(sch_1):page269_i61"
				( attribute "BOM_COST" "PROC_SIDEBAND"
					( Origin gFrontEnd )
				)
				( attribute "CDS_LIB" "mstr_ttl"
					( Origin gPackager )
				)
				( attribute "CDS_LOCATION" "U25W17"
					( Origin gPackager )
				)
				( attribute "CDS_SEC" "1"
					( Origin gPackager )
				)
				( attribute "LOCATION" "U25W17"
					( Origin gFrontEnd )
				)
				( attribute "MATERIAL" "IC"
					( Origin gFrontEnd )
				)
				( attribute "PACK_TYPE" "SOTLF"
					( Origin gFrontEnd )
				)
				( attribute "PART_NUMBER" "D10321-001"
					( Origin gFrontEnd )
				)
				( attribute "PHYS_PAGE" "254"
					( Origin gFrontEnd )
				)
				( attribute "ROOM" "CAT_ERR"
					( Origin gFrontEnd )
				)
				( attribute "ROT" "0"
					( Origin gFrontEnd )
				)
				( attribute "SEC" "1"
					( Origin gFrontEnd )
				)
				( attribute "SEC_TYPE" "SOTLF"
					( Origin gFrontEnd )
				)
				( attribute "VALUE" "NC7SZ08"
					( Origin gFrontEnd )
				)
				( attribute "VER" "1"
					( Origin gFrontEnd )
				)
				( attribute "XY" "(-5100,4000)"
					( Origin gFrontEnd )
				)
				( attribute "CHIPS_PART_NAME" "TTL1G08"
					( Origin gPackager )
				)
				( attribute "CDS_PART_NAME" "TTL1G08_SOTLF-NC7SZ08,IC,D1032B"
					( Origin gPackager )
				)
				( objectStatus "U25W17" )
			)
			( gate "@baseboard_fab2_lib.baseboard_fab2(sch_1):page269_i62"
				( attribute "BOM_COST" "PROC_SIDEBAND"
					( Origin gFrontEnd )
				)
				( attribute "CDS_LIB" "dev_discrete"
					( Origin gPackager )
				)
				( attribute "CDS_LOCATION" "C25W99"
					( Origin gPackager )
				)
				( attribute "CDS_SEC" "1"
					( Origin gPackager )
				)
				( attribute "LOCATION" "C25W99"
					( Origin gFrontEnd )
				)
				( attribute "MATERIAL" "X7R"
					( Origin gFrontEnd )
				)
				( attribute "PACK_TYPE" "0402V"
					( Origin gFrontEnd )
				)
				( attribute "PART_NUMBER" "A36096-030"
					( Origin gFrontEnd )
				)
				( attribute "PHYS_PAGE" "254"
					( Origin gFrontEnd )
				)
				( attribute "ROOM" "PROC_SIDEBAND"
					( Origin gFrontEnd )
				)
				( attribute "ROT" "0"
					( Origin gFrontEnd )
				)
				( attribute "SEC" "1"
					( Origin gFrontEnd )
				)
				( attribute "SEC_TYPE" "0402V"
					( Origin gFrontEnd )
				)
				( attribute "TOLERANCE" "10%"
					( Origin gFrontEnd )
				)
				( attribute "VALUE" "0.1UF"
					( Origin gFrontEnd )
				)
				( attribute "VER" "1"
					( Origin gFrontEnd )
				)
				( attribute "VOLTAGE" "16V"
					( Units "uVoltage" "V" 1.000000)
					( Origin gFrontEnd )
				)
				( attribute "XY" "(-5350,4450)"
					( Origin gFrontEnd )
				)
				( attribute "CHIPS_PART_NAME" "CAP_A"
					( Origin gPackager )
				)
				( attribute "CDS_PART_NAME" "CAP_A_0402V-0.1UF,16V,10%,X7R,A"
					( Origin gPackager )
				)
				( objectStatus "C25W99" )
			)
			( gate "@baseboard_fab2_lib.baseboard_fab2(sch_1):page268_i57"
				( attribute "BOM_COST" "PROC_SIDEBAND"
					( Origin gFrontEnd )
				)
				( attribute "CDS_LIB" "mstr_ttl"
					( Origin gPackager )
				)
				( attribute "CDS_LOCATION" "U25W18"
					( Origin gPackager )
				)
				( attribute "CDS_SEC" "1"
					( Origin gPackager )
				)
				( attribute "LOCATION" "U25W18"
					( Origin gFrontEnd )
				)
				( attribute "MATERIAL" "IC"
					( Origin gFrontEnd )
				)
				( attribute "PACK_TYPE" "SOTLF"
					( Origin gFrontEnd )
				)
				( attribute "PART_NUMBER" "D10321-001"
					( Origin gFrontEnd )
				)
				( attribute "PHYS_PAGE" "255"
					( Origin gFrontEnd )
				)
				( attribute "ROOM" "CAT_ERR"
					( Origin gFrontEnd )
				)
				( attribute "ROT" "0"
					( Origin gFrontEnd )
				)
				( attribute "SEC" "1"
					( Origin gFrontEnd )
				)
				( attribute "SEC_TYPE" "SOTLF"
					( Origin gFrontEnd )
				)
				( attribute "VALUE" "NC7SZ08"
					( Origin gFrontEnd )
				)
				( attribute "VER" "1"
					( Origin gFrontEnd )
				)
				( attribute "XY" "(-3400,4200)"
					( Origin gFrontEnd )
				)
				( attribute "CHIPS_PART_NAME" "TTL1G08"
					( Origin gPackager )
				)
				( attribute "CDS_PART_NAME" "TTL1G08_SOTLF-NC7SZ08,IC,D1032B"
					( Origin gPackager )
				)
				( objectStatus "U25W18" )
			)
			( gate "@baseboard_fab2_lib.baseboard_fab2(sch_1):page268_i60"
				( attribute "BOM_COST" "PROC_SIDEBAND"
					( Origin gFrontEnd )
				)
				( attribute "CDS_LIB" "dev_discrete"
					( Origin gPackager )
				)
				( attribute "CDS_LOCATION" "C25W100"
					( Origin gPackager )
				)
				( attribute "CDS_SEC" "1"
					( Origin gPackager )
				)
				( attribute "LOCATION" "C25W100"
					( Origin gFrontEnd )
				)
				( attribute "MATERIAL" "X7R"
					( Origin gFrontEnd )
				)
				( attribute "PACK_TYPE" "0402V"
					( Origin gFrontEnd )
				)
				( attribute "PART_NUMBER" "A36096-030"
					( Origin gFrontEnd )
				)
				( attribute "PHYS_PAGE" "255"
					( Origin gFrontEnd )
				)
				( attribute "ROOM" "PROC_SIDEBAND"
					( Origin gFrontEnd )
				)
				( attribute "ROT" "0"
					( Origin gFrontEnd )
				)
				( attribute "SEC" "1"
					( Origin gFrontEnd )
				)
				( attribute "SEC_TYPE" "0402V"
					( Origin gFrontEnd )
				)
				( attribute "TOLERANCE" "10%"
					( Origin gFrontEnd )
				)
				( attribute "VALUE" "0.1UF"
					( Origin gFrontEnd )
				)
				( attribute "VER" "1"
					( Origin gFrontEnd )
				)
				( attribute "VOLTAGE" "16V"
					( Units "uVoltage" "V" 1.000000)
					( Origin gFrontEnd )
				)
				( attribute "XY" "(-2700,3800)"
					( Origin gFrontEnd )
				)
				( attribute "CHIPS_PART_NAME" "CAP_A"
					( Origin gPackager )
				)
				( attribute "CDS_PART_NAME" "CAP_A_0402V-0.1UF,16V,10%,X7R,A"
					( Origin gPackager )
				)
				( objectStatus "C25W100" )
			)
			( gate "@baseboard_fab2_lib.baseboard_fab2(sch_1):page158_i153"
				( attribute "BOM_COST" "SM_CONTROLLER"
					( Origin gFrontEnd )
				)
				( attribute "CDS_LIB" "mstr_discrete"
					( Origin gPackager )
				)
				( attribute "CDS_LOCATION" "R9W33"
					( Origin gPackager )
				)
				( attribute "CDS_SEC" "1"
					( Origin gPackager )
				)
				( attribute "LOCATION" "R9W33"
					( Origin gFrontEnd )
				)
				( attribute "MATERIAL" "CHIP"
					( Origin gFrontEnd )
				)
				( attribute "PACK_TYPE" "0402"
					( Origin gFrontEnd )
				)
				( attribute "PART_NUMBER" "G21796-072"
					( Origin gFrontEnd )
				)
				( attribute "PHYS_PAGE" "158"
					( Origin gFrontEnd )
				)
				( attribute "POP" "NOPOP"
					( Origin gFrontEnd )
				)
				( attribute "ROOM" "BMC_MISC"
					( Origin gFrontEnd )
				)
				( attribute "ROT" "0"
					( Origin gFrontEnd )
				)
				( attribute "SEC" "1"
					( Origin gFrontEnd )
				)
				( attribute "SEC_TYPE" "0402"
					( Origin gFrontEnd )
				)
				( attribute "TOLERANCE" "1%"
					( Origin gFrontEnd )
				)
				( attribute "VALUE" "4.75K"
					( Origin gFrontEnd )
				)
				( attribute "VER" "2"
					( Origin gFrontEnd )
				)
				( attribute "WATTAGE" "1/16W"
					( Origin gFrontEnd )
				)
				( attribute "XY" "(-2300,1200)"
					( Origin gFrontEnd )
				)
				( attribute "CHIPS_PART_NAME" "RES"
					( Origin gPackager )
				)
				( attribute "CDS_PART_NAME" "RES_0402-4.75K,1%,1/16W,CHIP,GA"
					( Origin gPackager )
				)
				( objectStatus "R9W33" )
			)
			( gate "@baseboard_fab2_lib.baseboard_fab2(sch_1):page158_i154"
				( attribute "BOM_COST" "SM_CONTROLLER"
					( Origin gFrontEnd )
				)
				( attribute "CDS_LIB" "mstr_discrete"
					( Origin gPackager )
				)
				( attribute "CDS_LOCATION" "R9W34"
					( Origin gPackager )
				)
				( attribute "CDS_SEC" "1"
					( Origin gPackager )
				)
				( attribute "LOCATION" "R9W34"
					( Origin gFrontEnd )
				)
				( attribute "MATERIAL" "CHIP"
					( Origin gFrontEnd )
				)
				( attribute "PACK_TYPE" "0402"
					( Origin gFrontEnd )
				)
				( attribute "PART_NUMBER" "G21796-072"
					( Origin gFrontEnd )
				)
				( attribute "PHYS_PAGE" "158"
					( Origin gFrontEnd )
				)
				( attribute "ROOM" "BMC_MISC"
					( Origin gFrontEnd )
				)
				( attribute "ROT" "0"
					( Origin gFrontEnd )
				)
				( attribute "SEC" "1"
					( Origin gFrontEnd )
				)
				( attribute "SEC_TYPE" "0402"
					( Origin gFrontEnd )
				)
				( attribute "TOLERANCE" "1%"
					( Origin gFrontEnd )
				)
				( attribute "VALUE" "4.75K"
					( Origin gFrontEnd )
				)
				( attribute "VER" "2"
					( Origin gFrontEnd )
				)
				( attribute "WATTAGE" "1/16W"
					( Origin gFrontEnd )
				)
				( attribute "XY" "(-2025,1200)"
					( Origin gFrontEnd )
				)
				( attribute "CHIPS_PART_NAME" "RES"
					( Origin gPackager )
				)
				( attribute "CDS_PART_NAME" "RES_0402-4.75K,1%,1/16W,CHIP,GA"
					( Origin gPackager )
				)
				( attribute "POP" "NOPOP"
					( Origin gFrontEnd )
				)
				( objectStatus "R9W34" )
			)
			( gate "@baseboard_fab2_lib.baseboard_fab2(sch_1):page158_i155"
				( attribute "BOM_COST" "SM_CONTROLLER"
					( Origin gFrontEnd )
				)
				( attribute "CDS_LIB" "mstr_discrete"
					( Origin gPackager )
				)
				( attribute "CDS_LOCATION" "R9W35"
					( Origin gPackager )
				)
				( attribute "CDS_SEC" "1"
					( Origin gPackager )
				)
				( attribute "LOCATION" "R9W35"
					( Origin gFrontEnd )
				)
				( attribute "MATERIAL" "CHIP"
					( Origin gFrontEnd )
				)
				( attribute "PACK_TYPE" "0402"
					( Origin gFrontEnd )
				)
				( attribute "PART_NUMBER" "G21796-072"
					( Origin gFrontEnd )
				)
				( attribute "PHYS_PAGE" "158"
					( Origin gFrontEnd )
				)
				( attribute "ROOM" "BMC_MISC"
					( Origin gFrontEnd )
				)
				( attribute "ROT" "0"
					( Origin gFrontEnd )
				)
				( attribute "SEC" "1"
					( Origin gFrontEnd )
				)
				( attribute "SEC_TYPE" "0402"
					( Origin gFrontEnd )
				)
				( attribute "TOLERANCE" "1%"
					( Origin gFrontEnd )
				)
				( attribute "VALUE" "4.75K"
					( Origin gFrontEnd )
				)
				( attribute "VER" "2"
					( Origin gFrontEnd )
				)
				( attribute "WATTAGE" "1/16W"
					( Origin gFrontEnd )
				)
				( attribute "XY" "(-1750,1200)"
					( Origin gFrontEnd )
				)
				( attribute "CHIPS_PART_NAME" "RES"
					( Origin gPackager )
				)
				( attribute "CDS_PART_NAME" "RES_0402-4.75K,1%,1/16W,CHIP,GA"
					( Origin gPackager )
				)
				( attribute "POP" "NOPOP"
					( Origin gFrontEnd )
				)
				( objectStatus "R9W35" )
			)
			( gate "@baseboard_fab2_lib.baseboard_fab2(sch_1):page155_i202"
				( attribute "CDS_LIB" "mstr_discrete"
					( Origin gPackager )
				)
				( attribute "CDS_LOCATION" "CR9W1"
					( Origin gPackager )
				)
				( attribute "CDS_SEC" "1"
					( Origin gPackager )
				)
				( attribute "LOCATION" "CR9W1"
					( Origin gFrontEnd )
				)
				( attribute "MATERIAL" "IC"
					( Origin gFrontEnd )
				)
				( attribute "PACK_TYPE" "SMLF"
					( Origin gFrontEnd )
				)
				( attribute "PART_NUMBER" "C73510-001"
					( Origin gFrontEnd )
				)
				( attribute "PHYS_PAGE" "155"
					( Origin gFrontEnd )
				)
				( attribute "ROT" "0"
					( Origin gFrontEnd )
				)
				( attribute "SEC" "1"
					( Origin gFrontEnd )
				)
				( attribute "SEC_TYPE" "SMLF"
					( Origin gFrontEnd )
				)
				( attribute "VALUE" "BAT54WS"
					( Origin gFrontEnd )
				)
				( attribute "VER" "3"
					( Origin gFrontEnd )
				)
				( attribute "XY" "(-2900,1400)"
					( Origin gFrontEnd )
				)
				( attribute "CHIPS_PART_NAME" "DIODE"
					( Origin gPackager )
				)
				( attribute "CDS_PART_NAME" "DIODE_SMLF-BAT54WS,IC,C73510-0A"
					( Origin gPackager )
				)
				( objectStatus "CR9W1" )
			)
			( gate "@baseboard_fab2_lib.baseboard_fab2(sch_1):page238_i46"
				( attribute "BOM_COST" "P1V26_BMC_STBY_VR"
					( Origin gFrontEnd )
				)
				( attribute "CDS_LIB" "mstr_discrete"
					( Origin gPackager )
				)
				( attribute "CDS_LOCATION" "C9W14"
					( Origin gPackager )
				)
				( attribute "CDS_SEC" "1"
					( Origin gPackager )
				)
				( attribute "LOCATION" "C9W14"
					( Origin gFrontEnd )
				)
				( attribute "MATERIAL" "X6S"
					( Origin gFrontEnd )
				)
				( attribute "PACK_TYPE" "0603"
					( Origin gFrontEnd )
				)
				( attribute "PART_NUMBER" "E15431-002"
					( Origin gFrontEnd )
				)
				( attribute "PHYS_PAGE" "238"
					( Origin gFrontEnd )
				)
				( attribute "POP" "NOPOP"
					( Origin gFrontEnd )
				)
				( attribute "ROOM" "P1V26_BMC_STBY_VR"
					( Origin gFrontEnd )
				)
				( attribute "ROT" "0"
					( Origin gFrontEnd )
				)
				( attribute "SEC" "1"
					( Origin gFrontEnd )
				)
				( attribute "SEC_TYPE" "0603"
					( Origin gFrontEnd )
				)
				( attribute "TOLERANCE" "20%"
					( Origin gFrontEnd )
				)
				( attribute "VALUE" "10UF"
					( Origin gFrontEnd )
				)
				( attribute "VER" "1"
					( Origin gFrontEnd )
				)
				( attribute "VOLTAGE" "6.3V"
					( Units "uVoltage" "V" 1.000000)
					( Origin gFrontEnd )
				)
				( attribute "XY" "(-2050,3050)"
					( Origin gFrontEnd )
				)
				( attribute "CHIPS_PART_NAME" "CAP"
					( Origin gPackager )
				)
				( attribute "CDS_PART_NAME" "CAP_0603-10UF,6.3V,20%,X6S,E15A"
					( Origin gPackager )
				)
				( objectStatus "C9W14" )
			)
			( gate "@baseboard_fab2_lib.baseboard_fab2(sch_1):page239_i104"
				( attribute "BOM_COST" "P1V26_BMC_STBY_VR"
					( Origin gFrontEnd )
				)
				( attribute "CDS_LIB" "mstr_discrete"
					( Origin gPackager )
				)
				( attribute "CDS_LOCATION" "C9W17"
					( Origin gPackager )
				)
				( attribute "CDS_SEC" "1"
					( Origin gPackager )
				)
				( attribute "LOCATION" "C9W17"
					( Origin gFrontEnd )
				)
				( attribute "MATERIAL" "X6S"
					( Origin gFrontEnd )
				)
				( attribute "PACK_TYPE" "0603"
					( Origin gFrontEnd )
				)
				( attribute "PART_NUMBER" "E15431-002"
					( Origin gFrontEnd )
				)
				( attribute "PHYS_PAGE" "239"
					( Origin gFrontEnd )
				)
				( attribute "POP" "NOPOP"
					( Origin gFrontEnd )
				)
				( attribute "ROOM" "P1V26_BMC_STBY_VR"
					( Origin gFrontEnd )
				)
				( attribute "ROT" "0"
					( Origin gFrontEnd )
				)
				( attribute "SEC" "1"
					( Origin gFrontEnd )
				)
				( attribute "SEC_TYPE" "0603"
					( Origin gFrontEnd )
				)
				( attribute "TOLERANCE" "20%"
					( Origin gFrontEnd )
				)
				( attribute "VALUE" "10UF"
					( Origin gFrontEnd )
				)
				( attribute "VER" "1"
					( Origin gFrontEnd )
				)
				( attribute "VOLTAGE" "6.3V"
					( Units "uVoltage" "V" 1.000000)
					( Origin gFrontEnd )
				)
				( attribute "XY" "(6550,4250)"
					( Origin gFrontEnd )
				)
				( attribute "CHIPS_PART_NAME" "CAP"
					( Origin gPackager )
				)
				( attribute "CDS_PART_NAME" "CAP_0603-10UF,6.3V,20%,X6S,E15A"
					( Origin gPackager )
				)
				( objectStatus "C9W17" )
			)
			( gate "@baseboard_fab2_lib.baseboard_fab2(sch_1):page238_i50"
				( attribute "BOM_COST" "PROC_SOCKET"
					( Origin gFrontEnd )
				)
				( attribute "CDS_LIB" "dev_discrete"
					( Origin gPackager )
				)
				( attribute "CDS_LOCATION" "C9W16"
					( Origin gPackager )
				)
				( attribute "CDS_SEC" "1"
					( Origin gPackager )
				)
				( attribute "LOCATION" "C9W16"
					( Origin gFrontEnd )
				)
				( attribute "MATERIAL" "X6S"
					( Origin gFrontEnd )
				)
				( attribute "PACK_TYPE" "0603V"
					( Origin gFrontEnd )
				)
				( attribute "PART_NUMBER" "E15431-004"
					( Origin gFrontEnd )
				)
				( attribute "PHYS_PAGE" "238"
					( Origin gFrontEnd )
				)
				( attribute "POP" "NOPOP"
					( Origin gFrontEnd )
				)
				( attribute "ROOM" "PVCCIN_CPU0_DECAP_VR"
					( Origin gFrontEnd )
				)
				( attribute "ROT" "0"
					( Origin gFrontEnd )
				)
				( attribute "SEC" "1"
					( Origin gPackager )
				)
				( attribute "TOLERANCE" "20%"
					( Origin gFrontEnd )
				)
				( attribute "VALUE" "22.0UF"
					( Origin gFrontEnd )
				)
				( attribute "VER" "1"
					( Origin gFrontEnd )
				)
				( attribute "VOLTAGE" "4V"
					( Units "uVoltage" "V" 1.000000)
					( Origin gFrontEnd )
				)
				( attribute "XY" "(1950,2550)"
					( Origin gFrontEnd )
				)
				( attribute "CHIPS_PART_NAME" "CAP_A"
					( Origin gPackager )
				)
				( attribute "CDS_PART_NAME" "CAP_A_0603V-22.0UF,4V,20%,X6S,A"
					( Origin gPackager )
				)
				( objectStatus "C9W16" )
			)
			( gate "@baseboard_fab2_lib.baseboard_fab2(sch_1):page239_i111"
				( attribute "BOM_COST" "PROC_SOCKET"
					( Origin gFrontEnd )
				)
				( attribute "CDS_LIB" "dev_discrete"
					( Origin gPackager )
				)
				( attribute "CDS_LOCATION" "C9W19"
					( Origin gPackager )
				)
				( attribute "CDS_SEC" "1"
					( Origin gPackager )
				)
				( attribute "LOCATION" "C9W19"
					( Origin gFrontEnd )
				)
				( attribute "MATERIAL" "X6S"
					( Origin gFrontEnd )
				)
				( attribute "PACK_TYPE" "0603V"
					( Origin gFrontEnd )
				)
				( attribute "PART_NUMBER" "E15431-004"
					( Origin gFrontEnd )
				)
				( attribute "PHYS_PAGE" "239"
					( Origin gFrontEnd )
				)
				( attribute "POP" "NOPOP"
					( Origin gFrontEnd )
				)
				( attribute "ROOM" "PVCCIN_CPU0_DECAP_VR"
					( Origin gFrontEnd )
				)
				( attribute "ROT" "0"
					( Origin gFrontEnd )
				)
				( attribute "SEC" "1"
					( Origin gPackager )
				)
				( attribute "TOLERANCE" "20%"
					( Origin gFrontEnd )
				)
				( attribute "VALUE" "22.0UF"
					( Origin gFrontEnd )
				)
				( attribute "VER" "1"
					( Origin gFrontEnd )
				)
				( attribute "VOLTAGE" "4V"
					( Units "uVoltage" "V" 1.000000)
					( Origin gFrontEnd )
				)
				( attribute "XY" "(11250,3650)"
					( Origin gFrontEnd )
				)
				( attribute "CHIPS_PART_NAME" "CAP_A"
					( Origin gPackager )
				)
				( attribute "CDS_PART_NAME" "CAP_A_0603V-22.0UF,4V,20%,X6S,A"
					( Origin gPackager )
				)
				( objectStatus "C9W19" )
			)
			( gate "@baseboard_fab2_lib.baseboard_fab2(sch_1):page104_i103"
				( attribute "CDS_LIB" "mstr_discrete"
					( Origin gPackager )
				)
				( attribute "CDS_LOCATION" "R7D39"
					( Origin gPackager )
				)
				( attribute "CDS_SEC" "1"
					( Origin gPackager )
				)
				( attribute "LOCATION" "R7D39"
					( Origin gFrontEnd )
				)
				( attribute "MATERIAL" "CHIP"
					( Origin gFrontEnd )
				)
				( attribute "NO_XNET_CONNECTION" "1"
					( Origin gFrontEnd )
				)
				( attribute "PACK_TYPE" "0402"
					( Origin gFrontEnd )
				)
				( attribute "PART_NUMBER" "G21497-005"
					( Origin gFrontEnd )
				)
				( attribute "PHYS_PAGE" "104"
					( Origin gFrontEnd )
				)
				( attribute "ROOM" "CLOCK_CPU1_OSC"
					( Origin gFrontEnd )
				)
				( attribute "ROT" "0"
					( Origin gFrontEnd )
				)
				( attribute "SEC" "1"
					( Origin gFrontEnd )
				)
				( attribute "SEC_TYPE" "0402"
					( Origin gFrontEnd )
				)
				( attribute "TOLERANCE" "5%"
					( Origin gFrontEnd )
				)
				( attribute "VALUE" "0.0"
					( Origin gFrontEnd )
				)
				( attribute "VER" "1"
					( Origin gFrontEnd )
				)
				( attribute "WATTAGE" "1/16W"
					( Origin gFrontEnd )
				)
				( attribute "XY" "(550,1800)"
					( Origin gFrontEnd )
				)
				( attribute "CHIPS_PART_NAME" "RES"
					( Origin gPackager )
				)
				( attribute "CDS_PART_NAME" "RES_0402-0.0,5%,1/16W,CHIP,G21A"
					( Origin gPackager )
				)
				( objectStatus "R7D39" )
			)
			( gate "@baseboard_fab2_lib.baseboard_fab2(sch_1):page104_i104"
				( attribute "CDS_LIB" "mstr_discrete"
					( Origin gPackager )
				)
				( attribute "CDS_LOCATION" "R7D37"
					( Origin gPackager )
				)
				( attribute "CDS_SEC" "1"
					( Origin gPackager )
				)
				( attribute "LOCATION" "R7D37"
					( Origin gFrontEnd )
				)
				( attribute "MATERIAL" "CHIP"
					( Origin gFrontEnd )
				)
				( attribute "NO_XNET_CONNECTION" "1"
					( Origin gFrontEnd )
				)
				( attribute "PACK_TYPE" "0402"
					( Origin gFrontEnd )
				)
				( attribute "PART_NUMBER" "G21497-005"
					( Origin gFrontEnd )
				)
				( attribute "PHYS_PAGE" "104"
					( Origin gFrontEnd )
				)
				( attribute "ROOM" "CLOCK_CPU1_OSC"
					( Origin gFrontEnd )
				)
				( attribute "ROT" "0"
					( Origin gFrontEnd )
				)
				( attribute "SEC" "1"
					( Origin gFrontEnd )
				)
				( attribute "SEC_TYPE" "0402"
					( Origin gFrontEnd )
				)
				( attribute "TOLERANCE" "5%"
					( Origin gFrontEnd )
				)
				( attribute "VALUE" "0.0"
					( Origin gFrontEnd )
				)
				( attribute "VER" "1"
					( Origin gFrontEnd )
				)
				( attribute "WATTAGE" "1/16W"
					( Origin gFrontEnd )
				)
				( attribute "XY" "(550,1100)"
					( Origin gFrontEnd )
				)
				( attribute "CHIPS_PART_NAME" "RES"
					( Origin gPackager )
				)
				( attribute "CDS_PART_NAME" "RES_0402-0.0,5%,1/16W,CHIP,G21A"
					( Origin gPackager )
				)
				( objectStatus "R7D37" )
			)
			( gate "@baseboard_fab2_lib.baseboard_fab2(sch_1):page268_i63"
				( attribute "CDS_LIB" "w_hdl"
					( Origin gPackager )
				)
				( attribute "CDS_LMAN_SYM_OUTLINE" "-100,175,100,-175"
					( Origin gPackager )
				)
				( attribute "LOCATION" "S9W1"
					( Origin gFrontEnd )
				)
				( attribute "PACK_TYPE" "DISCRET-G6"
					( Origin gFrontEnd )
				)
				( attribute "PART_NUMBER" "62.40018.461"
					( Origin gFrontEnd )
				)
				( attribute "PHYS_PAGE" "255"
					( Origin gFrontEnd )
				)
				( attribute "ROT" "2"
					( Origin gFrontEnd )
				)
				( attribute "SEC" "1"
					( Origin gFrontEnd )
				)
				( attribute "SEC_TYPE" "DISCRET-G6"
					( Origin gFrontEnd )
				)
				( attribute "VALUE" "SW-SLIDE75-GP"
					( Origin gFrontEnd )
				)
				( attribute "VER" "1"
					( Origin gFrontEnd )
				)
				( attribute "XY" "(-2050,3325)"
					( Origin gFrontEnd )
				)
				( attribute "CHIPS_PART_NAME" "SW-SLIDE75-GP"
					( Origin gPackager )
				)
				( attribute "CDS_PART_NAME" "SW-SLIDE75-GP_DISCRET-G6-SW-SLA"
					( Origin gPackager )
				)
				( attribute "CDS_LOCATION" "S9W1"
					( Origin gPackager )
				)
				( attribute "CDS_SEC" "1"
					( Origin gPackager )
				)
				( objectStatus "S9W1" )
			)
			( gate "@baseboard_fab2_lib.baseboard_fab2(sch_1):page269_i71"
				( attribute "CDS_LIB" "w_hdl"
					( Origin gPackager )
				)
				( attribute "CDS_LMAN_SYM_OUTLINE" "-50,100,50,-100"
					( Origin gPackager )
				)
				( attribute "LOCATION" "FB25W1"
					( Origin gFrontEnd )
				)
				( attribute "PACK_TYPE" "DISCRET-G"
					( Origin gFrontEnd )
				)
				( attribute "PART_NUMBER" "68.00084.921"
					( Origin gFrontEnd )
				)
				( attribute "PHYS_PAGE" "254"
					( Origin gFrontEnd )
				)
				( attribute "ROT" "1"
					( Origin gFrontEnd )
				)
				( attribute "SEC" "1"
					( Origin gFrontEnd )
				)
				( attribute "SEC_TYPE" "DISCRET-G"
					( Origin gFrontEnd )
				)
				( attribute "VALUE" "BLM15AG121SN-1GP"
					( Origin gFrontEnd )
				)
				( attribute "VER" "1"
					( Origin gFrontEnd )
				)
				( attribute "XY" "(-2800,3700)"
					( Origin gFrontEnd )
				)
				( attribute "CHIPS_PART_NAME" "BLM15AG121SN-1GP"
					( Origin gPackager )
				)
				( attribute "CDS_PART_NAME" "BLM15AG121SN-1GP_DISCRET-G-BLMA"
					( Origin gPackager )
				)
				( attribute "CDS_LOCATION" "FB25W1"
					( Origin gPackager )
				)
				( attribute "CDS_SEC" "1"
					( Origin gPackager )
				)
				( objectStatus "FB25W1" )
			)
			( gate "@baseboard_fab2_lib.baseboard_fab2(sch_1):page269_i72"
				( attribute "CDS_LIB" "w_hdl"
					( Origin gPackager )
				)
				( attribute "CDS_LMAN_SYM_OUTLINE" "-50,100,50,-100"
					( Origin gPackager )
				)
				( attribute "LOCATION" "FB25W2"
					( Origin gFrontEnd )
				)
				( attribute "PACK_TYPE" "DISCRET-G"
					( Origin gFrontEnd )
				)
				( attribute "PART_NUMBER" "68.00084.921"
					( Origin gFrontEnd )
				)
				( attribute "PHYS_PAGE" "254"
					( Origin gFrontEnd )
				)
				( attribute "ROT" "1"
					( Origin gFrontEnd )
				)
				( attribute "SEC" "1"
					( Origin gFrontEnd )
				)
				( attribute "SEC_TYPE" "DISCRET-G"
					( Origin gFrontEnd )
				)
				( attribute "VALUE" "BLM15AG121SN-1GP"
					( Origin gFrontEnd )
				)
				( attribute "VER" "1"
					( Origin gFrontEnd )
				)
				( attribute "XY" "(-2800,3900)"
					( Origin gFrontEnd )
				)
				( attribute "CHIPS_PART_NAME" "BLM15AG121SN-1GP"
					( Origin gPackager )
				)
				( attribute "CDS_PART_NAME" "BLM15AG121SN-1GP_DISCRET-G-BLMA"
					( Origin gPackager )
				)
				( attribute "CDS_LOCATION" "FB25W2"
					( Origin gPackager )
				)
				( attribute "CDS_SEC" "1"
					( Origin gPackager )
				)
				( objectStatus "FB25W2" )
			)
			( gate "@baseboard_fab2_lib.baseboard_fab2(sch_1):page269_i73"
				( attribute "CDS_LIB" "w_hdl"
					( Origin gPackager )
				)
				( attribute "CDS_LMAN_SYM_OUTLINE" "-50,100,50,-100"
					( Origin gPackager )
				)
				( attribute "LOCATION" "FB25W3"
					( Origin gFrontEnd )
				)
				( attribute "PACK_TYPE" "DISCRET-G"
					( Origin gFrontEnd )
				)
				( attribute "PART_NUMBER" "68.00084.921"
					( Origin gFrontEnd )
				)
				( attribute "PHYS_PAGE" "254"
					( Origin gFrontEnd )
				)
				( attribute "ROT" "1"
					( Origin gFrontEnd )
				)
				( attribute "SEC" "1"
					( Origin gFrontEnd )
				)
				( attribute "SEC_TYPE" "DISCRET-G"
					( Origin gFrontEnd )
				)
				( attribute "VALUE" "BLM15AG121SN-1GP"
					( Origin gFrontEnd )
				)
				( attribute "VER" "1"
					( Origin gFrontEnd )
				)
				( attribute "XY" "(-2800,4100)"
					( Origin gFrontEnd )
				)
				( attribute "CHIPS_PART_NAME" "BLM15AG121SN-1GP"
					( Origin gPackager )
				)
				( attribute "CDS_PART_NAME" "BLM15AG121SN-1GP_DISCRET-G-BLMA"
					( Origin gPackager )
				)
				( attribute "CDS_LOCATION" "FB25W3"
					( Origin gPackager )
				)
				( attribute "CDS_SEC" "1"
					( Origin gPackager )
				)
				( objectStatus "FB25W3" )
			)
			( gate "@baseboard_fab2_lib.baseboard_fab2(sch_1):page269_i74"
				( attribute "CDS_LIB" "w_hdl"
					( Origin gPackager )
				)
				( attribute "CDS_LMAN_SYM_OUTLINE" "-50,100,50,-100"
					( Origin gPackager )
				)
				( attribute "CDS_LOCATION" "FB25W5"
					( Origin gPackager )
				)
				( attribute "CDS_SEC" "1"
					( Origin gPackager )
				)
				( attribute "LOCATION" "FB25W5"
					( Origin gFrontEnd )
				)
				( attribute "PACK_TYPE" "DISCRET-G"
					( Origin gFrontEnd )
				)
				( attribute "PART_NUMBER" "68.00084.921"
					( Origin gFrontEnd )
				)
				( attribute "PHYS_PAGE" "254"
					( Origin gFrontEnd )
				)
				( attribute "ROT" "1"
					( Origin gFrontEnd )
				)
				( attribute "SEC" "1"
					( Origin gFrontEnd )
				)
				( attribute "SEC_TYPE" "DISCRET-G"
					( Origin gFrontEnd )
				)
				( attribute "VALUE" "BLM15AG121SN-1GP"
					( Origin gFrontEnd )
				)
				( attribute "VER" "1"
					( Origin gFrontEnd )
				)
				( attribute "XY" "(-3550,5500)"
					( Origin gFrontEnd )
				)
				( attribute "CHIPS_PART_NAME" "BLM15AG121SN-1GP"
					( Origin gPackager )
				)
				( attribute "CDS_PART_NAME" "BLM15AG121SN-1GP_DISCRET-G-BLMA"
					( Origin gPackager )
				)
				( objectStatus "FB25W5" )
			)
			( gate "@baseboard_fab2_lib.baseboard_fab2(sch_1):page269_i75"
				( attribute "CDS_LIB" "w_hdl"
					( Origin gPackager )
				)
				( attribute "CDS_LMAN_SYM_OUTLINE" "-50,100,50,-100"
					( Origin gPackager )
				)
				( attribute "CDS_LOCATION" "FB25W4"
					( Origin gPackager )
				)
				( attribute "CDS_SEC" "1"
					( Origin gPackager )
				)
				( attribute "LOCATION" "FB25W4"
					( Origin gFrontEnd )
				)
				( attribute "PACK_TYPE" "DISCRET-G"
					( Origin gFrontEnd )
				)
				( attribute "PART_NUMBER" "68.00084.921"
					( Origin gFrontEnd )
				)
				( attribute "PHYS_PAGE" "254"
					( Origin gFrontEnd )
				)
				( attribute "ROT" "1"
					( Origin gFrontEnd )
				)
				( attribute "SEC" "1"
					( Origin gFrontEnd )
				)
				( attribute "SEC_TYPE" "DISCRET-G"
					( Origin gFrontEnd )
				)
				( attribute "VALUE" "BLM15AG121SN-1GP"
					( Origin gFrontEnd )
				)
				( attribute "VER" "1"
					( Origin gFrontEnd )
				)
				( attribute "XY" "(-3850,5450)"
					( Origin gFrontEnd )
				)
				( attribute "CHIPS_PART_NAME" "BLM15AG121SN-1GP"
					( Origin gPackager )
				)
				( attribute "CDS_PART_NAME" "BLM15AG121SN-1GP_DISCRET-G-BLMA"
					( Origin gPackager )
				)
				( objectStatus "FB25W4" )
			)
			( gate "@baseboard_fab2_lib.baseboard_fab2(sch_1):page225_i327"
				( attribute "CDS_LIB" "w_hdl"
					( Origin gPackager )
				)
				( attribute "CDS_LMAN_SYM_OUTLINE" "-50,25,50,-25"
					( Origin gPackager )
				)
				( attribute "LOCATION" "C1G15"
					( Origin gFrontEnd )
				)
				( attribute "NEW_SIZE" "B2"
					( Origin gFrontEnd )
				)
				( attribute "NEW_VALUE" "33UF"
					( Origin gFrontEnd )
				)
				( attribute "PACK_TYPE" "SMD-TCG2"
					( Origin gFrontEnd )
				)
				( attribute "PART_NUMBER" "077.C2771.0001"
					( Origin gFrontEnd )
				)
				( attribute "PHYS_PAGE" "225"
					( Origin gFrontEnd )
				)
				( attribute "ROT" "0"
					( Origin gFrontEnd )
				)
				( attribute "SEC" "1"
					( Origin gFrontEnd )
				)
				( attribute "SEC_TYPE" "SMD-TCG2"
					( Origin gFrontEnd )
				)
				( attribute "VALUE" "ST270U2D5VBM-GP"
					( Origin gFrontEnd )
				)
				( attribute "VER" "1"
					( Origin gFrontEnd )
				)
				( attribute "XY" "(-1250,1150)"
					( Origin gFrontEnd )
				)
				( attribute "CHIPS_PART_NAME" "ST270U2D5VBM-GP"
					( Origin gPackager )
				)
				( attribute "CDS_PART_NAME" "ST270U2D5VBM-GP_SMD-TCG2-ST270A"
					( Origin gPackager )
				)
				( attribute "CDS_LOCATION" "C1G15"
					( Origin gPackager )
				)
				( attribute "CDS_SEC" "1"
					( Origin gPackager )
				)
				( attribute "NEW_PN" "077.C3361.0001"
					( Origin gFrontEnd )
				)
				( objectStatus "C1G15" )
			)
			( gate "@baseboard_fab2_lib.baseboard_fab2(sch_1):page225_i328"
				( attribute "CDS_LIB" "w_hdl"
					( Origin gPackager )
				)
				( attribute "CDS_LMAN_SYM_OUTLINE" "-50,25,50,-25"
					( Origin gPackager )
				)
				( attribute "LOCATION" "C1G12"
					( Origin gFrontEnd )
				)
				( attribute "NEW_SIZE" "B2"
					( Origin gFrontEnd )
				)
				( attribute "NEW_VALUE" "33UF"
					( Origin gFrontEnd )
				)
				( attribute "PACK_TYPE" "SMD-TCG2"
					( Origin gFrontEnd )
				)
				( attribute "PART_NUMBER" "077.C2771.0001"
					( Origin gFrontEnd )
				)
				( attribute "PHYS_PAGE" "225"
					( Origin gFrontEnd )
				)
				( attribute "ROT" "0"
					( Origin gFrontEnd )
				)
				( attribute "SEC" "1"
					( Origin gFrontEnd )
				)
				( attribute "SEC_TYPE" "SMD-TCG2"
					( Origin gFrontEnd )
				)
				( attribute "VALUE" "ST270U2D5VBM-GP"
					( Origin gFrontEnd )
				)
				( attribute "VER" "1"
					( Origin gFrontEnd )
				)
				( attribute "XY" "(-550,1150)"
					( Origin gFrontEnd )
				)
				( attribute "CHIPS_PART_NAME" "ST270U2D5VBM-GP"
					( Origin gPackager )
				)
				( attribute "CDS_PART_NAME" "ST270U2D5VBM-GP_SMD-TCG2-ST270A"
					( Origin gPackager )
				)
				( attribute "CDS_LOCATION" "C1G12"
					( Origin gPackager )
				)
				( attribute "CDS_SEC" "1"
					( Origin gPackager )
				)
				( attribute "NEW_PN" "077.C3361.0001"
					( Origin gFrontEnd )
				)
				( objectStatus "C1G12" )
			)
			( gate "@baseboard_fab2_lib.baseboard_fab2(sch_1):page225_i329"
				( attribute "CDS_LIB" "w_hdl"
					( Origin gPackager )
				)
				( attribute "CDS_LMAN_SYM_OUTLINE" "-50,25,50,-25"
					( Origin gPackager )
				)
				( attribute "LOCATION" "C1G7"
					( Origin gFrontEnd )
				)
				( attribute "NEW_SIZE" "B2"
					( Origin gFrontEnd )
				)
				( attribute "NEW_VALUE" "33UF"
					( Origin gFrontEnd )
				)
				( attribute "PACK_TYPE" "SMD-TCG2"
					( Origin gFrontEnd )
				)
				( attribute "PART_NUMBER" "077.C2771.0001"
					( Origin gFrontEnd )
				)
				( attribute "PHYS_PAGE" "225"
					( Origin gFrontEnd )
				)
				( attribute "ROT" "0"
					( Origin gFrontEnd )
				)
				( attribute "SEC" "1"
					( Origin gFrontEnd )
				)
				( attribute "SEC_TYPE" "SMD-TCG2"
					( Origin gFrontEnd )
				)
				( attribute "VALUE" "ST270U2D5VBM-GP"
					( Origin gFrontEnd )
				)
				( attribute "VER" "1"
					( Origin gFrontEnd )
				)
				( attribute "XY" "(850,1150)"
					( Origin gFrontEnd )
				)
				( attribute "CHIPS_PART_NAME" "ST270U2D5VBM-GP"
					( Origin gPackager )
				)
				( attribute "CDS_PART_NAME" "ST270U2D5VBM-GP_SMD-TCG2-ST270A"
					( Origin gPackager )
				)
				( attribute "CDS_LOCATION" "C1G7"
					( Origin gPackager )
				)
				( attribute "CDS_SEC" "1"
					( Origin gPackager )
				)
				( attribute "NEW_PN" "077.C3361.0001"
					( Origin gFrontEnd )
				)
				( objectStatus "C1G7" )
			)
			( gate "@baseboard_fab2_lib.baseboard_fab2(sch_1):page220_i324"
				( attribute "ATTRIBUTE" "100UF"
					( Origin gFrontEnd )
				)
				( attribute "CDS_LIB" "w_hdl"
					( Origin gPackager )
				)
				( attribute "CDS_LMAN_SYM_OUTLINE" "-50,25,50,-25"
					( Origin gPackager )
				)
				( attribute "LOCATION" "C7W2"
					( Origin gFrontEnd )
				)
				( attribute "PACK_TYPE" "SMD-TCG2"
					( Origin gFrontEnd )
				)
				( attribute "PART_NUMBER" "077.51081.0011"
					( Origin gFrontEnd )
				)
				( attribute "PHYS_PAGE" "220"
					( Origin gFrontEnd )
				)
				( attribute "RATED" "16V"
					( Origin gFrontEnd )
				)
				( attribute "ROT" "0"
					( Origin gFrontEnd )
				)
				( attribute "SEC" "1"
					( Origin gFrontEnd )
				)
				( attribute "SEC_TYPE" "SMD-TCG2"
					( Origin gFrontEnd )
				)
				( attribute "VALUE" "SE100U16VM-48-GP"
					( Origin gFrontEnd )
				)
				( attribute "VER" "1"
					( Origin gFrontEnd )
				)
				( attribute "XY" "(-1450,1025)"
					( Origin gFrontEnd )
				)
				( attribute "CHIPS_PART_NAME" "SE100U16VM-48-GP"
					( Origin gPackager )
				)
				( attribute "CDS_PART_NAME" "SE100U16VM-48-GP_SMD-TCG2-SE10A"
					( Origin gPackager )
				)
				( attribute "CDS_LOCATION" "C7W2"
					( Origin gPackager )
				)
				( attribute "CDS_SEC" "1"
					( Origin gPackager )
				)
				( objectStatus "C7W2" )
			)
			( gate "@baseboard_fab2_lib.baseboard_fab2(sch_1):page271_i30"
				( attribute "CDS_LIB" "w_hdl"
					( Origin gPackager )
				)
				( attribute "CDS_LMAN_SYM_OUTLINE" "-75,100,75,-100"
					( Origin gPackager )
				)
				( attribute "LOCATION" "T1P14"
					( Origin gFrontEnd )
				)
				( attribute "PACK_TYPE" "DISCRET-GB3"
					( Origin gFrontEnd )
				)
				( attribute "PART_NUMBER" "ZZ.00PAD.NW1"
					( Origin gFrontEnd )
				)
				( attribute "PHYS_PAGE" "256"
					( Origin gFrontEnd )
				)
				( attribute "ROT" "0"
					( Origin gFrontEnd )
				)
				( attribute "SEC" "1"
					( Origin gFrontEnd )
				)
				( attribute "SEC_TYPE" "DISCRET-GB3"
					( Origin gFrontEnd )
				)
				( attribute "VALUE" "TPAD-DIFF-4P-GP"
					( Origin gFrontEnd )
				)
				( attribute "VER" "1"
					( Origin gFrontEnd )
				)
				( attribute "XY" "(-4200,5675)"
					( Origin gFrontEnd )
				)
				( attribute "CHIPS_PART_NAME" "TPAD-DIFF-4P-GP"
					( Origin gPackager )
				)
				( attribute "CDS_PART_NAME" "TPAD-DIFF-4P-GP_DISCRET-GB3-TPA"
					( Origin gPackager )
				)
				( attribute "CDS_LOCATION" "T1P14"
					( Origin gPackager )
				)
				( attribute "CDS_SEC" "1"
					( Origin gPackager )
				)
				( objectStatus "T1P14" )
			)
			( gate "@baseboard_fab2_lib.baseboard_fab2(sch_1):page271_i3"
				( attribute "CDS_LIB" "w_hdl"
					( Origin gPackager )
				)
				( attribute "CDS_LMAN_SYM_OUTLINE" "-75,100,75,-100"
					( Origin gPackager )
				)
				( attribute "LOCATION" "T1P1"
					( Origin gFrontEnd )
				)
				( attribute "PACK_TYPE" "DISCRET-GB3"
					( Origin gFrontEnd )
				)
				( attribute "PART_NUMBER" "ZZ.00PAD.NW1"
					( Origin gFrontEnd )
				)
				( attribute "PHYS_PAGE" "256"
					( Origin gFrontEnd )
				)
				( attribute "ROT" "0"
					( Origin gFrontEnd )
				)
				( attribute "SEC" "1"
					( Origin gFrontEnd )
				)
				( attribute "SEC_TYPE" "DISCRET-GB3"
					( Origin gFrontEnd )
				)
				( attribute "VALUE" "TPAD-DIFF-4P-GP"
					( Origin gFrontEnd )
				)
				( attribute "VER" "1"
					( Origin gFrontEnd )
				)
				( attribute "XY" "(-7975,6100)"
					( Origin gFrontEnd )
				)
				( attribute "CHIPS_PART_NAME" "TPAD-DIFF-4P-GP"
					( Origin gPackager )
				)
				( attribute "CDS_PART_NAME" "TPAD-DIFF-4P-GP_DISCRET-GB3-TPA"
					( Origin gPackager )
				)
				( attribute "CDS_LOCATION" "T1P1"
					( Origin gPackager )
				)
				( attribute "CDS_SEC" "1"
					( Origin gPackager )
				)
				( objectStatus "T1P1" )
			)
			( gate "@baseboard_fab2_lib.baseboard_fab2(sch_1):page270_i17"
				( attribute "CDS_LIB" "w_hdl"
					( Origin gPackager )
				)
				( attribute "CDS_LMAN_SYM_OUTLINE" "-75,375,75,-375"
					( Origin gPackager )
				)
				( attribute "LOCATION" "T1D10"
					( Origin gFrontEnd )
				)
				( attribute "PACK_TYPE" "DISCRET-GB1"
					( Origin gFrontEnd )
				)
				( attribute "PART_NUMBER" "ZZ.00PAD.MJ1"
					( Origin gFrontEnd )
				)
				( attribute "PHYS_PAGE" "257"
					( Origin gFrontEnd )
				)
				( attribute "ROT" "2"
					( Origin gFrontEnd )
				)
				( attribute "SEC" "1"
					( Origin gFrontEnd )
				)
				( attribute "SEC_TYPE" "DISCRET-GB1"
					( Origin gFrontEnd )
				)
				( attribute "VALUE" "TEST-PAD-12P-1-GP-U"
					( Origin gFrontEnd )
				)
				( attribute "VER" "1"
					( Origin gFrontEnd )
				)
				( attribute "XY" "(-4775,5050)"
					( Origin gFrontEnd )
				)
				( attribute "CHIPS_PART_NAME" "TEST-PAD-12P-1-GP-U"
					( Origin gPackager )
				)
				( attribute "CDS_PART_NAME" "TEST-PAD-12P-1-GP-U_DISCRET-GBA"
					( Origin gPackager )
				)
				( attribute "CDS_LOCATION" "T1D10"
					( Origin gPackager )
				)
				( attribute "CDS_SEC" "1"
					( Origin gPackager )
				)
				( objectStatus "T1D10" )
			)
			( gate "@baseboard_fab2_lib.baseboard_fab2(sch_1):page270_i1"
				( attribute "CDS_LIB" "w_hdl"
					( Origin gPackager )
				)
				( attribute "CDS_LMAN_SYM_OUTLINE" "-75,375,75,-375"
					( Origin gPackager )
				)
				( attribute "LOCATION" "T1D1"
					( Origin gFrontEnd )
				)
				( attribute "PACK_TYPE" "DISCRET-GB1"
					( Origin gFrontEnd )
				)
				( attribute "PART_NUMBER" "ZZ.00PAD.MJ1"
					( Origin gFrontEnd )
				)
				( attribute "PHYS_PAGE" "257"
					( Origin gFrontEnd )
				)
				( attribute "ROT" "0"
					( Origin gFrontEnd )
				)
				( attribute "SEC" "1"
					( Origin gFrontEnd )
				)
				( attribute "SEC_TYPE" "DISCRET-GB1"
					( Origin gFrontEnd )
				)
				( attribute "VALUE" "TEST-PAD-12P-1-GP-U"
					( Origin gFrontEnd )
				)
				( attribute "VER" "1"
					( Origin gFrontEnd )
				)
				( attribute "XY" "(-8825,5975)"
					( Origin gFrontEnd )
				)
				( attribute "CHIPS_PART_NAME" "TEST-PAD-12P-1-GP-U"
					( Origin gPackager )
				)
				( attribute "CDS_PART_NAME" "TEST-PAD-12P-1-GP-U_DISCRET-GBA"
					( Origin gPackager )
				)
				( attribute "CDS_LOCATION" "T1D1"
					( Origin gPackager )
				)
				( attribute "CDS_SEC" "1"
					( Origin gPackager )
				)
				( objectStatus "T1D1" )
			)
			( gate "@baseboard_fab2_lib.baseboard_fab2(sch_1):page270_i3"
				( attribute "CDS_LIB" "w_hdl"
					( Origin gPackager )
				)
				( attribute "CDS_LMAN_SYM_OUTLINE" "-75,375,75,-375"
					( Origin gPackager )
				)
				( attribute "LOCATION" "T1D2"
					( Origin gFrontEnd )
				)
				( attribute "PACK_TYPE" "DISCRET-GB1"
					( Origin gFrontEnd )
				)
				( attribute "PART_NUMBER" "ZZ.00PAD.MJ1"
					( Origin gFrontEnd )
				)
				( attribute "PHYS_PAGE" "257"
					( Origin gFrontEnd )
				)
				( attribute "ROT" "2"
					( Origin gFrontEnd )
				)
				( attribute "SEC" "1"
					( Origin gFrontEnd )
				)
				( attribute "SEC_TYPE" "DISCRET-GB1"
					( Origin gFrontEnd )
				)
				( attribute "VALUE" "TEST-PAD-12P-1-GP-U"
					( Origin gFrontEnd )
				)
				( attribute "VER" "1"
					( Origin gFrontEnd )
				)
				( attribute "XY" "(-7225,5975)"
					( Origin gFrontEnd )
				)
				( attribute "CHIPS_PART_NAME" "TEST-PAD-12P-1-GP-U"
					( Origin gPackager )
				)
				( attribute "CDS_PART_NAME" "TEST-PAD-12P-1-GP-U_DISCRET-GBA"
					( Origin gPackager )
				)
				( attribute "CDS_LOCATION" "T1D2"
					( Origin gPackager )
				)
				( attribute "CDS_SEC" "1"
					( Origin gPackager )
				)
				( objectStatus "T1D2" )
			)
			( gate "@baseboard_fab2_lib.baseboard_fab2(sch_1):page270_i5"
				( attribute "CDS_LIB" "w_hdl"
					( Origin gPackager )
				)
				( attribute "CDS_LMAN_SYM_OUTLINE" "-75,375,75,-375"
					( Origin gPackager )
				)
				( attribute "LOCATION" "T1D3"
					( Origin gFrontEnd )
				)
				( attribute "PACK_TYPE" "DISCRET-GB1"
					( Origin gFrontEnd )
				)
				( attribute "PART_NUMBER" "ZZ.00PAD.MJ1"
					( Origin gFrontEnd )
				)
				( attribute "PHYS_PAGE" "257"
					( Origin gFrontEnd )
				)
				( attribute "ROT" "0"
					( Origin gFrontEnd )
				)
				( attribute "SEC" "1"
					( Origin gFrontEnd )
				)
				( attribute "SEC_TYPE" "DISCRET-GB1"
					( Origin gFrontEnd )
				)
				( attribute "VALUE" "TEST-PAD-12P-1-GP-U"
					( Origin gFrontEnd )
				)
				( attribute "VER" "1"
					( Origin gFrontEnd )
				)
				( attribute "XY" "(-8825,5025)"
					( Origin gFrontEnd )
				)
				( attribute "CHIPS_PART_NAME" "TEST-PAD-12P-1-GP-U"
					( Origin gPackager )
				)
				( attribute "CDS_PART_NAME" "TEST-PAD-12P-1-GP-U_DISCRET-GBA"
					( Origin gPackager )
				)
				( attribute "CDS_LOCATION" "T1D3"
					( Origin gPackager )
				)
				( attribute "CDS_SEC" "1"
					( Origin gPackager )
				)
				( objectStatus "T1D3" )
			)
			( gate "@baseboard_fab2_lib.baseboard_fab2(sch_1):page270_i6"
				( attribute "CDS_LIB" "w_hdl"
					( Origin gPackager )
				)
				( attribute "CDS_LMAN_SYM_OUTLINE" "-75,375,75,-375"
					( Origin gPackager )
				)
				( attribute "LOCATION" "T1D4"
					( Origin gFrontEnd )
				)
				( attribute "PACK_TYPE" "DISCRET-GB1"
					( Origin gFrontEnd )
				)
				( attribute "PART_NUMBER" "ZZ.00PAD.MJ1"
					( Origin gFrontEnd )
				)
				( attribute "PHYS_PAGE" "257"
					( Origin gFrontEnd )
				)
				( attribute "ROT" "2"
					( Origin gFrontEnd )
				)
				( attribute "SEC" "1"
					( Origin gFrontEnd )
				)
				( attribute "SEC_TYPE" "DISCRET-GB1"
					( Origin gFrontEnd )
				)
				( attribute "VALUE" "TEST-PAD-12P-1-GP-U"
					( Origin gFrontEnd )
				)
				( attribute "VER" "1"
					( Origin gFrontEnd )
				)
				( attribute "XY" "(-7225,5025)"
					( Origin gFrontEnd )
				)
				( attribute "CHIPS_PART_NAME" "TEST-PAD-12P-1-GP-U"
					( Origin gPackager )
				)
				( attribute "CDS_PART_NAME" "TEST-PAD-12P-1-GP-U_DISCRET-GBA"
					( Origin gPackager )
				)
				( attribute "CDS_LOCATION" "T1D4"
					( Origin gPackager )
				)
				( attribute "CDS_SEC" "1"
					( Origin gPackager )
				)
				( objectStatus "T1D4" )
			)
			( gate "@baseboard_fab2_lib.baseboard_fab2(sch_1):page270_i9"
				( attribute "CDS_LIB" "w_hdl"
					( Origin gPackager )
				)
				( attribute "CDS_LMAN_SYM_OUTLINE" "-75,375,75,-375"
					( Origin gPackager )
				)
				( attribute "LOCATION" "T1D6"
					( Origin gFrontEnd )
				)
				( attribute "PACK_TYPE" "DISCRET-GB1"
					( Origin gFrontEnd )
				)
				( attribute "PART_NUMBER" "ZZ.00PAD.MJ1"
					( Origin gFrontEnd )
				)
				( attribute "PHYS_PAGE" "257"
					( Origin gFrontEnd )
				)
				( attribute "ROT" "2"
					( Origin gFrontEnd )
				)
				( attribute "SEC" "1"
					( Origin gFrontEnd )
				)
				( attribute "SEC_TYPE" "DISCRET-GB1"
					( Origin gFrontEnd )
				)
				( attribute "VALUE" "TEST-PAD-12P-1-GP-U"
					( Origin gFrontEnd )
				)
				( attribute "VER" "1"
					( Origin gFrontEnd )
				)
				( attribute "XY" "(-7225,4075)"
					( Origin gFrontEnd )
				)
				( attribute "CHIPS_PART_NAME" "TEST-PAD-12P-1-GP-U"
					( Origin gPackager )
				)
				( attribute "CDS_PART_NAME" "TEST-PAD-12P-1-GP-U_DISCRET-GBA"
					( Origin gPackager )
				)
				( attribute "CDS_LOCATION" "T1D6"
					( Origin gPackager )
				)
				( attribute "CDS_SEC" "1"
					( Origin gPackager )
				)
				( objectStatus "T1D6" )
			)
			( gate "@baseboard_fab2_lib.baseboard_fab2(sch_1):page270_i12"
				( attribute "CDS_LIB" "w_hdl"
					( Origin gPackager )
				)
				( attribute "CDS_LMAN_SYM_OUTLINE" "-75,375,75,-375"
					( Origin gPackager )
				)
				( attribute "LOCATION" "T1D5"
					( Origin gFrontEnd )
				)
				( attribute "PACK_TYPE" "DISCRET-GB1"
					( Origin gFrontEnd )
				)
				( attribute "PART_NUMBER" "ZZ.00PAD.MJ1"
					( Origin gFrontEnd )
				)
				( attribute "PHYS_PAGE" "257"
					( Origin gFrontEnd )
				)
				( attribute "ROT" "0"
					( Origin gFrontEnd )
				)
				( attribute "SEC" "1"
					( Origin gFrontEnd )
				)
				( attribute "SEC_TYPE" "DISCRET-GB1"
					( Origin gFrontEnd )
				)
				( attribute "VALUE" "TEST-PAD-12P-1-GP-U"
					( Origin gFrontEnd )
				)
				( attribute "VER" "1"
					( Origin gFrontEnd )
				)
				( attribute "XY" "(-8825,4075)"
					( Origin gFrontEnd )
				)
				( attribute "CHIPS_PART_NAME" "TEST-PAD-12P-1-GP-U"
					( Origin gPackager )
				)
				( attribute "CDS_PART_NAME" "TEST-PAD-12P-1-GP-U_DISCRET-GBA"
					( Origin gPackager )
				)
				( attribute "CDS_LOCATION" "T1D5"
					( Origin gPackager )
				)
				( attribute "CDS_SEC" "1"
					( Origin gPackager )
				)
				( objectStatus "T1D5" )
			)
			( gate "@baseboard_fab2_lib.baseboard_fab2(sch_1):page270_i13"
				( attribute "CDS_LIB" "w_hdl"
					( Origin gPackager )
				)
				( attribute "CDS_LMAN_SYM_OUTLINE" "-75,375,75,-375"
					( Origin gPackager )
				)
				( attribute "LOCATION" "T1D8"
					( Origin gFrontEnd )
				)
				( attribute "PACK_TYPE" "DISCRET-GB1"
					( Origin gFrontEnd )
				)
				( attribute "PART_NUMBER" "ZZ.00PAD.MJ1"
					( Origin gFrontEnd )
				)
				( attribute "PHYS_PAGE" "257"
					( Origin gFrontEnd )
				)
				( attribute "ROT" "2"
					( Origin gFrontEnd )
				)
				( attribute "SEC" "1"
					( Origin gFrontEnd )
				)
				( attribute "SEC_TYPE" "DISCRET-GB1"
					( Origin gFrontEnd )
				)
				( attribute "VALUE" "TEST-PAD-12P-1-GP-U"
					( Origin gFrontEnd )
				)
				( attribute "VER" "1"
					( Origin gFrontEnd )
				)
				( attribute "XY" "(-4775,6000)"
					( Origin gFrontEnd )
				)
				( attribute "CHIPS_PART_NAME" "TEST-PAD-12P-1-GP-U"
					( Origin gPackager )
				)
				( attribute "CDS_PART_NAME" "TEST-PAD-12P-1-GP-U_DISCRET-GBA"
					( Origin gPackager )
				)
				( attribute "CDS_LOCATION" "T1D8"
					( Origin gPackager )
				)
				( attribute "CDS_SEC" "1"
					( Origin gPackager )
				)
				( objectStatus "T1D8" )
			)
			( gate "@baseboard_fab2_lib.baseboard_fab2(sch_1):page270_i16"
				( attribute "CDS_LIB" "w_hdl"
					( Origin gPackager )
				)
				( attribute "CDS_LMAN_SYM_OUTLINE" "-75,375,75,-375"
					( Origin gPackager )
				)
				( attribute "LOCATION" "T1D7"
					( Origin gFrontEnd )
				)
				( attribute "PACK_TYPE" "DISCRET-GB1"
					( Origin gFrontEnd )
				)
				( attribute "PART_NUMBER" "ZZ.00PAD.MJ1"
					( Origin gFrontEnd )
				)
				( attribute "PHYS_PAGE" "257"
					( Origin gFrontEnd )
				)
				( attribute "ROT" "0"
					( Origin gFrontEnd )
				)
				( attribute "SEC" "1"
					( Origin gFrontEnd )
				)
				( attribute "SEC_TYPE" "DISCRET-GB1"
					( Origin gFrontEnd )
				)
				( attribute "VALUE" "TEST-PAD-12P-1-GP-U"
					( Origin gFrontEnd )
				)
				( attribute "VER" "1"
					( Origin gFrontEnd )
				)
				( attribute "XY" "(-6375,6000)"
					( Origin gFrontEnd )
				)
				( attribute "CHIPS_PART_NAME" "TEST-PAD-12P-1-GP-U"
					( Origin gPackager )
				)
				( attribute "CDS_PART_NAME" "TEST-PAD-12P-1-GP-U_DISCRET-GBA"
					( Origin gPackager )
				)
				( attribute "CDS_LOCATION" "T1D7"
					( Origin gPackager )
				)
				( attribute "CDS_SEC" "1"
					( Origin gPackager )
				)
				( objectStatus "T1D7" )
			)
			( gate "@baseboard_fab2_lib.baseboard_fab2(sch_1):page270_i18"
				( attribute "CDS_LIB" "w_hdl"
					( Origin gPackager )
				)
				( attribute "CDS_LMAN_SYM_OUTLINE" "-75,375,75,-375"
					( Origin gPackager )
				)
				( attribute "LOCATION" "T1D9"
					( Origin gFrontEnd )
				)
				( attribute "PACK_TYPE" "DISCRET-GB1"
					( Origin gFrontEnd )
				)
				( attribute "PART_NUMBER" "ZZ.00PAD.MJ1"
					( Origin gFrontEnd )
				)
				( attribute "PHYS_PAGE" "257"
					( Origin gFrontEnd )
				)
				( attribute "ROT" "0"
					( Origin gFrontEnd )
				)
				( attribute "SEC" "1"
					( Origin gFrontEnd )
				)
				( attribute "SEC_TYPE" "DISCRET-GB1"
					( Origin gFrontEnd )
				)
				( attribute "VALUE" "TEST-PAD-12P-1-GP-U"
					( Origin gFrontEnd )
				)
				( attribute "VER" "1"
					( Origin gFrontEnd )
				)
				( attribute "XY" "(-6375,5050)"
					( Origin gFrontEnd )
				)
				( attribute "CHIPS_PART_NAME" "TEST-PAD-12P-1-GP-U"
					( Origin gPackager )
				)
				( attribute "CDS_PART_NAME" "TEST-PAD-12P-1-GP-U_DISCRET-GBA"
					( Origin gPackager )
				)
				( attribute "CDS_LOCATION" "T1D9"
					( Origin gPackager )
				)
				( attribute "CDS_SEC" "1"
					( Origin gPackager )
				)
				( objectStatus "T1D9" )
			)
			( gate "@baseboard_fab2_lib.baseboard_fab2(sch_1):page270_i21"
				( attribute "CDS_LIB" "w_hdl"
					( Origin gPackager )
				)
				( attribute "CDS_LMAN_SYM_OUTLINE" "-75,375,75,-375"
					( Origin gPackager )
				)
				( attribute "LOCATION" "T1D12"
					( Origin gFrontEnd )
				)
				( attribute "PACK_TYPE" "DISCRET-GB1"
					( Origin gFrontEnd )
				)
				( attribute "PART_NUMBER" "ZZ.00PAD.MJ1"
					( Origin gFrontEnd )
				)
				( attribute "PHYS_PAGE" "257"
					( Origin gFrontEnd )
				)
				( attribute "ROT" "2"
					( Origin gFrontEnd )
				)
				( attribute "SEC" "1"
					( Origin gFrontEnd )
				)
				( attribute "SEC_TYPE" "DISCRET-GB1"
					( Origin gFrontEnd )
				)
				( attribute "VALUE" "TEST-PAD-12P-1-GP-U"
					( Origin gFrontEnd )
				)
				( attribute "VER" "1"
					( Origin gFrontEnd )
				)
				( attribute "XY" "(-4775,4100)"
					( Origin gFrontEnd )
				)
				( attribute "CHIPS_PART_NAME" "TEST-PAD-12P-1-GP-U"
					( Origin gPackager )
				)
				( attribute "CDS_PART_NAME" "TEST-PAD-12P-1-GP-U_DISCRET-GBA"
					( Origin gPackager )
				)
				( attribute "CDS_LOCATION" "T1D12"
					( Origin gPackager )
				)
				( attribute "CDS_SEC" "1"
					( Origin gPackager )
				)
				( objectStatus "T1D12" )
			)
			( gate "@baseboard_fab2_lib.baseboard_fab2(sch_1):page270_i24"
				( attribute "CDS_LIB" "w_hdl"
					( Origin gPackager )
				)
				( attribute "CDS_LMAN_SYM_OUTLINE" "-75,375,75,-375"
					( Origin gPackager )
				)
				( attribute "LOCATION" "T1D11"
					( Origin gFrontEnd )
				)
				( attribute "PACK_TYPE" "DISCRET-GB1"
					( Origin gFrontEnd )
				)
				( attribute "PART_NUMBER" "ZZ.00PAD.MJ1"
					( Origin gFrontEnd )
				)
				( attribute "PHYS_PAGE" "257"
					( Origin gFrontEnd )
				)
				( attribute "ROT" "0"
					( Origin gFrontEnd )
				)
				( attribute "SEC" "1"
					( Origin gFrontEnd )
				)
				( attribute "SEC_TYPE" "DISCRET-GB1"
					( Origin gFrontEnd )
				)
				( attribute "VALUE" "TEST-PAD-12P-1-GP-U"
					( Origin gFrontEnd )
				)
				( attribute "VER" "1"
					( Origin gFrontEnd )
				)
				( attribute "XY" "(-6375,4100)"
					( Origin gFrontEnd )
				)
				( attribute "CHIPS_PART_NAME" "TEST-PAD-12P-1-GP-U"
					( Origin gPackager )
				)
				( attribute "CDS_PART_NAME" "TEST-PAD-12P-1-GP-U_DISCRET-GBA"
					( Origin gPackager )
				)
				( attribute "CDS_LOCATION" "T1D11"
					( Origin gPackager )
				)
				( attribute "CDS_SEC" "1"
					( Origin gPackager )
				)
				( objectStatus "T1D11" )
			)
			( gate "@baseboard_fab2_lib.baseboard_fab2(sch_1):page272_i1"
				( attribute "CDS_LIB" "w_hdl"
					( Origin gPackager )
				)
				( attribute "CDS_LMAN_SYM_OUTLINE" "-75,375,75,-375"
					( Origin gPackager )
				)
				( attribute "LOCATION" "T1D17"
					( Origin gFrontEnd )
				)
				( attribute "PACK_TYPE" "DISCRET-GB1"
					( Origin gFrontEnd )
				)
				( attribute "PART_NUMBER" "ZZ.00PAD.MJ1"
					( Origin gFrontEnd )
				)
				( attribute "PHYS_PAGE" "258"
					( Origin gFrontEnd )
				)
				( attribute "ROT" "0"
					( Origin gFrontEnd )
				)
				( attribute "SEC" "1"
					( Origin gFrontEnd )
				)
				( attribute "SEC_TYPE" "DISCRET-GB1"
					( Origin gFrontEnd )
				)
				( attribute "VALUE" "TEST-PAD-12P-1-GP-U"
					( Origin gFrontEnd )
				)
				( attribute "VER" "1"
					( Origin gFrontEnd )
				)
				( attribute "XY" "(-7600,3425)"
					( Origin gFrontEnd )
				)
				( attribute "CHIPS_PART_NAME" "TEST-PAD-12P-1-GP-U"
					( Origin gPackager )
				)
				( attribute "CDS_PART_NAME" "TEST-PAD-12P-1-GP-U_DISCRET-GBA"
					( Origin gPackager )
				)
				( attribute "CDS_LOCATION" "T1D17"
					( Origin gPackager )
				)
				( attribute "CDS_SEC" "1"
					( Origin gPackager )
				)
				( objectStatus "T1D17" )
			)
			( gate "@baseboard_fab2_lib.baseboard_fab2(sch_1):page272_i3"
				( attribute "CDS_LIB" "w_hdl"
					( Origin gPackager )
				)
				( attribute "CDS_LMAN_SYM_OUTLINE" "-75,375,75,-375"
					( Origin gPackager )
				)
				( attribute "LOCATION" "T1D15"
					( Origin gFrontEnd )
				)
				( attribute "PACK_TYPE" "DISCRET-GB1"
					( Origin gFrontEnd )
				)
				( attribute "PART_NUMBER" "ZZ.00PAD.MJ1"
					( Origin gFrontEnd )
				)
				( attribute "PHYS_PAGE" "258"
					( Origin gFrontEnd )
				)
				( attribute "ROT" "0"
					( Origin gFrontEnd )
				)
				( attribute "SEC" "1"
					( Origin gFrontEnd )
				)
				( attribute "SEC_TYPE" "DISCRET-GB1"
					( Origin gFrontEnd )
				)
				( attribute "VALUE" "TEST-PAD-12P-1-GP-U"
					( Origin gFrontEnd )
				)
				( attribute "VER" "1"
					( Origin gFrontEnd )
				)
				( attribute "XY" "(-7600,4375)"
					( Origin gFrontEnd )
				)
				( attribute "CHIPS_PART_NAME" "TEST-PAD-12P-1-GP-U"
					( Origin gPackager )
				)
				( attribute "CDS_PART_NAME" "TEST-PAD-12P-1-GP-U_DISCRET-GBA"
					( Origin gPackager )
				)
				( attribute "CDS_LOCATION" "T1D15"
					( Origin gPackager )
				)
				( attribute "CDS_SEC" "1"
					( Origin gPackager )
				)
				( objectStatus "T1D15" )
			)
			( gate "@baseboard_fab2_lib.baseboard_fab2(sch_1):page272_i5"
				( attribute "CDS_LIB" "w_hdl"
					( Origin gPackager )
				)
				( attribute "CDS_LMAN_SYM_OUTLINE" "-75,375,75,-375"
					( Origin gPackager )
				)
				( attribute "LOCATION" "T1D13"
					( Origin gFrontEnd )
				)
				( attribute "PACK_TYPE" "DISCRET-GB1"
					( Origin gFrontEnd )
				)
				( attribute "PART_NUMBER" "ZZ.00PAD.MJ1"
					( Origin gFrontEnd )
				)
				( attribute "PHYS_PAGE" "258"
					( Origin gFrontEnd )
				)
				( attribute "ROT" "0"
					( Origin gFrontEnd )
				)
				( attribute "SEC" "1"
					( Origin gFrontEnd )
				)
				( attribute "SEC_TYPE" "DISCRET-GB1"
					( Origin gFrontEnd )
				)
				( attribute "VALUE" "TEST-PAD-12P-1-GP-U"
					( Origin gFrontEnd )
				)
				( attribute "VER" "1"
					( Origin gFrontEnd )
				)
				( attribute "XY" "(-7600,5325)"
					( Origin gFrontEnd )
				)
				( attribute "CHIPS_PART_NAME" "TEST-PAD-12P-1-GP-U"
					( Origin gPackager )
				)
				( attribute "CDS_PART_NAME" "TEST-PAD-12P-1-GP-U_DISCRET-GBA"
					( Origin gPackager )
				)
				( attribute "CDS_LOCATION" "T1D13"
					( Origin gPackager )
				)
				( attribute "CDS_SEC" "1"
					( Origin gPackager )
				)
				( objectStatus "T1D13" )
			)
			( gate "@baseboard_fab2_lib.baseboard_fab2(sch_1):page272_i8"
				( attribute "CDS_LIB" "w_hdl"
					( Origin gPackager )
				)
				( attribute "CDS_LMAN_SYM_OUTLINE" "-75,375,75,-375"
					( Origin gPackager )
				)
				( attribute "LOCATION" "T1D18"
					( Origin gFrontEnd )
				)
				( attribute "PACK_TYPE" "DISCRET-GB1"
					( Origin gFrontEnd )
				)
				( attribute "PART_NUMBER" "ZZ.00PAD.MJ1"
					( Origin gFrontEnd )
				)
				( attribute "PHYS_PAGE" "258"
					( Origin gFrontEnd )
				)
				( attribute "ROT" "2"
					( Origin gFrontEnd )
				)
				( attribute "SEC" "1"
					( Origin gFrontEnd )
				)
				( attribute "SEC_TYPE" "DISCRET-GB1"
					( Origin gFrontEnd )
				)
				( attribute "VALUE" "TEST-PAD-12P-1-GP-U"
					( Origin gFrontEnd )
				)
				( attribute "VER" "1"
					( Origin gFrontEnd )
				)
				( attribute "XY" "(-6000,3425)"
					( Origin gFrontEnd )
				)
				( attribute "CHIPS_PART_NAME" "TEST-PAD-12P-1-GP-U"
					( Origin gPackager )
				)
				( attribute "CDS_PART_NAME" "TEST-PAD-12P-1-GP-U_DISCRET-GBA"
					( Origin gPackager )
				)
				( attribute "CDS_LOCATION" "T1D18"
					( Origin gPackager )
				)
				( attribute "CDS_SEC" "1"
					( Origin gPackager )
				)
				( objectStatus "T1D18" )
			)
			( gate "@baseboard_fab2_lib.baseboard_fab2(sch_1):page272_i9"
				( attribute "CDS_LIB" "w_hdl"
					( Origin gPackager )
				)
				( attribute "CDS_LMAN_SYM_OUTLINE" "-75,375,75,-375"
					( Origin gPackager )
				)
				( attribute "LOCATION" "T1D23"
					( Origin gFrontEnd )
				)
				( attribute "PACK_TYPE" "DISCRET-GB1"
					( Origin gFrontEnd )
				)
				( attribute "PART_NUMBER" "ZZ.00PAD.MJ1"
					( Origin gFrontEnd )
				)
				( attribute "PHYS_PAGE" "258"
					( Origin gFrontEnd )
				)
				( attribute "ROT" "0"
					( Origin gFrontEnd )
				)
				( attribute "SEC" "1"
					( Origin gFrontEnd )
				)
				( attribute "SEC_TYPE" "DISCRET-GB1"
					( Origin gFrontEnd )
				)
				( attribute "VALUE" "TEST-PAD-12P-1-GP-U"
					( Origin gFrontEnd )
				)
				( attribute "VER" "1"
					( Origin gFrontEnd )
				)
				( attribute "XY" "(-5150,3450)"
					( Origin gFrontEnd )
				)
				( attribute "CHIPS_PART_NAME" "TEST-PAD-12P-1-GP-U"
					( Origin gPackager )
				)
				( attribute "CDS_PART_NAME" "TEST-PAD-12P-1-GP-U_DISCRET-GBA"
					( Origin gPackager )
				)
				( attribute "CDS_LOCATION" "T1D23"
					( Origin gPackager )
				)
				( attribute "CDS_SEC" "1"
					( Origin gPackager )
				)
				( objectStatus "T1D23" )
			)
			( gate "@baseboard_fab2_lib.baseboard_fab2(sch_1):page272_i12"
				( attribute "CDS_LIB" "w_hdl"
					( Origin gPackager )
				)
				( attribute "CDS_LMAN_SYM_OUTLINE" "-75,375,75,-375"
					( Origin gPackager )
				)
				( attribute "LOCATION" "T1D24"
					( Origin gFrontEnd )
				)
				( attribute "PACK_TYPE" "DISCRET-GB1"
					( Origin gFrontEnd )
				)
				( attribute "PART_NUMBER" "ZZ.00PAD.MJ1"
					( Origin gFrontEnd )
				)
				( attribute "PHYS_PAGE" "258"
					( Origin gFrontEnd )
				)
				( attribute "ROT" "2"
					( Origin gFrontEnd )
				)
				( attribute "SEC" "1"
					( Origin gFrontEnd )
				)
				( attribute "SEC_TYPE" "DISCRET-GB1"
					( Origin gFrontEnd )
				)
				( attribute "VALUE" "TEST-PAD-12P-1-GP-U"
					( Origin gFrontEnd )
				)
				( attribute "VER" "1"
					( Origin gFrontEnd )
				)
				( attribute "XY" "(-3550,3450)"
					( Origin gFrontEnd )
				)
				( attribute "CHIPS_PART_NAME" "TEST-PAD-12P-1-GP-U"
					( Origin gPackager )
				)
				( attribute "CDS_PART_NAME" "TEST-PAD-12P-1-GP-U_DISCRET-GBA"
					( Origin gPackager )
				)
				( attribute "CDS_LOCATION" "T1D24"
					( Origin gPackager )
				)
				( attribute "CDS_SEC" "1"
					( Origin gPackager )
				)
				( objectStatus "T1D24" )
			)
			( gate "@baseboard_fab2_lib.baseboard_fab2(sch_1):page272_i14"
				( attribute "CDS_LIB" "w_hdl"
					( Origin gPackager )
				)
				( attribute "CDS_LMAN_SYM_OUTLINE" "-75,375,75,-375"
					( Origin gPackager )
				)
				( attribute "LOCATION" "T1D16"
					( Origin gFrontEnd )
				)
				( attribute "PACK_TYPE" "DISCRET-GB1"
					( Origin gFrontEnd )
				)
				( attribute "PART_NUMBER" "ZZ.00PAD.MJ1"
					( Origin gFrontEnd )
				)
				( attribute "PHYS_PAGE" "258"
					( Origin gFrontEnd )
				)
				( attribute "ROT" "2"
					( Origin gFrontEnd )
				)
				( attribute "SEC" "1"
					( Origin gFrontEnd )
				)
				( attribute "SEC_TYPE" "DISCRET-GB1"
					( Origin gFrontEnd )
				)
				( attribute "VALUE" "TEST-PAD-12P-1-GP-U"
					( Origin gFrontEnd )
				)
				( attribute "VER" "1"
					( Origin gFrontEnd )
				)
				( attribute "XY" "(-6000,4375)"
					( Origin gFrontEnd )
				)
				( attribute "CHIPS_PART_NAME" "TEST-PAD-12P-1-GP-U"
					( Origin gPackager )
				)
				( attribute "CDS_PART_NAME" "TEST-PAD-12P-1-GP-U_DISCRET-GBA"
					( Origin gPackager )
				)
				( attribute "CDS_LOCATION" "T1D16"
					( Origin gPackager )
				)
				( attribute "CDS_SEC" "1"
					( Origin gPackager )
				)
				( objectStatus "T1D16" )
			)
			( gate "@baseboard_fab2_lib.baseboard_fab2(sch_1):page272_i16"
				( attribute "CDS_LIB" "w_hdl"
					( Origin gPackager )
				)
				( attribute "CDS_LMAN_SYM_OUTLINE" "-75,375,75,-375"
					( Origin gPackager )
				)
				( attribute "LOCATION" "T1D21"
					( Origin gFrontEnd )
				)
				( attribute "PACK_TYPE" "DISCRET-GB1"
					( Origin gFrontEnd )
				)
				( attribute "PART_NUMBER" "ZZ.00PAD.MJ1"
					( Origin gFrontEnd )
				)
				( attribute "PHYS_PAGE" "258"
					( Origin gFrontEnd )
				)
				( attribute "ROT" "0"
					( Origin gFrontEnd )
				)
				( attribute "SEC" "1"
					( Origin gFrontEnd )
				)
				( attribute "SEC_TYPE" "DISCRET-GB1"
					( Origin gFrontEnd )
				)
				( attribute "VALUE" "TEST-PAD-12P-1-GP-U"
					( Origin gFrontEnd )
				)
				( attribute "VER" "1"
					( Origin gFrontEnd )
				)
				( attribute "XY" "(-5150,4400)"
					( Origin gFrontEnd )
				)
				( attribute "CHIPS_PART_NAME" "TEST-PAD-12P-1-GP-U"
					( Origin gPackager )
				)
				( attribute "CDS_PART_NAME" "TEST-PAD-12P-1-GP-U_DISCRET-GBA"
					( Origin gPackager )
				)
				( attribute "CDS_LOCATION" "T1D21"
					( Origin gPackager )
				)
				( attribute "CDS_SEC" "1"
					( Origin gPackager )
				)
				( objectStatus "T1D21" )
			)
			( gate "@baseboard_fab2_lib.baseboard_fab2(sch_1):page272_i21"
				( attribute "CDS_LIB" "w_hdl"
					( Origin gPackager )
				)
				( attribute "CDS_LMAN_SYM_OUTLINE" "-75,375,75,-375"
					( Origin gPackager )
				)
				( attribute "LOCATION" "T1D22"
					( Origin gFrontEnd )
				)
				( attribute "PACK_TYPE" "DISCRET-GB1"
					( Origin gFrontEnd )
				)
				( attribute "PART_NUMBER" "ZZ.00PAD.MJ1"
					( Origin gFrontEnd )
				)
				( attribute "PHYS_PAGE" "258"
					( Origin gFrontEnd )
				)
				( attribute "ROT" "2"
					( Origin gFrontEnd )
				)
				( attribute "SEC" "1"
					( Origin gFrontEnd )
				)
				( attribute "SEC_TYPE" "DISCRET-GB1"
					( Origin gFrontEnd )
				)
				( attribute "VALUE" "TEST-PAD-12P-1-GP-U"
					( Origin gFrontEnd )
				)
				( attribute "VER" "1"
					( Origin gFrontEnd )
				)
				( attribute "XY" "(-3550,4400)"
					( Origin gFrontEnd )
				)
				( attribute "CHIPS_PART_NAME" "TEST-PAD-12P-1-GP-U"
					( Origin gPackager )
				)
				( attribute "CDS_PART_NAME" "TEST-PAD-12P-1-GP-U_DISCRET-GBA"
					( Origin gPackager )
				)
				( attribute "CDS_LOCATION" "T1D22"
					( Origin gPackager )
				)
				( attribute "CDS_SEC" "1"
					( Origin gPackager )
				)
				( objectStatus "T1D22" )
			)
			( gate "@baseboard_fab2_lib.baseboard_fab2(sch_1):page272_i22"
				( attribute "CDS_LIB" "w_hdl"
					( Origin gPackager )
				)
				( attribute "CDS_LMAN_SYM_OUTLINE" "-75,375,75,-375"
					( Origin gPackager )
				)
				( attribute "LOCATION" "T1D14"
					( Origin gFrontEnd )
				)
				( attribute "PACK_TYPE" "DISCRET-GB1"
					( Origin gFrontEnd )
				)
				( attribute "PART_NUMBER" "ZZ.00PAD.MJ1"
					( Origin gFrontEnd )
				)
				( attribute "PHYS_PAGE" "258"
					( Origin gFrontEnd )
				)
				( attribute "ROT" "2"
					( Origin gFrontEnd )
				)
				( attribute "SEC" "1"
					( Origin gFrontEnd )
				)
				( attribute "SEC_TYPE" "DISCRET-GB1"
					( Origin gFrontEnd )
				)
				( attribute "VALUE" "TEST-PAD-12P-1-GP-U"
					( Origin gFrontEnd )
				)
				( attribute "VER" "1"
					( Origin gFrontEnd )
				)
				( attribute "XY" "(-6000,5325)"
					( Origin gFrontEnd )
				)
				( attribute "CHIPS_PART_NAME" "TEST-PAD-12P-1-GP-U"
					( Origin gPackager )
				)
				( attribute "CDS_PART_NAME" "TEST-PAD-12P-1-GP-U_DISCRET-GBA"
					( Origin gPackager )
				)
				( attribute "CDS_LOCATION" "T1D14"
					( Origin gPackager )
				)
				( attribute "CDS_SEC" "1"
					( Origin gPackager )
				)
				( objectStatus "T1D14" )
			)
			( gate "@baseboard_fab2_lib.baseboard_fab2(sch_1):page272_i23"
				( attribute "CDS_LIB" "w_hdl"
					( Origin gPackager )
				)
				( attribute "CDS_LMAN_SYM_OUTLINE" "-75,375,75,-375"
					( Origin gPackager )
				)
				( attribute "LOCATION" "T1D19"
					( Origin gFrontEnd )
				)
				( attribute "PACK_TYPE" "DISCRET-GB1"
					( Origin gFrontEnd )
				)
				( attribute "PART_NUMBER" "ZZ.00PAD.MJ1"
					( Origin gFrontEnd )
				)
				( attribute "PHYS_PAGE" "258"
					( Origin gFrontEnd )
				)
				( attribute "ROT" "0"
					( Origin gFrontEnd )
				)
				( attribute "SEC" "1"
					( Origin gFrontEnd )
				)
				( attribute "SEC_TYPE" "DISCRET-GB1"
					( Origin gFrontEnd )
				)
				( attribute "VALUE" "TEST-PAD-12P-1-GP-U"
					( Origin gFrontEnd )
				)
				( attribute "VER" "1"
					( Origin gFrontEnd )
				)
				( attribute "XY" "(-5150,5350)"
					( Origin gFrontEnd )
				)
				( attribute "CHIPS_PART_NAME" "TEST-PAD-12P-1-GP-U"
					( Origin gPackager )
				)
				( attribute "CDS_PART_NAME" "TEST-PAD-12P-1-GP-U_DISCRET-GBA"
					( Origin gPackager )
				)
				( attribute "CDS_LOCATION" "T1D19"
					( Origin gPackager )
				)
				( attribute "CDS_SEC" "1"
					( Origin gPackager )
				)
				( objectStatus "T1D19" )
			)
			( gate "@baseboard_fab2_lib.baseboard_fab2(sch_1):page272_i24"
				( attribute "CDS_LIB" "w_hdl"
					( Origin gPackager )
				)
				( attribute "CDS_LMAN_SYM_OUTLINE" "-75,375,75,-375"
					( Origin gPackager )
				)
				( attribute "LOCATION" "T1D20"
					( Origin gFrontEnd )
				)
				( attribute "PACK_TYPE" "DISCRET-GB1"
					( Origin gFrontEnd )
				)
				( attribute "PART_NUMBER" "ZZ.00PAD.MJ1"
					( Origin gFrontEnd )
				)
				( attribute "PHYS_PAGE" "258"
					( Origin gFrontEnd )
				)
				( attribute "ROT" "2"
					( Origin gFrontEnd )
				)
				( attribute "SEC" "1"
					( Origin gFrontEnd )
				)
				( attribute "SEC_TYPE" "DISCRET-GB1"
					( Origin gFrontEnd )
				)
				( attribute "VALUE" "TEST-PAD-12P-1-GP-U"
					( Origin gFrontEnd )
				)
				( attribute "VER" "1"
					( Origin gFrontEnd )
				)
				( attribute "XY" "(-3550,5350)"
					( Origin gFrontEnd )
				)
				( attribute "CHIPS_PART_NAME" "TEST-PAD-12P-1-GP-U"
					( Origin gPackager )
				)
				( attribute "CDS_PART_NAME" "TEST-PAD-12P-1-GP-U_DISCRET-GBA"
					( Origin gPackager )
				)
				( attribute "CDS_LOCATION" "T1D20"
					( Origin gPackager )
				)
				( attribute "CDS_SEC" "1"
					( Origin gPackager )
				)
				( objectStatus "T1D20" )
			)
			( gate "@baseboard_fab2_lib.baseboard_fab2(sch_1):page271_i5"
				( attribute "CDS_LIB" "w_hdl"
					( Origin gPackager )
				)
				( attribute "CDS_LMAN_SYM_OUTLINE" "-75,100,75,-100"
					( Origin gPackager )
				)
				( attribute "LOCATION" "T1P2"
					( Origin gFrontEnd )
				)
				( attribute "PACK_TYPE" "DISCRET-GB3"
					( Origin gFrontEnd )
				)
				( attribute "PART_NUMBER" "ZZ.00PAD.NW1"
					( Origin gFrontEnd )
				)
				( attribute "PHYS_PAGE" "256"
					( Origin gFrontEnd )
				)
				( attribute "ROT" "0"
					( Origin gFrontEnd )
				)
				( attribute "SEC" "1"
					( Origin gFrontEnd )
				)
				( attribute "SEC_TYPE" "DISCRET-GB3"
					( Origin gFrontEnd )
				)
				( attribute "VALUE" "TPAD-DIFF-4P-GP"
					( Origin gFrontEnd )
				)
				( attribute "VER" "1"
					( Origin gFrontEnd )
				)
				( attribute "XY" "(-7975,5700)"
					( Origin gFrontEnd )
				)
				( attribute "CHIPS_PART_NAME" "TPAD-DIFF-4P-GP"
					( Origin gPackager )
				)
				( attribute "CDS_PART_NAME" "TPAD-DIFF-4P-GP_DISCRET-GB3-TPA"
					( Origin gPackager )
				)
				( attribute "CDS_LOCATION" "T1P2"
					( Origin gPackager )
				)
				( attribute "CDS_SEC" "1"
					( Origin gPackager )
				)
				( objectStatus "T1P2" )
			)
			( gate "@baseboard_fab2_lib.baseboard_fab2(sch_1):page271_i7"
				( attribute "CDS_LIB" "w_hdl"
					( Origin gPackager )
				)
				( attribute "CDS_LMAN_SYM_OUTLINE" "-75,100,75,-100"
					( Origin gPackager )
				)
				( attribute "LOCATION" "T1P4"
					( Origin gFrontEnd )
				)
				( attribute "PACK_TYPE" "DISCRET-GB3"
					( Origin gFrontEnd )
				)
				( attribute "PART_NUMBER" "ZZ.00PAD.NW1"
					( Origin gFrontEnd )
				)
				( attribute "PHYS_PAGE" "256"
					( Origin gFrontEnd )
				)
				( attribute "ROT" "0"
					( Origin gFrontEnd )
				)
				( attribute "SEC" "1"
					( Origin gFrontEnd )
				)
				( attribute "SEC_TYPE" "DISCRET-GB3"
					( Origin gFrontEnd )
				)
				( attribute "VALUE" "TPAD-DIFF-4P-GP"
					( Origin gFrontEnd )
				)
				( attribute "VER" "1"
					( Origin gFrontEnd )
				)
				( attribute "XY" "(-7975,4925)"
					( Origin gFrontEnd )
				)
				( attribute "CHIPS_PART_NAME" "TPAD-DIFF-4P-GP"
					( Origin gPackager )
				)
				( attribute "CDS_PART_NAME" "TPAD-DIFF-4P-GP_DISCRET-GB3-TPA"
					( Origin gPackager )
				)
				( attribute "CDS_LOCATION" "T1P4"
					( Origin gPackager )
				)
				( attribute "CDS_SEC" "1"
					( Origin gPackager )
				)
				( objectStatus "T1P4" )
			)
			( gate "@baseboard_fab2_lib.baseboard_fab2(sch_1):page271_i8"
				( attribute "CDS_LIB" "w_hdl"
					( Origin gPackager )
				)
				( attribute "CDS_LMAN_SYM_OUTLINE" "-75,100,75,-100"
					( Origin gPackager )
				)
				( attribute "LOCATION" "T1P3"
					( Origin gFrontEnd )
				)
				( attribute "PACK_TYPE" "DISCRET-GB3"
					( Origin gFrontEnd )
				)
				( attribute "PART_NUMBER" "ZZ.00PAD.NW1"
					( Origin gFrontEnd )
				)
				( attribute "PHYS_PAGE" "256"
					( Origin gFrontEnd )
				)
				( attribute "ROT" "0"
					( Origin gFrontEnd )
				)
				( attribute "SEC" "1"
					( Origin gFrontEnd )
				)
				( attribute "SEC_TYPE" "DISCRET-GB3"
					( Origin gFrontEnd )
				)
				( attribute "VALUE" "TPAD-DIFF-4P-GP"
					( Origin gFrontEnd )
				)
				( attribute "VER" "1"
					( Origin gFrontEnd )
				)
				( attribute "XY" "(-7975,5325)"
					( Origin gFrontEnd )
				)
				( attribute "CHIPS_PART_NAME" "TPAD-DIFF-4P-GP"
					( Origin gPackager )
				)
				( attribute "CDS_PART_NAME" "TPAD-DIFF-4P-GP_DISCRET-GB3-TPA"
					( Origin gPackager )
				)
				( attribute "CDS_LOCATION" "T1P3"
					( Origin gPackager )
				)
				( attribute "CDS_SEC" "1"
					( Origin gPackager )
				)
				( objectStatus "T1P3" )
			)
			( gate "@baseboard_fab2_lib.baseboard_fab2(sch_1):page271_i11"
				( attribute "CDS_LIB" "w_hdl"
					( Origin gPackager )
				)
				( attribute "CDS_LMAN_SYM_OUTLINE" "-75,100,75,-100"
					( Origin gPackager )
				)
				( attribute "LOCATION" "T1P5"
					( Origin gFrontEnd )
				)
				( attribute "PACK_TYPE" "DISCRET-GB3"
					( Origin gFrontEnd )
				)
				( attribute "PART_NUMBER" "ZZ.00PAD.NW1"
					( Origin gFrontEnd )
				)
				( attribute "PHYS_PAGE" "256"
					( Origin gFrontEnd )
				)
				( attribute "ROT" "0"
					( Origin gFrontEnd )
				)
				( attribute "SEC" "1"
					( Origin gFrontEnd )
				)
				( attribute "SEC_TYPE" "DISCRET-GB3"
					( Origin gFrontEnd )
				)
				( attribute "VALUE" "TPAD-DIFF-4P-GP"
					( Origin gFrontEnd )
				)
				( attribute "VER" "1"
					( Origin gFrontEnd )
				)
				( attribute "XY" "(-7950,4575)"
					( Origin gFrontEnd )
				)
				( attribute "CHIPS_PART_NAME" "TPAD-DIFF-4P-GP"
					( Origin gPackager )
				)
				( attribute "CDS_PART_NAME" "TPAD-DIFF-4P-GP_DISCRET-GB3-TPA"
					( Origin gPackager )
				)
				( attribute "CDS_LOCATION" "T1P5"
					( Origin gPackager )
				)
				( attribute "CDS_SEC" "1"
					( Origin gPackager )
				)
				( objectStatus "T1P5" )
			)
			( gate "@baseboard_fab2_lib.baseboard_fab2(sch_1):page271_i13"
				( attribute "CDS_LIB" "w_hdl"
					( Origin gPackager )
				)
				( attribute "CDS_LMAN_SYM_OUTLINE" "-75,100,75,-100"
					( Origin gPackager )
				)
				( attribute "LOCATION" "T1P6"
					( Origin gFrontEnd )
				)
				( attribute "PACK_TYPE" "DISCRET-GB3"
					( Origin gFrontEnd )
				)
				( attribute "PART_NUMBER" "ZZ.00PAD.NW1"
					( Origin gFrontEnd )
				)
				( attribute "PHYS_PAGE" "256"
					( Origin gFrontEnd )
				)
				( attribute "ROT" "0"
					( Origin gFrontEnd )
				)
				( attribute "SEC" "1"
					( Origin gFrontEnd )
				)
				( attribute "SEC_TYPE" "DISCRET-GB3"
					( Origin gFrontEnd )
				)
				( attribute "VALUE" "TPAD-DIFF-4P-GP"
					( Origin gFrontEnd )
				)
				( attribute "VER" "1"
					( Origin gFrontEnd )
				)
				( attribute "XY" "(-7950,4175)"
					( Origin gFrontEnd )
				)
				( attribute "CHIPS_PART_NAME" "TPAD-DIFF-4P-GP"
					( Origin gPackager )
				)
				( attribute "CDS_PART_NAME" "TPAD-DIFF-4P-GP_DISCRET-GB3-TPA"
					( Origin gPackager )
				)
				( attribute "CDS_LOCATION" "T1P6"
					( Origin gPackager )
				)
				( attribute "CDS_SEC" "1"
					( Origin gPackager )
				)
				( objectStatus "T1P6" )
			)
			( gate "@baseboard_fab2_lib.baseboard_fab2(sch_1):page271_i15"
				( attribute "CDS_LIB" "w_hdl"
					( Origin gPackager )
				)
				( attribute "CDS_LMAN_SYM_OUTLINE" "-75,100,75,-100"
					( Origin gPackager )
				)
				( attribute "LOCATION" "T1P10"
					( Origin gFrontEnd )
				)
				( attribute "PACK_TYPE" "DISCRET-GB3"
					( Origin gFrontEnd )
				)
				( attribute "PART_NUMBER" "ZZ.00PAD.NW1"
					( Origin gFrontEnd )
				)
				( attribute "PHYS_PAGE" "256"
					( Origin gFrontEnd )
				)
				( attribute "ROT" "0"
					( Origin gFrontEnd )
				)
				( attribute "SEC" "1"
					( Origin gFrontEnd )
				)
				( attribute "SEC_TYPE" "DISCRET-GB3"
					( Origin gFrontEnd )
				)
				( attribute "VALUE" "TPAD-DIFF-4P-GP"
					( Origin gFrontEnd )
				)
				( attribute "VER" "1"
					( Origin gFrontEnd )
				)
				( attribute "XY" "(-6000,4900)"
					( Origin gFrontEnd )
				)
				( attribute "CHIPS_PART_NAME" "TPAD-DIFF-4P-GP"
					( Origin gPackager )
				)
				( attribute "CDS_PART_NAME" "TPAD-DIFF-4P-GP_DISCRET-GB3-TPA"
					( Origin gPackager )
				)
				( attribute "CDS_LOCATION" "T1P10"
					( Origin gPackager )
				)
				( attribute "CDS_SEC" "1"
					( Origin gPackager )
				)
				( objectStatus "T1P10" )
			)
			( gate "@baseboard_fab2_lib.baseboard_fab2(sch_1):page271_i16"
				( attribute "CDS_LIB" "w_hdl"
					( Origin gPackager )
				)
				( attribute "CDS_LMAN_SYM_OUTLINE" "-75,100,75,-100"
					( Origin gPackager )
				)
				( attribute "LOCATION" "T1P8"
					( Origin gFrontEnd )
				)
				( attribute "PACK_TYPE" "DISCRET-GB3"
					( Origin gFrontEnd )
				)
				( attribute "PART_NUMBER" "ZZ.00PAD.NW1"
					( Origin gFrontEnd )
				)
				( attribute "PHYS_PAGE" "256"
					( Origin gFrontEnd )
				)
				( attribute "ROT" "0"
					( Origin gFrontEnd )
				)
				( attribute "SEC" "1"
					( Origin gFrontEnd )
				)
				( attribute "SEC_TYPE" "DISCRET-GB3"
					( Origin gFrontEnd )
				)
				( attribute "VALUE" "TPAD-DIFF-4P-GP"
					( Origin gFrontEnd )
				)
				( attribute "VER" "1"
					( Origin gFrontEnd )
				)
				( attribute "XY" "(-6000,5675)"
					( Origin gFrontEnd )
				)
				( attribute "CHIPS_PART_NAME" "TPAD-DIFF-4P-GP"
					( Origin gPackager )
				)
				( attribute "CDS_PART_NAME" "TPAD-DIFF-4P-GP_DISCRET-GB3-TPA"
					( Origin gPackager )
				)
				( attribute "CDS_LOCATION" "T1P8"
					( Origin gPackager )
				)
				( attribute "CDS_SEC" "1"
					( Origin gPackager )
				)
				( objectStatus "T1P8" )
			)
			( gate "@baseboard_fab2_lib.baseboard_fab2(sch_1):page271_i17"
				( attribute "CDS_LIB" "w_hdl"
					( Origin gPackager )
				)
				( attribute "CDS_LMAN_SYM_OUTLINE" "-75,100,75,-100"
					( Origin gPackager )
				)
				( attribute "LOCATION" "T1P7"
					( Origin gFrontEnd )
				)
				( attribute "PACK_TYPE" "DISCRET-GB3"
					( Origin gFrontEnd )
				)
				( attribute "PART_NUMBER" "ZZ.00PAD.NW1"
					( Origin gFrontEnd )
				)
				( attribute "PHYS_PAGE" "256"
					( Origin gFrontEnd )
				)
				( attribute "ROT" "0"
					( Origin gFrontEnd )
				)
				( attribute "SEC" "1"
					( Origin gFrontEnd )
				)
				( attribute "SEC_TYPE" "DISCRET-GB3"
					( Origin gFrontEnd )
				)
				( attribute "VALUE" "TPAD-DIFF-4P-GP"
					( Origin gFrontEnd )
				)
				( attribute "VER" "1"
					( Origin gFrontEnd )
				)
				( attribute "XY" "(-6000,6075)"
					( Origin gFrontEnd )
				)
				( attribute "CHIPS_PART_NAME" "TPAD-DIFF-4P-GP"
					( Origin gPackager )
				)
				( attribute "CDS_PART_NAME" "TPAD-DIFF-4P-GP_DISCRET-GB3-TPA"
					( Origin gPackager )
				)
				( attribute "CDS_LOCATION" "T1P7"
					( Origin gPackager )
				)
				( attribute "CDS_SEC" "1"
					( Origin gPackager )
				)
				( objectStatus "T1P7" )
			)
			( gate "@baseboard_fab2_lib.baseboard_fab2(sch_1):page271_i19"
				( attribute "CDS_LIB" "w_hdl"
					( Origin gPackager )
				)
				( attribute "CDS_LMAN_SYM_OUTLINE" "-75,100,75,-100"
					( Origin gPackager )
				)
				( attribute "LOCATION" "T1P9"
					( Origin gFrontEnd )
				)
				( attribute "PACK_TYPE" "DISCRET-GB3"
					( Origin gFrontEnd )
				)
				( attribute "PART_NUMBER" "ZZ.00PAD.NW1"
					( Origin gFrontEnd )
				)
				( attribute "PHYS_PAGE" "256"
					( Origin gFrontEnd )
				)
				( attribute "ROT" "0"
					( Origin gFrontEnd )
				)
				( attribute "SEC" "1"
					( Origin gFrontEnd )
				)
				( attribute "SEC_TYPE" "DISCRET-GB3"
					( Origin gFrontEnd )
				)
				( attribute "VALUE" "TPAD-DIFF-4P-GP"
					( Origin gFrontEnd )
				)
				( attribute "VER" "1"
					( Origin gFrontEnd )
				)
				( attribute "XY" "(-6000,5300)"
					( Origin gFrontEnd )
				)
				( attribute "CHIPS_PART_NAME" "TPAD-DIFF-4P-GP"
					( Origin gPackager )
				)
				( attribute "CDS_PART_NAME" "TPAD-DIFF-4P-GP_DISCRET-GB3-TPA"
					( Origin gPackager )
				)
				( attribute "CDS_LOCATION" "T1P9"
					( Origin gPackager )
				)
				( attribute "CDS_SEC" "1"
					( Origin gPackager )
				)
				( objectStatus "T1P9" )
			)
			( gate "@baseboard_fab2_lib.baseboard_fab2(sch_1):page271_i23"
				( attribute "CDS_LIB" "w_hdl"
					( Origin gPackager )
				)
				( attribute "CDS_LMAN_SYM_OUTLINE" "-75,100,75,-100"
					( Origin gPackager )
				)
				( attribute "LOCATION" "T1P11"
					( Origin gFrontEnd )
				)
				( attribute "PACK_TYPE" "DISCRET-GB3"
					( Origin gFrontEnd )
				)
				( attribute "PART_NUMBER" "ZZ.00PAD.NW1"
					( Origin gFrontEnd )
				)
				( attribute "PHYS_PAGE" "256"
					( Origin gFrontEnd )
				)
				( attribute "ROT" "0"
					( Origin gFrontEnd )
				)
				( attribute "SEC" "1"
					( Origin gFrontEnd )
				)
				( attribute "SEC_TYPE" "DISCRET-GB3"
					( Origin gFrontEnd )
				)
				( attribute "VALUE" "TPAD-DIFF-4P-GP"
					( Origin gFrontEnd )
				)
				( attribute "VER" "1"
					( Origin gFrontEnd )
				)
				( attribute "XY" "(-5975,4550)"
					( Origin gFrontEnd )
				)
				( attribute "CHIPS_PART_NAME" "TPAD-DIFF-4P-GP"
					( Origin gPackager )
				)
				( attribute "CDS_PART_NAME" "TPAD-DIFF-4P-GP_DISCRET-GB3-TPA"
					( Origin gPackager )
				)
				( attribute "CDS_LOCATION" "T1P11"
					( Origin gPackager )
				)
				( attribute "CDS_SEC" "1"
					( Origin gPackager )
				)
				( objectStatus "T1P11" )
			)
			( gate "@baseboard_fab2_lib.baseboard_fab2(sch_1):page271_i24"
				( attribute "CDS_LIB" "w_hdl"
					( Origin gPackager )
				)
				( attribute "CDS_LMAN_SYM_OUTLINE" "-75,100,75,-100"
					( Origin gPackager )
				)
				( attribute "LOCATION" "T1P12"
					( Origin gFrontEnd )
				)
				( attribute "PACK_TYPE" "DISCRET-GB3"
					( Origin gFrontEnd )
				)
				( attribute "PART_NUMBER" "ZZ.00PAD.NW1"
					( Origin gFrontEnd )
				)
				( attribute "PHYS_PAGE" "256"
					( Origin gFrontEnd )
				)
				( attribute "ROT" "0"
					( Origin gFrontEnd )
				)
				( attribute "SEC" "1"
					( Origin gFrontEnd )
				)
				( attribute "SEC_TYPE" "DISCRET-GB3"
					( Origin gFrontEnd )
				)
				( attribute "VALUE" "TPAD-DIFF-4P-GP"
					( Origin gFrontEnd )
				)
				( attribute "VER" "1"
					( Origin gFrontEnd )
				)
				( attribute "XY" "(-5975,4150)"
					( Origin gFrontEnd )
				)
				( attribute "CHIPS_PART_NAME" "TPAD-DIFF-4P-GP"
					( Origin gPackager )
				)
				( attribute "CDS_PART_NAME" "TPAD-DIFF-4P-GP_DISCRET-GB3-TPA"
					( Origin gPackager )
				)
				( attribute "CDS_LOCATION" "T1P12"
					( Origin gPackager )
				)
				( attribute "CDS_SEC" "1"
					( Origin gPackager )
				)
				( objectStatus "T1P12" )
			)
			( gate "@baseboard_fab2_lib.baseboard_fab2(sch_1):page271_i36"
				( attribute "CDS_LIB" "w_hdl"
					( Origin gPackager )
				)
				( attribute "CDS_LMAN_SYM_OUTLINE" "-75,100,75,-100"
					( Origin gPackager )
				)
				( attribute "LOCATION" "T1P17"
					( Origin gFrontEnd )
				)
				( attribute "PACK_TYPE" "DISCRET-GB3"
					( Origin gFrontEnd )
				)
				( attribute "PART_NUMBER" "ZZ.00PAD.NW1"
					( Origin gFrontEnd )
				)
				( attribute "PHYS_PAGE" "256"
					( Origin gFrontEnd )
				)
				( attribute "ROT" "0"
					( Origin gFrontEnd )
				)
				( attribute "SEC" "1"
					( Origin gFrontEnd )
				)
				( attribute "SEC_TYPE" "DISCRET-GB3"
					( Origin gFrontEnd )
				)
				( attribute "VALUE" "TPAD-DIFF-4P-GP"
					( Origin gFrontEnd )
				)
				( attribute "VER" "1"
					( Origin gFrontEnd )
				)
				( attribute "XY" "(-4175,4550)"
					( Origin gFrontEnd )
				)
				( attribute "CHIPS_PART_NAME" "TPAD-DIFF-4P-GP"
					( Origin gPackager )
				)
				( attribute "CDS_PART_NAME" "TPAD-DIFF-4P-GP_DISCRET-GB3-TPA"
					( Origin gPackager )
				)
				( attribute "CDS_LOCATION" "T1P17"
					( Origin gPackager )
				)
				( attribute "CDS_SEC" "1"
					( Origin gPackager )
				)
				( objectStatus "T1P17" )
			)
			( gate "@baseboard_fab2_lib.baseboard_fab2(sch_1):page271_i38"
				( attribute "CDS_LIB" "w_hdl"
					( Origin gPackager )
				)
				( attribute "CDS_LMAN_SYM_OUTLINE" "-75,100,75,-100"
					( Origin gPackager )
				)
				( attribute "LOCATION" "T1P24"
					( Origin gFrontEnd )
				)
				( attribute "PACK_TYPE" "DISCRET-GB3"
					( Origin gFrontEnd )
				)
				( attribute "PART_NUMBER" "ZZ.00PAD.NW1"
					( Origin gFrontEnd )
				)
				( attribute "PHYS_PAGE" "256"
					( Origin gFrontEnd )
				)
				( attribute "ROT" "0"
					( Origin gFrontEnd )
				)
				( attribute "SEC" "1"
					( Origin gFrontEnd )
				)
				( attribute "SEC_TYPE" "DISCRET-GB3"
					( Origin gFrontEnd )
				)
				( attribute "VALUE" "TPAD-DIFF-4P-GP"
					( Origin gFrontEnd )
				)
				( attribute "VER" "1"
					( Origin gFrontEnd )
				)
				( attribute "XY" "(-2375,4200)"
					( Origin gFrontEnd )
				)
				( attribute "CHIPS_PART_NAME" "TPAD-DIFF-4P-GP"
					( Origin gPackager )
				)
				( attribute "CDS_PART_NAME" "TPAD-DIFF-4P-GP_DISCRET-GB3-TPA"
					( Origin gPackager )
				)
				( attribute "CDS_LOCATION" "T1P24"
					( Origin gPackager )
				)
				( attribute "CDS_SEC" "1"
					( Origin gPackager )
				)
				( objectStatus "T1P24" )
			)
			( gate "@baseboard_fab2_lib.baseboard_fab2(sch_1):page271_i39"
				( attribute "CDS_LIB" "w_hdl"
					( Origin gPackager )
				)
				( attribute "CDS_LMAN_SYM_OUTLINE" "-75,100,75,-100"
					( Origin gPackager )
				)
				( attribute "LOCATION" "T1P19"
					( Origin gFrontEnd )
				)
				( attribute "PACK_TYPE" "DISCRET-GB3"
					( Origin gFrontEnd )
				)
				( attribute "PART_NUMBER" "ZZ.00PAD.NW1"
					( Origin gFrontEnd )
				)
				( attribute "PHYS_PAGE" "256"
					( Origin gFrontEnd )
				)
				( attribute "ROT" "0"
					( Origin gFrontEnd )
				)
				( attribute "SEC" "1"
					( Origin gFrontEnd )
				)
				( attribute "SEC_TYPE" "DISCRET-GB3"
					( Origin gFrontEnd )
				)
				( attribute "VALUE" "TPAD-DIFF-4P-GP"
					( Origin gFrontEnd )
				)
				( attribute "VER" "1"
					( Origin gFrontEnd )
				)
				( attribute "XY" "(-2400,6125)"
					( Origin gFrontEnd )
				)
				( attribute "CHIPS_PART_NAME" "TPAD-DIFF-4P-GP"
					( Origin gPackager )
				)
				( attribute "CDS_PART_NAME" "TPAD-DIFF-4P-GP_DISCRET-GB3-TPA"
					( Origin gPackager )
				)
				( attribute "CDS_LOCATION" "T1P19"
					( Origin gPackager )
				)
				( attribute "CDS_SEC" "1"
					( Origin gPackager )
				)
				( objectStatus "T1P19" )
			)
			( gate "@baseboard_fab2_lib.baseboard_fab2(sch_1):page271_i45"
				( attribute "CDS_LIB" "w_hdl"
					( Origin gPackager )
				)
				( attribute "CDS_LMAN_SYM_OUTLINE" "-75,100,75,-100"
					( Origin gPackager )
				)
				( attribute "LOCATION" "T1P22"
					( Origin gFrontEnd )
				)
				( attribute "PACK_TYPE" "DISCRET-GB3"
					( Origin gFrontEnd )
				)
				( attribute "PART_NUMBER" "ZZ.00PAD.NW1"
					( Origin gFrontEnd )
				)
				( attribute "PHYS_PAGE" "256"
					( Origin gFrontEnd )
				)
				( attribute "ROT" "0"
					( Origin gFrontEnd )
				)
				( attribute "SEC" "1"
					( Origin gFrontEnd )
				)
				( attribute "SEC_TYPE" "DISCRET-GB3"
					( Origin gFrontEnd )
				)
				( attribute "VALUE" "TPAD-DIFF-4P-GP"
					( Origin gFrontEnd )
				)
				( attribute "VER" "1"
					( Origin gFrontEnd )
				)
				( attribute "XY" "(-2400,4950)"
					( Origin gFrontEnd )
				)
				( attribute "CHIPS_PART_NAME" "TPAD-DIFF-4P-GP"
					( Origin gPackager )
				)
				( attribute "CDS_PART_NAME" "TPAD-DIFF-4P-GP_DISCRET-GB3-TPA"
					( Origin gPackager )
				)
				( attribute "CDS_LOCATION" "T1P22"
					( Origin gPackager )
				)
				( attribute "CDS_SEC" "1"
					( Origin gPackager )
				)
				( objectStatus "T1P22" )
			)
			( gate "@baseboard_fab2_lib.baseboard_fab2(sch_1):page271_i47"
				( attribute "CDS_LIB" "w_hdl"
					( Origin gPackager )
				)
				( attribute "CDS_LMAN_SYM_OUTLINE" "-75,100,75,-100"
					( Origin gPackager )
				)
				( attribute "LOCATION" "T1P23"
					( Origin gFrontEnd )
				)
				( attribute "PACK_TYPE" "DISCRET-GB3"
					( Origin gFrontEnd )
				)
				( attribute "PART_NUMBER" "ZZ.00PAD.NW1"
					( Origin gFrontEnd )
				)
				( attribute "PHYS_PAGE" "256"
					( Origin gFrontEnd )
				)
				( attribute "ROT" "0"
					( Origin gFrontEnd )
				)
				( attribute "SEC" "1"
					( Origin gFrontEnd )
				)
				( attribute "SEC_TYPE" "DISCRET-GB3"
					( Origin gFrontEnd )
				)
				( attribute "VALUE" "TPAD-DIFF-4P-GP"
					( Origin gFrontEnd )
				)
				( attribute "VER" "1"
					( Origin gFrontEnd )
				)
				( attribute "XY" "(-2375,4600)"
					( Origin gFrontEnd )
				)
				( attribute "CHIPS_PART_NAME" "TPAD-DIFF-4P-GP"
					( Origin gPackager )
				)
				( attribute "CDS_PART_NAME" "TPAD-DIFF-4P-GP_DISCRET-GB3-TPA"
					( Origin gPackager )
				)
				( attribute "CDS_LOCATION" "T1P23"
					( Origin gPackager )
				)
				( attribute "CDS_SEC" "1"
					( Origin gPackager )
				)
				( objectStatus "T1P23" )
			)
			( gate "@baseboard_fab2_lib.baseboard_fab2(sch_1):page271_i50"
				( attribute "CDS_LIB" "w_hdl"
					( Origin gPackager )
				)
				( attribute "CDS_LMAN_SYM_OUTLINE" "-75,100,75,-100"
					( Origin gPackager )
				)
				( attribute "LOCATION" "T1P25"
					( Origin gFrontEnd )
				)
				( attribute "PACK_TYPE" "DISCRET-GA1"
					( Origin gFrontEnd )
				)
				( attribute "PART_NUMBER" "ZZ.00PAD.NU1"
					( Origin gFrontEnd )
				)
				( attribute "PHYS_PAGE" "256"
					( Origin gFrontEnd )
				)
				( attribute "ROT" "2"
					( Origin gFrontEnd )
				)
				( attribute "VALUE" "TPAD-SE-2P-GP"
					( Origin gFrontEnd )
				)
				( attribute "VER" "1"
					( Origin gFrontEnd )
				)
				( attribute "XY" "(-8300,3500)"
					( Origin gFrontEnd )
				)
				( attribute "CHIPS_PART_NAME" "TPAD-SE-2P-GP"
					( Origin gPackager )
				)
				( attribute "CDS_PART_NAME" "TPAD-SE-2P-GP_DISCRET-GA1-TPADA"
					( Origin gPackager )
				)
				( attribute "CDS_LOCATION" "T1P25"
					( Origin gPackager )
				)
				( attribute "CDS_SEC" "1"
					( Origin gPackager )
				)
				( attribute "SEC" "1"
					( Origin gPackager )
				)
				( objectStatus "T1P25" )
			)
			( gate "@baseboard_fab2_lib.baseboard_fab2(sch_1):page271_i52"
				( attribute "CDS_LIB" "w_hdl"
					( Origin gPackager )
				)
				( attribute "CDS_LMAN_SYM_OUTLINE" "-75,100,75,-100"
					( Origin gPackager )
				)
				( attribute "LOCATION" "T1P26"
					( Origin gFrontEnd )
				)
				( attribute "PACK_TYPE" "DISCRET-GA1"
					( Origin gFrontEnd )
				)
				( attribute "PART_NUMBER" "ZZ.00PAD.NU1"
					( Origin gFrontEnd )
				)
				( attribute "PHYS_PAGE" "256"
					( Origin gFrontEnd )
				)
				( attribute "ROT" "2"
					( Origin gFrontEnd )
				)
				( attribute "VALUE" "TPAD-SE-2P-GP"
					( Origin gFrontEnd )
				)
				( attribute "VER" "1"
					( Origin gFrontEnd )
				)
				( attribute "XY" "(-8300,3100)"
					( Origin gFrontEnd )
				)
				( attribute "CHIPS_PART_NAME" "TPAD-SE-2P-GP"
					( Origin gPackager )
				)
				( attribute "CDS_PART_NAME" "TPAD-SE-2P-GP_DISCRET-GA1-TPADA"
					( Origin gPackager )
				)
				( attribute "CDS_LOCATION" "T1P26"
					( Origin gPackager )
				)
				( attribute "CDS_SEC" "1"
					( Origin gPackager )
				)
				( attribute "SEC" "1"
					( Origin gPackager )
				)
				( objectStatus "T1P26" )
			)
			( gate "@baseboard_fab2_lib.baseboard_fab2(sch_1):page271_i54"
				( attribute "CDS_LIB" "w_hdl"
					( Origin gPackager )
				)
				( attribute "CDS_LMAN_SYM_OUTLINE" "-75,100,75,-100"
					( Origin gPackager )
				)
				( attribute "LOCATION" "T1P27"
					( Origin gFrontEnd )
				)
				( attribute "PACK_TYPE" "DISCRET-GA1"
					( Origin gFrontEnd )
				)
				( attribute "PART_NUMBER" "ZZ.00PAD.NU1"
					( Origin gFrontEnd )
				)
				( attribute "PHYS_PAGE" "256"
					( Origin gFrontEnd )
				)
				( attribute "ROT" "2"
					( Origin gFrontEnd )
				)
				( attribute "VALUE" "TPAD-SE-2P-GP"
					( Origin gFrontEnd )
				)
				( attribute "VER" "1"
					( Origin gFrontEnd )
				)
				( attribute "XY" "(-8300,2625)"
					( Origin gFrontEnd )
				)
				( attribute "CHIPS_PART_NAME" "TPAD-SE-2P-GP"
					( Origin gPackager )
				)
				( attribute "CDS_PART_NAME" "TPAD-SE-2P-GP_DISCRET-GA1-TPADA"
					( Origin gPackager )
				)
				( attribute "CDS_LOCATION" "T1P27"
					( Origin gPackager )
				)
				( attribute "CDS_SEC" "1"
					( Origin gPackager )
				)
				( attribute "SEC" "1"
					( Origin gPackager )
				)
				( objectStatus "T1P27" )
			)
			( gate "@baseboard_fab2_lib.baseboard_fab2(sch_1):page271_i56"
				( attribute "CDS_LIB" "w_hdl"
					( Origin gPackager )
				)
				( attribute "CDS_LMAN_SYM_OUTLINE" "-75,100,75,-100"
					( Origin gPackager )
				)
				( attribute "LOCATION" "T1P29"
					( Origin gFrontEnd )
				)
				( attribute "PACK_TYPE" "DISCRET-GA1"
					( Origin gFrontEnd )
				)
				( attribute "PART_NUMBER" "ZZ.00PAD.NU1"
					( Origin gFrontEnd )
				)
				( attribute "PHYS_PAGE" "256"
					( Origin gFrontEnd )
				)
				( attribute "ROT" "2"
					( Origin gFrontEnd )
				)
				( attribute "VALUE" "TPAD-SE-2P-GP"
					( Origin gFrontEnd )
				)
				( attribute "VER" "1"
					( Origin gFrontEnd )
				)
				( attribute "XY" "(-6525,3075)"
					( Origin gFrontEnd )
				)
				( attribute "CHIPS_PART_NAME" "TPAD-SE-2P-GP"
					( Origin gPackager )
				)
				( attribute "CDS_PART_NAME" "TPAD-SE-2P-GP_DISCRET-GA1-TPADA"
					( Origin gPackager )
				)
				( attribute "CDS_LOCATION" "T1P29"
					( Origin gPackager )
				)
				( attribute "CDS_SEC" "1"
					( Origin gPackager )
				)
				( attribute "SEC" "1"
					( Origin gPackager )
				)
				( objectStatus "T1P29" )
			)
			( gate "@baseboard_fab2_lib.baseboard_fab2(sch_1):page271_i60"
				( attribute "CDS_LIB" "w_hdl"
					( Origin gPackager )
				)
				( attribute "CDS_LMAN_SYM_OUTLINE" "-75,100,75,-100"
					( Origin gPackager )
				)
				( attribute "LOCATION" "T1P28"
					( Origin gFrontEnd )
				)
				( attribute "PACK_TYPE" "DISCRET-GA1"
					( Origin gFrontEnd )
				)
				( attribute "PART_NUMBER" "ZZ.00PAD.NU1"
					( Origin gFrontEnd )
				)
				( attribute "PHYS_PAGE" "256"
					( Origin gFrontEnd )
				)
				( attribute "ROT" "2"
					( Origin gFrontEnd )
				)
				( attribute "VALUE" "TPAD-SE-2P-GP"
					( Origin gFrontEnd )
				)
				( attribute "VER" "1"
					( Origin gFrontEnd )
				)
				( attribute "XY" "(-6525,3475)"
					( Origin gFrontEnd )
				)
				( attribute "CHIPS_PART_NAME" "TPAD-SE-2P-GP"
					( Origin gPackager )
				)
				( attribute "CDS_PART_NAME" "TPAD-SE-2P-GP_DISCRET-GA1-TPADA"
					( Origin gPackager )
				)
				( attribute "CDS_LOCATION" "T1P28"
					( Origin gPackager )
				)
				( attribute "CDS_SEC" "1"
					( Origin gPackager )
				)
				( attribute "SEC" "1"
					( Origin gPackager )
				)
				( objectStatus "T1P28" )
			)
			( gate "@baseboard_fab2_lib.baseboard_fab2(sch_1):page271_i61"
				( attribute "CDS_LIB" "w_hdl"
					( Origin gPackager )
				)
				( attribute "CDS_LMAN_SYM_OUTLINE" "-75,100,75,-100"
					( Origin gPackager )
				)
				( attribute "LOCATION" "T1P30"
					( Origin gFrontEnd )
				)
				( attribute "PACK_TYPE" "DISCRET-GA1"
					( Origin gFrontEnd )
				)
				( attribute "PART_NUMBER" "ZZ.00PAD.NU1"
					( Origin gFrontEnd )
				)
				( attribute "PHYS_PAGE" "256"
					( Origin gFrontEnd )
				)
				( attribute "ROT" "2"
					( Origin gFrontEnd )
				)
				( attribute "VALUE" "TPAD-SE-2P-GP"
					( Origin gFrontEnd )
				)
				( attribute "VER" "1"
					( Origin gFrontEnd )
				)
				( attribute "XY" "(-6525,2600)"
					( Origin gFrontEnd )
				)
				( attribute "CHIPS_PART_NAME" "TPAD-SE-2P-GP"
					( Origin gPackager )
				)
				( attribute "CDS_PART_NAME" "TPAD-SE-2P-GP_DISCRET-GA1-TPADA"
					( Origin gPackager )
				)
				( attribute "CDS_LOCATION" "T1P30"
					( Origin gPackager )
				)
				( attribute "CDS_SEC" "1"
					( Origin gPackager )
				)
				( attribute "SEC" "1"
					( Origin gPackager )
				)
				( objectStatus "T1P30" )
			)
			( gate "@baseboard_fab2_lib.baseboard_fab2(sch_1):page271_i62"
				( attribute "CDS_LIB" "w_hdl"
					( Origin gPackager )
				)
				( attribute "CDS_LMAN_SYM_OUTLINE" "-75,100,75,-100"
					( Origin gPackager )
				)
				( attribute "LOCATION" "T1P34"
					( Origin gFrontEnd )
				)
				( attribute "PACK_TYPE" "DISCRET-GA1"
					( Origin gFrontEnd )
				)
				( attribute "PART_NUMBER" "ZZ.00PAD.NU1"
					( Origin gFrontEnd )
				)
				( attribute "PHYS_PAGE" "256"
					( Origin gFrontEnd )
				)
				( attribute "ROT" "2"
					( Origin gFrontEnd )
				)
				( attribute "VALUE" "TPAD-SE-2P-GP"
					( Origin gFrontEnd )
				)
				( attribute "VER" "1"
					( Origin gFrontEnd )
				)
				( attribute "XY" "(-2750,3450)"
					( Origin gFrontEnd )
				)
				( attribute "CHIPS_PART_NAME" "TPAD-SE-2P-GP"
					( Origin gPackager )
				)
				( attribute "CDS_PART_NAME" "TPAD-SE-2P-GP_DISCRET-GA1-TPADA"
					( Origin gPackager )
				)
				( attribute "CDS_LOCATION" "T1P34"
					( Origin gPackager )
				)
				( attribute "CDS_SEC" "1"
					( Origin gPackager )
				)
				( attribute "SEC" "1"
					( Origin gPackager )
				)
				( objectStatus "T1P34" )
			)
			( gate "@baseboard_fab2_lib.baseboard_fab2(sch_1):page271_i63"
				( attribute "CDS_LIB" "w_hdl"
					( Origin gPackager )
				)
				( attribute "CDS_LMAN_SYM_OUTLINE" "-75,100,75,-100"
					( Origin gPackager )
				)
				( attribute "LOCATION" "T1P36"
					( Origin gFrontEnd )
				)
				( attribute "PACK_TYPE" "DISCRET-GA1"
					( Origin gFrontEnd )
				)
				( attribute "PART_NUMBER" "ZZ.00PAD.NU1"
					( Origin gFrontEnd )
				)
				( attribute "PHYS_PAGE" "256"
					( Origin gFrontEnd )
				)
				( attribute "ROT" "2"
					( Origin gFrontEnd )
				)
				( attribute "VALUE" "TPAD-SE-2P-GP"
					( Origin gFrontEnd )
				)
				( attribute "VER" "1"
					( Origin gFrontEnd )
				)
				( attribute "XY" "(-2750,2575)"
					( Origin gFrontEnd )
				)
				( attribute "CHIPS_PART_NAME" "TPAD-SE-2P-GP"
					( Origin gPackager )
				)
				( attribute "CDS_PART_NAME" "TPAD-SE-2P-GP_DISCRET-GA1-TPADA"
					( Origin gPackager )
				)
				( attribute "CDS_LOCATION" "T1P36"
					( Origin gPackager )
				)
				( attribute "CDS_SEC" "1"
					( Origin gPackager )
				)
				( attribute "SEC" "1"
					( Origin gPackager )
				)
				( objectStatus "T1P36" )
			)
			( gate "@baseboard_fab2_lib.baseboard_fab2(sch_1):page271_i67"
				( attribute "CDS_LIB" "w_hdl"
					( Origin gPackager )
				)
				( attribute "CDS_LMAN_SYM_OUTLINE" "-75,100,75,-100"
					( Origin gPackager )
				)
				( attribute "LOCATION" "T1P35"
					( Origin gFrontEnd )
				)
				( attribute "PACK_TYPE" "DISCRET-GA1"
					( Origin gFrontEnd )
				)
				( attribute "PART_NUMBER" "ZZ.00PAD.NU1"
					( Origin gFrontEnd )
				)
				( attribute "PHYS_PAGE" "256"
					( Origin gFrontEnd )
				)
				( attribute "ROT" "2"
					( Origin gFrontEnd )
				)
				( attribute "VALUE" "TPAD-SE-2P-GP"
					( Origin gFrontEnd )
				)
				( attribute "VER" "1"
					( Origin gFrontEnd )
				)
				( attribute "XY" "(-2750,3050)"
					( Origin gFrontEnd )
				)
				( attribute "CHIPS_PART_NAME" "TPAD-SE-2P-GP"
					( Origin gPackager )
				)
				( attribute "CDS_PART_NAME" "TPAD-SE-2P-GP_DISCRET-GA1-TPADA"
					( Origin gPackager )
				)
				( attribute "CDS_LOCATION" "T1P35"
					( Origin gPackager )
				)
				( attribute "CDS_SEC" "1"
					( Origin gPackager )
				)
				( attribute "SEC" "1"
					( Origin gPackager )
				)
				( objectStatus "T1P35" )
			)
			( gate "@baseboard_fab2_lib.baseboard_fab2(sch_1):page271_i71"
				( attribute "CDS_LIB" "w_hdl"
					( Origin gPackager )
				)
				( attribute "CDS_LMAN_SYM_OUTLINE" "-75,100,75,-100"
					( Origin gPackager )
				)
				( attribute "LOCATION" "T1P31"
					( Origin gFrontEnd )
				)
				( attribute "PACK_TYPE" "DISCRET-GA1"
					( Origin gFrontEnd )
				)
				( attribute "PART_NUMBER" "ZZ.00PAD.NU1"
					( Origin gFrontEnd )
				)
				( attribute "PHYS_PAGE" "256"
					( Origin gFrontEnd )
				)
				( attribute "ROT" "2"
					( Origin gFrontEnd )
				)
				( attribute "VALUE" "TPAD-SE-2P-GP"
					( Origin gFrontEnd )
				)
				( attribute "VER" "1"
					( Origin gFrontEnd )
				)
				( attribute "XY" "(-4525,3475)"
					( Origin gFrontEnd )
				)
				( attribute "CHIPS_PART_NAME" "TPAD-SE-2P-GP"
					( Origin gPackager )
				)
				( attribute "CDS_PART_NAME" "TPAD-SE-2P-GP_DISCRET-GA1-TPADA"
					( Origin gPackager )
				)
				( attribute "CDS_LOCATION" "T1P31"
					( Origin gPackager )
				)
				( attribute "CDS_SEC" "1"
					( Origin gPackager )
				)
				( attribute "SEC" "1"
					( Origin gPackager )
				)
				( objectStatus "T1P31" )
			)
			( gate "@baseboard_fab2_lib.baseboard_fab2(sch_1):page271_i72"
				( attribute "CDS_LIB" "w_hdl"
					( Origin gPackager )
				)
				( attribute "CDS_LMAN_SYM_OUTLINE" "-75,100,75,-100"
					( Origin gPackager )
				)
				( attribute "LOCATION" "T1P32"
					( Origin gFrontEnd )
				)
				( attribute "PACK_TYPE" "DISCRET-GA1"
					( Origin gFrontEnd )
				)
				( attribute "PART_NUMBER" "ZZ.00PAD.NU1"
					( Origin gFrontEnd )
				)
				( attribute "PHYS_PAGE" "256"
					( Origin gFrontEnd )
				)
				( attribute "ROT" "2"
					( Origin gFrontEnd )
				)
				( attribute "VALUE" "TPAD-SE-2P-GP"
					( Origin gFrontEnd )
				)
				( attribute "VER" "1"
					( Origin gFrontEnd )
				)
				( attribute "XY" "(-4525,3075)"
					( Origin gFrontEnd )
				)
				( attribute "CHIPS_PART_NAME" "TPAD-SE-2P-GP"
					( Origin gPackager )
				)
				( attribute "CDS_PART_NAME" "TPAD-SE-2P-GP_DISCRET-GA1-TPADA"
					( Origin gPackager )
				)
				( attribute "CDS_LOCATION" "T1P32"
					( Origin gPackager )
				)
				( attribute "CDS_SEC" "1"
					( Origin gPackager )
				)
				( attribute "SEC" "1"
					( Origin gPackager )
				)
				( objectStatus "T1P32" )
			)
			( gate "@baseboard_fab2_lib.baseboard_fab2(sch_1):page271_i73"
				( attribute "CDS_LIB" "w_hdl"
					( Origin gPackager )
				)
				( attribute "CDS_LMAN_SYM_OUTLINE" "-75,100,75,-100"
					( Origin gPackager )
				)
				( attribute "LOCATION" "T1P33"
					( Origin gFrontEnd )
				)
				( attribute "PACK_TYPE" "DISCRET-GA1"
					( Origin gFrontEnd )
				)
				( attribute "PART_NUMBER" "ZZ.00PAD.NU1"
					( Origin gFrontEnd )
				)
				( attribute "PHYS_PAGE" "256"
					( Origin gFrontEnd )
				)
				( attribute "ROT" "2"
					( Origin gFrontEnd )
				)
				( attribute "VALUE" "TPAD-SE-2P-GP"
					( Origin gFrontEnd )
				)
				( attribute "VER" "1"
					( Origin gFrontEnd )
				)
				( attribute "XY" "(-4525,2600)"
					( Origin gFrontEnd )
				)
				( attribute "CHIPS_PART_NAME" "TPAD-SE-2P-GP"
					( Origin gPackager )
				)
				( attribute "CDS_PART_NAME" "TPAD-SE-2P-GP_DISCRET-GA1-TPADA"
					( Origin gPackager )
				)
				( attribute "CDS_LOCATION" "T1P33"
					( Origin gPackager )
				)
				( attribute "CDS_SEC" "1"
					( Origin gPackager )
				)
				( attribute "SEC" "1"
					( Origin gPackager )
				)
				( objectStatus "T1P33" )
			)
			( gate "@baseboard_fab2_lib.baseboard_fab2(sch_1):page118_i176"
				( attribute "BOM_COST" "SB"
					( Origin gFrontEnd )
				)
				( attribute "CDS_LIB" "mstr_discrete"
					( Origin gPackager )
				)
				( attribute "CDS_LOCATION" "R7W6"
					( Origin gPackager )
				)
				( attribute "CDS_SEC" "1"
					( Origin gPackager )
				)
				( attribute "LOCATION" "R7W6"
					( Origin gFrontEnd )
				)
				( attribute "MATERIAL" "CHIP"
					( Origin gFrontEnd )
				)
				( attribute "PACK_TYPE" "0402"
					( Origin gFrontEnd )
				)
				( attribute "PART_NUMBER" "G21497-005"
					( Origin gFrontEnd )
				)
				( attribute "PHYS_PAGE" "118"
					( Origin gFrontEnd )
				)
				( attribute "ROOM" "SB"
					( Origin gFrontEnd )
				)
				( attribute "ROT" "0"
					( Origin gFrontEnd )
				)
				( attribute "SEC" "1"
					( Origin gFrontEnd )
				)
				( attribute "SEC_TYPE" "0402"
					( Origin gFrontEnd )
				)
				( attribute "TOLERANCE" "5%"
					( Origin gFrontEnd )
				)
				( attribute "VALUE" "0.0"
					( Origin gFrontEnd )
				)
				( attribute "VER" "1"
					( Origin gFrontEnd )
				)
				( attribute "WATTAGE" "1/16W"
					( Origin gFrontEnd )
				)
				( attribute "XY" "(-6650,4225)"
					( Origin gFrontEnd )
				)
				( attribute "CHIPS_PART_NAME" "RES"
					( Origin gPackager )
				)
				( attribute "CDS_PART_NAME" "RES_0402-0.0,5%,1/16W,CHIP,G21A"
					( Origin gPackager )
				)
				( attribute "POP" "NOPOP"
					( Origin gFrontEnd )
				)
				( objectStatus "R7W6" )
			)
			( gate "@baseboard_fab2_lib.baseboard_fab2(sch_1):page120_i269"
				( attribute "BOM_COST" "PROC_SIDEBAND"
					( Origin gFrontEnd )
				)
				( attribute "CDS_LIB" "mstr_discrete"
					( Origin gPackager )
				)
				( attribute "CDS_LOCATION" "R7W8"
					( Origin gPackager )
				)
				( attribute "CDS_SEC" "1"
					( Origin gPackager )
				)
				( attribute "LOCATION" "R7W8"
					( Origin gFrontEnd )
				)
				( attribute "MATERIAL" "CHIP"
					( Origin gFrontEnd )
				)
				( attribute "PACK_TYPE" "0402"
					( Origin gFrontEnd )
				)
				( attribute "PART_NUMBER" "G21497-005"
					( Origin gFrontEnd )
				)
				( attribute "PHYS_PAGE" "120"
					( Origin gFrontEnd )
				)
				( attribute "ROOM" "CPU0"
					( Origin gFrontEnd )
				)
				( attribute "ROT" "0"
					( Origin gFrontEnd )
				)
				( attribute "SEC" "1"
					( Origin gFrontEnd )
				)
				( attribute "SEC_TYPE" "0402"
					( Origin gFrontEnd )
				)
				( attribute "TOLERANCE" "5%"
					( Origin gFrontEnd )
				)
				( attribute "VALUE" "0.0"
					( Origin gFrontEnd )
				)
				( attribute "VER" "1"
					( Origin gFrontEnd )
				)
				( attribute "WATTAGE" "1/16W"
					( Origin gFrontEnd )
				)
				( attribute "XY" "(-6650,3800)"
					( Origin gFrontEnd )
				)
				( attribute "CHIPS_PART_NAME" "RES"
					( Origin gPackager )
				)
				( attribute "CDS_PART_NAME" "RES_0402-0.0,5%,1/16W,CHIP,G21A"
					( Origin gPackager )
				)
				( objectStatus "R7W8" )
			)
			( gate "@baseboard_fab2_lib.baseboard_fab2(sch_1):page118_i177"
				( attribute "BOM_COST" "SB"
					( Origin gFrontEnd )
				)
				( attribute "CDS_LIB" "mstr_discrete"
					( Origin gPackager )
				)
				( attribute "CDS_LOCATION" "R7W9"
					( Origin gPackager )
				)
				( attribute "CDS_SEC" "1"
					( Origin gPackager )
				)
				( attribute "LOCATION" "R7W9"
					( Origin gFrontEnd )
				)
				( attribute "MATERIAL" "CHIP"
					( Origin gFrontEnd )
				)
				( attribute "PACK_TYPE" "0402"
					( Origin gFrontEnd )
				)
				( attribute "PART_NUMBER" "G21497-005"
					( Origin gFrontEnd )
				)
				( attribute "PHYS_PAGE" "118"
					( Origin gFrontEnd )
				)
				( attribute "ROOM" "SB"
					( Origin gFrontEnd )
				)
				( attribute "ROT" "0"
					( Origin gFrontEnd )
				)
				( attribute "SEC" "1"
					( Origin gFrontEnd )
				)
				( attribute "SEC_TYPE" "0402"
					( Origin gFrontEnd )
				)
				( attribute "TOLERANCE" "5%"
					( Origin gFrontEnd )
				)
				( attribute "VALUE" "0.0"
					( Origin gFrontEnd )
				)
				( attribute "VER" "1"
					( Origin gFrontEnd )
				)
				( attribute "WATTAGE" "1/16W"
					( Origin gFrontEnd )
				)
				( attribute "XY" "(-6650,4375)"
					( Origin gFrontEnd )
				)
				( attribute "CHIPS_PART_NAME" "RES"
					( Origin gPackager )
				)
				( attribute "CDS_PART_NAME" "RES_0402-0.0,5%,1/16W,CHIP,G21A"
					( Origin gPackager )
				)
				( attribute "POP" "NOPOP"
					( Origin gFrontEnd )
				)
				( objectStatus "R7W9" )
			)
			( gate "@baseboard_fab2_lib.baseboard_fab2(sch_1):page120_i270"
				( attribute "BOM_COST" "PROC_SIDEBAND"
					( Origin gFrontEnd )
				)
				( attribute "CDS_LIB" "mstr_discrete"
					( Origin gPackager )
				)
				( attribute "CDS_LOCATION" "R7W10"
					( Origin gPackager )
				)
				( attribute "CDS_SEC" "1"
					( Origin gPackager )
				)
				( attribute "LOCATION" "R7W10"
					( Origin gFrontEnd )
				)
				( attribute "MATERIAL" "CHIP"
					( Origin gFrontEnd )
				)
				( attribute "PACK_TYPE" "0402"
					( Origin gFrontEnd )
				)
				( attribute "PART_NUMBER" "G21497-005"
					( Origin gFrontEnd )
				)
				( attribute "PHYS_PAGE" "120"
					( Origin gFrontEnd )
				)
				( attribute "ROOM" "CPU0"
					( Origin gFrontEnd )
				)
				( attribute "ROT" "0"
					( Origin gFrontEnd )
				)
				( attribute "SEC" "1"
					( Origin gFrontEnd )
				)
				( attribute "SEC_TYPE" "0402"
					( Origin gFrontEnd )
				)
				( attribute "TOLERANCE" "5%"
					( Origin gFrontEnd )
				)
				( attribute "VALUE" "0.0"
					( Origin gFrontEnd )
				)
				( attribute "VER" "1"
					( Origin gFrontEnd )
				)
				( attribute "WATTAGE" "1/16W"
					( Origin gFrontEnd )
				)
				( attribute "XY" "(-6200,3700)"
					( Origin gFrontEnd )
				)
				( attribute "CHIPS_PART_NAME" "RES"
					( Origin gPackager )
				)
				( attribute "CDS_PART_NAME" "RES_0402-0.0,5%,1/16W,CHIP,G21A"
					( Origin gPackager )
				)
				( objectStatus "R7W10" )
			)
			( gate "@baseboard_fab2_lib.baseboard_fab2(sch_1):page120_i271"
				( attribute "BOM_COST" "PROC_SIDEBAND"
					( Origin gFrontEnd )
				)
				( attribute "CDS_LIB" "mstr_discrete"
					( Origin gPackager )
				)
				( attribute "CDS_LOCATION" "R7W12"
					( Origin gPackager )
				)
				( attribute "CDS_SEC" "1"
					( Origin gPackager )
				)
				( attribute "LOCATION" "R7W12"
					( Origin gFrontEnd )
				)
				( attribute "MATERIAL" "CHIP"
					( Origin gFrontEnd )
				)
				( attribute "PACK_TYPE" "0402"
					( Origin gFrontEnd )
				)
				( attribute "PART_NUMBER" "G21497-005"
					( Origin gFrontEnd )
				)
				( attribute "PHYS_PAGE" "120"
					( Origin gFrontEnd )
				)
				( attribute "ROOM" "CPU0"
					( Origin gFrontEnd )
				)
				( attribute "ROT" "0"
					( Origin gFrontEnd )
				)
				( attribute "SEC" "1"
					( Origin gFrontEnd )
				)
				( attribute "SEC_TYPE" "0402"
					( Origin gFrontEnd )
				)
				( attribute "TOLERANCE" "5%"
					( Origin gFrontEnd )
				)
				( attribute "VALUE" "0.0"
					( Origin gFrontEnd )
				)
				( attribute "VER" "1"
					( Origin gFrontEnd )
				)
				( attribute "WATTAGE" "1/16W"
					( Origin gFrontEnd )
				)
				( attribute "XY" "(-6400,3750)"
					( Origin gFrontEnd )
				)
				( attribute "CHIPS_PART_NAME" "RES"
					( Origin gPackager )
				)
				( attribute "CDS_PART_NAME" "RES_0402-0.0,5%,1/16W,CHIP,G21A"
					( Origin gPackager )
				)
				( objectStatus "R7W12" )
			)
			( gate "@baseboard_fab2_lib.baseboard_fab2(sch_1):page120_i273"
				( attribute "BOM_COST" "PROC_SIDEBAND"
					( Origin gFrontEnd )
				)
				( attribute "CDS_LIB" "mstr_discrete"
					( Origin gPackager )
				)
				( attribute "CDS_LOCATION" "R7W11"
					( Origin gPackager )
				)
				( attribute "CDS_SEC" "1"
					( Origin gPackager )
				)
				( attribute "LOCATION" "R7W11"
					( Origin gFrontEnd )
				)
				( attribute "MATERIAL" "CHIP"
					( Origin gFrontEnd )
				)
				( attribute "PACK_TYPE" "0402"
					( Origin gFrontEnd )
				)
				( attribute "PART_NUMBER" "G21497-005"
					( Origin gFrontEnd )
				)
				( attribute "PHYS_PAGE" "120"
					( Origin gFrontEnd )
				)
				( attribute "ROOM" "CPU0"
					( Origin gFrontEnd )
				)
				( attribute "ROT" "0"
					( Origin gFrontEnd )
				)
				( attribute "SEC" "1"
					( Origin gFrontEnd )
				)
				( attribute "SEC_TYPE" "0402"
					( Origin gFrontEnd )
				)
				( attribute "TOLERANCE" "5%"
					( Origin gFrontEnd )
				)
				( attribute "VALUE" "0.0"
					( Origin gFrontEnd )
				)
				( attribute "VER" "1"
					( Origin gFrontEnd )
				)
				( attribute "WATTAGE" "1/16W"
					( Origin gFrontEnd )
				)
				( attribute "XY" "(-950,2800)"
					( Origin gFrontEnd )
				)
				( attribute "CHIPS_PART_NAME" "RES"
					( Origin gPackager )
				)
				( attribute "CDS_PART_NAME" "RES_0402-0.0,5%,1/16W,CHIP,G21A"
					( Origin gPackager )
				)
				( objectStatus "R7W11" )
			)
			( gate "@baseboard_fab2_lib.baseboard_fab2(sch_1):page268_i66"
				( attribute "BOM_COST" "PROC_SIDEBAND"
					( Origin gFrontEnd )
				)
				( attribute "CDS_LIB" "mstr_discrete"
					( Origin gPackager )
				)
				( attribute "CDS_LOCATION" "R25W187"
					( Origin gPackager )
				)
				( attribute "CDS_SEC" "1"
					( Origin gPackager )
				)
				( attribute "LOCATION" "R25W187"
					( Origin gFrontEnd )
				)
				( attribute "MATERIAL" "CHIP"
					( Origin gFrontEnd )
				)
				( attribute "PACK_TYPE" "0402"
					( Origin gFrontEnd )
				)
				( attribute "PART_NUMBER" "G21497-005"
					( Origin gFrontEnd )
				)
				( attribute "PHYS_PAGE" "255"
					( Origin gFrontEnd )
				)
				( attribute "ROOM" "CPU0"
					( Origin gFrontEnd )
				)
				( attribute "ROT" "0"
					( Origin gFrontEnd )
				)
				( attribute "SEC" "1"
					( Origin gFrontEnd )
				)
				( attribute "SEC_TYPE" "0402"
					( Origin gFrontEnd )
				)
				( attribute "TOLERANCE" "5%"
					( Origin gFrontEnd )
				)
				( attribute "VALUE" "0.0"
					( Origin gFrontEnd )
				)
				( attribute "VER" "1"
					( Origin gFrontEnd )
				)
				( attribute "WATTAGE" "1/16W"
					( Origin gFrontEnd )
				)
				( attribute "XY" "(-6000,5300)"
					( Origin gFrontEnd )
				)
				( attribute "CHIPS_PART_NAME" "RES"
					( Origin gPackager )
				)
				( attribute "CDS_PART_NAME" "RES_0402-0.0,5%,1/16W,CHIP,G21A"
					( Origin gPackager )
				)
				( objectStatus "R25W187" )
			)
			( gate "@baseboard_fab2_lib.baseboard_fab2(sch_1):page188_i128"
				( attribute "CDS_LIB" "mstr_discrete"
					( Origin gPackager )
				)
				( attribute "CDS_LOCATION" "R1W40"
					( Origin gPackager )
				)
				( attribute "CDS_SEC" "1"
					( Origin gPackager )
				)
				( attribute "LOCATION" "R1W40"
					( Origin gFrontEnd )
				)
				( attribute "MATERIAL" "CHIP"
					( Origin gFrontEnd )
				)
				( attribute "PACK_TYPE" "0402"
					( Origin gFrontEnd )
				)
				( attribute "PART_NUMBER" "G21796-072"
					( Origin gFrontEnd )
				)
				( attribute "PHYS_PAGE" "188"
					( Origin gFrontEnd )
				)
				( attribute "ROOM" "CPU0"
					( Origin gFrontEnd )
				)
				( attribute "ROT" "1"
					( Origin gFrontEnd )
				)
				( attribute "SEC" "1"
					( Origin gFrontEnd )
				)
				( attribute "SEC_TYPE" "0402"
					( Origin gFrontEnd )
				)
				( attribute "TOLERANCE" "1%"
					( Origin gFrontEnd )
				)
				( attribute "VALUE" "4.75K"
					( Origin gFrontEnd )
				)
				( attribute "VER" "2"
					( Origin gFrontEnd )
				)
				( attribute "WATTAGE" "1/16W"
					( Origin gFrontEnd )
				)
				( attribute "XY" "(-3250,2750)"
					( Origin gFrontEnd )
				)
				( attribute "CHIPS_PART_NAME" "RES"
					( Origin gPackager )
				)
				( attribute "CDS_PART_NAME" "RES_0402-4.75K,1%,1/16W,CHIP,GA"
					( Origin gPackager )
				)
				( attribute "GROUP" "KR"
					( Origin gFrontEnd )
				)
				( objectStatus "R1W40" )
			)
			( gate "@baseboard_fab2_lib.baseboard_fab2(sch_1):page188_i129"
				( attribute "CDS_LIB" "mstr_discrete"
					( Origin gPackager )
				)
				( attribute "CDS_LOCATION" "R1W41"
					( Origin gPackager )
				)
				( attribute "CDS_SEC" "1"
					( Origin gPackager )
				)
				( attribute "LOCATION" "R1W41"
					( Origin gFrontEnd )
				)
				( attribute "MATERIAL" "CHIP"
					( Origin gFrontEnd )
				)
				( attribute "PACK_TYPE" "0402"
					( Origin gFrontEnd )
				)
				( attribute "PART_NUMBER" "G21796-072"
					( Origin gFrontEnd )
				)
				( attribute "PHYS_PAGE" "188"
					( Origin gFrontEnd )
				)
				( attribute "ROOM" "CPU0"
					( Origin gFrontEnd )
				)
				( attribute "ROT" "1"
					( Origin gFrontEnd )
				)
				( attribute "SEC" "1"
					( Origin gFrontEnd )
				)
				( attribute "SEC_TYPE" "0402"
					( Origin gFrontEnd )
				)
				( attribute "TOLERANCE" "1%"
					( Origin gFrontEnd )
				)
				( attribute "VALUE" "4.75K"
					( Origin gFrontEnd )
				)
				( attribute "VER" "2"
					( Origin gFrontEnd )
				)
				( attribute "WATTAGE" "1/16W"
					( Origin gFrontEnd )
				)
				( attribute "XY" "(-3250,2600)"
					( Origin gFrontEnd )
				)
				( attribute "CHIPS_PART_NAME" "RES"
					( Origin gPackager )
				)
				( attribute "CDS_PART_NAME" "RES_0402-4.75K,1%,1/16W,CHIP,GA"
					( Origin gPackager )
				)
				( attribute "POP" "NOPOP"
					( Origin gFrontEnd )
				)
				( attribute "GROUP" "KR"
					( Origin gFrontEnd )
				)
				( objectStatus "R1W41" )
			)
			( gate "@baseboard_fab2_lib.baseboard_fab2(sch_1):page119_i226"
				( attribute "BOM_COST" "PROC_SIDEBAND"
					( Origin gFrontEnd )
				)
				( attribute "CDS_LIB" "mstr_discrete"
					( Origin gPackager )
				)
				( attribute "CDS_LOCATION" "R7W13"
					( Origin gPackager )
				)
				( attribute "LOCATION" "R7W13"
					( Origin gFrontEnd )
				)
				( attribute "MATERIAL" "CHIP"
					( Origin gFrontEnd )
				)
				( attribute "PACK_TYPE" "0402"
					( Origin gFrontEnd )
				)
				( attribute "PART_NUMBER" "G21497-005"
					( Origin gFrontEnd )
				)
				( attribute "PHYS_PAGE" "119"
					( Origin gFrontEnd )
				)
				( attribute "ROOM" "CPU0"
					( Origin gFrontEnd )
				)
				( attribute "ROT" "0"
					( Origin gFrontEnd )
				)
				( attribute "SEC" "1"
					( Origin gFrontEnd )
				)
				( attribute "SEC_TYPE" "0402"
					( Origin gFrontEnd )
				)
				( attribute "TOLERANCE" "5%"
					( Origin gFrontEnd )
				)
				( attribute "VALUE" "0.0"
					( Origin gFrontEnd )
				)
				( attribute "VER" "1"
					( Origin gFrontEnd )
				)
				( attribute "WATTAGE" "1/16W"
					( Origin gFrontEnd )
				)
				( attribute "XY" "(-6950,4400)"
					( Origin gFrontEnd )
				)
				( attribute "CHIPS_PART_NAME" "RES"
					( Origin gPackager )
				)
				( attribute "CDS_PART_NAME" "RES_0402-0.0,5%,1/16W,CHIP,G21A"
					( Origin gPackager )
				)
				( attribute "CDS_SEC" "1"
					( Origin gPackager )
				)
				( objectStatus "R7W13" )
			)
			( gate "@baseboard_fab2_lib.baseboard_fab2(sch_1):page120_i274"
				( attribute "BOM_COST" "PROC_SIDEBAND"
					( Origin gFrontEnd )
				)
				( attribute "CDS_LIB" "mstr_discrete"
					( Origin gPackager )
				)
				( attribute "CDS_LOCATION" "R7W14"
					( Origin gPackager )
				)
				( attribute "CDS_SEC" "1"
					( Origin gPackager )
				)
				( attribute "LOCATION" "R7W14"
					( Origin gFrontEnd )
				)
				( attribute "MATERIAL" "CHIP"
					( Origin gFrontEnd )
				)
				( attribute "PACK_TYPE" "0402"
					( Origin gFrontEnd )
				)
				( attribute "PART_NUMBER" "G21497-005"
					( Origin gFrontEnd )
				)
				( attribute "PHYS_PAGE" "120"
					( Origin gFrontEnd )
				)
				( attribute "ROOM" "CPU0"
					( Origin gFrontEnd )
				)
				( attribute "ROT" "0"
					( Origin gFrontEnd )
				)
				( attribute "SEC" "1"
					( Origin gFrontEnd )
				)
				( attribute "SEC_TYPE" "0402"
					( Origin gFrontEnd )
				)
				( attribute "TOLERANCE" "5%"
					( Origin gFrontEnd )
				)
				( attribute "VALUE" "0.0"
					( Origin gFrontEnd )
				)
				( attribute "VER" "1"
					( Origin gFrontEnd )
				)
				( attribute "WATTAGE" "1/16W"
					( Origin gFrontEnd )
				)
				( attribute "XY" "(-6775,2650)"
					( Origin gFrontEnd )
				)
				( attribute "CHIPS_PART_NAME" "RES"
					( Origin gPackager )
				)
				( attribute "CDS_PART_NAME" "RES_0402-0.0,5%,1/16W,CHIP,G21A"
					( Origin gPackager )
				)
				( objectStatus "R7W14" )
			)
			( gate "@baseboard_fab2_lib.baseboard_fab2(sch_1):page119_i227"
				( attribute "BOM_COST" "PROC_SIDEBAND"
					( Origin gFrontEnd )
				)
				( attribute "CDS_LIB" "mstr_discrete"
					( Origin gPackager )
				)
				( attribute "CDS_LOCATION" "R7W15"
					( Origin gPackager )
				)
				( attribute "CDS_SEC" "1"
					( Origin gPackager )
				)
				( attribute "LOCATION" "R7W15"
					( Origin gFrontEnd )
				)
				( attribute "MATERIAL" "CHIP"
					( Origin gFrontEnd )
				)
				( attribute "PACK_TYPE" "0402"
					( Origin gFrontEnd )
				)
				( attribute "PART_NUMBER" "G21497-005"
					( Origin gFrontEnd )
				)
				( attribute "PHYS_PAGE" "119"
					( Origin gFrontEnd )
				)
				( attribute "ROOM" "CPU0"
					( Origin gFrontEnd )
				)
				( attribute "ROT" "0"
					( Origin gFrontEnd )
				)
				( attribute "SEC" "1"
					( Origin gFrontEnd )
				)
				( attribute "SEC_TYPE" "0402"
					( Origin gFrontEnd )
				)
				( attribute "TOLERANCE" "5%"
					( Origin gFrontEnd )
				)
				( attribute "VALUE" "0.0"
					( Origin gFrontEnd )
				)
				( attribute "VER" "1"
					( Origin gFrontEnd )
				)
				( attribute "WATTAGE" "1/16W"
					( Origin gFrontEnd )
				)
				( attribute "XY" "(-6700,4300)"
					( Origin gFrontEnd )
				)
				( attribute "CHIPS_PART_NAME" "RES"
					( Origin gPackager )
				)
				( attribute "CDS_PART_NAME" "RES_0402-0.0,5%,1/16W,CHIP,G21A"
					( Origin gPackager )
				)
				( attribute "POP" "NOPOP"
					( Origin gFrontEnd )
				)
				( objectStatus "R7W15" )
			)
			( gate "@baseboard_fab2_lib.baseboard_fab2(sch_1):page120_i275"
				( attribute "CDS_LIB" "mstr_discrete"
					( Origin gPackager )
				)
				( attribute "CDS_LOCATION" "R8C21"
					( Origin gPackager )
				)
				( attribute "LOCATION" "R8C21"
					( Origin gFrontEnd )
				)
				( attribute "MATERIAL" "CHIP"
					( Origin gFrontEnd )
				)
				( attribute "PACK_TYPE" "0402"
					( Origin gFrontEnd )
				)
				( attribute "PART_NUMBER" "G21796-017"
					( Origin gFrontEnd )
				)
				( attribute "PHYS_PAGE" "120"
					( Origin gFrontEnd )
				)
				( attribute "ROOM" "SB"
					( Origin gFrontEnd )
				)
				( attribute "ROT" "1"
					( Origin gFrontEnd )
				)
				( attribute "SEC" "1"
					( Origin gFrontEnd )
				)
				( attribute "SEC_TYPE" "0402"
					( Origin gFrontEnd )
				)
				( attribute "TOLERANCE" "1%"
					( Origin gFrontEnd )
				)
				( attribute "VALUE" "100.0"
					( Origin gFrontEnd )
				)
				( attribute "VER" "2"
					( Origin gFrontEnd )
				)
				( attribute "WATTAGE" "1/16W"
					( Origin gFrontEnd )
				)
				( attribute "XY" "(-1400,3050)"
					( Origin gFrontEnd )
				)
				( attribute "CHIPS_PART_NAME" "RES"
					( Origin gPackager )
				)
				( attribute "CDS_PART_NAME" "RES_0402-100.0,1%,1/16W,CHIP,GA"
					( Origin gPackager )
				)
				( attribute "CDS_SEC" "1"
					( Origin gPackager )
				)
				( objectStatus "R8C21" )
			)
			( gate "@baseboard_fab2_lib.baseboard_fab2(sch_1):page119_i228"
				( attribute "BOM_COST" "PROC_SIDEBAND"
					( Origin gFrontEnd )
				)
				( attribute "CDS_LIB" "mstr_discrete"
					( Origin gPackager )
				)
				( attribute "CDS_LOCATION" "R2U50"
					( Origin gPackager )
				)
				( attribute "CDS_SEC" "1"
					( Origin gPackager )
				)
				( attribute "LOCATION" "R2U50"
					( Origin gFrontEnd )
				)
				( attribute "MATERIAL" "CHIP"
					( Origin gFrontEnd )
				)
				( attribute "PACK_TYPE" "0402"
					( Origin gFrontEnd )
				)
				( attribute "PART_NUMBER" "G21497-005"
					( Origin gFrontEnd )
				)
				( attribute "PHYS_PAGE" "119"
					( Origin gFrontEnd )
				)
				( attribute "POP" "NOPOP"
					( Origin gFrontEnd )
				)
				( attribute "ROOM" "CPU0"
					( Origin gFrontEnd )
				)
				( attribute "ROT" "0"
					( Origin gFrontEnd )
				)
				( attribute "SEC" "1"
					( Origin gFrontEnd )
				)
				( attribute "SEC_TYPE" "0402"
					( Origin gFrontEnd )
				)
				( attribute "TOLERANCE" "5%"
					( Origin gFrontEnd )
				)
				( attribute "VALUE" "0.0"
					( Origin gFrontEnd )
				)
				( attribute "VER" "1"
					( Origin gFrontEnd )
				)
				( attribute "WATTAGE" "1/16W"
					( Origin gFrontEnd )
				)
				( attribute "XY" "(-1475,4100)"
					( Origin gFrontEnd )
				)
				( attribute "CHIPS_PART_NAME" "RES"
					( Origin gPackager )
				)
				( attribute "CDS_PART_NAME" "RES_0402-0.0,5%,1/16W,CHIP,G21A"
					( Origin gPackager )
				)
				( objectStatus "R2U50" )
			)
			( gate "@baseboard_fab2_lib.baseboard_fab2(sch_1):page188_i131"
				( attribute "CDS_LIB" "mstr_discrete"
					( Origin gPackager )
				)
				( attribute "CDS_LOCATION" "R1W42"
					( Origin gPackager )
				)
				( attribute "CDS_SEC" "1"
					( Origin gPackager )
				)
				( attribute "LOCATION" "R1W42"
					( Origin gFrontEnd )
				)
				( attribute "MATERIAL" "CHIP"
					( Origin gFrontEnd )
				)
				( attribute "PACK_TYPE" "0402"
					( Origin gFrontEnd )
				)
				( attribute "PART_NUMBER" "G21796-072"
					( Origin gFrontEnd )
				)
				( attribute "PHYS_PAGE" "188"
					( Origin gFrontEnd )
				)
				( attribute "ROOM" "CPU0"
					( Origin gFrontEnd )
				)
				( attribute "ROT" "1"
					( Origin gFrontEnd )
				)
				( attribute "SEC" "1"
					( Origin gFrontEnd )
				)
				( attribute "SEC_TYPE" "0402"
					( Origin gFrontEnd )
				)
				( attribute "TOLERANCE" "1%"
					( Origin gFrontEnd )
				)
				( attribute "VALUE" "4.75K"
					( Origin gFrontEnd )
				)
				( attribute "VER" "2"
					( Origin gFrontEnd )
				)
				( attribute "WATTAGE" "1/16W"
					( Origin gFrontEnd )
				)
				( attribute "XY" "(-3250,2350)"
					( Origin gFrontEnd )
				)
				( attribute "CHIPS_PART_NAME" "RES"
					( Origin gPackager )
				)
				( attribute "CDS_PART_NAME" "RES_0402-4.75K,1%,1/16W,CHIP,GA"
					( Origin gPackager )
				)
				( objectStatus "R1W42" )
			)
			( gate "@baseboard_fab2_lib.baseboard_fab2(sch_1):page188_i132"
				( attribute "CDS_LIB" "mstr_discrete"
					( Origin gPackager )
				)
				( attribute "CDS_LOCATION" "R1W43"
					( Origin gPackager )
				)
				( attribute "CDS_SEC" "1"
					( Origin gPackager )
				)
				( attribute "LOCATION" "R1W43"
					( Origin gFrontEnd )
				)
				( attribute "MATERIAL" "CHIP"
					( Origin gFrontEnd )
				)
				( attribute "PACK_TYPE" "0402"
					( Origin gFrontEnd )
				)
				( attribute "PART_NUMBER" "G21796-072"
					( Origin gFrontEnd )
				)
				( attribute "PHYS_PAGE" "188"
					( Origin gFrontEnd )
				)
				( attribute "ROOM" "CPU0"
					( Origin gFrontEnd )
				)
				( attribute "ROT" "1"
					( Origin gFrontEnd )
				)
				( attribute "SEC" "1"
					( Origin gFrontEnd )
				)
				( attribute "SEC_TYPE" "0402"
					( Origin gFrontEnd )
				)
				( attribute "TOLERANCE" "1%"
					( Origin gFrontEnd )
				)
				( attribute "VALUE" "4.75K"
					( Origin gFrontEnd )
				)
				( attribute "VER" "2"
					( Origin gFrontEnd )
				)
				( attribute "WATTAGE" "1/16W"
					( Origin gFrontEnd )
				)
				( attribute "XY" "(-3250,2200)"
					( Origin gFrontEnd )
				)
				( attribute "CHIPS_PART_NAME" "RES"
					( Origin gPackager )
				)
				( attribute "CDS_PART_NAME" "RES_0402-4.75K,1%,1/16W,CHIP,GA"
					( Origin gPackager )
				)
				( objectStatus "R1W43" )
			)
			( gate "@baseboard_fab2_lib.baseboard_fab2(sch_1):page188_i133"
				( attribute "CDS_LIB" "mstr_discrete"
					( Origin gPackager )
				)
				( attribute "CDS_LOCATION" "R1W44"
					( Origin gPackager )
				)
				( attribute "CDS_SEC" "1"
					( Origin gPackager )
				)
				( attribute "LOCATION" "R1W44"
					( Origin gFrontEnd )
				)
				( attribute "MATERIAL" "CHIP"
					( Origin gFrontEnd )
				)
				( attribute "PACK_TYPE" "0402"
					( Origin gFrontEnd )
				)
				( attribute "PART_NUMBER" "G21796-072"
					( Origin gFrontEnd )
				)
				( attribute "PHYS_PAGE" "188"
					( Origin gFrontEnd )
				)
				( attribute "ROOM" "CPU0"
					( Origin gFrontEnd )
				)
				( attribute "ROT" "1"
					( Origin gFrontEnd )
				)
				( attribute "SEC" "1"
					( Origin gFrontEnd )
				)
				( attribute "SEC_TYPE" "0402"
					( Origin gFrontEnd )
				)
				( attribute "TOLERANCE" "1%"
					( Origin gFrontEnd )
				)
				( attribute "VALUE" "4.75K"
					( Origin gFrontEnd )
				)
				( attribute "VER" "2"
					( Origin gFrontEnd )
				)
				( attribute "WATTAGE" "1/16W"
					( Origin gFrontEnd )
				)
				( attribute "XY" "(-3250,2050)"
					( Origin gFrontEnd )
				)
				( attribute "CHIPS_PART_NAME" "RES"
					( Origin gPackager )
				)
				( attribute "CDS_PART_NAME" "RES_0402-4.75K,1%,1/16W,CHIP,GA"
					( Origin gPackager )
				)
				( objectStatus "R1W44" )
			)
			( gate "@baseboard_fab2_lib.baseboard_fab2(sch_1):page188_i134"
				( attribute "CDS_LIB" "mstr_discrete"
					( Origin gPackager )
				)
				( attribute "CDS_LOCATION" "R1W45"
					( Origin gPackager )
				)
				( attribute "CDS_SEC" "1"
					( Origin gPackager )
				)
				( attribute "LOCATION" "R1W45"
					( Origin gFrontEnd )
				)
				( attribute "MATERIAL" "CHIP"
					( Origin gFrontEnd )
				)
				( attribute "PACK_TYPE" "0402"
					( Origin gFrontEnd )
				)
				( attribute "PART_NUMBER" "G21796-072"
					( Origin gFrontEnd )
				)
				( attribute "PHYS_PAGE" "188"
					( Origin gFrontEnd )
				)
				( attribute "ROOM" "CPU0"
					( Origin gFrontEnd )
				)
				( attribute "ROT" "1"
					( Origin gFrontEnd )
				)
				( attribute "SEC" "1"
					( Origin gFrontEnd )
				)
				( attribute "SEC_TYPE" "0402"
					( Origin gFrontEnd )
				)
				( attribute "TOLERANCE" "1%"
					( Origin gFrontEnd )
				)
				( attribute "VALUE" "4.75K"
					( Origin gFrontEnd )
				)
				( attribute "VER" "2"
					( Origin gFrontEnd )
				)
				( attribute "WATTAGE" "1/16W"
					( Origin gFrontEnd )
				)
				( attribute "XY" "(-3250,1900)"
					( Origin gFrontEnd )
				)
				( attribute "CHIPS_PART_NAME" "RES"
					( Origin gPackager )
				)
				( attribute "CDS_PART_NAME" "RES_0402-4.75K,1%,1/16W,CHIP,GA"
					( Origin gPackager )
				)
				( objectStatus "R1W45" )
			)
			( gate "@baseboard_fab2_lib.baseboard_fab2(sch_1):page120_i277"
				( attribute "BOM_COST" "PROC_SIDEBAND"
					( Origin gFrontEnd )
				)
				( attribute "CDS_LIB" "mstr_discrete"
					( Origin gPackager )
				)
				( attribute "CDS_LOCATION" "R7W18"
					( Origin gPackager )
				)
				( attribute "CDS_SEC" "1"
					( Origin gPackager )
				)
				( attribute "LOCATION" "R7W18"
					( Origin gFrontEnd )
				)
				( attribute "MATERIAL" "CHIP"
					( Origin gFrontEnd )
				)
				( attribute "PACK_TYPE" "0402"
					( Origin gFrontEnd )
				)
				( attribute "PART_NUMBER" "G21497-005"
					( Origin gFrontEnd )
				)
				( attribute "PHYS_PAGE" "120"
					( Origin gFrontEnd )
				)
				( attribute "ROOM" "CPU0"
					( Origin gFrontEnd )
				)
				( attribute "ROT" "0"
					( Origin gFrontEnd )
				)
				( attribute "SEC" "1"
					( Origin gFrontEnd )
				)
				( attribute "SEC_TYPE" "0402"
					( Origin gFrontEnd )
				)
				( attribute "TOLERANCE" "5%"
					( Origin gFrontEnd )
				)
				( attribute "VALUE" "0.0"
					( Origin gFrontEnd )
				)
				( attribute "VER" "1"
					( Origin gFrontEnd )
				)
				( attribute "WATTAGE" "1/16W"
					( Origin gFrontEnd )
				)
				( attribute "XY" "(-6850,3050)"
					( Origin gFrontEnd )
				)
				( attribute "CHIPS_PART_NAME" "RES"
					( Origin gPackager )
				)
				( attribute "CDS_PART_NAME" "RES_0402-0.0,5%,1/16W,CHIP,G21A"
					( Origin gPackager )
				)
				( objectStatus "R7W18" )
			)
			( gate "@baseboard_fab2_lib.baseboard_fab2(sch_1):page200_i252"
				( attribute "CDS_LIB" "mstr_discrete"
					( Origin gPackager )
				)
				( attribute "CDS_LOCATION" "R9P7"
					( Origin gPackager )
				)
				( attribute "CDS_SEC" "1"
					( Origin gPackager )
				)
				( attribute "LOCATION" "R9P7"
					( Origin gFrontEnd )
				)
				( attribute "MATERIAL" "CHIP"
					( Origin gFrontEnd )
				)
				( attribute "PACK_TYPE" "0402"
					( Origin gFrontEnd )
				)
				( attribute "PART_NUMBER" "G21796-010"
					( Origin gFrontEnd )
				)
				( attribute "PHYS_PAGE" "200"
					( Origin gFrontEnd )
				)
				( attribute "ROOM" "V_SUPER"
					( Origin gFrontEnd )
				)
				( attribute "ROT" "0"
					( Origin gFrontEnd )
				)
				( attribute "SEC" "1"
					( Origin gFrontEnd )
				)
				( attribute "SEC_TYPE" "0402"
					( Origin gFrontEnd )
				)
				( attribute "TOLERANCE" "1%"
					( Origin gFrontEnd )
				)
				( attribute "VALUE" "100.0K"
					( Origin gFrontEnd )
				)
				( attribute "VER" "2"
					( Origin gFrontEnd )
				)
				( attribute "WATTAGE" "1/16W"
					( Origin gFrontEnd )
				)
				( attribute "XY" "(-1975,800)"
					( Origin gFrontEnd )
				)
				( attribute "CHIPS_PART_NAME" "RES"
					( Origin gPackager )
				)
				( attribute "CDS_PART_NAME" "RES_0402-100.0K,1%,1/16W,CHIP,A"
					( Origin gPackager )
				)
				( objectStatus "R9P7" )
			)
			( gate "@baseboard_fab2_lib.baseboard_fab2(sch_1):page176_i181"
				( attribute "CDS_LIB" "mstr_discrete"
					( Origin gPackager )
				)
				( attribute "LOCATION" "L1M2"
					( Origin gFrontEnd )
				)
				( attribute "MATERIAL" "IND"
					( Origin gFrontEnd )
				)
				( attribute "PACK_TYPE" "SMLF"
					( Origin gFrontEnd )
				)
				( attribute "PART_NUMBER" "752402-015"
					( Origin gFrontEnd )
				)
				( attribute "PHYS_PAGE" "176"
					( Origin gFrontEnd )
				)
				( attribute "ROT" "0"
					( Origin gFrontEnd )
				)
				( attribute "SEC" "1"
					( Origin gFrontEnd )
				)
				( attribute "SEC_TYPE" "SMLF"
					( Origin gFrontEnd )
				)
				( attribute "VALUE" "90 OHM"
					( Origin gFrontEnd )
				)
				( attribute "VER" "1"
					( Origin gFrontEnd )
				)
				( attribute "XY" "(-5500,5025)"
					( Origin gFrontEnd )
				)
				( attribute "CHIPS_PART_NAME" "CHOKE_4PIN"
					( Origin gPackager )
				)
				( attribute "CDS_PART_NAME" "CHOKE_4PIN_SMLF-90 OHM,IND,752A"
					( Origin gPackager )
				)
				( attribute "CDS_LOCATION" "L1M2"
					( Origin gPackager )
				)
				( attribute "CDS_SEC" "1"
					( Origin gPackager )
				)
				( objectStatus "L1M2" )
			)
			( gate "@baseboard_fab2_lib.baseboard_fab2(sch_1):page216_i155"
				( attribute "ATTRIBUTE" "120NH"
					( Origin gFrontEnd )
				)
				( attribute "BOM_DS" "068.9002N.1021"
					( Origin gFrontEnd )
				)
				( attribute "BOM_SS" "NOPOP"
					( Origin gFrontEnd )
				)
				( attribute "CDS_LIB" "w_hdl"
					( Origin gPackager )
				)
				( attribute "CDS_LMAN_SYM_OUTLINE" "-75,100,75,-100"
					( Origin gPackager )
				)
				( attribute "CDS_LOCATION" "L7G2"
					( Origin gPackager )
				)
				( attribute "CDS_SEC" "1"
					( Origin gPackager )
				)
				( attribute "DS_VALUE" "90NH"
					( Origin gFrontEnd )
				)
				( attribute "LOCATION" "L7G2"
					( Origin gFrontEnd )
				)
				( attribute "NEW_PACK_SIZE" "DCR=0.17MOHM"
					( Origin gFrontEnd )
				)
				( attribute "NEW_RATED" "DS_ISAT=134A@25C"
					( Origin gFrontEnd )
				)
				( attribute "NEW_TYPE" "IRMS=66A@DELTA_T<40C"
					( Origin gFrontEnd )
				)
				( attribute "PACK_SIZE" "DCR=0.17MOHM"
					( Origin gFrontEnd )
				)
				( attribute "PACK_TYPE" "DISCRET-GB2"
					( Origin gFrontEnd )
				)
				( attribute "PART_NUMBER" "068.1202N.M001"
					( Origin gFrontEnd )
				)
				( attribute "PHYS_PAGE" "216"
					( Origin gFrontEnd )
				)
				( attribute "RATED" "ISAT=94A@25C"
					( Origin gFrontEnd )
				)
				( attribute "ROT" "1"
					( Origin gFrontEnd )
				)
				( attribute "SEC" "1"
					( Origin gFrontEnd )
				)
				( attribute "SEC_TYPE" "DISCRET-GB2"
					( Origin gFrontEnd )
				)
				( attribute "TYPE" "IRMS=66A@DELTA_T<40C"
					( Origin gFrontEnd )
				)
				( attribute "VALUE" "IND-120NH-30-GP"
					( Origin gFrontEnd )
				)
				( attribute "VER" "1"
					( Origin gFrontEnd )
				)
				( attribute "XY" "(3950,-350)"
					( Origin gFrontEnd )
				)
				( attribute "CHIPS_PART_NAME" "IND-120NH-30-GP"
					( Origin gPackager )
				)
				( attribute "CDS_PART_NAME" "IND-120NH-30-GP_DISCRET-GB2-INA"
					( Origin gPackager )
				)
				( objectStatus "L7G2" )
			)
			( gate "@baseboard_fab2_lib.baseboard_fab2(sch_1):page200_i253"
				( attribute "BOM_COST" "SM_HM"
					( Origin gFrontEnd )
				)
				( attribute "BOM_DS" "64.16935.6DL"
					( Origin gFrontEnd )
				)
				( attribute "CDS_LIB" "mstr_discrete"
					( Origin gPackager )
				)
				( attribute "CDS_LOCATION" "R1D20"
					( Origin gPackager )
				)
				( attribute "CDS_SEC" "1"
					( Origin gPackager )
				)
				( attribute "LOCATION" "R1D20"
					( Origin gFrontEnd )
				)
				( attribute "MATERIAL" "CHIP"
					( Origin gFrontEnd )
				)
				( attribute "PACK_TYPE" "0402"
					( Origin gFrontEnd )
				)
				( attribute "PART_NUMBER" "G21796-080"
					( Origin gFrontEnd )
				)
				( attribute "PHYS_PAGE" "200"
					( Origin gFrontEnd )
				)
				( attribute "ROOM" "BMC_VOLT_MONITOR"
					( Origin gFrontEnd )
				)
				( attribute "ROT" "0"
					( Origin gFrontEnd )
				)
				( attribute "SEC" "1"
					( Origin gFrontEnd )
				)
				( attribute "SEC_TYPE" "0402"
					( Origin gFrontEnd )
				)
				( attribute "TOLERANCE" "1%"
					( Origin gFrontEnd )
				)
				( attribute "VALUE" "200.0K"
					( Origin gFrontEnd )
				)
				( attribute "VER" "2"
					( Origin gFrontEnd )
				)
				( attribute "WATTAGE" "1/16W"
					( Origin gFrontEnd )
				)
				( attribute "XY" "(-4150,2825)"
					( Origin gFrontEnd )
				)
				( attribute "CHIPS_PART_NAME" "RES"
					( Origin gPackager )
				)
				( attribute "CDS_PART_NAME" "RES_0402-200.0K,1%,1/16W,CHIP,A"
					( Origin gPackager )
				)
				( objectStatus "R1D20" )
			)
			( gate "@baseboard_fab2_lib.baseboard_fab2(sch_1):page227_i154"
				( attribute "BOM_COST" "PROC_SIDEBAND"
					( Origin gFrontEnd )
				)
				( attribute "CDS_LIB" "mstr_discrete"
					( Origin gPackager )
				)
				( attribute "CDS_LOCATION" "R9L9"
					( Origin gPackager )
				)
				( attribute "CDS_SEC" "1"
					( Origin gPackager )
				)
				( attribute "LOCATION" "R9L9"
					( Origin gFrontEnd )
				)
				( attribute "MATERIAL" "CHIP"
					( Origin gFrontEnd )
				)
				( attribute "PACK_TYPE" "0402"
					( Origin gFrontEnd )
				)
				( attribute "PART_NUMBER" "G21497-005"
					( Origin gFrontEnd )
				)
				( attribute "PHYS_PAGE" "227"
					( Origin gFrontEnd )
				)
				( attribute "ROOM" "CPU0"
					( Origin gFrontEnd )
				)
				( attribute "ROT" "0"
					( Origin gFrontEnd )
				)
				( attribute "SEC" "1"
					( Origin gFrontEnd )
				)
				( attribute "SEC_TYPE" "0402"
					( Origin gFrontEnd )
				)
				( attribute "TOLERANCE" "5%"
					( Origin gFrontEnd )
				)
				( attribute "VALUE" "0.0"
					( Origin gFrontEnd )
				)
				( attribute "VER" "1"
					( Origin gFrontEnd )
				)
				( attribute "WATTAGE" "1/16W"
					( Origin gFrontEnd )
				)
				( attribute "XY" "(-750,3100)"
					( Origin gFrontEnd )
				)
				( attribute "CHIPS_PART_NAME" "RES"
					( Origin gPackager )
				)
				( attribute "CDS_PART_NAME" "RES_0402-0.0,5%,1/16W,CHIP,G21A"
					( Origin gPackager )
				)
				( objectStatus "R9L9" )
			)
			( gate "@baseboard_fab2_lib.baseboard_fab2(sch_1):page227_i155"
				( attribute "BOM_COST" "PROC_SIDEBAND"
					( Origin gFrontEnd )
				)
				( attribute "BOM_SS" "NOPOP"
					( Origin gFrontEnd )
				)
				( attribute "CDS_LIB" "mstr_discrete"
					( Origin gPackager )
				)
				( attribute "CDS_LOCATION" "R9L4"
					( Origin gPackager )
				)
				( attribute "CDS_SEC" "1"
					( Origin gPackager )
				)
				( attribute "LOCATION" "R9L4"
					( Origin gFrontEnd )
				)
				( attribute "MATERIAL" "CHIP"
					( Origin gFrontEnd )
				)
				( attribute "PACK_TYPE" "0402"
					( Origin gFrontEnd )
				)
				( attribute "PART_NUMBER" "G21497-005"
					( Origin gFrontEnd )
				)
				( attribute "PHYS_PAGE" "227"
					( Origin gFrontEnd )
				)
				( attribute "ROOM" "CPU0"
					( Origin gFrontEnd )
				)
				( attribute "ROT" "0"
					( Origin gFrontEnd )
				)
				( attribute "SEC" "1"
					( Origin gFrontEnd )
				)
				( attribute "SEC_TYPE" "0402"
					( Origin gFrontEnd )
				)
				( attribute "TOLERANCE" "5%"
					( Origin gFrontEnd )
				)
				( attribute "VALUE" "0.0"
					( Origin gFrontEnd )
				)
				( attribute "VER" "1"
					( Origin gFrontEnd )
				)
				( attribute "WATTAGE" "1/16W"
					( Origin gFrontEnd )
				)
				( attribute "XY" "(-675,800)"
					( Origin gFrontEnd )
				)
				( attribute "CHIPS_PART_NAME" "RES"
					( Origin gPackager )
				)
				( attribute "CDS_PART_NAME" "RES_0402-0.0,5%,1/16W,CHIP,G21A"
					( Origin gPackager )
				)
				( objectStatus "R9L4" )
			)
			( gate "@baseboard_fab2_lib.baseboard_fab2(sch_1):page118_i178"
				( attribute "CDS_LIB" "mstr_discrete"
					( Origin gPackager )
				)
				( attribute "LOCATION" "C8C1"
					( Origin gFrontEnd )
				)
				( attribute "MATERIAL" "COG"
					( Origin gFrontEnd )
				)
				( attribute "PACK_TYPE" "0402LF"
					( Origin gFrontEnd )
				)
				( attribute "PART_NUMBER" "A36095-031"
					( Origin gFrontEnd )
				)
				( attribute "PHYS_PAGE" "118"
					( Origin gFrontEnd )
				)
				( attribute "ROT" "0"
					( Origin gFrontEnd )
				)
				( attribute "SEC" "1"
					( Origin gFrontEnd )
				)
				( attribute "SEC_TYPE" "0402LF"
					( Origin gFrontEnd )
				)
				( attribute "TOLERANCE" "5%"
					( Origin gFrontEnd )
				)
				( attribute "VALUE" "33.0PF"
					( Origin gFrontEnd )
				)
				( attribute "VER" "1"
					( Origin gFrontEnd )
				)
				( attribute "VOLTAGE" "50V"
					( Units "uVoltage" "V" 1.000000)
					( Origin gFrontEnd )
				)
				( attribute "XY" "(-7700,600)"
					( Origin gFrontEnd )
				)
				( attribute "CHIPS_PART_NAME" "CAP"
					( Origin gPackager )
				)
				( attribute "CDS_PART_NAME" "CAP_0402LF-33.0PF,50V,5%,COG,AA"
					( Origin gPackager )
				)
				( attribute "CDS_LOCATION" "C8C1"
					( Origin gPackager )
				)
				( attribute "CDS_SEC" "1"
					( Origin gPackager )
				)
				( objectStatus "C8C1" )
			)
			( gate "@baseboard_fab2_lib.baseboard_fab2(sch_1):page118_i179"
				( attribute "CDS_LIB" "mstr_discrete"
					( Origin gPackager )
				)
				( attribute "LOCATION" "C8C2"
					( Origin gFrontEnd )
				)
				( attribute "MATERIAL" "COG"
					( Origin gFrontEnd )
				)
				( attribute "PACK_TYPE" "0402LF"
					( Origin gFrontEnd )
				)
				( attribute "PART_NUMBER" "A36095-031"
					( Origin gFrontEnd )
				)
				( attribute "PHYS_PAGE" "118"
					( Origin gFrontEnd )
				)
				( attribute "ROT" "0"
					( Origin gFrontEnd )
				)
				( attribute "SEC" "1"
					( Origin gFrontEnd )
				)
				( attribute "SEC_TYPE" "0402LF"
					( Origin gFrontEnd )
				)
				( attribute "TOLERANCE" "5%"
					( Origin gFrontEnd )
				)
				( attribute "VALUE" "33.0PF"
					( Origin gFrontEnd )
				)
				( attribute "VER" "1"
					( Origin gFrontEnd )
				)
				( attribute "VOLTAGE" "50V"
					( Units "uVoltage" "V" 1.000000)
					( Origin gFrontEnd )
				)
				( attribute "XY" "(-7250,600)"
					( Origin gFrontEnd )
				)
				( attribute "CHIPS_PART_NAME" "CAP"
					( Origin gPackager )
				)
				( attribute "CDS_PART_NAME" "CAP_0402LF-33.0PF,50V,5%,COG,AA"
					( Origin gPackager )
				)
				( attribute "CDS_LOCATION" "C8C2"
					( Origin gPackager )
				)
				( attribute "CDS_SEC" "1"
					( Origin gPackager )
				)
				( objectStatus "C8C2" )
			)
			( gate "@baseboard_fab2_lib.baseboard_fab2(sch_1):page181_i137"
				( attribute "BOM_COST" "PROC"
					( Origin gFrontEnd )
				)
				( attribute "CDS_LIB" "mstr_discrete"
					( Origin gPackager )
				)
				( attribute "CDS_LOCATION" "R9T8"
					( Origin gPackager )
				)
				( attribute "CDS_SEC" "1"
					( Origin gPackager )
				)
				( attribute "LOCATION" "R9T8"
					( Origin gFrontEnd )
				)
				( attribute "MATERIAL" "CHIP"
					( Origin gFrontEnd )
				)
				( attribute "PACK_TYPE" "0402"
					( Origin gFrontEnd )
				)
				( attribute "PART_NUMBER" "G21497-005"
					( Origin gFrontEnd )
				)
				( attribute "PHYS_PAGE" "181"
					( Origin gFrontEnd )
				)
				( attribute "ROOM" "PROC_SIDEBAND"
					( Origin gFrontEnd )
				)
				( attribute "ROT" "3"
					( Origin gFrontEnd )
				)
				( attribute "SEC" "1"
					( Origin gFrontEnd )
				)
				( attribute "SEC_TYPE" "0402"
					( Origin gFrontEnd )
				)
				( attribute "TOLERANCE" "5%"
					( Origin gFrontEnd )
				)
				( attribute "VALUE" "0.0"
					( Origin gFrontEnd )
				)
				( attribute "VER" "1"
					( Origin gFrontEnd )
				)
				( attribute "WATTAGE" "1/16W"
					( Origin gFrontEnd )
				)
				( attribute "XY" "(-2200,1300)"
					( Origin gFrontEnd )
				)
				( attribute "CHIPS_PART_NAME" "RES"
					( Origin gPackager )
				)
				( attribute "CDS_PART_NAME" "RES_0402-0.0,5%,1/16W,CHIP,G21A"
					( Origin gPackager )
				)
				( objectStatus "R9T8" )
			)
			( gate "@baseboard_fab2_lib.baseboard_fab2(sch_1):page269_i79"
				( attribute "BOM_COST" "DEBUG"
					( Origin gFrontEnd )
				)
				( attribute "CDS_LIB" "dev_discrete"
					( Origin gPackager )
				)
				( attribute "CDS_LOCATION" "C25W101"
					( Origin gPackager )
				)
				( attribute "CDS_SEC" "1"
					( Origin gPackager )
				)
				( attribute "LOCATION" "C25W101"
					( Origin gFrontEnd )
				)
				( attribute "MATERIAL" "X7R"
					( Origin gFrontEnd )
				)
				( attribute "PACK_TYPE" "0402V"
					( Origin gFrontEnd )
				)
				( attribute "PART_NUMBER" "A36096-030"
					( Origin gFrontEnd )
				)
				( attribute "PHYS_PAGE" "254"
					( Origin gFrontEnd )
				)
				( attribute "ROOM" "UART_MUX"
					( Origin gFrontEnd )
				)
				( attribute "ROT" "0"
					( Origin gFrontEnd )
				)
				( attribute "SEC" "1"
					( Origin gFrontEnd )
				)
				( attribute "SEC_TYPE" "0402V"
					( Origin gFrontEnd )
				)
				( attribute "TOLERANCE" "10%"
					( Origin gFrontEnd )
				)
				( attribute "VALUE" "0.1UF"
					( Origin gFrontEnd )
				)
				( attribute "VER" "1"
					( Origin gFrontEnd )
				)
				( attribute "VOLTAGE" "16V"
					( Units "uVoltage" "V" 1.000000)
					( Origin gFrontEnd )
				)
				( attribute "XY" "(-7050,4700)"
					( Origin gFrontEnd )
				)
				( attribute "CHIPS_PART_NAME" "CAP_A"
					( Origin gPackager )
				)
				( attribute "CDS_PART_NAME" "CAP_A_0402V-0.1UF,16V,10%,X7R,A"
					( Origin gPackager )
				)
				( objectStatus "C25W101" )
			)
			( gate "@baseboard_fab2_lib.baseboard_fab2(sch_1):page245_i56"
				( attribute "BOM_COST" "DEBUG"
					( Origin gFrontEnd )
				)
				( attribute "CDS_LIB" "mstr_discrete"
					( Origin gPackager )
				)
				( attribute "CDS_LOCATION" "R8W10"
					( Origin gPackager )
				)
				( attribute "CDS_SEC" "1"
					( Origin gPackager )
				)
				( attribute "LOCATION" "R8W10"
					( Origin gFrontEnd )
				)
				( attribute "MATERIAL" "CHIP"
					( Origin gFrontEnd )
				)
				( attribute "PACK_TYPE" "0402"
					( Origin gFrontEnd )
				)
				( attribute "PART_NUMBER" "G21497-005"
					( Origin gFrontEnd )
				)
				( attribute "PHYS_PAGE" "245"
					( Origin gFrontEnd )
				)
				( attribute "ROOM" "BMC_DEBUG_HEADER"
					( Origin gFrontEnd )
				)
				( attribute "ROT" "0"
					( Origin gFrontEnd )
				)
				( attribute "SEC" "1"
					( Origin gFrontEnd )
				)
				( attribute "SEC_TYPE" "0402"
					( Origin gFrontEnd )
				)
				( attribute "TOLERANCE" "5%"
					( Origin gFrontEnd )
				)
				( attribute "VALUE" "0.0"
					( Origin gFrontEnd )
				)
				( attribute "VER" "1"
					( Origin gFrontEnd )
				)
				( attribute "WATTAGE" "1/16W"
					( Origin gFrontEnd )
				)
				( attribute "XY" "(-2700,3175)"
					( Origin gFrontEnd )
				)
				( attribute "CHIPS_PART_NAME" "RES"
					( Origin gPackager )
				)
				( attribute "CDS_PART_NAME" "RES_0402-0.0,5%,1/16W,CHIP,G21A"
					( Origin gPackager )
				)
				( objectStatus "R8W10" )
			)
			( gate "@baseboard_fab2_lib.baseboard_fab2(sch_1):page245_i57"
				( attribute "BOM_COST" "DEBUG"
					( Origin gFrontEnd )
				)
				( attribute "CDS_LIB" "mstr_discrete"
					( Origin gPackager )
				)
				( attribute "CDS_LOCATION" "R8W11"
					( Origin gPackager )
				)
				( attribute "CDS_SEC" "1"
					( Origin gPackager )
				)
				( attribute "LOCATION" "R8W11"
					( Origin gFrontEnd )
				)
				( attribute "MATERIAL" "CHIP"
					( Origin gFrontEnd )
				)
				( attribute "PACK_TYPE" "0402"
					( Origin gFrontEnd )
				)
				( attribute "PART_NUMBER" "G21497-005"
					( Origin gFrontEnd )
				)
				( attribute "PHYS_PAGE" "245"
					( Origin gFrontEnd )
				)
				( attribute "ROOM" "BMC_DEBUG_HEADER"
					( Origin gFrontEnd )
				)
				( attribute "ROT" "0"
					( Origin gFrontEnd )
				)
				( attribute "SEC" "1"
					( Origin gFrontEnd )
				)
				( attribute "SEC_TYPE" "0402"
					( Origin gFrontEnd )
				)
				( attribute "TOLERANCE" "5%"
					( Origin gFrontEnd )
				)
				( attribute "VALUE" "0.0"
					( Origin gFrontEnd )
				)
				( attribute "VER" "1"
					( Origin gFrontEnd )
				)
				( attribute "WATTAGE" "1/16W"
					( Origin gFrontEnd )
				)
				( attribute "XY" "(-2700,3125)"
					( Origin gFrontEnd )
				)
				( attribute "CHIPS_PART_NAME" "RES"
					( Origin gPackager )
				)
				( attribute "CDS_PART_NAME" "RES_0402-0.0,5%,1/16W,CHIP,G21A"
					( Origin gPackager )
				)
				( objectStatus "R8W11" )
			)
			( gate "@baseboard_fab2_lib.baseboard_fab2(sch_1):page245_i58"
				( attribute "BOM_COST" "DEBUG"
					( Origin gFrontEnd )
				)
				( attribute "CDS_LIB" "mstr_discrete"
					( Origin gPackager )
				)
				( attribute "CDS_LOCATION" "R8W12"
					( Origin gPackager )
				)
				( attribute "CDS_SEC" "1"
					( Origin gPackager )
				)
				( attribute "LOCATION" "R8W12"
					( Origin gFrontEnd )
				)
				( attribute "MATERIAL" "CHIP"
					( Origin gFrontEnd )
				)
				( attribute "PACK_TYPE" "0402"
					( Origin gFrontEnd )
				)
				( attribute "PART_NUMBER" "G21497-005"
					( Origin gFrontEnd )
				)
				( attribute "PHYS_PAGE" "245"
					( Origin gFrontEnd )
				)
				( attribute "ROOM" "BMC_DEBUG_HEADER"
					( Origin gFrontEnd )
				)
				( attribute "ROT" "0"
					( Origin gFrontEnd )
				)
				( attribute "SEC" "1"
					( Origin gFrontEnd )
				)
				( attribute "SEC_TYPE" "0402"
					( Origin gFrontEnd )
				)
				( attribute "TOLERANCE" "5%"
					( Origin gFrontEnd )
				)
				( attribute "VALUE" "0.0"
					( Origin gFrontEnd )
				)
				( attribute "VER" "1"
					( Origin gFrontEnd )
				)
				( attribute "WATTAGE" "1/16W"
					( Origin gFrontEnd )
				)
				( attribute "XY" "(-2700,3025)"
					( Origin gFrontEnd )
				)
				( attribute "CHIPS_PART_NAME" "RES"
					( Origin gPackager )
				)
				( attribute "CDS_PART_NAME" "RES_0402-0.0,5%,1/16W,CHIP,G21A"
					( Origin gPackager )
				)
				( objectStatus "R8W12" )
			)
			( gate "@baseboard_fab2_lib.baseboard_fab2(sch_1):page245_i59"
				( attribute "BOM_COST" "DEBUG"
					( Origin gFrontEnd )
				)
				( attribute "CDS_LIB" "mstr_discrete"
					( Origin gPackager )
				)
				( attribute "CDS_LOCATION" "R8W13"
					( Origin gPackager )
				)
				( attribute "LOCATION" "R8W13"
					( Origin gFrontEnd )
				)
				( attribute "MATERIAL" "CHIP"
					( Origin gFrontEnd )
				)
				( attribute "PACK_TYPE" "0402"
					( Origin gFrontEnd )
				)
				( attribute "PART_NUMBER" "G21497-005"
					( Origin gFrontEnd )
				)
				( attribute "PHYS_PAGE" "245"
					( Origin gFrontEnd )
				)
				( attribute "ROOM" "BMC_DEBUG_HEADER"
					( Origin gFrontEnd )
				)
				( attribute "ROT" "0"
					( Origin gFrontEnd )
				)
				( attribute "SEC" "1"
					( Origin gFrontEnd )
				)
				( attribute "SEC_TYPE" "0402"
					( Origin gFrontEnd )
				)
				( attribute "TOLERANCE" "5%"
					( Origin gFrontEnd )
				)
				( attribute "VALUE" "0.0"
					( Origin gFrontEnd )
				)
				( attribute "VER" "1"
					( Origin gFrontEnd )
				)
				( attribute "WATTAGE" "1/16W"
					( Origin gFrontEnd )
				)
				( attribute "XY" "(-6500,3225)"
					( Origin gFrontEnd )
				)
				( attribute "CHIPS_PART_NAME" "RES"
					( Origin gPackager )
				)
				( attribute "CDS_PART_NAME" "RES_0402-0.0,5%,1/16W,CHIP,G21A"
					( Origin gPackager )
				)
				( attribute "CDS_SEC" "1"
					( Origin gPackager )
				)
				( objectStatus "R8W13" )
			)
			( gate "@baseboard_fab2_lib.baseboard_fab2(sch_1):page245_i60"
				( attribute "BOM_COST" "DEBUG"
					( Origin gFrontEnd )
				)
				( attribute "CDS_LIB" "mstr_discrete"
					( Origin gPackager )
				)
				( attribute "CDS_LOCATION" "R8W14"
					( Origin gPackager )
				)
				( attribute "LOCATION" "R8W14"
					( Origin gFrontEnd )
				)
				( attribute "MATERIAL" "CHIP"
					( Origin gFrontEnd )
				)
				( attribute "PACK_TYPE" "0402"
					( Origin gFrontEnd )
				)
				( attribute "PART_NUMBER" "G21497-005"
					( Origin gFrontEnd )
				)
				( attribute "PHYS_PAGE" "245"
					( Origin gFrontEnd )
				)
				( attribute "ROOM" "BMC_DEBUG_HEADER"
					( Origin gFrontEnd )
				)
				( attribute "ROT" "0"
					( Origin gFrontEnd )
				)
				( attribute "SEC" "1"
					( Origin gFrontEnd )
				)
				( attribute "SEC_TYPE" "0402"
					( Origin gFrontEnd )
				)
				( attribute "TOLERANCE" "5%"
					( Origin gFrontEnd )
				)
				( attribute "VALUE" "0.0"
					( Origin gFrontEnd )
				)
				( attribute "VER" "1"
					( Origin gFrontEnd )
				)
				( attribute "WATTAGE" "1/16W"
					( Origin gFrontEnd )
				)
				( attribute "XY" "(-6500,3175)"
					( Origin gFrontEnd )
				)
				( attribute "CHIPS_PART_NAME" "RES"
					( Origin gPackager )
				)
				( attribute "CDS_PART_NAME" "RES_0402-0.0,5%,1/16W,CHIP,G21A"
					( Origin gPackager )
				)
				( attribute "CDS_SEC" "1"
					( Origin gPackager )
				)
				( objectStatus "R8W14" )
			)
			( gate "@baseboard_fab2_lib.baseboard_fab2(sch_1):page245_i64"
				( attribute "BOM_COST" "DEBUG"
					( Origin gFrontEnd )
				)
				( attribute "CDS_LIB" "mstr_ttl"
					( Origin gPackager )
				)
				( attribute "CDS_LOCATION" "U8W1"
					( Origin gPackager )
				)
				( attribute "CDS_SEC" "1"
					( Origin gPackager )
				)
				( attribute "LOCATION" "U8W1"
					( Origin gFrontEnd )
				)
				( attribute "MATERIAL" "IC"
					( Origin gFrontEnd )
				)
				( attribute "PACK_TYPE" "SMLF"
					( Origin gFrontEnd )
				)
				( attribute "PART_NUMBER" "C88177-001"
					( Origin gFrontEnd )
				)
				( attribute "PHYS_PAGE" "245"
					( Origin gFrontEnd )
				)
				( attribute "ROOM" "DEBUG"
					( Origin gFrontEnd )
				)
				( attribute "ROT" "0"
					( Origin gFrontEnd )
				)
				( attribute "SEC" "1"
					( Origin gFrontEnd )
				)
				( attribute "SEC_TYPE" "SMLF"
					( Origin gFrontEnd )
				)
				( attribute "VER" "1"
					( Origin gFrontEnd )
				)
				( attribute "XY" "(-3900,2000)"
					( Origin gFrontEnd )
				)
				( attribute "CHIPS_PART_NAME" "74CBTLV1G125"
					( Origin gPackager )
				)
				( attribute "CDS_PART_NAME" "74CBTLV1G125_SMLF-IC,C88177-00A"
					( Origin gPackager )
				)
				( objectStatus "U8W1" )
			)
			( gate "@baseboard_fab2_lib.baseboard_fab2(sch_1):page245_i66"
				( attribute "BOM_COST" "DEBUG"
					( Origin gFrontEnd )
				)
				( attribute "CDS_LIB" "mstr_analog"
					( Origin gPackager )
				)
				( attribute "CDS_LOCATION" "U8W2"
					( Origin gPackager )
				)
				( attribute "CDS_SEC" "1"
					( Origin gPackager )
				)
				( attribute "LOCATION" "U8W2"
					( Origin gFrontEnd )
				)
				( attribute "MATERIAL" "IC"
					( Origin gFrontEnd )
				)
				( attribute "PACK_TYPE" "SMLF"
					( Origin gFrontEnd )
				)
				( attribute "PART_NUMBER" "C99406-001"
					( Origin gFrontEnd )
				)
				( attribute "PHYS_PAGE" "245"
					( Origin gFrontEnd )
				)
				( attribute "ROOM" "DEBUG"
					( Origin gFrontEnd )
				)
				( attribute "ROT" "2"
					( Origin gFrontEnd )
				)
				( attribute "SEC" "1"
					( Origin gPackager )
				)
				( attribute "VER" "1"
					( Origin gFrontEnd )
				)
				( attribute "XY" "(-5950,1500)"
					( Origin gFrontEnd )
				)
				( attribute "CHIPS_PART_NAME" "NC7SB3157"
					( Origin gPackager )
				)
				( attribute "CDS_PART_NAME" "NC7SB3157_SMLF-IC,C99406-001"
					( Origin gPackager )
				)
				( objectStatus "U8W2" )
			)
			( gate "@baseboard_fab2_lib.baseboard_fab2(sch_1):page245_i71"
				( attribute "BOM_COST" "DEBUG"
					( Origin gFrontEnd )
				)
				( attribute "CDS_LIB" "dev_discrete"
					( Origin gPackager )
				)
				( attribute "CDS_LOCATION" "C8W6"
					( Origin gPackager )
				)
				( attribute "CDS_SEC" "1"
					( Origin gPackager )
				)
				( attribute "LOCATION" "C8W6"
					( Origin gFrontEnd )
				)
				( attribute "MATERIAL" "X7R"
					( Origin gFrontEnd )
				)
				( attribute "PACK_TYPE" "0402V"
					( Origin gFrontEnd )
				)
				( attribute "PART_NUMBER" "A36096-045"
					( Origin gFrontEnd )
				)
				( attribute "PHYS_PAGE" "245"
					( Origin gFrontEnd )
				)
				( attribute "ROOM" "DEBUG"
					( Origin gFrontEnd )
				)
				( attribute "ROT" "2"
					( Origin gFrontEnd )
				)
				( attribute "SEC" "1"
					( Origin gFrontEnd )
				)
				( attribute "SEC_TYPE" "0402V"
					( Origin gFrontEnd )
				)
				( attribute "TOLERANCE" "10%"
					( Origin gFrontEnd )
				)
				( attribute "VALUE" "0.01UF"
					( Origin gFrontEnd )
				)
				( attribute "VER" "1"
					( Origin gFrontEnd )
				)
				( attribute "VOLTAGE" "25V"
					( Units "uVoltage" "V" 1.000000)
					( Origin gFrontEnd )
				)
				( attribute "XY" "(-5450,825)"
					( Origin gFrontEnd )
				)
				( attribute "CHIPS_PART_NAME" "CAP_A"
					( Origin gPackager )
				)
				( attribute "CDS_PART_NAME" "CAP_A_0402V-0.01UF,25V,10%,X7RA"
					( Origin gPackager )
				)
				( objectStatus "C8W6" )
			)
			( gate "@baseboard_fab2_lib.baseboard_fab2(sch_1):page245_i74"
				( attribute "BOM_COST" "DEBUG"
					( Origin gFrontEnd )
				)
				( attribute "CDS_LIB" "dev_discrete"
					( Origin gPackager )
				)
				( attribute "CDS_LOCATION" "C8W5"
					( Origin gPackager )
				)
				( attribute "CDS_SEC" "1"
					( Origin gPackager )
				)
				( attribute "LOCATION" "C8W5"
					( Origin gFrontEnd )
				)
				( attribute "MATERIAL" "X6S"
					( Origin gFrontEnd )
				)
				( attribute "PACK_TYPE" "0402V"
					( Origin gFrontEnd )
				)
				( attribute "PART_NUMBER" "D97712-004"
					( Origin gFrontEnd )
				)
				( attribute "PHYS_PAGE" "245"
					( Origin gFrontEnd )
				)
				( attribute "ROOM" "DEBUG"
					( Origin gFrontEnd )
				)
				( attribute "ROT" "2"
					( Origin gFrontEnd )
				)
				( attribute "SEC" "1"
					( Origin gPackager )
				)
				( attribute "TOLERANCE" "10%"
					( Origin gFrontEnd )
				)
				( attribute "VALUE" "1.0UF"
					( Origin gFrontEnd )
				)
				( attribute "VER" "1"
					( Origin gFrontEnd )
				)
				( attribute "VOLTAGE" "6.3V"
					( Units "uVoltage" "V" 1.000000)
					( Origin gFrontEnd )
				)
				( attribute "XY" "(-5850,825)"
					( Origin gFrontEnd )
				)
				( attribute "CHIPS_PART_NAME" "CAP_A"
					( Origin gPackager )
				)
				( attribute "CDS_PART_NAME" "CAP_A_0402V-1.0UF,6.3V,10%,X6SA"
					( Origin gPackager )
				)
				( objectStatus "C8W5" )
			)
			( gate "@baseboard_fab2_lib.baseboard_fab2(sch_1):page245_i78"
				( attribute "BOM_COST" "SM_CONTROLLER"
					( Origin gFrontEnd )
				)
				( attribute "CDS_LIB" "mstr_discrete"
					( Origin gPackager )
				)
				( attribute "CDS_LOCATION" "R8W15"
					( Origin gPackager )
				)
				( attribute "CDS_SEC" "1"
					( Origin gPackager )
				)
				( attribute "LOCATION" "R8W15"
					( Origin gFrontEnd )
				)
				( attribute "MATERIAL" "CHIP"
					( Origin gFrontEnd )
				)
				( attribute "PACK_TYPE" "0402"
					( Origin gFrontEnd )
				)
				( attribute "PART_NUMBER" "G21796-072"
					( Origin gFrontEnd )
				)
				( attribute "PHYS_PAGE" "245"
					( Origin gFrontEnd )
				)
				( attribute "ROOM" "BMC_MISC"
					( Origin gFrontEnd )
				)
				( attribute "ROT" "0"
					( Origin gFrontEnd )
				)
				( attribute "SEC" "1"
					( Origin gFrontEnd )
				)
				( attribute "SEC_TYPE" "0402"
					( Origin gFrontEnd )
				)
				( attribute "TOLERANCE" "1%"
					( Origin gFrontEnd )
				)
				( attribute "VALUE" "4.75K"
					( Origin gFrontEnd )
				)
				( attribute "VER" "2"
					( Origin gFrontEnd )
				)
				( attribute "WATTAGE" "1/16W"
					( Origin gFrontEnd )
				)
				( attribute "XY" "(-5500,2150)"
					( Origin gFrontEnd )
				)
				( attribute "CHIPS_PART_NAME" "RES"
					( Origin gPackager )
				)
				( attribute "CDS_PART_NAME" "RES_0402-4.75K,1%,1/16W,CHIP,GA"
					( Origin gPackager )
				)
				( objectStatus "R8W15" )
			)
			( gate "@baseboard_fab2_lib.baseboard_fab2(sch_1):page118_i180"
				( attribute "CDS_LIB" "mstr_discrete"
					( Origin gPackager )
				)
				( attribute "CDS_LOCATION" "R7W19"
					( Origin gPackager )
				)
				( attribute "CDS_SEC" "1"
					( Origin gPackager )
				)
				( attribute "LOCATION" "R7W19"
					( Origin gFrontEnd )
				)
				( attribute "MATERIAL" "CHIP"
					( Origin gFrontEnd )
				)
				( attribute "PACK_TYPE" "0402"
					( Origin gFrontEnd )
				)
				( attribute "PART_NUMBER" "G21796-072"
					( Origin gFrontEnd )
				)
				( attribute "PHYS_PAGE" "118"
					( Origin gFrontEnd )
				)
				( attribute "ROOM" "CPU0"
					( Origin gFrontEnd )
				)
				( attribute "ROT" "0"
					( Origin gFrontEnd )
				)
				( attribute "SEC" "1"
					( Origin gFrontEnd )
				)
				( attribute "SEC_TYPE" "0402"
					( Origin gFrontEnd )
				)
				( attribute "TOLERANCE" "1%"
					( Origin gFrontEnd )
				)
				( attribute "VALUE" "4.75K"
					( Origin gFrontEnd )
				)
				( attribute "VER" "2"
					( Origin gFrontEnd )
				)
				( attribute "WATTAGE" "1/16W"
					( Origin gFrontEnd )
				)
				( attribute "XY" "(-6450,4600)"
					( Origin gFrontEnd )
				)
				( attribute "CHIPS_PART_NAME" "RES"
					( Origin gPackager )
				)
				( attribute "CDS_PART_NAME" "RES_0402-4.75K,1%,1/16W,CHIP,GA"
					( Origin gPackager )
				)
				( objectStatus "R7W19" )
			)
			( gate "@baseboard_fab2_lib.baseboard_fab2(sch_1):page120_i278"
				( attribute "CDS_LIB" "mstr_discrete"
					( Origin gPackager )
				)
				( attribute "CDS_LOCATION" "R7W20"
					( Origin gPackager )
				)
				( attribute "CDS_SEC" "1"
					( Origin gPackager )
				)
				( attribute "LOCATION" "R7W20"
					( Origin gFrontEnd )
				)
				( attribute "MATERIAL" "CHIP"
					( Origin gFrontEnd )
				)
				( attribute "PACK_TYPE" "0402"
					( Origin gFrontEnd )
				)
				( attribute "PART_NUMBER" "G21796-072"
					( Origin gFrontEnd )
				)
				( attribute "PHYS_PAGE" "120"
					( Origin gFrontEnd )
				)
				( attribute "ROOM" "CPU0"
					( Origin gFrontEnd )
				)
				( attribute "ROT" "0"
					( Origin gFrontEnd )
				)
				( attribute "SEC" "1"
					( Origin gFrontEnd )
				)
				( attribute "SEC_TYPE" "0402"
					( Origin gFrontEnd )
				)
				( attribute "TOLERANCE" "1%"
					( Origin gFrontEnd )
				)
				( attribute "VALUE" "4.75K"
					( Origin gFrontEnd )
				)
				( attribute "VER" "2"
					( Origin gFrontEnd )
				)
				( attribute "WATTAGE" "1/16W"
					( Origin gFrontEnd )
				)
				( attribute "XY" "(-6500,4500)"
					( Origin gFrontEnd )
				)
				( attribute "CHIPS_PART_NAME" "RES"
					( Origin gPackager )
				)
				( attribute "CDS_PART_NAME" "RES_0402-4.75K,1%,1/16W,CHIP,GA"
					( Origin gPackager )
				)
				( attribute "POP" "NOPOP"
					( Origin gFrontEnd )
				)
				( objectStatus "R7W20" )
			)
			( gate "@baseboard_fab2_lib.baseboard_fab2(sch_1):page164_i100"
				( attribute "BOM_COST" "SM_CONTROLLER"
					( Origin gFrontEnd )
				)
				( attribute "CDS_LIB" "mstr_discrete"
					( Origin gPackager )
				)
				( attribute "CDS_LOCATION" "R1T4"
					( Origin gPackager )
				)
				( attribute "CDS_SEC" "1"
					( Origin gPackager )
				)
				( attribute "LOCATION" "R1T4"
					( Origin gFrontEnd )
				)
				( attribute "MATERIAL" "CHIP"
					( Origin gFrontEnd )
				)
				( attribute "PACK_TYPE" "0402"
					( Origin gFrontEnd )
				)
				( attribute "PART_NUMBER" "G21796-344"
					( Origin gFrontEnd )
				)
				( attribute "PHYS_PAGE" "164"
					( Origin gFrontEnd )
				)
				( attribute "ROOM" "BMC_MISC"
					( Origin gFrontEnd )
				)
				( attribute "ROT" "0"
					( Origin gFrontEnd )
				)
				( attribute "SEC" "1"
					( Origin gFrontEnd )
				)
				( attribute "SEC_TYPE" "0402"
					( Origin gFrontEnd )
				)
				( attribute "TOLERANCE" "1%"
					( Origin gFrontEnd )
				)
				( attribute "VALUE" "2.7K"
					( Origin gFrontEnd )
				)
				( attribute "VER" "1"
					( Origin gFrontEnd )
				)
				( attribute "WATTAGE" "1/16W"
					( Origin gFrontEnd )
				)
				( attribute "XY" "(-7400,1200)"
					( Origin gFrontEnd )
				)
				( attribute "CHIPS_PART_NAME" "RES"
					( Origin gPackager )
				)
				( attribute "CDS_PART_NAME" "RES_0402-2.7K,1%,1/16W,CHIP,G2A"
					( Origin gPackager )
				)
				( objectStatus "R1T4" )
			)
			( gate "@baseboard_fab2_lib.baseboard_fab2(sch_1):page150_i241"
				( attribute "BOM_COST" "SM_CONTROLLER"
					( Origin gFrontEnd )
				)
				( attribute "CDS_LIB" "mstr_discrete"
					( Origin gPackager )
				)
				( attribute "CDS_LOCATION" "R25W101"
					( Origin gPackager )
				)
				( attribute "CDS_SEC" "1"
					( Origin gPackager )
				)
				( attribute "LOCATION" "R25W101"
					( Origin gFrontEnd )
				)
				( attribute "MATERIAL" "EMPTY"
					( Origin gFrontEnd )
				)
				( attribute "PACK_TYPE" "0402"
					( Origin gFrontEnd )
				)
				( attribute "PART_NUMBER" "G21796-072"
					( Origin gFrontEnd )
				)
				( attribute "PHYS_PAGE" "150"
					( Origin gFrontEnd )
				)
				( attribute "ROOM" "BMC"
					( Origin gFrontEnd )
				)
				( attribute "ROT" "0"
					( Origin gFrontEnd )
				)
				( attribute "SEC" "1"
					( Origin gFrontEnd )
				)
				( attribute "SEC_TYPE" "0402"
					( Origin gFrontEnd )
				)
				( attribute "TOLERANCE" "1%"
					( Origin gFrontEnd )
				)
				( attribute "VALUE" "4.75K"
					( Origin gFrontEnd )
				)
				( attribute "VER" "1"
					( Origin gFrontEnd )
				)
				( attribute "WATTAGE" "1/16W"
					( Origin gFrontEnd )
				)
				( attribute "XY" "(1850,-800)"
					( Origin gFrontEnd )
				)
				( attribute "CHIPS_PART_NAME" "RES"
					( Origin gPackager )
				)
				( attribute "CDS_PART_NAME" "RES_0402-4.75K,1%,1/16W,EMPTY,A"
					( Origin gPackager )
				)
				( objectStatus "R25W101" )
			)
			( gate "@baseboard_fab2_lib.baseboard_fab2(sch_1):page176_i182"
				( attribute "BOM_COST" "DEBUG"
					( Origin gFrontEnd )
				)
				( attribute "CDS_LIB" "mstr_analog"
					( Origin gPackager )
				)
				( attribute "CDS_LOCATION" "U6W12"
					( Origin gPackager )
				)
				( attribute "CDS_SEC" "1"
					( Origin gPackager )
				)
				( attribute "LOCATION" "U6W12"
					( Origin gFrontEnd )
				)
				( attribute "MATERIAL" "IC"
					( Origin gFrontEnd )
				)
				( attribute "PACK_TYPE" "SMLF"
					( Origin gFrontEnd )
				)
				( attribute "PART_NUMBER" "C99406-001"
					( Origin gFrontEnd )
				)
				( attribute "PHYS_PAGE" "176"
					( Origin gFrontEnd )
				)
				( attribute "ROOM" "DEBUG"
					( Origin gFrontEnd )
				)
				( attribute "ROT" "0"
					( Origin gFrontEnd )
				)
				( attribute "SEC" "1"
					( Origin gPackager )
				)
				( attribute "VER" "1"
					( Origin gFrontEnd )
				)
				( attribute "XY" "(-750,1850)"
					( Origin gFrontEnd )
				)
				( attribute "CHIPS_PART_NAME" "NC7SB3157"
					( Origin gPackager )
				)
				( attribute "CDS_PART_NAME" "NC7SB3157_SMLF-IC,C99406-001"
					( Origin gPackager )
				)
				( objectStatus "U6W12" )
			)
			( gate "@baseboard_fab2_lib.baseboard_fab2(sch_1):page253_i44"
				( attribute "CDS_LIB" "w_hdl"
					( Origin gPackager )
				)
				( attribute "CDS_LMAN_SYM_OUTLINE" "-125,50,125,-50"
					( Origin gPackager )
				)
				( attribute "GROUP" "NO_KR"
					( Origin gFrontEnd )
				)
				( attribute "LOCATION" "F30W1"
					( Origin gFrontEnd )
				)
				( attribute "PACK_TYPE" "DISCRET-G7"
					( Origin gFrontEnd )
				)
				( attribute "PART_NUMBER" "69.50007.D81"
					( Origin gFrontEnd )
				)
				( attribute "PHYS_PAGE" "253"
					( Origin gFrontEnd )
				)
				( attribute "ROT" "0"
					( Origin gFrontEnd )
				)
				( attribute "SEC" "1"
					( Origin gFrontEnd )
				)
				( attribute "SEC_TYPE" "DISCRET-G7"
					( Origin gFrontEnd )
				)
				( attribute "VALUE" "POLYSW-1D1A6V-2-GP-U"
					( Origin gFrontEnd )
				)
				( attribute "VER" "1"
					( Origin gFrontEnd )
				)
				( attribute "XY" "(-5225,4675)"
					( Origin gFrontEnd )
				)
				( attribute "CHIPS_PART_NAME" "POLYSW-1D1A6V-2-GP-U"
					( Origin gPackager )
				)
				( attribute "CDS_PART_NAME" "POLYSW-1D1A6V-2-GP-U_DISCRET-GA"
					( Origin gPackager )
				)
				( attribute "CDS_LOCATION" "F30W1"
					( Origin gPackager )
				)
				( attribute "CDS_SEC" "1"
					( Origin gPackager )
				)
				( objectStatus "F30W1" )
			)
			( gate "@baseboard_fab2_lib.baseboard_fab2(sch_1):page119_i230"
				( attribute "CDS_LIB" "mstr_discrete"
					( Origin gPackager )
				)
				( attribute "CDS_LOCATION" "R7W22"
					( Origin gPackager )
				)
				( attribute "CDS_SEC" "1"
					( Origin gPackager )
				)
				( attribute "LOCATION" "R7W22"
					( Origin gFrontEnd )
				)
				( attribute "MATERIAL" "CHIP"
					( Origin gFrontEnd )
				)
				( attribute "PACK_TYPE" "0402"
					( Origin gFrontEnd )
				)
				( attribute "PART_NUMBER" "G21796-072"
					( Origin gFrontEnd )
				)
				( attribute "PHYS_PAGE" "119"
					( Origin gFrontEnd )
				)
				( attribute "POP" "NOPOP"
					( Origin gFrontEnd )
				)
				( attribute "ROOM" "CPU0"
					( Origin gFrontEnd )
				)
				( attribute "ROT" "0"
					( Origin gFrontEnd )
				)
				( attribute "SEC" "1"
					( Origin gFrontEnd )
				)
				( attribute "SEC_TYPE" "0402"
					( Origin gFrontEnd )
				)
				( attribute "TOLERANCE" "1%"
					( Origin gFrontEnd )
				)
				( attribute "VALUE" "4.75K"
					( Origin gFrontEnd )
				)
				( attribute "VER" "2"
					( Origin gFrontEnd )
				)
				( attribute "WATTAGE" "1/16W"
					( Origin gFrontEnd )
				)
				( attribute "XY" "(-1700,1600)"
					( Origin gFrontEnd )
				)
				( attribute "CHIPS_PART_NAME" "RES"
					( Origin gPackager )
				)
				( attribute "CDS_PART_NAME" "RES_0402-4.75K,1%,1/16W,CHIP,GA"
					( Origin gPackager )
				)
				( objectStatus "R7W22" )
			)
			( gate "@baseboard_fab2_lib.baseboard_fab2(sch_1):page118_i183"
				( attribute "CDS_LIB" "mstr_discrete"
					( Origin gPackager )
				)
				( attribute "CDS_LOCATION" "R7W21"
					( Origin gPackager )
				)
				( attribute "CDS_SEC" "1"
					( Origin gPackager )
				)
				( attribute "LOCATION" "R7W21"
					( Origin gFrontEnd )
				)
				( attribute "MATERIAL" "CHIP"
					( Origin gFrontEnd )
				)
				( attribute "PACK_TYPE" "0402"
					( Origin gFrontEnd )
				)
				( attribute "PART_NUMBER" "G21796-072"
					( Origin gFrontEnd )
				)
				( attribute "PHYS_PAGE" "118"
					( Origin gFrontEnd )
				)
				( attribute "ROOM" "CPU0"
					( Origin gFrontEnd )
				)
				( attribute "ROT" "0"
					( Origin gFrontEnd )
				)
				( attribute "SEC" "1"
					( Origin gFrontEnd )
				)
				( attribute "SEC_TYPE" "0402"
					( Origin gFrontEnd )
				)
				( attribute "TOLERANCE" "1%"
					( Origin gFrontEnd )
				)
				( attribute "VALUE" "4.75K"
					( Origin gFrontEnd )
				)
				( attribute "VER" "2"
					( Origin gFrontEnd )
				)
				( attribute "WATTAGE" "1/16W"
					( Origin gFrontEnd )
				)
				( attribute "XY" "(-6200,4600)"
					( Origin gFrontEnd )
				)
				( attribute "CHIPS_PART_NAME" "RES"
					( Origin gPackager )
				)
				( attribute "CDS_PART_NAME" "RES_0402-4.75K,1%,1/16W,CHIP,GA"
					( Origin gPackager )
				)
				( objectStatus "R7W21" )
			)
			( gate "@baseboard_fab2_lib.baseboard_fab2(sch_1):page150_i242"
				( attribute "BOM_COST" "SM_CONTROLLER"
					( Origin gFrontEnd )
				)
				( attribute "CDS_LIB" "mstr_discrete"
					( Origin gPackager )
				)
				( attribute "CDS_LOCATION" "R25W115"
					( Origin gPackager )
				)
				( attribute "CDS_SEC" "1"
					( Origin gPackager )
				)
				( attribute "LOCATION" "R25W115"
					( Origin gFrontEnd )
				)
				( attribute "MATERIAL" "EMPTY"
					( Origin gFrontEnd )
				)
				( attribute "PACK_TYPE" "0402"
					( Origin gFrontEnd )
				)
				( attribute "PART_NUMBER" "G21796-072"
					( Origin gFrontEnd )
				)
				( attribute "PHYS_PAGE" "150"
					( Origin gFrontEnd )
				)
				( attribute "ROOM" "BMC"
					( Origin gFrontEnd )
				)
				( attribute "ROT" "0"
					( Origin gFrontEnd )
				)
				( attribute "SEC" "1"
					( Origin gFrontEnd )
				)
				( attribute "SEC_TYPE" "0402"
					( Origin gFrontEnd )
				)
				( attribute "TOLERANCE" "1%"
					( Origin gFrontEnd )
				)
				( attribute "VALUE" "4.75K"
					( Origin gFrontEnd )
				)
				( attribute "VER" "1"
					( Origin gFrontEnd )
				)
				( attribute "WATTAGE" "1/16W"
					( Origin gFrontEnd )
				)
				( attribute "XY" "(-600,-2900)"
					( Origin gFrontEnd )
				)
				( attribute "CHIPS_PART_NAME" "RES"
					( Origin gPackager )
				)
				( attribute "CDS_PART_NAME" "RES_0402-4.75K,1%,1/16W,EMPTY,A"
					( Origin gPackager )
				)
				( objectStatus "R25W115" )
			)
			( gate "@baseboard_fab2_lib.baseboard_fab2(sch_1):page102_i115"
				( attribute "CDS_LIB" "mstr_discrete"
					( Origin gPackager )
				)
				( attribute "CDS_LOCATION" "R6P48"
					( Origin gPackager )
				)
				( attribute "CDS_SEC" "1"
					( Origin gPackager )
				)
				( attribute "LOCATION" "R6P48"
					( Origin gFrontEnd )
				)
				( attribute "MATERIAL" "CHIP"
					( Origin gFrontEnd )
				)
				( attribute "PACK_TYPE" "0402"
					( Origin gFrontEnd )
				)
				( attribute "PART_NUMBER" "G21796-026"
					( Origin gFrontEnd )
				)
				( attribute "PHYS_PAGE" "102"
					( Origin gFrontEnd )
				)
				( attribute "ROOM" "PROC_SIDEBAND"
					( Origin gFrontEnd )
				)
				( attribute "ROT" "0"
					( Origin gFrontEnd )
				)
				( attribute "SEC" "1"
					( Origin gFrontEnd )
				)
				( attribute "SEC_TYPE" "0402"
					( Origin gFrontEnd )
				)
				( attribute "TOLERANCE" "1%"
					( Origin gFrontEnd )
				)
				( attribute "VALUE" "1.00K"
					( Origin gFrontEnd )
				)
				( attribute "VER" "2"
					( Origin gFrontEnd )
				)
				( attribute "WATTAGE" "1/16W"
					( Origin gFrontEnd )
				)
				( attribute "XY" "(-750,1075)"
					( Origin gFrontEnd )
				)
				( attribute "CHIPS_PART_NAME" "RES"
					( Origin gPackager )
				)
				( attribute "CDS_PART_NAME" "RES_0402-1.00K,1%,1/16W,CHIP,GA"
					( Origin gPackager )
				)
				( objectStatus "R6P48" )
			)
			( pin "@baseboard_fab2_lib.baseboard_fab2(sch_1):page21_i149:a"
				( attribute "PN" "1"
					( Origin gPackager )
				)
				( objectStatus "R6N10.1" )
			)
			( pin "@baseboard_fab2_lib.baseboard_fab2(sch_1):page21_i149:b"
				( attribute "PN" "2"
					( Origin gPackager )
				)
				( objectStatus "R6N10.2" )
			)
			( pin "@baseboard_fab2_lib.baseboard_fab2(sch_1):page21_i150:a"
				( attribute "PN" "1"
					( Origin gPackager )
				)
				( objectStatus "R6N12.1" )
			)
			( pin "@baseboard_fab2_lib.baseboard_fab2(sch_1):page21_i150:b"
				( attribute "PN" "2"
					( Origin gPackager )
				)
				( objectStatus "R6N12.2" )
			)
			( pin "@baseboard_fab2_lib.baseboard_fab2(sch_1):page21_i151:a"
				( attribute "PN" "1"
					( Origin gPackager )
				)
				( objectStatus "R6N11.1" )
			)
			( pin "@baseboard_fab2_lib.baseboard_fab2(sch_1):page21_i151:b"
				( attribute "PN" "2"
					( Origin gPackager )
				)
				( objectStatus "R6N11.2" )
			)
			( pin "@baseboard_fab2_lib.baseboard_fab2(sch_1):page21_i152:a"
				( attribute "PN" "1"
					( Origin gPackager )
				)
				( objectStatus "R6B3.1" )
			)
			( pin "@baseboard_fab2_lib.baseboard_fab2(sch_1):page21_i152:b"
				( attribute "PN" "2"
					( Origin gPackager )
				)
				( objectStatus "R6B3.2" )
			)
			( pin "@baseboard_fab2_lib.baseboard_fab2(sch_1):page21_i153:a"
				( attribute "PN" "1"
					( Origin gPackager )
				)
				( objectStatus "R6B5.1" )
			)
			( pin "@baseboard_fab2_lib.baseboard_fab2(sch_1):page21_i153:b"
				( attribute "PN" "2"
					( Origin gPackager )
				)
				( objectStatus "R6B5.2" )
			)
			( pin "@baseboard_fab2_lib.baseboard_fab2(sch_1):page21_i154:a"
				( attribute "PN" "1"
					( Origin gPackager )
				)
				( objectStatus "R6B4.1" )
			)
			( pin "@baseboard_fab2_lib.baseboard_fab2(sch_1):page21_i154:b"
				( attribute "PN" "2"
					( Origin gPackager )
				)
				( objectStatus "R6B4.2" )
			)
			( pin "@baseboard_fab2_lib.baseboard_fab2(sch_1):page21_i159:a"
				( attribute "PN" "1"
					( Origin gPackager )
				)
				( objectStatus "R6B2.1" )
			)
			( pin "@baseboard_fab2_lib.baseboard_fab2(sch_1):page21_i159:b"
				( attribute "PN" "2"
					( Origin gPackager )
				)
				( objectStatus "R6B2.2" )
			)
			( pin "@baseboard_fab2_lib.baseboard_fab2(sch_1):page21_i161:a"
				( attribute "PN" "1"
					( Origin gPackager )
				)
				( objectStatus "R6B1.1" )
			)
			( pin "@baseboard_fab2_lib.baseboard_fab2(sch_1):page21_i161:b"
				( attribute "PN" "2"
					( Origin gPackager )
				)
				( objectStatus "R6B1.2" )
			)
			( pin "@baseboard_fab2_lib.baseboard_fab2(sch_1):page21_i163:a"
				( attribute "PN" "1"
					( Origin gPackager )
				)
				( objectStatus "R6N2.1" )
			)
			( pin "@baseboard_fab2_lib.baseboard_fab2(sch_1):page21_i163:b"
				( attribute "PN" "2"
					( Origin gPackager )
				)
				( objectStatus "R6N2.2" )
			)
			( pin "@baseboard_fab2_lib.baseboard_fab2(sch_1):page21_i164:a"
				( attribute "PN" "1"
					( Origin gPackager )
				)
				( objectStatus "R6N1.1" )
			)
			( pin "@baseboard_fab2_lib.baseboard_fab2(sch_1):page21_i164:b"
				( attribute "PN" "2"
					( Origin gPackager )
				)
				( objectStatus "R6N1.2" )
			)
			( pin "@baseboard_fab2_lib.baseboard_fab2(sch_1):page21_i177:a"
				( attribute "PN" "1"
					( Origin gPackager )
				)
				( objectStatus "R5D1.1" )
			)
			( pin "@baseboard_fab2_lib.baseboard_fab2(sch_1):page21_i177:b"
				( attribute "PN" "2"
					( Origin gPackager )
				)
				( objectStatus "R5D1.2" )
			)
			( pin "@baseboard_fab2_lib.baseboard_fab2(sch_1):page21_i178:a"
				( attribute "PN" "1"
					( Origin gPackager )
				)
				( objectStatus "R5D2.1" )
			)
			( pin "@baseboard_fab2_lib.baseboard_fab2(sch_1):page21_i178:b"
				( attribute "PN" "2"
					( Origin gPackager )
				)
				( objectStatus "R5D2.2" )
			)
			( pin "@baseboard_fab2_lib.baseboard_fab2(sch_1):page21_i179:a"
				( attribute "PN" "1"
					( Origin gPackager )
				)
				( objectStatus "R6D1.1" )
			)
			( pin "@baseboard_fab2_lib.baseboard_fab2(sch_1):page21_i179:b"
				( attribute "PN" "2"
					( Origin gPackager )
				)
				( objectStatus "R6D1.2" )
			)
			( pin "@baseboard_fab2_lib.baseboard_fab2(sch_1):page21_i180:a"
				( attribute "PN" "1"
					( Origin gPackager )
				)
				( objectStatus "R4P8.1" )
			)
			( pin "@baseboard_fab2_lib.baseboard_fab2(sch_1):page21_i180:b"
				( attribute "PN" "2"
					( Origin gPackager )
				)
				( objectStatus "R4P8.2" )
			)
			( pin "@baseboard_fab2_lib.baseboard_fab2(sch_1):page21_i181:a"
				( attribute "PN" "1"
					( Origin gPackager )
				)
				( objectStatus "R4P10.1" )
			)
			( pin "@baseboard_fab2_lib.baseboard_fab2(sch_1):page21_i181:b"
				( attribute "PN" "2"
					( Origin gPackager )
				)
				( objectStatus "R4P10.2" )
			)
			( pin "@baseboard_fab2_lib.baseboard_fab2(sch_1):page21_i182:a"
				( attribute "PN" "1"
					( Origin gPackager )
				)
				( objectStatus "R4P11.1" )
			)
			( pin "@baseboard_fab2_lib.baseboard_fab2(sch_1):page21_i182:b"
				( attribute "PN" "2"
					( Origin gPackager )
				)
				( objectStatus "R4P11.2" )
			)
			( pin "@baseboard_fab2_lib.baseboard_fab2(sch_1):page21_i184:a"
				( attribute "PN" "1"
					( Origin gPackager )
				)
				( objectStatus "R6D11.1" )
			)
			( pin "@baseboard_fab2_lib.baseboard_fab2(sch_1):page21_i184:b"
				( attribute "PN" "2"
					( Origin gPackager )
				)
				( objectStatus "R6D11.2" )
			)
			( pin "@baseboard_fab2_lib.baseboard_fab2(sch_1):page21_i186:a"
				( attribute "PN" "1"
					( Origin gPackager )
				)
				( objectStatus "R4P3.1" )
			)
			( pin "@baseboard_fab2_lib.baseboard_fab2(sch_1):page21_i186:b"
				( attribute "PN" "2"
					( Origin gPackager )
				)
				( objectStatus "R4P3.2" )
			)
			( pin "@baseboard_fab2_lib.baseboard_fab2(sch_1):page21_i188:a"
				( attribute "PN" "1"
					( Origin gPackager )
				)
				( objectStatus "R4P2.1" )
			)
			( pin "@baseboard_fab2_lib.baseboard_fab2(sch_1):page21_i188:b"
				( attribute "PN" "2"
					( Origin gPackager )
				)
				( objectStatus "R4P2.2" )
			)
			( pin "@baseboard_fab2_lib.baseboard_fab2(sch_1):page21_i189:a"
				( attribute "PN" "1"
					( Origin gPackager )
				)
				( objectStatus "R4P4.1" )
			)
			( pin "@baseboard_fab2_lib.baseboard_fab2(sch_1):page21_i189:b"
				( attribute "PN" "2"
					( Origin gPackager )
				)
				( objectStatus "R4P4.2" )
			)
			( pin "@baseboard_fab2_lib.baseboard_fab2(sch_1):page21_i204:a"
				( attribute "PN" "1"
					( Origin gPackager )
				)
				( objectStatus "R6D2.1" )
			)
			( pin "@baseboard_fab2_lib.baseboard_fab2(sch_1):page21_i204:b"
				( attribute "PN" "2"
					( Origin gPackager )
				)
				( objectStatus "R6D2.2" )
			)
			( pin "@baseboard_fab2_lib.baseboard_fab2(sch_1):page21_i219:a"
				( attribute "PN" "1"
					( Origin gPackager )
				)
				( objectStatus "R4P19.1" )
			)
			( pin "@baseboard_fab2_lib.baseboard_fab2(sch_1):page21_i219:b"
				( attribute "PN" "2"
					( Origin gPackager )
				)
				( objectStatus "R4P19.2" )
			)
			( pin "@baseboard_fab2_lib.baseboard_fab2(sch_1):page21_i227:a"
				( attribute "PN" "1"
					( Origin gPackager )
				)
				( objectStatus "R5N2.1" )
			)
			( pin "@baseboard_fab2_lib.baseboard_fab2(sch_1):page21_i227:b"
				( attribute "PN" "2"
					( Origin gPackager )
				)
				( objectStatus "R5N2.2" )
			)
			( pin "@baseboard_fab2_lib.baseboard_fab2(sch_1):page21_i238:a"
				( attribute "PN" "1"
					( Origin gPackager )
				)
				( objectStatus "R5N1.1" )
			)
			( pin "@baseboard_fab2_lib.baseboard_fab2(sch_1):page21_i238:b"
				( attribute "PN" "2"
					( Origin gPackager )
				)
				( objectStatus "R5N1.2" )
			)
			( pin "@baseboard_fab2_lib.baseboard_fab2(sch_1):page21_i239:a"
				( attribute "PN" "1"
					( Origin gPackager )
				)
				( objectStatus "R5N5.1" )
			)
			( pin "@baseboard_fab2_lib.baseboard_fab2(sch_1):page21_i239:b"
				( attribute "PN" "2"
					( Origin gPackager )
				)
				( objectStatus "R5N5.2" )
			)
			( pin "@baseboard_fab2_lib.baseboard_fab2(sch_1):page21_i240:a"
				( attribute "PN" "1"
					( Origin gPackager )
				)
				( objectStatus "R5N3.1" )
			)
			( pin "@baseboard_fab2_lib.baseboard_fab2(sch_1):page21_i240:b"
				( attribute "PN" "2"
					( Origin gPackager )
				)
				( objectStatus "R5N3.2" )
			)
			( pin "@baseboard_fab2_lib.baseboard_fab2(sch_1):page21_i241:a"
				( attribute "PN" "1"
					( Origin gPackager )
				)
				( objectStatus "R5N4.1" )
			)
			( pin "@baseboard_fab2_lib.baseboard_fab2(sch_1):page21_i241:b"
				( attribute "PN" "2"
					( Origin gPackager )
				)
				( objectStatus "R5N4.2" )
			)
			( pin "@baseboard_fab2_lib.baseboard_fab2(sch_1):page21_i244:a"
				( attribute "PN" "1"
					( Origin gPackager )
				)
				( objectStatus "R4P18.1" )
			)
			( pin "@baseboard_fab2_lib.baseboard_fab2(sch_1):page21_i244:b"
				( attribute "PN" "2"
					( Origin gPackager )
				)
				( objectStatus "R4P18.2" )
			)
			( pin "@baseboard_fab2_lib.baseboard_fab2(sch_1):page21_i258:a"
				( attribute "PN" "1"
					( Origin gPackager )
				)
				( objectStatus "R4R5.1" )
			)
			( pin "@baseboard_fab2_lib.baseboard_fab2(sch_1):page21_i258:b"
				( attribute "PN" "2"
					( Origin gPackager )
				)
				( objectStatus "R4R5.2" )
			)
			( pin "@baseboard_fab2_lib.baseboard_fab2(sch_1):page21_i259:bclk0_dn"
				( attribute "PN" "AU24"
					( Origin gPackager )
				)
				( objectStatus "U5D1.AU24" )
			)
			( pin "@baseboard_fab2_lib.baseboard_fab2(sch_1):page21_i259:bclk0_dp"
				( attribute "PN" "AW24"
					( Origin gPackager )
				)
				( objectStatus "U5D1.AW24" )
			)
			( pin "@baseboard_fab2_lib.baseboard_fab2(sch_1):page21_i259:bclk1_dn"
				( attribute "PN" "CR26"
					( Origin gPackager )
				)
				( objectStatus "U5D1.CR26" )
			)
			( pin "@baseboard_fab2_lib.baseboard_fab2(sch_1):page21_i259:bclk1_dp"
				( attribute "PN" "CP27"
					( Origin gPackager )
				)
				( objectStatus "U5D1.CP27" )
			)
			( pin "@baseboard_fab2_lib.baseboard_fab2(sch_1):page21_i259:bclk2_dn"
				( attribute "PN" "CT25"
					( Origin gPackager )
				)
				( objectStatus "U5D1.CT25" )
			)
			( pin "@baseboard_fab2_lib.baseboard_fab2(sch_1):page21_i259:bclk2_dp"
				( attribute "PN" "CU26"
					( Origin gPackager )
				)
				( objectStatus "U5D1.CU26" )
			)
			( pin "@baseboard_fab2_lib.baseboard_fab2(sch_1):page21_i259:bist_enable"
				( attribute "PN" "BA20"
					( Origin gPackager )
				)
				( objectStatus "U5D1.BA20" )
			)
			( pin "@baseboard_fab2_lib.baseboard_fab2(sch_1):page21_i259:bmcinit"
				( attribute "PN" "BD23"
					( Origin gPackager )
				)
				( objectStatus "U5D1.BD23" )
			)
			( pin "@baseboard_fab2_lib.baseboard_fab2(sch_1):page21_i259:bpm_n(0)"
				( attribute "PN" "AJ10"
					( Origin gPackager )
				)
				( objectStatus "U5D1.AJ10" )
			)
			( pin "@baseboard_fab2_lib.baseboard_fab2(sch_1):page21_i259:bpm_n(1)"
				( attribute "PN" "AH11"
					( Origin gPackager )
				)
				( objectStatus "U5D1.AH11" )
			)
			( pin "@baseboard_fab2_lib.baseboard_fab2(sch_1):page21_i259:bpm_n(2)"
				( attribute "PN" "AG10"
					( Origin gPackager )
				)
				( objectStatus "U5D1.AG10" )
			)
			( pin "@baseboard_fab2_lib.baseboard_fab2(sch_1):page21_i259:bpm_n(3)"
				( attribute "PN" "AF11"
					( Origin gPackager )
				)
				( objectStatus "U5D1.AF11" )
			)
			( pin "@baseboard_fab2_lib.baseboard_fab2(sch_1):page21_i259:bpm_n(4)"
				( attribute "PN" "AA12"
					( Origin gPackager )
				)
				( objectStatus "U5D1.AA12" )
			)
			( pin "@baseboard_fab2_lib.baseboard_fab2(sch_1):page21_i259:bpm_n(5)"
				( attribute "PN" "Y11"
					( Origin gPackager )
				)
				( objectStatus "U5D1.Y11" )
			)
			( pin "@baseboard_fab2_lib.baseboard_fab2(sch_1):page21_i259:bpm_n(6)"
				( attribute "PN" "AE12"
					( Origin gPackager )
				)
				( objectStatus "U5D1.AE12" )
			)
			( pin "@baseboard_fab2_lib.baseboard_fab2(sch_1):page21_i259:bpm_n(7)"
				( attribute "PN" "AC12"
					( Origin gPackager )
				)
				( objectStatus "U5D1.AC12" )
			)
			( pin "@baseboard_fab2_lib.baseboard_fab2(sch_1):page21_i259:caterr_n"
				( attribute "PN" "AL14"
					( Origin gPackager )
				)
				( objectStatus "U5D1.AL14" )
			)
			( pin "@baseboard_fab2_lib.baseboard_fab2(sch_1):page21_i259:ddr0_cavref"
				( attribute "PN" "AJ64"
					( Origin gPackager )
				)
				( objectStatus "U5D1.AJ64" )
			)
			( pin "@baseboard_fab2_lib.baseboard_fab2(sch_1):page21_i259:ddr1_cavref"
				( attribute "PN" "AK63"
					( Origin gPackager )
				)
				( objectStatus "U5D1.AK63" )
			)
			( pin "@baseboard_fab2_lib.baseboard_fab2(sch_1):page21_i259:ddr2_cavref"
				( attribute "PN" "AH63"
					( Origin gPackager )
				)
				( objectStatus "U5D1.AH63" )
			)
			( pin "@baseboard_fab2_lib.baseboard_fab2(sch_1):page21_i259:ddr3_cavref"
				( attribute "PN" "CP61"
					( Origin gPackager )
				)
				( objectStatus "U5D1.CP61" )
			)
			( pin "@baseboard_fab2_lib.baseboard_fab2(sch_1):page21_i259:ddr4_cavref"
				( attribute "PN" "CT61"
					( Origin gPackager )
				)
				( objectStatus "U5D1.CT61" )
			)
			( pin "@baseboard_fab2_lib.baseboard_fab2(sch_1):page21_i259:ddr5_cavref"
				( attribute "PN" "CV61"
					( Origin gPackager )
				)
				( objectStatus "U5D1.CV61" )
			)
			( pin "@baseboard_fab2_lib.baseboard_fab2(sch_1):page21_i259:ddr012_dram_pwr_ok"
				( attribute "PN" "AN30"
					( Origin gPackager )
				)
				( objectStatus "U5D1.AN30" )
			)
			( pin "@baseboard_fab2_lib.baseboard_fab2(sch_1):page21_i259:ddr012_rcomp(0)"
				( attribute "PN" "Y43"
					( Origin gPackager )
				)
				( objectStatus "U5D1.Y43" )
			)
			( pin "@baseboard_fab2_lib.baseboard_fab2(sch_1):page21_i259:ddr012_rcomp(1)"
				( attribute "PN" "AB43"
					( Origin gPackager )
				)
				( objectStatus "U5D1.AB43" )
			)
			( pin "@baseboard_fab2_lib.baseboard_fab2(sch_1):page21_i259:ddr012_rcomp(2)"
				( attribute "PN" "AC42"
					( Origin gPackager )
				)
				( objectStatus "U5D1.AC42" )
			)
			( pin "@baseboard_fab2_lib.baseboard_fab2(sch_1):page21_i259:ddr012_reset_n"
				( attribute "PN" "U64"
					( Origin gPackager )
				)
				( objectStatus "U5D1.U64" )
			)
			( pin "@baseboard_fab2_lib.baseboard_fab2(sch_1):page21_i259:ddr012_spdscl"
				( attribute "PN" "AJ18"
					( Origin gPackager )
				)
				( objectStatus "U5D1.AJ18" )
			)
			( pin "@baseboard_fab2_lib.baseboard_fab2(sch_1):page21_i259:ddr012_spdsda"
				( attribute "PN" "AF17"
					( Origin gPackager )
				)
				( objectStatus "U5D1.AF17" )
			)
			( pin "@baseboard_fab2_lib.baseboard_fab2(sch_1):page21_i259:ddr345_dram_pwr_ok"
				( attribute "PN" "CR28"
					( Origin gPackager )
				)
				( objectStatus "U5D1.CR28" )
			)
			( pin "@baseboard_fab2_lib.baseboard_fab2(sch_1):page21_i259:ddr345_rcomp(0)"
				( attribute "PN" "DC48"
					( Origin gPackager )
				)
				( objectStatus "U5D1.DC48" )
			)
			( pin "@baseboard_fab2_lib.baseboard_fab2(sch_1):page21_i259:ddr345_rcomp(1)"
				( attribute "PN" "DD47"
					( Origin gPackager )
				)
				( objectStatus "U5D1.DD47" )
			)
			( pin "@baseboard_fab2_lib.baseboard_fab2(sch_1):page21_i259:ddr345_rcomp(2)"
				( attribute "PN" "DD49"
					( Origin gPackager )
				)
				( objectStatus "U5D1.DD49" )
			)
			( pin "@baseboard_fab2_lib.baseboard_fab2(sch_1):page21_i259:ddr345_reset_n"
				( attribute "PN" "DV63"
					( Origin gPackager )
				)
				( objectStatus "U5D1.DV63" )
			)
			( pin "@baseboard_fab2_lib.baseboard_fab2(sch_1):page21_i259:ddr345_spdscl"
				( attribute "PN" "AE18"
					( Origin gPackager )
				)
				( objectStatus "U5D1.AE18" )
			)
			( pin "@baseboard_fab2_lib.baseboard_fab2(sch_1):page21_i259:ddr345_spdsda"
				( attribute "PN" "AD17"
					( Origin gPackager )
				)
				( objectStatus "U5D1.AD17" )
			)
			( pin "@baseboard_fab2_lib.baseboard_fab2(sch_1):page21_i259:ear_n"
				( attribute "PN" "AJ14"
					( Origin gPackager )
				)
				( objectStatus "U5D1.AJ14" )
			)
			( pin "@baseboard_fab2_lib.baseboard_fab2(sch_1):page21_i259:error_n(0)"
				( attribute "PN" "AJ12"
					( Origin gPackager )
				)
				( objectStatus "U5D1.AJ12" )
			)
			( pin "@baseboard_fab2_lib.baseboard_fab2(sch_1):page21_i259:error_n(1)"
				( attribute "PN" "AK11"
					( Origin gPackager )
				)
				( objectStatus "U5D1.AK11" )
			)
			( pin "@baseboard_fab2_lib.baseboard_fab2(sch_1):page21_i259:error_n(2)"
				( attribute "PN" "AL12"
					( Origin gPackager )
				)
				( objectStatus "U5D1.AL12" )
			)
			( pin "@baseboard_fab2_lib.baseboard_fab2(sch_1):page21_i259:frmagent"
				( attribute "PN" "AV17"
					( Origin gPackager )
				)
				( objectStatus "U5D1.AV17" )
			)
			( pin "@baseboard_fab2_lib.baseboard_fab2(sch_1):page21_i259:legacy_skt"
				( attribute "PN" "AE20"
					( Origin gPackager )
				)
				( objectStatus "U5D1.AE20" )
			)
			( pin "@baseboard_fab2_lib.baseboard_fab2(sch_1):page21_i259:mcp01_rbias(0)"
				( attribute "PN" "CU32"
					( Origin gPackager )
				)
				( objectStatus "U5D1.CU32" )
			)
			( pin "@baseboard_fab2_lib.baseboard_fab2(sch_1):page21_i259:mcp01_rbias(1)"
				( attribute "PN" "CT31"
					( Origin gPackager )
				)
				( objectStatus "U5D1.CT31" )
			)
			( pin "@baseboard_fab2_lib.baseboard_fab2(sch_1):page21_i259:mem_hot_c012_n"
				( attribute "PN" "AH13"
					( Origin gPackager )
				)
				( objectStatus "U5D1.AH13" )
			)
			( pin "@baseboard_fab2_lib.baseboard_fab2(sch_1):page21_i259:mem_hot_c345_n"
				( attribute "PN" "AF13"
					( Origin gPackager )
				)
				( objectStatus "U5D1.AF13" )
			)
			( pin "@baseboard_fab2_lib.baseboard_fab2(sch_1):page21_i259:msmi_n"
				( attribute "PN" "AN20"
					( Origin gPackager )
				)
				( objectStatus "U5D1.AN20" )
			)
			( pin "@baseboard_fab2_lib.baseboard_fab2(sch_1):page21_i259:nmi"
				( attribute "PN" "AP11"
					( Origin gPackager )
				)
				( objectStatus "U5D1.AP11" )
			)
			( pin "@baseboard_fab2_lib.baseboard_fab2(sch_1):page21_i259:pe3_rbias(0)"
				( attribute "PN" "CP29"
					( Origin gPackager )
				)
				( objectStatus "U5D1.CP29" )
			)
			( pin "@baseboard_fab2_lib.baseboard_fab2(sch_1):page21_i259:pe3_rbias(1)"
				( attribute "PN" "CR30"
					( Origin gPackager )
				)
				( objectStatus "U5D1.CR30" )
			)
			( pin "@baseboard_fab2_lib.baseboard_fab2(sch_1):page21_i259:pe012_rbias(0)"
				( attribute "PN" "CN30"
					( Origin gPackager )
				)
				( objectStatus "U5D1.CN30" )
			)
			( pin "@baseboard_fab2_lib.baseboard_fab2(sch_1):page21_i259:pe012_rbias(1)"
				( attribute "PN" "CL30"
					( Origin gPackager )
				)
				( objectStatus "U5D1.CL30" )
			)
			( pin "@baseboard_fab2_lib.baseboard_fab2(sch_1):page21_i259:pe_hp_scl"
				( attribute "PN" "AM19"
					( Origin gPackager )
				)
				( objectStatus "U5D1.AM19" )
			)
			( pin "@baseboard_fab2_lib.baseboard_fab2(sch_1):page21_i259:pe_hp_sda"
				( attribute "PN" "AL18"
					( Origin gPackager )
				)
				( objectStatus "U5D1.AL18" )
			)
			( pin "@baseboard_fab2_lib.baseboard_fab2(sch_1):page21_i259:peci"
				( attribute "PN" "AU12"
					( Origin gPackager )
				)
				( objectStatus "U5D1.AU12" )
			)
			( pin "@baseboard_fab2_lib.baseboard_fab2(sch_1):page21_i259:pirom_addr(0)"
				( attribute "PN" "CU58"
					( Origin gPackager )
				)
				( objectStatus "U5D1.CU58" )
			)
			( pin "@baseboard_fab2_lib.baseboard_fab2(sch_1):page21_i259:pirom_addr(1)"
				( attribute "PN" "CV57"
					( Origin gPackager )
				)
				( objectStatus "U5D1.CV57" )
			)
			( pin "@baseboard_fab2_lib.baseboard_fab2(sch_1):page21_i259:pirom_addr(2)"
				( attribute "PN" "CW56"
					( Origin gPackager )
				)
				( objectStatus "U5D1.CW56" )
			)
			( pin "@baseboard_fab2_lib.baseboard_fab2(sch_1):page21_i259:pkgid(0)"
				( attribute "PN" "DC72"
					( Origin gPackager )
				)
				( objectStatus "U5D1.DC72" )
			)
			( pin "@baseboard_fab2_lib.baseboard_fab2(sch_1):page21_i259:pkgid(1)"
				( attribute "PN" "CW72"
					( Origin gPackager )
				)
				( objectStatus "U5D1.CW72" )
			)
			( pin "@baseboard_fab2_lib.baseboard_fab2(sch_1):page21_i259:pkgid(2)"
				( attribute "PN" "DA72"
					( Origin gPackager )
				)
				( objectStatus "U5D1.DA72" )
			)
			( pin "@baseboard_fab2_lib.baseboard_fab2(sch_1):page21_i259:pm_fast_wake_n"
				( attribute "PN" "AF15"
					( Origin gPackager )
				)
				( objectStatus "U5D1.AF15" )
			)
			( pin "@baseboard_fab2_lib.baseboard_fab2(sch_1):page21_i259:pmsync"
				( attribute "PN" "AR14"
					( Origin gPackager )
				)
				( objectStatus "U5D1.AR14" )
			)
			( pin "@baseboard_fab2_lib.baseboard_fab2(sch_1):page21_i259:pmsync_clk"
				( attribute "PN" "AT19"
					( Origin gPackager )
				)
				( objectStatus "U5D1.AT19" )
			)
			( pin "@baseboard_fab2_lib.baseboard_fab2(sch_1):page21_i259:prdy_n"
				( attribute "PN" "AG16"
					( Origin gPackager )
				)
				( objectStatus "U5D1.AG16" )
			)
			( pin "@baseboard_fab2_lib.baseboard_fab2(sch_1):page21_i259:preq_n"
				( attribute "PN" "AR12"
					( Origin gPackager )
				)
				( objectStatus "U5D1.AR12" )
			)
			( pin "@baseboard_fab2_lib.baseboard_fab2(sch_1):page21_i259:proc_id(0)"
				( attribute "PN" "CY71"
					( Origin gPackager )
				)
				( objectStatus "U5D1.CY71" )
			)
			( pin "@baseboard_fab2_lib.baseboard_fab2(sch_1):page21_i259:proc_id(1)"
				( attribute "PN" "DB71"
					( Origin gPackager )
				)
				( objectStatus "U5D1.DB71" )
			)
			( pin "@baseboard_fab2_lib.baseboard_fab2(sch_1):page21_i259:procdis_n"
				( attribute "PN" "AB17"
					( Origin gPackager )
				)
				( objectStatus "U5D1.AB17" )
			)
			( pin "@baseboard_fab2_lib.baseboard_fab2(sch_1):page21_i259:prochot_n"
				( attribute "PN" "AC16"
					( Origin gPackager )
				)
				( objectStatus "U5D1.AC16" )
			)
			( pin "@baseboard_fab2_lib.baseboard_fab2(sch_1):page21_i259:pwrgood"
				( attribute "PN" "BC24"
					( Origin gPackager )
				)
				( objectStatus "U5D1.BC24" )
			)
			( pin "@baseboard_fab2_lib.baseboard_fab2(sch_1):page21_i259:reset_n"
				( attribute "PN" "AP21"
					( Origin gPackager )
				)
				( objectStatus "U5D1.AP21" )
			)
			( pin "@baseboard_fab2_lib.baseboard_fab2(sch_1):page21_i259:safe_mode_boot"
				( attribute "PN" "AR18"
					( Origin gPackager )
				)
				( objectStatus "U5D1.AR18" )
			)
			( pin "@baseboard_fab2_lib.baseboard_fab2(sch_1):page21_i259:sktocc_n"
				( attribute "PN" "AB13"
					( Origin gPackager )
				)
				( objectStatus "U5D1.AB13" )
			)
			( pin "@baseboard_fab2_lib.baseboard_fab2(sch_1):page21_i259:sm_wp"
				( attribute "PN" "CV59"
					( Origin gPackager )
				)
				( objectStatus "U5D1.CV59" )
			)
			( pin "@baseboard_fab2_lib.baseboard_fab2(sch_1):page21_i259:smbclk"
				( attribute "PN" "CT59"
					( Origin gPackager )
				)
				( objectStatus "U5D1.CT59" )
			)
			( pin "@baseboard_fab2_lib.baseboard_fab2(sch_1):page21_i259:smbdat"
				( attribute "PN" "CW58"
					( Origin gPackager )
				)
				( objectStatus "U5D1.CW58" )
			)
			( pin "@baseboard_fab2_lib.baseboard_fab2(sch_1):page21_i259:socket_id(0)"
				( attribute "PN" "AU22"
					( Origin gPackager )
				)
				( objectStatus "U5D1.AU22" )
			)
			( pin "@baseboard_fab2_lib.baseboard_fab2(sch_1):page21_i259:socket_id(1)"
				( attribute "PN" "AU16"
					( Origin gPackager )
				)
				( objectStatus "U5D1.AU16" )
			)
			( pin "@baseboard_fab2_lib.baseboard_fab2(sch_1):page21_i259:socket_id(2)"
				( attribute "PN" "AU20"
					( Origin gPackager )
				)
				( objectStatus "U5D1.AU20" )
			)
			( pin "@baseboard_fab2_lib.baseboard_fab2(sch_1):page21_i259:svidalert_n(0)"
				( attribute "PN" "DE44"
					( Origin gPackager )
				)
				( objectStatus "U5D1.DE44" )
			)
			( pin "@baseboard_fab2_lib.baseboard_fab2(sch_1):page21_i259:svidalert_n(1)"
				( attribute "PN" "DL44"
					( Origin gPackager )
				)
				( objectStatus "U5D1.DL44" )
			)
			( pin "@baseboard_fab2_lib.baseboard_fab2(sch_1):page21_i259:svidclk(0)"
				( attribute "PN" "DC44"
					( Origin gPackager )
				)
				( objectStatus "U5D1.DC44" )
			)
			( pin "@baseboard_fab2_lib.baseboard_fab2(sch_1):page21_i259:svidclk(1)"
				( attribute "PN" "DG44"
					( Origin gPackager )
				)
				( objectStatus "U5D1.DG44" )
			)
			( pin "@baseboard_fab2_lib.baseboard_fab2(sch_1):page21_i259:sviddata(0)"
				( attribute "PN" "DB45"
					( Origin gPackager )
				)
				( objectStatus "U5D1.DB45" )
			)
			( pin "@baseboard_fab2_lib.baseboard_fab2(sch_1):page21_i259:sviddata(1)"
				( attribute "PN" "DJ44"
					( Origin gPackager )
				)
				( objectStatus "U5D1.DJ44" )
			)
			( pin "@baseboard_fab2_lib.baseboard_fab2(sch_1):page21_i259:tck"
				( attribute "PN" "AA14"
					( Origin gPackager )
				)
				( objectStatus "U5D1.AA14" )
			)
			( pin "@baseboard_fab2_lib.baseboard_fab2(sch_1):page21_i259:tdi"
				( attribute "PN" "AC14"
					( Origin gPackager )
				)
				( objectStatus "U5D1.AC14" )
			)
			( pin "@baseboard_fab2_lib.baseboard_fab2(sch_1):page21_i259:tdo"
				( attribute "PN" "AE14"
					( Origin gPackager )
				)
				( objectStatus "U5D1.AE14" )
			)
			( pin "@baseboard_fab2_lib.baseboard_fab2(sch_1):page21_i259:test_12"
				( attribute "PN" "AY19"
					( Origin gPackager )
				)
				( objectStatus "U5D1.AY19" )
			)
			( pin "@baseboard_fab2_lib.baseboard_fab2(sch_1):page21_i259:test_13"
				( attribute "PN" "DB51"
					( Origin gPackager )
				)
				( objectStatus "U5D1.DB51" )
			)
			( pin "@baseboard_fab2_lib.baseboard_fab2(sch_1):page21_i259:test_14"
				( attribute "PN" "DC50"
					( Origin gPackager )
				)
				( objectStatus "U5D1.DC50" )
			)
			( pin "@baseboard_fab2_lib.baseboard_fab2(sch_1):page21_i259:test_15"
				( attribute "PN" "AW14"
					( Origin gPackager )
				)
				( objectStatus "U5D1.AW14" )
			)
			( pin "@baseboard_fab2_lib.baseboard_fab2(sch_1):page21_i259:thermtrip_n"
				( attribute "PN" "AB15"
					( Origin gPackager )
				)
				( objectStatus "U5D1.AB15" )
			)
			( pin "@baseboard_fab2_lib.baseboard_fab2(sch_1):page21_i259:tms"
				( attribute "PN" "W14"
					( Origin gPackager )
				)
				( objectStatus "U5D1.W14" )
			)
			( pin "@baseboard_fab2_lib.baseboard_fab2(sch_1):page21_i259:trst_n"
				( attribute "PN" "Y13"
					( Origin gPackager )
				)
				( objectStatus "U5D1.Y13" )
			)
			( pin "@baseboard_fab2_lib.baseboard_fab2(sch_1):page21_i259:tsc_sync"
				( attribute "PN" "AM11"
					( Origin gPackager )
				)
				( objectStatus "U5D1.AM11" )
			)
			( pin "@baseboard_fab2_lib.baseboard_fab2(sch_1):page21_i259:txt_agent"
				( attribute "PN" "AW18"
					( Origin gPackager )
				)
				( objectStatus "U5D1.AW18" )
			)
			( pin "@baseboard_fab2_lib.baseboard_fab2(sch_1):page21_i259:txt_plten"
				( attribute "PN" "AV15"
					( Origin gPackager )
				)
				( objectStatus "U5D1.AV15" )
			)
			( pin "@baseboard_fab2_lib.baseboard_fab2(sch_1):page21_i259:upi01_rbias(0)"
				( attribute "PN" "AT29"
					( Origin gPackager )
				)
				( objectStatus "U5D1.AT29" )
			)
			( pin "@baseboard_fab2_lib.baseboard_fab2(sch_1):page21_i259:upi01_rbias(1)"
				( attribute "PN" "AP29"
					( Origin gPackager )
				)
				( objectStatus "U5D1.AP29" )
			)
			( pin "@baseboard_fab2_lib.baseboard_fab2(sch_1):page21_i259:upi2_rbias(0)"
				( attribute "PN" "CL28"
					( Origin gPackager )
				)
				( objectStatus "U5D1.CL28" )
			)
			( pin "@baseboard_fab2_lib.baseboard_fab2(sch_1):page21_i259:upi2_rbias(1)"
				( attribute "PN" "CK29"
					( Origin gPackager )
				)
				( objectStatus "U5D1.CK29" )
			)
			( pin "@baseboard_fab2_lib.baseboard_fab2(sch_1):page22_i188:a"
				( attribute "PN" "1"
					( Origin gPackager )
				)
				( objectStatus "R5R1.1" )
			)
			( pin "@baseboard_fab2_lib.baseboard_fab2(sch_1):page22_i188:b"
				( attribute "PN" "2"
					( Origin gPackager )
				)
				( objectStatus "R5R1.2" )
			)
			( pin "@baseboard_fab2_lib.baseboard_fab2(sch_1):page22_i190:a"
				( attribute "PN" "1"
					( Origin gPackager )
				)
				( objectStatus "R5P4.1" )
			)
			( pin "@baseboard_fab2_lib.baseboard_fab2(sch_1):page22_i190:b"
				( attribute "PN" "2"
					( Origin gPackager )
				)
				( objectStatus "R5P4.2" )
			)
			( pin "@baseboard_fab2_lib.baseboard_fab2(sch_1):page22_i204:debug_en_n"
				( attribute "PN" "AV21"
					( Origin gPackager )
				)
				( objectStatus "U5D1.AV21" )
			)
			( pin "@baseboard_fab2_lib.baseboard_fab2(sch_1):page22_i204:dmimode_override"
				( attribute "PN" "AW12"
					( Origin gPackager )
				)
				( objectStatus "U5D1.AW12" )
			)
			( pin "@baseboard_fab2_lib.baseboard_fab2(sch_1):page22_i204:fivr_fault"
				( attribute "PN" "AU14"
					( Origin gPackager )
				)
				( objectStatus "U5D1.AU14" )
			)
			( pin "@baseboard_fab2_lib.baseboard_fab2(sch_1):page22_i204:pwr_debug_n"
				( attribute "PN" "AP17"
					( Origin gPackager )
				)
				( objectStatus "U5D1.AP17" )
			)
			( pin "@baseboard_fab2_lib.baseboard_fab2(sch_1):page22_i204:rsvd(194)"
				( attribute "PN" "AP61"
					( Origin gPackager )
				)
				( objectStatus "U5D1.AP61" )
			)
			( pin "@baseboard_fab2_lib.baseboard_fab2(sch_1):page22_i204:rsvd(195)"
				( attribute "PN" "AP27"
					( Origin gPackager )
				)
				( objectStatus "U5D1.AP27" )
			)
			( pin "@baseboard_fab2_lib.baseboard_fab2(sch_1):page22_i204:rsvd(196)"
				( attribute "PN" "AP25"
					( Origin gPackager )
				)
				( objectStatus "U5D1.AP25" )
			)
			( pin "@baseboard_fab2_lib.baseboard_fab2(sch_1):page22_i204:rsvd(197)"
				( attribute "PN" "AP23"
					( Origin gPackager )
				)
				( objectStatus "U5D1.AP23" )
			)
			( pin "@baseboard_fab2_lib.baseboard_fab2(sch_1):page22_i204:rsvd(198)"
				( attribute "PN" "AN62"
					( Origin gPackager )
				)
				( objectStatus "U5D1.AN62" )
			)
			( pin "@baseboard_fab2_lib.baseboard_fab2(sch_1):page22_i204:rsvd(199)"
				( attribute "PN" "AN60"
					( Origin gPackager )
				)
				( objectStatus "U5D1.AN60" )
			)
			( pin "@baseboard_fab2_lib.baseboard_fab2(sch_1):page22_i204:rsvd(200)"
				( attribute "PN" "AN26"
					( Origin gPackager )
				)
				( objectStatus "U5D1.AN26" )
			)
			( pin "@baseboard_fab2_lib.baseboard_fab2(sch_1):page22_i204:rsvd(201)"
				( attribute "PN" "AN24"
					( Origin gPackager )
				)
				( objectStatus "U5D1.AN24" )
			)
			( pin "@baseboard_fab2_lib.baseboard_fab2(sch_1):page22_i204:rsvd(202)"
				( attribute "PN" "AN22"
					( Origin gPackager )
				)
				( objectStatus "U5D1.AN22" )
			)
			( pin "@baseboard_fab2_lib.baseboard_fab2(sch_1):page22_i204:rsvd(203)"
				( attribute "PN" "AN18"
					( Origin gPackager )
				)
				( objectStatus "U5D1.AN18" )
			)
			( pin "@baseboard_fab2_lib.baseboard_fab2(sch_1):page22_i204:rsvd(204)"
				( attribute "PN" "AM61"
					( Origin gPackager )
				)
				( objectStatus "U5D1.AM61" )
			)
			( pin "@baseboard_fab2_lib.baseboard_fab2(sch_1):page22_i204:rsvd(205)"
				( attribute "PN" "AM59"
					( Origin gPackager )
				)
				( objectStatus "U5D1.AM59" )
			)
			( pin "@baseboard_fab2_lib.baseboard_fab2(sch_1):page22_i204:rsvd(206)"
				( attribute "PN" "AM27"
					( Origin gPackager )
				)
				( objectStatus "U5D1.AM27" )
			)
			( pin "@baseboard_fab2_lib.baseboard_fab2(sch_1):page22_i204:rsvd(207)"
				( attribute "PN" "AM25"
					( Origin gPackager )
				)
				( objectStatus "U5D1.AM25" )
			)
			( pin "@baseboard_fab2_lib.baseboard_fab2(sch_1):page22_i204:rsvd(208)"
				( attribute "PN" "AM23"
					( Origin gPackager )
				)
				( objectStatus "U5D1.AM23" )
			)
			( pin "@baseboard_fab2_lib.baseboard_fab2(sch_1):page22_i204:rsvd(209)"
				( attribute "PN" "AM21"
					( Origin gPackager )
				)
				( objectStatus "U5D1.AM21" )
			)
			( pin "@baseboard_fab2_lib.baseboard_fab2(sch_1):page22_i204:rsvd(210)"
				( attribute "PN" "AL62"
					( Origin gPackager )
				)
				( objectStatus "U5D1.AL62" )
			)
			( pin "@baseboard_fab2_lib.baseboard_fab2(sch_1):page22_i204:rsvd(211)"
				( attribute "PN" "AL60"
					( Origin gPackager )
				)
				( objectStatus "U5D1.AL60" )
			)
			( pin "@baseboard_fab2_lib.baseboard_fab2(sch_1):page22_i204:rsvd(212)"
				( attribute "PN" "AL58"
					( Origin gPackager )
				)
				( objectStatus "U5D1.AL58" )
			)
			( pin "@baseboard_fab2_lib.baseboard_fab2(sch_1):page22_i204:rsvd(213)"
				( attribute "PN" "AL26"
					( Origin gPackager )
				)
				( objectStatus "U5D1.AL26" )
			)
			( pin "@baseboard_fab2_lib.baseboard_fab2(sch_1):page22_i204:rsvd(214)"
				( attribute "PN" "AL22"
					( Origin gPackager )
				)
				( objectStatus "U5D1.AL22" )
			)
			( pin "@baseboard_fab2_lib.baseboard_fab2(sch_1):page22_i204:rsvd(215)"
				( attribute "PN" "AL20"
					( Origin gPackager )
				)
				( objectStatus "U5D1.AL20" )
			)
			( pin "@baseboard_fab2_lib.baseboard_fab2(sch_1):page22_i204:rsvd(216)"
				( attribute "PN" "AK69"
					( Origin gPackager )
				)
				( objectStatus "U5D1.AK69" )
			)
			( pin "@baseboard_fab2_lib.baseboard_fab2(sch_1):page22_i204:rsvd(217)"
				( attribute "PN" "AK61"
					( Origin gPackager )
				)
				( objectStatus "U5D1.AK61" )
			)
			( pin "@baseboard_fab2_lib.baseboard_fab2(sch_1):page22_i204:rsvd(218)"
				( attribute "PN" "AK59"
					( Origin gPackager )
				)
				( objectStatus "U5D1.AK59" )
			)
			( pin "@baseboard_fab2_lib.baseboard_fab2(sch_1):page22_i204:rsvd(219)"
				( attribute "PN" "AK57"
					( Origin gPackager )
				)
				( objectStatus "U5D1.AK57" )
			)
			( pin "@baseboard_fab2_lib.baseboard_fab2(sch_1):page22_i204:rsvd(220)"
				( attribute "PN" "AK27"
					( Origin gPackager )
				)
				( objectStatus "U5D1.AK27" )
			)
			( pin "@baseboard_fab2_lib.baseboard_fab2(sch_1):page22_i204:rsvd(221)"
				( attribute "PN" "AK21"
					( Origin gPackager )
				)
				( objectStatus "U5D1.AK21" )
			)
			( pin "@baseboard_fab2_lib.baseboard_fab2(sch_1):page22_i204:rsvd(222)"
				( attribute "PN" "AJ70"
					( Origin gPackager )
				)
				( objectStatus "U5D1.AJ70" )
			)
			( pin "@baseboard_fab2_lib.baseboard_fab2(sch_1):page22_i204:rsvd(223)"
				( attribute "PN" "AJ62"
					( Origin gPackager )
				)
				( objectStatus "U5D1.AJ62" )
			)
			( pin "@baseboard_fab2_lib.baseboard_fab2(sch_1):page22_i204:rsvd(224)"
				( attribute "PN" "AJ60"
					( Origin gPackager )
				)
				( objectStatus "U5D1.AJ60" )
			)
			( pin "@baseboard_fab2_lib.baseboard_fab2(sch_1):page22_i204:rsvd(225)"
				( attribute "PN" "AJ58"
					( Origin gPackager )
				)
				( objectStatus "U5D1.AJ58" )
			)
			( pin "@baseboard_fab2_lib.baseboard_fab2(sch_1):page22_i204:rsvd(226)"
				( attribute "PN" "AJ56"
					( Origin gPackager )
				)
				( objectStatus "U5D1.AJ56" )
			)
			( pin "@baseboard_fab2_lib.baseboard_fab2(sch_1):page22_i204:rsvd(227)"
				( attribute "PN" "AJ20"
					( Origin gPackager )
				)
				( objectStatus "U5D1.AJ20" )
			)
			( pin "@baseboard_fab2_lib.baseboard_fab2(sch_1):page22_i204:rsvd(228)"
				( attribute "PN" "AH73"
					( Origin gPackager )
				)
				( objectStatus "U5D1.AH73" )
			)
			( pin "@baseboard_fab2_lib.baseboard_fab2(sch_1):page22_i204:rsvd(229)"
				( attribute "PN" "AH71"
					( Origin gPackager )
				)
				( objectStatus "U5D1.AH71" )
			)
			( pin "@baseboard_fab2_lib.baseboard_fab2(sch_1):page22_i204:rsvd(230)"
				( attribute "PN" "AH57"
					( Origin gPackager )
				)
				( objectStatus "U5D1.AH57" )
			)
			( pin "@baseboard_fab2_lib.baseboard_fab2(sch_1):page22_i204:rsvd(231)"
				( attribute "PN" "AH55"
					( Origin gPackager )
				)
				( objectStatus "U5D1.AH55" )
			)
			( pin "@baseboard_fab2_lib.baseboard_fab2(sch_1):page22_i204:rsvd(232)"
				( attribute "PN" "AH19"
					( Origin gPackager )
				)
				( objectStatus "U5D1.AH19" )
			)
			( pin "@baseboard_fab2_lib.baseboard_fab2(sch_1):page22_i204:rsvd(233)"
				( attribute "PN" "AH15"
					( Origin gPackager )
				)
				( objectStatus "U5D1.AH15" )
			)
			( pin "@baseboard_fab2_lib.baseboard_fab2(sch_1):page22_i204:rsvd(234)"
				( attribute "PN" "AG72"
					( Origin gPackager )
				)
				( objectStatus "U5D1.AG72" )
			)
			( pin "@baseboard_fab2_lib.baseboard_fab2(sch_1):page22_i204:rsvd(235)"
				( attribute "PN" "AG56"
					( Origin gPackager )
				)
				( objectStatus "U5D1.AG56" )
			)
			( pin "@baseboard_fab2_lib.baseboard_fab2(sch_1):page22_i204:rsvd(236)"
				( attribute "PN" "AG54"
					( Origin gPackager )
				)
				( objectStatus "U5D1.AG54" )
			)
			( pin "@baseboard_fab2_lib.baseboard_fab2(sch_1):page22_i204:rsvd(237)"
				( attribute "PN" "AG52"
					( Origin gPackager )
				)
				( objectStatus "U5D1.AG52" )
			)
			( pin "@baseboard_fab2_lib.baseboard_fab2(sch_1):page22_i204:rsvd(238)"
				( attribute "PN" "AG50"
					( Origin gPackager )
				)
				( objectStatus "U5D1.AG50" )
			)
			( pin "@baseboard_fab2_lib.baseboard_fab2(sch_1):page22_i204:rsvd(239)"
				( attribute "PN" "AG48"
					( Origin gPackager )
				)
				( objectStatus "U5D1.AG48" )
			)
			( pin "@baseboard_fab2_lib.baseboard_fab2(sch_1):page22_i204:rsvd(240)"
				( attribute "PN" "AG20"
					( Origin gPackager )
				)
				( objectStatus "U5D1.AG20" )
			)
			( pin "@baseboard_fab2_lib.baseboard_fab2(sch_1):page22_i204:rsvd(241)"
				( attribute "PN" "AF71"
					( Origin gPackager )
				)
				( objectStatus "U5D1.AF71" )
			)
			( pin "@baseboard_fab2_lib.baseboard_fab2(sch_1):page22_i204:rsvd(242)"
				( attribute "PN" "AF53"
					( Origin gPackager )
				)
				( objectStatus "U5D1.AF53" )
			)
			( pin "@baseboard_fab2_lib.baseboard_fab2(sch_1):page22_i204:rsvd(243)"
				( attribute "PN" "AF51"
					( Origin gPackager )
				)
				( objectStatus "U5D1.AF51" )
			)
			( pin "@baseboard_fab2_lib.baseboard_fab2(sch_1):page22_i204:rsvd(244)"
				( attribute "PN" "AF49"
					( Origin gPackager )
				)
				( objectStatus "U5D1.AF49" )
			)
			( pin "@baseboard_fab2_lib.baseboard_fab2(sch_1):page22_i204:rsvd(245)"
				( attribute "PN" "AF47"
					( Origin gPackager )
				)
				( objectStatus "U5D1.AF47" )
			)
			( pin "@baseboard_fab2_lib.baseboard_fab2(sch_1):page22_i204:rsvd(246)"
				( attribute "PN" "AF19"
					( Origin gPackager )
				)
				( objectStatus "U5D1.AF19" )
			)
			( pin "@baseboard_fab2_lib.baseboard_fab2(sch_1):page22_i204:rsvd(247)"
				( attribute "PN" "AE72"
					( Origin gPackager )
				)
				( objectStatus "U5D1.AE72" )
			)
			( pin "@baseboard_fab2_lib.baseboard_fab2(sch_1):page22_i204:rsvd(248)"
				( attribute "PN" "AE52"
					( Origin gPackager )
				)
				( objectStatus "U5D1.AE52" )
			)
			( pin "@baseboard_fab2_lib.baseboard_fab2(sch_1):page22_i204:rsvd(249)"
				( attribute "PN" "AE50"
					( Origin gPackager )
				)
				( objectStatus "U5D1.AE50" )
			)
			( pin "@baseboard_fab2_lib.baseboard_fab2(sch_1):page22_i204:rsvd(250)"
				( attribute "PN" "AE48"
					( Origin gPackager )
				)
				( objectStatus "U5D1.AE48" )
			)
			( pin "@baseboard_fab2_lib.baseboard_fab2(sch_1):page22_i204:rsvd(251)"
				( attribute "PN" "AE46"
					( Origin gPackager )
				)
				( objectStatus "U5D1.AE46" )
			)
			( pin "@baseboard_fab2_lib.baseboard_fab2(sch_1):page22_i204:rsvd(252)"
				( attribute "PN" "AD51"
					( Origin gPackager )
				)
				( objectStatus "U5D1.AD51" )
			)
			( pin "@baseboard_fab2_lib.baseboard_fab2(sch_1):page22_i204:rsvd(253)"
				( attribute "PN" "AD49"
					( Origin gPackager )
				)
				( objectStatus "U5D1.AD49" )
			)
			( pin "@baseboard_fab2_lib.baseboard_fab2(sch_1):page22_i204:rsvd(254)"
				( attribute "PN" "AD47"
					( Origin gPackager )
				)
				( objectStatus "U5D1.AD47" )
			)
			( pin "@baseboard_fab2_lib.baseboard_fab2(sch_1):page22_i204:rsvd(255)"
				( attribute "CDS_NOT_ON_SYM" "TRUE"
					( Origin gFrontEnd )
				)
			)
			( pin "@baseboard_fab2_lib.baseboard_fab2(sch_1):page22_i204:rsvd(256)"
				( attribute "PN" "Y65"
					( Origin gPackager )
				)
				( objectStatus "U5D1.Y65" )
			)
			( pin "@baseboard_fab2_lib.baseboard_fab2(sch_1):page22_i204:rsvd(257)"
				( attribute "PN" "Y23"
					( Origin gPackager )
				)
				( objectStatus "U5D1.Y23" )
			)
			( pin "@baseboard_fab2_lib.baseboard_fab2(sch_1):page22_i204:rsvd(258)"
				( attribute "PN" "W66"
					( Origin gPackager )
				)
				( objectStatus "U5D1.W66" )
			)
			( pin "@baseboard_fab2_lib.baseboard_fab2(sch_1):page22_i204:rsvd(259)"
				( attribute "PN" "V67"
					( Origin gPackager )
				)
				( objectStatus "U5D1.V67" )
			)
			( pin "@baseboard_fab2_lib.baseboard_fab2(sch_1):page22_i204:rsvd(260)"
				( attribute "PN" "V65"
					( Origin gPackager )
				)
				( objectStatus "U5D1.V65" )
			)
			( pin "@baseboard_fab2_lib.baseboard_fab2(sch_1):page22_i204:rsvd(261)"
				( attribute "PN" "U66"
					( Origin gPackager )
				)
				( objectStatus "U5D1.U66" )
			)
			( pin "@baseboard_fab2_lib.baseboard_fab2(sch_1):page22_i204:rsvd(262)"
				( attribute "PN" "T67"
					( Origin gPackager )
				)
				( objectStatus "U5D1.T67" )
			)
			( pin "@baseboard_fab2_lib.baseboard_fab2(sch_1):page22_i204:rsvd(263)"
				( attribute "PN" "R66"
					( Origin gPackager )
				)
				( objectStatus "U5D1.R66" )
			)
			( pin "@baseboard_fab2_lib.baseboard_fab2(sch_1):page22_i204:rsvd(264)"
				( attribute "PN" "R62"
					( Origin gPackager )
				)
				( objectStatus "U5D1.R62" )
			)
			( pin "@baseboard_fab2_lib.baseboard_fab2(sch_1):page22_i204:rsvd(265)"
				( attribute "PN" "P65"
					( Origin gPackager )
				)
				( objectStatus "U5D1.P65" )
			)
			( pin "@baseboard_fab2_lib.baseboard_fab2(sch_1):page22_i204:rsvd(266)"
				( attribute "PN" "M63"
					( Origin gPackager )
				)
				( objectStatus "U5D1.M63" )
			)
			( pin "@baseboard_fab2_lib.baseboard_fab2(sch_1):page22_i204:rsvd(267)"
				( attribute "PN" "K61"
					( Origin gPackager )
				)
				( objectStatus "U5D1.K61" )
			)
			( pin "@baseboard_fab2_lib.baseboard_fab2(sch_1):page22_i204:rsvd(268)"
				( attribute "PN" "J62"
					( Origin gPackager )
				)
				( objectStatus "U5D1.J62" )
			)
			( pin "@baseboard_fab2_lib.baseboard_fab2(sch_1):page22_i204:rsvd(269)"
				( attribute "PN" "J46"
					( Origin gPackager )
				)
				( objectStatus "U5D1.J46" )
			)
			( pin "@baseboard_fab2_lib.baseboard_fab2(sch_1):page22_i204:rsvd(270)"
				( attribute "PN" "H85"
					( Origin gPackager )
				)
				( objectStatus "U5D1.H85" )
			)
			( pin "@baseboard_fab2_lib.baseboard_fab2(sch_1):page22_i204:rsvd(271)"
				( attribute "PN" "H83"
					( Origin gPackager )
				)
				( objectStatus "U5D1.H83" )
			)
			( pin "@baseboard_fab2_lib.baseboard_fab2(sch_1):page22_i204:rsvd(272)"
				( attribute "PN" "H1"
					( Origin gPackager )
				)
				( objectStatus "U5D1.H1" )
			)
			( pin "@baseboard_fab2_lib.baseboard_fab2(sch_1):page22_i204:rsvd(273)"
				( attribute "PN" "G84"
					( Origin gPackager )
				)
				( objectStatus "U5D1.G84" )
			)
			( pin "@baseboard_fab2_lib.baseboard_fab2(sch_1):page22_i204:rsvd(274)"
				( attribute "PN" "G64"
					( Origin gPackager )
				)
				( objectStatus "U5D1.G64" )
			)
			( pin "@baseboard_fab2_lib.baseboard_fab2(sch_1):page22_i204:rsvd(275)"
				( attribute "PN" "G2"
					( Origin gPackager )
				)
				( objectStatus "U5D1.G2" )
			)
			( pin "@baseboard_fab2_lib.baseboard_fab2(sch_1):page22_i204:rsvd(276)"
				( attribute "PN" "F83"
					( Origin gPackager )
				)
				( objectStatus "U5D1.F83" )
			)
			( pin "@baseboard_fab2_lib.baseboard_fab2(sch_1):page22_i204:rsvd(277)"
				( attribute "PN" "F65"
					( Origin gPackager )
				)
				( objectStatus "U5D1.F65" )
			)
			( pin "@baseboard_fab2_lib.baseboard_fab2(sch_1):page22_i204:rsvd(278)"
				( attribute "PN" "F23"
					( Origin gPackager )
				)
				( objectStatus "U5D1.F23" )
			)
			( pin "@baseboard_fab2_lib.baseboard_fab2(sch_1):page22_i204:rsvd(279)"
				( attribute "PN" "F3"
					( Origin gPackager )
				)
				( objectStatus "U5D1.F3" )
			)
			( pin "@baseboard_fab2_lib.baseboard_fab2(sch_1):page22_i204:rsvd(280)"
				( attribute "PN" "E84"
					( Origin gPackager )
				)
				( objectStatus "U5D1.E84" )
			)
			( pin "@baseboard_fab2_lib.baseboard_fab2(sch_1):page22_i204:rsvd(281)"
				( attribute "PN" "E24"
					( Origin gPackager )
				)
				( objectStatus "U5D1.E24" )
			)
			( pin "@baseboard_fab2_lib.baseboard_fab2(sch_1):page22_i204:rsvd(282)"
				( attribute "PN" "E4"
					( Origin gPackager )
				)
				( objectStatus "U5D1.E4" )
			)
			( pin "@baseboard_fab2_lib.baseboard_fab2(sch_1):page22_i204:rsvd(283)"
				( attribute "PN" "E2"
					( Origin gPackager )
				)
				( objectStatus "U5D1.E2" )
			)
			( pin "@baseboard_fab2_lib.baseboard_fab2(sch_1):page22_i204:rsvd(284)"
				( attribute "PN" "D83"
					( Origin gPackager )
				)
				( objectStatus "U5D1.D83" )
			)
			( pin "@baseboard_fab2_lib.baseboard_fab2(sch_1):page22_i204:rsvd(285)"
				( attribute "PN" "D65"
					( Origin gPackager )
				)
				( objectStatus "U5D1.D65" )
			)
			( pin "@baseboard_fab2_lib.baseboard_fab2(sch_1):page22_i204:rsvd(286)"
				( attribute "PN" "D17"
					( Origin gPackager )
				)
				( objectStatus "U5D1.D17" )
			)
			( pin "@baseboard_fab2_lib.baseboard_fab2(sch_1):page22_i204:rsvd(287)"
				( attribute "PN" "D5"
					( Origin gPackager )
				)
				( objectStatus "U5D1.D5" )
			)
			( pin "@baseboard_fab2_lib.baseboard_fab2(sch_1):page22_i204:rsvd(288)"
				( attribute "PN" "C82"
					( Origin gPackager )
				)
				( objectStatus "U5D1.C82" )
			)
			( pin "@baseboard_fab2_lib.baseboard_fab2(sch_1):page22_i204:rsvd(289)"
				( attribute "PN" "C24"
					( Origin gPackager )
				)
				( objectStatus "U5D1.C24" )
			)
			( pin "@baseboard_fab2_lib.baseboard_fab2(sch_1):page22_i204:rsvd(290)"
				( attribute "PN" "C18"
					( Origin gPackager )
				)
				( objectStatus "U5D1.C18" )
			)
			( pin "@baseboard_fab2_lib.baseboard_fab2(sch_1):page22_i204:rsvd(291)"
				( attribute "PN" "C6"
					( Origin gPackager )
				)
				( objectStatus "U5D1.C6" )
			)
			( pin "@baseboard_fab2_lib.baseboard_fab2(sch_1):page22_i204:rsvd(292)"
				( attribute "PN" "B81"
					( Origin gPackager )
				)
				( objectStatus "U5D1.B81" )
			)
			( pin "@baseboard_fab2_lib.baseboard_fab2(sch_1):page22_i204:rsvd(293)"
				( attribute "PN" "B77"
					( Origin gPackager )
				)
				( objectStatus "U5D1.B77" )
			)
			( pin "@baseboard_fab2_lib.baseboard_fab2(sch_1):page22_i204:rsvd(294)"
				( attribute "PN" "B17"
					( Origin gPackager )
				)
				( objectStatus "U5D1.B17" )
			)
			( pin "@baseboard_fab2_lib.baseboard_fab2(sch_1):page22_i204:rsvd(295)"
				( attribute "PN" "B15"
					( Origin gPackager )
				)
				( objectStatus "U5D1.B15" )
			)
			( pin "@baseboard_fab2_lib.baseboard_fab2(sch_1):page22_i204:rsvd(296)"
				( attribute "PN" "B13"
					( Origin gPackager )
				)
				( objectStatus "U5D1.B13" )
			)
			( pin "@baseboard_fab2_lib.baseboard_fab2(sch_1):page22_i204:rsvd(297)"
				( attribute "CDS_NOT_ON_SYM" "TRUE"
					( Origin gFrontEnd )
				)
			)
			( pin "@baseboard_fab2_lib.baseboard_fab2(sch_1):page22_i204:rsvd(298)"
				( attribute "PN" "B7"
					( Origin gPackager )
				)
				( objectStatus "U5D1.B7" )
			)
			( pin "@baseboard_fab2_lib.baseboard_fab2(sch_1):page22_i204:rsvd(299)"
				( attribute "PN" "B3"
					( Origin gPackager )
				)
				( objectStatus "U5D1.B3" )
			)
			( pin "@baseboard_fab2_lib.baseboard_fab2(sch_1):page22_i204:rsvd(300)"
				( attribute "PN" "A24"
					( Origin gPackager )
				)
				( objectStatus "U5D1.A24" )
			)
			( pin "@baseboard_fab2_lib.baseboard_fab2(sch_1):page22_i204:rsvd(301)"
				( attribute "PN" "A16"
					( Origin gPackager )
				)
				( objectStatus "U5D1.A16" )
			)
			( pin "@baseboard_fab2_lib.baseboard_fab2(sch_1):page22_i204:rsvd(302)"
				( attribute "PN" "A14"
					( Origin gPackager )
				)
				( objectStatus "U5D1.A14" )
			)
			( pin "@baseboard_fab2_lib.baseboard_fab2(sch_1):page22_i204:rsvd(303)"
				( attribute "PN" "A6"
					( Origin gPackager )
				)
				( objectStatus "U5D1.A6" )
			)
			( pin "@baseboard_fab2_lib.baseboard_fab2(sch_1):page22_i204:rsvd(304)"
				( attribute "PN" "A4"
					( Origin gPackager )
				)
				( objectStatus "U5D1.A4" )
			)
			( pin "@baseboard_fab2_lib.baseboard_fab2(sch_1):page22_i204:test_1"
				( attribute "PN" "AF45"
					( Origin gPackager )
				)
				( objectStatus "U5D1.AF45" )
			)
			( pin "@baseboard_fab2_lib.baseboard_fab2(sch_1):page22_i204:test_2"
				( attribute "PN" "AG46"
					( Origin gPackager )
				)
				( objectStatus "U5D1.AG46" )
			)
			( pin "@baseboard_fab2_lib.baseboard_fab2(sch_1):page22_i204:test_3"
				( attribute "PN" "AM13"
					( Origin gPackager )
				)
				( objectStatus "U5D1.AM13" )
			)
			( pin "@baseboard_fab2_lib.baseboard_fab2(sch_1):page22_i204:test_4"
				( attribute "PN" "AN12"
					( Origin gPackager )
				)
				( objectStatus "U5D1.AN12" )
			)
			( pin "@baseboard_fab2_lib.baseboard_fab2(sch_1):page22_i204:test_5"
				( attribute "PN" "AN14"
					( Origin gPackager )
				)
				( objectStatus "U5D1.AN14" )
			)
			( pin "@baseboard_fab2_lib.baseboard_fab2(sch_1):page22_i204:test_11"
				( attribute "PN" "AY13"
					( Origin gPackager )
				)
				( objectStatus "U5D1.AY13" )
			)
			( pin "@baseboard_fab2_lib.baseboard_fab2(sch_1):page23_i172:ddr0_act_n"
				( attribute "PN" "J60"
					( Origin gPackager )
				)
				( objectStatus "U5D1.J60" )
			)
			( pin "@baseboard_fab2_lib.baseboard_fab2(sch_1):page23_i172:ddr0_alert_n"
				( attribute "PN" "B61"
					( Origin gPackager )
				)
				( objectStatus "U5D1.B61" )
			)
			( pin "@baseboard_fab2_lib.baseboard_fab2(sch_1):page23_i172:ddr0_ba(0)"
				( attribute "PN" "C52"
					( Origin gPackager )
				)
				( objectStatus "U5D1.C52" )
			)
			( pin "@baseboard_fab2_lib.baseboard_fab2(sch_1):page23_i172:ddr0_ba(1)"
				( attribute "PN" "G54"
					( Origin gPackager )
				)
				( objectStatus "U5D1.G54" )
			)
			( pin "@baseboard_fab2_lib.baseboard_fab2(sch_1):page23_i172:ddr0_bg(0)"
				( attribute "PN" "D61"
					( Origin gPackager )
				)
				( objectStatus "U5D1.D61" )
			)
			( pin "@baseboard_fab2_lib.baseboard_fab2(sch_1):page23_i172:ddr0_bg(1)"
				( attribute "PN" "F63"
					( Origin gPackager )
				)
				( objectStatus "U5D1.F63" )
			)
			( pin "@baseboard_fab2_lib.baseboard_fab2(sch_1):page23_i172:ddr0_cid(2)"
				( attribute "PN" "G46"
					( Origin gPackager )
				)
				( objectStatus "U5D1.G46" )
			)
			( pin "@baseboard_fab2_lib.baseboard_fab2(sch_1):page23_i172:ddr0_cke(0)"
				( attribute "PN" "C62"
					( Origin gPackager )
				)
				( objectStatus "U5D1.C62" )
			)
			( pin "@baseboard_fab2_lib.baseboard_fab2(sch_1):page23_i172:ddr0_cke(1)"
				( attribute "PN" "C64"
					( Origin gPackager )
				)
				( objectStatus "U5D1.C64" )
			)
			( pin "@baseboard_fab2_lib.baseboard_fab2(sch_1):page23_i172:ddr0_cke(2)"
				( attribute "PN" "B63"
					( Origin gPackager )
				)
				( objectStatus "U5D1.B63" )
			)
			( pin "@baseboard_fab2_lib.baseboard_fab2(sch_1):page23_i172:ddr0_cke(3)"
				( attribute "PN" "D63"
					( Origin gPackager )
				)
				( objectStatus "U5D1.D63" )
			)
			( pin "@baseboard_fab2_lib.baseboard_fab2(sch_1):page23_i172:ddr0_clk_dn(0)"
				( attribute "PN" "F55"
					( Origin gPackager )
				)
				( objectStatus "U5D1.F55" )
			)
			( pin "@baseboard_fab2_lib.baseboard_fab2(sch_1):page23_i172:ddr0_clk_dn(1)"
				( attribute "PN" "C54"
					( Origin gPackager )
				)
				( objectStatus "U5D1.C54" )
			)
			( pin "@baseboard_fab2_lib.baseboard_fab2(sch_1):page23_i172:ddr0_clk_dn(2)"
				( attribute "PN" "J56"
					( Origin gPackager )
				)
				( objectStatus "U5D1.J56" )
			)
			( pin "@baseboard_fab2_lib.baseboard_fab2(sch_1):page23_i172:ddr0_clk_dn(3)"
				( attribute "PN" "C56"
					( Origin gPackager )
				)
				( objectStatus "U5D1.C56" )
			)
			( pin "@baseboard_fab2_lib.baseboard_fab2(sch_1):page23_i172:ddr0_clk_dp(0)"
				( attribute "PN" "D55"
					( Origin gPackager )
				)
				( objectStatus "U5D1.D55" )
			)
			( pin "@baseboard_fab2_lib.baseboard_fab2(sch_1):page23_i172:ddr0_clk_dp(1)"
				( attribute "PN" "B55"
					( Origin gPackager )
				)
				( objectStatus "U5D1.B55" )
			)
			( pin "@baseboard_fab2_lib.baseboard_fab2(sch_1):page23_i172:ddr0_clk_dp(2)"
				( attribute "PN" "G56"
					( Origin gPackager )
				)
				( objectStatus "U5D1.G56" )
			)
			( pin "@baseboard_fab2_lib.baseboard_fab2(sch_1):page23_i172:ddr0_clk_dp(3)"
				( attribute "PN" "B57"
					( Origin gPackager )
				)
				( objectStatus "U5D1.B57" )
			)
			( pin "@baseboard_fab2_lib.baseboard_fab2(sch_1):page23_i172:ddr0_cs_n(0)"
				( attribute "PN" "G52"
					( Origin gPackager )
				)
				( objectStatus "U5D1.G52" )
			)
			( pin "@baseboard_fab2_lib.baseboard_fab2(sch_1):page23_i172:ddr0_cs_n(1)"
				( attribute "PN" "F49"
					( Origin gPackager )
				)
				( objectStatus "U5D1.F49" )
			)
			( pin "@baseboard_fab2_lib.baseboard_fab2(sch_1):page23_i172:ddr0_cs_n(2)"
				( attribute "PN" "D47"
					( Origin gPackager )
				)
				( objectStatus "U5D1.D47" )
			)
			( pin "@baseboard_fab2_lib.baseboard_fab2(sch_1):page23_i172:ddr0_cs_n(3)"
				( attribute "PN" "F47"
					( Origin gPackager )
				)
				( objectStatus "U5D1.F47" )
			)
			( pin "@baseboard_fab2_lib.baseboard_fab2(sch_1):page23_i172:ddr0_cs_n(4)"
				( attribute "PN" "B51"
					( Origin gPackager )
				)
				( objectStatus "U5D1.B51" )
			)
			( pin "@baseboard_fab2_lib.baseboard_fab2(sch_1):page23_i172:ddr0_cs_n(5)"
				( attribute "PN" "D49"
					( Origin gPackager )
				)
				( objectStatus "U5D1.D49" )
			)
			( pin "@baseboard_fab2_lib.baseboard_fab2(sch_1):page23_i172:ddr0_cs_n(6)"
				( attribute "PN" "F45"
					( Origin gPackager )
				)
				( objectStatus "U5D1.F45" )
			)
			( pin "@baseboard_fab2_lib.baseboard_fab2(sch_1):page23_i172:ddr0_cs_n(7)"
				( attribute "PN" "K45"
					( Origin gPackager )
				)
				( objectStatus "U5D1.K45" )
			)
			( pin "@baseboard_fab2_lib.baseboard_fab2(sch_1):page23_i172:ddr0_dq(0)"
				( attribute "PN" "AN86"
					( Origin gPackager )
				)
				( objectStatus "U5D1.AN86" )
			)
			( pin "@baseboard_fab2_lib.baseboard_fab2(sch_1):page23_i172:ddr0_dq(1)"
				( attribute "PN" "AN84"
					( Origin gPackager )
				)
				( objectStatus "U5D1.AN84" )
			)
			( pin "@baseboard_fab2_lib.baseboard_fab2(sch_1):page23_i172:ddr0_dq(2)"
				( attribute "PN" "AE86"
					( Origin gPackager )
				)
				( objectStatus "U5D1.AE86" )
			)
			( pin "@baseboard_fab2_lib.baseboard_fab2(sch_1):page23_i172:ddr0_dq(3)"
				( attribute "PN" "AE84"
					( Origin gPackager )
				)
				( objectStatus "U5D1.AE84" )
			)
			( pin "@baseboard_fab2_lib.baseboard_fab2(sch_1):page23_i172:ddr0_dq(4)"
				( attribute "PN" "AR86"
					( Origin gPackager )
				)
				( objectStatus "U5D1.AR86" )
			)
			( pin "@baseboard_fab2_lib.baseboard_fab2(sch_1):page23_i172:ddr0_dq(5)"
				( attribute "PN" "AR84"
					( Origin gPackager )
				)
				( objectStatus "U5D1.AR84" )
			)
			( pin "@baseboard_fab2_lib.baseboard_fab2(sch_1):page23_i172:ddr0_dq(6)"
				( attribute "PN" "AG86"
					( Origin gPackager )
				)
				( objectStatus "U5D1.AG86" )
			)
			( pin "@baseboard_fab2_lib.baseboard_fab2(sch_1):page23_i172:ddr0_dq(7)"
				( attribute "PN" "AG84"
					( Origin gPackager )
				)
				( objectStatus "U5D1.AG84" )
			)
			( pin "@baseboard_fab2_lib.baseboard_fab2(sch_1):page23_i172:ddr0_dq(8)"
				( attribute "PN" "W86"
					( Origin gPackager )
				)
				( objectStatus "U5D1.W86" )
			)
			( pin "@baseboard_fab2_lib.baseboard_fab2(sch_1):page23_i172:ddr0_dq(9)"
				( attribute "PN" "W84"
					( Origin gPackager )
				)
				( objectStatus "U5D1.W84" )
			)
			( pin "@baseboard_fab2_lib.baseboard_fab2(sch_1):page23_i172:ddr0_dq(10)"
				( attribute "PN" "L86"
					( Origin gPackager )
				)
				( objectStatus "U5D1.L86" )
			)
			( pin "@baseboard_fab2_lib.baseboard_fab2(sch_1):page23_i172:ddr0_dq(11)"
				( attribute "PN" "L84"
					( Origin gPackager )
				)
				( objectStatus "U5D1.L84" )
			)
			( pin "@baseboard_fab2_lib.baseboard_fab2(sch_1):page23_i172:ddr0_dq(12)"
				( attribute "PN" "AA86"
					( Origin gPackager )
				)
				( objectStatus "U5D1.AA86" )
			)
			( pin "@baseboard_fab2_lib.baseboard_fab2(sch_1):page23_i172:ddr0_dq(13)"
				( attribute "PN" "AA84"
					( Origin gPackager )
				)
				( objectStatus "U5D1.AA84" )
			)
			( pin "@baseboard_fab2_lib.baseboard_fab2(sch_1):page23_i172:ddr0_dq(14)"
				( attribute "PN" "N86"
					( Origin gPackager )
				)
				( objectStatus "U5D1.N86" )
			)
			( pin "@baseboard_fab2_lib.baseboard_fab2(sch_1):page23_i172:ddr0_dq(15)"
				( attribute "PN" "N84"
					( Origin gPackager )
				)
				( objectStatus "U5D1.N84" )
			)
			( pin "@baseboard_fab2_lib.baseboard_fab2(sch_1):page23_i172:ddr0_dq(16)"
				( attribute "PN" "V81"
					( Origin gPackager )
				)
				( objectStatus "U5D1.V81" )
			)
			( pin "@baseboard_fab2_lib.baseboard_fab2(sch_1):page23_i172:ddr0_dq(17)"
				( attribute "PN" "T79"
					( Origin gPackager )
				)
				( objectStatus "U5D1.T79" )
			)
			( pin "@baseboard_fab2_lib.baseboard_fab2(sch_1):page23_i172:ddr0_dq(18)"
				( attribute "PN" "N82"
					( Origin gPackager )
				)
				( objectStatus "U5D1.N82" )
			)
			( pin "@baseboard_fab2_lib.baseboard_fab2(sch_1):page23_i172:ddr0_dq(19)"
				( attribute "PN" "M81"
					( Origin gPackager )
				)
				( objectStatus "U5D1.M81" )
			)
			( pin "@baseboard_fab2_lib.baseboard_fab2(sch_1):page23_i172:ddr0_dq(20)"
				( attribute "PN" "W80"
					( Origin gPackager )
				)
				( objectStatus "U5D1.W80" )
			)
			( pin "@baseboard_fab2_lib.baseboard_fab2(sch_1):page23_i172:ddr0_dq(21)"
				( attribute "PN" "V79"
					( Origin gPackager )
				)
				( objectStatus "U5D1.V79" )
			)
			( pin "@baseboard_fab2_lib.baseboard_fab2(sch_1):page23_i172:ddr0_dq(22)"
				( attribute "PN" "R82"
					( Origin gPackager )
				)
				( objectStatus "U5D1.R82" )
			)
			( pin "@baseboard_fab2_lib.baseboard_fab2(sch_1):page23_i172:ddr0_dq(23)"
				( attribute "PN" "N80"
					( Origin gPackager )
				)
				( objectStatus "U5D1.N80" )
			)
			( pin "@baseboard_fab2_lib.baseboard_fab2(sch_1):page23_i172:ddr0_dq(24)"
				( attribute "PN" "L76"
					( Origin gPackager )
				)
				( objectStatus "U5D1.L76" )
			)
			( pin "@baseboard_fab2_lib.baseboard_fab2(sch_1):page23_i172:ddr0_dq(25)"
				( attribute "PN" "R76"
					( Origin gPackager )
				)
				( objectStatus "U5D1.R76" )
			)
			( pin "@baseboard_fab2_lib.baseboard_fab2(sch_1):page23_i172:ddr0_dq(26)"
				( attribute "PN" "M73"
					( Origin gPackager )
				)
				( objectStatus "U5D1.M73" )
			)
			( pin "@baseboard_fab2_lib.baseboard_fab2(sch_1):page23_i172:ddr0_dq(27)"
				( attribute "PN" "P73"
					( Origin gPackager )
				)
				( objectStatus "U5D1.P73" )
			)
			( pin "@baseboard_fab2_lib.baseboard_fab2(sch_1):page23_i172:ddr0_dq(28)"
				( attribute "PN" "M77"
					( Origin gPackager )
				)
				( objectStatus "U5D1.M77" )
			)
			( pin "@baseboard_fab2_lib.baseboard_fab2(sch_1):page23_i172:ddr0_dq(29)"
				( attribute "PN" "P77"
					( Origin gPackager )
				)
				( objectStatus "U5D1.P77" )
			)
			( pin "@baseboard_fab2_lib.baseboard_fab2(sch_1):page23_i172:ddr0_dq(30)"
				( attribute "PN" "L74"
					( Origin gPackager )
				)
				( objectStatus "U5D1.L74" )
			)
			( pin "@baseboard_fab2_lib.baseboard_fab2(sch_1):page23_i172:ddr0_dq(31)"
				( attribute "PN" "R74"
					( Origin gPackager )
				)
				( objectStatus "U5D1.R74" )
			)
			( pin "@baseboard_fab2_lib.baseboard_fab2(sch_1):page23_i172:ddr0_dq(32)"
				( attribute "PN" "C42"
					( Origin gPackager )
				)
				( objectStatus "U5D1.C42" )
			)
			( pin "@baseboard_fab2_lib.baseboard_fab2(sch_1):page23_i172:ddr0_dq(33)"
				( attribute "PN" "B41"
					( Origin gPackager )
				)
				( objectStatus "U5D1.B41" )
			)
			( pin "@baseboard_fab2_lib.baseboard_fab2(sch_1):page23_i172:ddr0_dq(34)"
				( attribute "PN" "C38"
					( Origin gPackager )
				)
				( objectStatus "U5D1.C38" )
			)
			( pin "@baseboard_fab2_lib.baseboard_fab2(sch_1):page23_i172:ddr0_dq(35)"
				( attribute "PN" "E38"
					( Origin gPackager )
				)
				( objectStatus "U5D1.E38" )
			)
			( pin "@baseboard_fab2_lib.baseboard_fab2(sch_1):page23_i172:ddr0_dq(36)"
				( attribute "PN" "E42"
					( Origin gPackager )
				)
				( objectStatus "U5D1.E42" )
			)
			( pin "@baseboard_fab2_lib.baseboard_fab2(sch_1):page23_i172:ddr0_dq(37)"
				( attribute "PN" "F41"
					( Origin gPackager )
				)
				( objectStatus "U5D1.F41" )
			)
			( pin "@baseboard_fab2_lib.baseboard_fab2(sch_1):page23_i172:ddr0_dq(38)"
				( attribute "PN" "B39"
					( Origin gPackager )
				)
				( objectStatus "U5D1.B39" )
			)
			( pin "@baseboard_fab2_lib.baseboard_fab2(sch_1):page23_i172:ddr0_dq(39)"
				( attribute "PN" "F39"
					( Origin gPackager )
				)
				( objectStatus "U5D1.F39" )
			)
			( pin "@baseboard_fab2_lib.baseboard_fab2(sch_1):page23_i172:ddr0_dq(40)"
				( attribute "PN" "K37"
					( Origin gPackager )
				)
				( objectStatus "U5D1.K37" )
			)
			( pin "@baseboard_fab2_lib.baseboard_fab2(sch_1):page23_i172:ddr0_dq(41)"
				( attribute "PN" "P37"
					( Origin gPackager )
				)
				( objectStatus "U5D1.P37" )
			)
			( pin "@baseboard_fab2_lib.baseboard_fab2(sch_1):page23_i172:ddr0_dq(42)"
				( attribute "PN" "L34"
					( Origin gPackager )
				)
				( objectStatus "U5D1.L34" )
			)
			( pin "@baseboard_fab2_lib.baseboard_fab2(sch_1):page23_i172:ddr0_dq(43)"
				( attribute "PN" "N34"
					( Origin gPackager )
				)
				( objectStatus "U5D1.N34" )
			)
			( pin "@baseboard_fab2_lib.baseboard_fab2(sch_1):page23_i172:ddr0_dq(44)"
				( attribute "PN" "L38"
					( Origin gPackager )
				)
				( objectStatus "U5D1.L38" )
			)
			( pin "@baseboard_fab2_lib.baseboard_fab2(sch_1):page23_i172:ddr0_dq(45)"
				( attribute "PN" "N38"
					( Origin gPackager )
				)
				( objectStatus "U5D1.N38" )
			)
			( pin "@baseboard_fab2_lib.baseboard_fab2(sch_1):page23_i172:ddr0_dq(46)"
				( attribute "PN" "K35"
					( Origin gPackager )
				)
				( objectStatus "U5D1.K35" )
			)
			( pin "@baseboard_fab2_lib.baseboard_fab2(sch_1):page23_i172:ddr0_dq(47)"
				( attribute "PN" "P35"
					( Origin gPackager )
				)
				( objectStatus "U5D1.P35" )
			)
			( pin "@baseboard_fab2_lib.baseboard_fab2(sch_1):page23_i172:ddr0_dq(48)"
				( attribute "PN" "K31"
					( Origin gPackager )
				)
				( objectStatus "U5D1.K31" )
			)
			( pin "@baseboard_fab2_lib.baseboard_fab2(sch_1):page23_i172:ddr0_dq(49)"
				( attribute "PN" "P31"
					( Origin gPackager )
				)
				( objectStatus "U5D1.P31" )
			)
			( pin "@baseboard_fab2_lib.baseboard_fab2(sch_1):page23_i172:ddr0_dq(50)"
				( attribute "PN" "L28"
					( Origin gPackager )
				)
				( objectStatus "U5D1.L28" )
			)
			( pin "@baseboard_fab2_lib.baseboard_fab2(sch_1):page23_i172:ddr0_dq(51)"
				( attribute "PN" "N28"
					( Origin gPackager )
				)
				( objectStatus "U5D1.N28" )
			)
			( pin "@baseboard_fab2_lib.baseboard_fab2(sch_1):page23_i172:ddr0_dq(52)"
				( attribute "PN" "L32"
					( Origin gPackager )
				)
				( objectStatus "U5D1.L32" )
			)
			( pin "@baseboard_fab2_lib.baseboard_fab2(sch_1):page23_i172:ddr0_dq(53)"
				( attribute "PN" "N32"
					( Origin gPackager )
				)
				( objectStatus "U5D1.N32" )
			)
			( pin "@baseboard_fab2_lib.baseboard_fab2(sch_1):page23_i172:ddr0_dq(54)"
				( attribute "PN" "K29"
					( Origin gPackager )
				)
				( objectStatus "U5D1.K29" )
			)
			( pin "@baseboard_fab2_lib.baseboard_fab2(sch_1):page23_i172:ddr0_dq(55)"
				( attribute "PN" "P29"
					( Origin gPackager )
				)
				( objectStatus "U5D1.P29" )
			)
			( pin "@baseboard_fab2_lib.baseboard_fab2(sch_1):page23_i172:ddr0_dq(56)"
				( attribute "PN" "K25"
					( Origin gPackager )
				)
				( objectStatus "U5D1.K25" )
			)
			( pin "@baseboard_fab2_lib.baseboard_fab2(sch_1):page23_i172:ddr0_dq(57)"
				( attribute "PN" "P25"
					( Origin gPackager )
				)
				( objectStatus "U5D1.P25" )
			)
			( pin "@baseboard_fab2_lib.baseboard_fab2(sch_1):page23_i172:ddr0_dq(58)"
				( attribute "PN" "P23"
					( Origin gPackager )
				)
				( objectStatus "U5D1.P23" )
			)
			( pin "@baseboard_fab2_lib.baseboard_fab2(sch_1):page23_i172:ddr0_dq(59)"
				( attribute "PN" "T23"
					( Origin gPackager )
				)
				( objectStatus "U5D1.T23" )
			)
			( pin "@baseboard_fab2_lib.baseboard_fab2(sch_1):page23_i172:ddr0_dq(60)"
				( attribute "PN" "L26"
					( Origin gPackager )
				)
				( objectStatus "U5D1.L26" )
			)
			( pin "@baseboard_fab2_lib.baseboard_fab2(sch_1):page23_i172:ddr0_dq(61)"
				( attribute "PN" "N26"
					( Origin gPackager )
				)
				( objectStatus "U5D1.N26" )
			)
			( pin "@baseboard_fab2_lib.baseboard_fab2(sch_1):page23_i172:ddr0_dq(62)"
				( attribute "PN" "H23"
					( Origin gPackager )
				)
				( objectStatus "U5D1.H23" )
			)
			( pin "@baseboard_fab2_lib.baseboard_fab2(sch_1):page23_i172:ddr0_dq(63)"
				( attribute "PN" "K23"
					( Origin gPackager )
				)
				( objectStatus "U5D1.K23" )
			)
			( pin "@baseboard_fab2_lib.baseboard_fab2(sch_1):page23_i172:ddr0_dqs_dn(0)"
				( attribute "PN" "AJ84"
					( Origin gPackager )
				)
				( objectStatus "U5D1.AJ84" )
			)
			( pin "@baseboard_fab2_lib.baseboard_fab2(sch_1):page23_i172:ddr0_dqs_dn(1)"
				( attribute "PN" "R84"
					( Origin gPackager )
				)
				( objectStatus "U5D1.R84" )
			)
			( pin "@baseboard_fab2_lib.baseboard_fab2(sch_1):page23_i172:ddr0_dqs_dn(2)"
				( attribute "PN" "P79"
					( Origin gPackager )
				)
				( objectStatus "U5D1.P79" )
			)
			( pin "@baseboard_fab2_lib.baseboard_fab2(sch_1):page23_i172:ddr0_dqs_dn(3)"
				( attribute "PN" "T75"
					( Origin gPackager )
				)
				( objectStatus "U5D1.T75" )
			)
			( pin "@baseboard_fab2_lib.baseboard_fab2(sch_1):page23_i172:ddr0_dqs_dn(4)"
				( attribute "PN" "G40"
					( Origin gPackager )
				)
				( objectStatus "U5D1.G40" )
			)
			( pin "@baseboard_fab2_lib.baseboard_fab2(sch_1):page23_i172:ddr0_dqs_dn(5)"
				( attribute "PN" "R36"
					( Origin gPackager )
				)
				( objectStatus "U5D1.R36" )
			)
			( pin "@baseboard_fab2_lib.baseboard_fab2(sch_1):page23_i172:ddr0_dqs_dn(6)"
				( attribute "PN" "R30"
					( Origin gPackager )
				)
				( objectStatus "U5D1.R30" )
			)
			( pin "@baseboard_fab2_lib.baseboard_fab2(sch_1):page23_i172:ddr0_dqs_dn(7)"
				( attribute "PN" "N24"
					( Origin gPackager )
				)
				( objectStatus "U5D1.N24" )
			)
			( pin "@baseboard_fab2_lib.baseboard_fab2(sch_1):page23_i172:ddr0_dqs_dn(8)"
				( attribute "PN" "AH67"
					( Origin gPackager )
				)
				( objectStatus "U5D1.AH67" )
			)
			( pin "@baseboard_fab2_lib.baseboard_fab2(sch_1):page23_i172:ddr0_dqs_dn(9)"
				( attribute "PN" "AL84"
					( Origin gPackager )
				)
				( objectStatus "U5D1.AL84" )
			)
			( pin "@baseboard_fab2_lib.baseboard_fab2(sch_1):page23_i172:ddr0_dqs_dn(10)"
				( attribute "PN" "U84"
					( Origin gPackager )
				)
				( objectStatus "U5D1.U84" )
			)
			( pin "@baseboard_fab2_lib.baseboard_fab2(sch_1):page23_i172:ddr0_dqs_dn(11)"
				( attribute "PN" "U82"
					( Origin gPackager )
				)
				( objectStatus "U5D1.U82" )
			)
			( pin "@baseboard_fab2_lib.baseboard_fab2(sch_1):page23_i172:ddr0_dqs_dn(12)"
				( attribute "PN" "K75"
					( Origin gPackager )
				)
				( objectStatus "U5D1.K75" )
			)
			( pin "@baseboard_fab2_lib.baseboard_fab2(sch_1):page23_i172:ddr0_dqs_dn(13)"
				( attribute "PN" "A40"
					( Origin gPackager )
				)
				( objectStatus "U5D1.A40" )
			)
			( pin "@baseboard_fab2_lib.baseboard_fab2(sch_1):page23_i172:ddr0_dqs_dn(14)"
				( attribute "PN" "J36"
					( Origin gPackager )
				)
				( objectStatus "U5D1.J36" )
			)
			( pin "@baseboard_fab2_lib.baseboard_fab2(sch_1):page23_i172:ddr0_dqs_dn(15)"
				( attribute "PN" "J30"
					( Origin gPackager )
				)
				( objectStatus "U5D1.J30" )
			)
			( pin "@baseboard_fab2_lib.baseboard_fab2(sch_1):page23_i172:ddr0_dqs_dn(16)"
				( attribute "PN" "J24"
					( Origin gPackager )
				)
				( objectStatus "U5D1.J24" )
			)
			( pin "@baseboard_fab2_lib.baseboard_fab2(sch_1):page23_i172:ddr0_dqs_dn(17)"
				( attribute "PN" "AB67"
					( Origin gPackager )
				)
				( objectStatus "U5D1.AB67" )
			)
			( pin "@baseboard_fab2_lib.baseboard_fab2(sch_1):page23_i172:ddr0_dqs_dp(0)"
				( attribute "PN" "AH85"
					( Origin gPackager )
				)
				( objectStatus "U5D1.AH85" )
			)
			( pin "@baseboard_fab2_lib.baseboard_fab2(sch_1):page23_i172:ddr0_dqs_dp(1)"
				( attribute "PN" "P85"
					( Origin gPackager )
				)
				( objectStatus "U5D1.P85" )
			)
			( pin "@baseboard_fab2_lib.baseboard_fab2(sch_1):page23_i172:ddr0_dqs_dp(2)"
				( attribute "PN" "R80"
					( Origin gPackager )
				)
				( objectStatus "U5D1.R80" )
			)
			( pin "@baseboard_fab2_lib.baseboard_fab2(sch_1):page23_i172:ddr0_dqs_dp(3)"
				( attribute "PN" "P75"
					( Origin gPackager )
				)
				( objectStatus "U5D1.P75" )
			)
			( pin "@baseboard_fab2_lib.baseboard_fab2(sch_1):page23_i172:ddr0_dqs_dp(4)"
				( attribute "PN" "E40"
					( Origin gPackager )
				)
				( objectStatus "U5D1.E40" )
			)
			( pin "@baseboard_fab2_lib.baseboard_fab2(sch_1):page23_i172:ddr0_dqs_dp(5)"
				( attribute "PN" "N36"
					( Origin gPackager )
				)
				( objectStatus "U5D1.N36" )
			)
			( pin "@baseboard_fab2_lib.baseboard_fab2(sch_1):page23_i172:ddr0_dqs_dp(6)"
				( attribute "PN" "N30"
					( Origin gPackager )
				)
				( objectStatus "U5D1.N30" )
			)
			( pin "@baseboard_fab2_lib.baseboard_fab2(sch_1):page23_i172:ddr0_dqs_dp(7)"
				( attribute "PN" "R24"
					( Origin gPackager )
				)
				( objectStatus "U5D1.R24" )
			)
			( pin "@baseboard_fab2_lib.baseboard_fab2(sch_1):page23_i172:ddr0_dqs_dp(8)"
				( attribute "PN" "AF67"
					( Origin gPackager )
				)
				( objectStatus "U5D1.AF67" )
			)
			( pin "@baseboard_fab2_lib.baseboard_fab2(sch_1):page23_i172:ddr0_dqs_dp(9)"
				( attribute "PN" "AM85"
					( Origin gPackager )
				)
				( objectStatus "U5D1.AM85" )
			)
			( pin "@baseboard_fab2_lib.baseboard_fab2(sch_1):page23_i172:ddr0_dqs_dp(10)"
				( attribute "PN" "V85"
					( Origin gPackager )
				)
				( objectStatus "U5D1.V85" )
			)
			( pin "@baseboard_fab2_lib.baseboard_fab2(sch_1):page23_i172:ddr0_dqs_dp(11)"
				( attribute "PN" "T81"
					( Origin gPackager )
				)
				( objectStatus "U5D1.T81" )
			)
			( pin "@baseboard_fab2_lib.baseboard_fab2(sch_1):page23_i172:ddr0_dqs_dp(12)"
				( attribute "PN" "M75"
					( Origin gPackager )
				)
				( objectStatus "U5D1.M75" )
			)
			( pin "@baseboard_fab2_lib.baseboard_fab2(sch_1):page23_i172:ddr0_dqs_dp(13)"
				( attribute "PN" "C40"
					( Origin gPackager )
				)
				( objectStatus "U5D1.C40" )
			)
			( pin "@baseboard_fab2_lib.baseboard_fab2(sch_1):page23_i172:ddr0_dqs_dp(14)"
				( attribute "PN" "L36"
					( Origin gPackager )
				)
				( objectStatus "U5D1.L36" )
			)
			( pin "@baseboard_fab2_lib.baseboard_fab2(sch_1):page23_i172:ddr0_dqs_dp(15)"
				( attribute "PN" "L30"
					( Origin gPackager )
				)
				( objectStatus "U5D1.L30" )
			)
			( pin "@baseboard_fab2_lib.baseboard_fab2(sch_1):page23_i172:ddr0_dqs_dp(16)"
				( attribute "PN" "L24"
					( Origin gPackager )
				)
				( objectStatus "U5D1.L24" )
			)
			( pin "@baseboard_fab2_lib.baseboard_fab2(sch_1):page23_i172:ddr0_dqs_dp(17)"
				( attribute "PN" "AD67"
					( Origin gPackager )
				)
				( objectStatus "U5D1.AD67" )
			)
			( pin "@baseboard_fab2_lib.baseboard_fab2(sch_1):page23_i172:ddr0_ecc(0)"
				( attribute "PN" "AC68"
					( Origin gPackager )
				)
				( objectStatus "U5D1.AC68" )
			)
			( pin "@baseboard_fab2_lib.baseboard_fab2(sch_1):page23_i172:ddr0_ecc(1)"
				( attribute "PN" "AG68"
					( Origin gPackager )
				)
				( objectStatus "U5D1.AG68" )
			)
			( pin "@baseboard_fab2_lib.baseboard_fab2(sch_1):page23_i172:ddr0_ecc(2)"
				( attribute "PN" "AD65"
					( Origin gPackager )
				)
				( objectStatus "U5D1.AD65" )
			)
			( pin "@baseboard_fab2_lib.baseboard_fab2(sch_1):page23_i172:ddr0_ecc(3)"
				( attribute "PN" "AF65"
					( Origin gPackager )
				)
				( objectStatus "U5D1.AF65" )
			)
			( pin "@baseboard_fab2_lib.baseboard_fab2(sch_1):page23_i172:ddr0_ecc(4)"
				( attribute "PN" "AD69"
					( Origin gPackager )
				)
				( objectStatus "U5D1.AD69" )
			)
			( pin "@baseboard_fab2_lib.baseboard_fab2(sch_1):page23_i172:ddr0_ecc(5)"
				( attribute "PN" "AF69"
					( Origin gPackager )
				)
				( objectStatus "U5D1.AF69" )
			)
			( pin "@baseboard_fab2_lib.baseboard_fab2(sch_1):page23_i172:ddr0_ecc(6)"
				( attribute "PN" "AC66"
					( Origin gPackager )
				)
				( objectStatus "U5D1.AC66" )
			)
			( pin "@baseboard_fab2_lib.baseboard_fab2(sch_1):page23_i172:ddr0_ecc(7)"
				( attribute "PN" "AG66"
					( Origin gPackager )
				)
				( objectStatus "U5D1.AG66" )
			)
			( pin "@baseboard_fab2_lib.baseboard_fab2(sch_1):page23_i172:ddr0_ma(0)"
				( attribute "PN" "F53"
					( Origin gPackager )
				)
				( objectStatus "U5D1.F53" )
			)
			( pin "@baseboard_fab2_lib.baseboard_fab2(sch_1):page23_i172:ddr0_ma(1)"
				( attribute "PN" "F57"
					( Origin gPackager )
				)
				( objectStatus "U5D1.F57" )
			)
			( pin "@baseboard_fab2_lib.baseboard_fab2(sch_1):page23_i172:ddr0_ma(2)"
				( attribute "PN" "D57"
					( Origin gPackager )
				)
				( objectStatus "U5D1.D57" )
			)
			( pin "@baseboard_fab2_lib.baseboard_fab2(sch_1):page23_i172:ddr0_ma(3)"
				( attribute "PN" "C58"
					( Origin gPackager )
				)
				( objectStatus "U5D1.C58" )
			)
			( pin "@baseboard_fab2_lib.baseboard_fab2(sch_1):page23_i172:ddr0_ma(4)"
				( attribute "PN" "G58"
					( Origin gPackager )
				)
				( objectStatus "U5D1.G58" )
			)
			( pin "@baseboard_fab2_lib.baseboard_fab2(sch_1):page23_i172:ddr0_ma(5)"
				( attribute "PN" "F59"
					( Origin gPackager )
				)
				( objectStatus "U5D1.F59" )
			)
			( pin "@baseboard_fab2_lib.baseboard_fab2(sch_1):page23_i172:ddr0_ma(6)"
				( attribute "PN" "D59"
					( Origin gPackager )
				)
				( objectStatus "U5D1.D59" )
			)
			( pin "@baseboard_fab2_lib.baseboard_fab2(sch_1):page23_i172:ddr0_ma(7)"
				( attribute "PN" "G60"
					( Origin gPackager )
				)
				( objectStatus "U5D1.G60" )
			)
			( pin "@baseboard_fab2_lib.baseboard_fab2(sch_1):page23_i172:ddr0_ma(8)"
				( attribute "PN" "C60"
					( Origin gPackager )
				)
				( objectStatus "U5D1.C60" )
			)
			( pin "@baseboard_fab2_lib.baseboard_fab2(sch_1):page23_i172:ddr0_ma(9)"
				( attribute "PN" "F61"
					( Origin gPackager )
				)
				( objectStatus "U5D1.F61" )
			)
			( pin "@baseboard_fab2_lib.baseboard_fab2(sch_1):page23_i172:ddr0_ma(10)"
				( attribute "PN" "J54"
					( Origin gPackager )
				)
				( objectStatus "U5D1.J54" )
			)
			( pin "@baseboard_fab2_lib.baseboard_fab2(sch_1):page23_i172:ddr0_ma(11)"
				( attribute "PN" "G62"
					( Origin gPackager )
				)
				( objectStatus "U5D1.G62" )
			)
			( pin "@baseboard_fab2_lib.baseboard_fab2(sch_1):page23_i172:ddr0_ma(12)"
				( attribute "PN" "J64"
					( Origin gPackager )
				)
				( objectStatus "U5D1.J64" )
			)
			( pin "@baseboard_fab2_lib.baseboard_fab2(sch_1):page23_i172:ddr0_ma(13)"
				( attribute "PN" "J48"
					( Origin gPackager )
				)
				( objectStatus "U5D1.J48" )
			)
			( pin "@baseboard_fab2_lib.baseboard_fab2(sch_1):page23_i172:ddr0_ma(14)"
				( attribute "PN" "F51"
					( Origin gPackager )
				)
				( objectStatus "U5D1.F51" )
			)
			( pin "@baseboard_fab2_lib.baseboard_fab2(sch_1):page23_i172:ddr0_ma(15)"
				( attribute "PN" "K49"
					( Origin gPackager )
				)
				( objectStatus "U5D1.K49" )
			)
			( pin "@baseboard_fab2_lib.baseboard_fab2(sch_1):page23_i172:ddr0_ma(16)"
				( attribute "PN" "D51"
					( Origin gPackager )
				)
				( objectStatus "U5D1.D51" )
			)
			( pin "@baseboard_fab2_lib.baseboard_fab2(sch_1):page23_i172:ddr0_ma(17)"
				( attribute "PN" "K47"
					( Origin gPackager )
				)
				( objectStatus "U5D1.K47" )
			)
			( pin "@baseboard_fab2_lib.baseboard_fab2(sch_1):page23_i172:ddr0_odt(0)"
				( attribute "PN" "C50"
					( Origin gPackager )
				)
				( objectStatus "U5D1.C50" )
			)
			( pin "@baseboard_fab2_lib.baseboard_fab2(sch_1):page23_i172:ddr0_odt(1)"
				( attribute "PN" "C48"
					( Origin gPackager )
				)
				( objectStatus "U5D1.C48" )
			)
			( pin "@baseboard_fab2_lib.baseboard_fab2(sch_1):page23_i172:ddr0_odt(2)"
				( attribute "PN" "G50"
					( Origin gPackager )
				)
				( objectStatus "U5D1.G50" )
			)
			( pin "@baseboard_fab2_lib.baseboard_fab2(sch_1):page23_i172:ddr0_odt(3)"
				( attribute "PN" "G48"
					( Origin gPackager )
				)
				( objectStatus "U5D1.G48" )
			)
			( pin "@baseboard_fab2_lib.baseboard_fab2(sch_1):page23_i172:ddr0_par"
				( attribute "PN" "D53"
					( Origin gPackager )
				)
				( objectStatus "U5D1.D53" )
			)
			( pin "@baseboard_fab2_lib.baseboard_fab2(sch_1):page24_i172:ddr1_act_n"
				( attribute "PN" "T63"
					( Origin gPackager )
				)
				( objectStatus "U5D1.T63" )
			)
			( pin "@baseboard_fab2_lib.baseboard_fab2(sch_1):page24_i172:ddr1_alert_n"
				( attribute "PN" "W62"
					( Origin gPackager )
				)
				( objectStatus "U5D1.W62" )
			)
			( pin "@baseboard_fab2_lib.baseboard_fab2(sch_1):page24_i172:ddr1_ba(0)"
				( attribute "PN" "T53"
					( Origin gPackager )
				)
				( objectStatus "U5D1.T53" )
			)
			( pin "@baseboard_fab2_lib.baseboard_fab2(sch_1):page24_i172:ddr1_ba(1)"
				( attribute "PN" "K55"
					( Origin gPackager )
				)
				( objectStatus "U5D1.K55" )
			)
			( pin "@baseboard_fab2_lib.baseboard_fab2(sch_1):page24_i172:ddr1_bg(0)"
				( attribute "PN" "M61"
					( Origin gPackager )
				)
				( objectStatus "U5D1.M61" )
			)
			( pin "@baseboard_fab2_lib.baseboard_fab2(sch_1):page24_i172:ddr1_bg(1)"
				( attribute "PN" "N60"
					( Origin gPackager )
				)
				( objectStatus "U5D1.N60" )
			)
			( pin "@baseboard_fab2_lib.baseboard_fab2(sch_1):page24_i172:ddr1_cid(2)"
				( attribute "PN" "M47"
					( Origin gPackager )
				)
				( objectStatus "U5D1.M47" )
			)
			( pin "@baseboard_fab2_lib.baseboard_fab2(sch_1):page24_i172:ddr1_cke(0)"
				( attribute "PN" "N62"
					( Origin gPackager )
				)
				( objectStatus "U5D1.N62" )
			)
			( pin "@baseboard_fab2_lib.baseboard_fab2(sch_1):page24_i172:ddr1_cke(1)"
				( attribute "PN" "R64"
					( Origin gPackager )
				)
				( objectStatus "U5D1.R64" )
			)
			( pin "@baseboard_fab2_lib.baseboard_fab2(sch_1):page24_i172:ddr1_cke(2)"
				( attribute "PN" "K63"
					( Origin gPackager )
				)
				( objectStatus "U5D1.K63" )
			)
			( pin "@baseboard_fab2_lib.baseboard_fab2(sch_1):page24_i172:ddr1_cke(3)"
				( attribute "PN" "L64"
					( Origin gPackager )
				)
				( objectStatus "U5D1.L64" )
			)
			( pin "@baseboard_fab2_lib.baseboard_fab2(sch_1):page24_i172:ddr1_clk_dn(0)"
				( attribute "PN" "M53"
					( Origin gPackager )
				)
				( objectStatus "U5D1.M53" )
			)
			( pin "@baseboard_fab2_lib.baseboard_fab2(sch_1):page24_i172:ddr1_clk_dn(1)"
				( attribute "PN" "R54"
					( Origin gPackager )
				)
				( objectStatus "U5D1.R54" )
			)
			( pin "@baseboard_fab2_lib.baseboard_fab2(sch_1):page24_i172:ddr1_clk_dn(2)"
				( attribute "PN" "N56"
					( Origin gPackager )
				)
				( objectStatus "U5D1.N56" )
			)
			( pin "@baseboard_fab2_lib.baseboard_fab2(sch_1):page24_i172:ddr1_clk_dn(3)"
				( attribute "PN" "R56"
					( Origin gPackager )
				)
				( objectStatus "U5D1.R56" )
			)
			( pin "@baseboard_fab2_lib.baseboard_fab2(sch_1):page24_i172:ddr1_clk_dp(0)"
				( attribute "PN" "N54"
					( Origin gPackager )
				)
				( objectStatus "U5D1.N54" )
			)
			( pin "@baseboard_fab2_lib.baseboard_fab2(sch_1):page24_i172:ddr1_clk_dp(1)"
				( attribute "PN" "T55"
					( Origin gPackager )
				)
				( objectStatus "U5D1.T55" )
			)
			( pin "@baseboard_fab2_lib.baseboard_fab2(sch_1):page24_i172:ddr1_clk_dp(2)"
				( attribute "PN" "M57"
					( Origin gPackager )
				)
				( objectStatus "U5D1.M57" )
			)
			( pin "@baseboard_fab2_lib.baseboard_fab2(sch_1):page24_i172:ddr1_clk_dp(3)"
				( attribute "PN" "T57"
					( Origin gPackager )
				)
				( objectStatus "U5D1.T57" )
			)
			( pin "@baseboard_fab2_lib.baseboard_fab2(sch_1):page24_i172:ddr1_cs_n(0)"
				( attribute "PN" "K51"
					( Origin gPackager )
				)
				( objectStatus "U5D1.K51" )
			)
			( pin "@baseboard_fab2_lib.baseboard_fab2(sch_1):page24_i172:ddr1_cs_n(1)"
				( attribute "PN" "R50"
					( Origin gPackager )
				)
				( objectStatus "U5D1.R50" )
			)
			( pin "@baseboard_fab2_lib.baseboard_fab2(sch_1):page24_i172:ddr1_cs_n(2)"
				( attribute "PN" "N46"
					( Origin gPackager )
				)
				( objectStatus "U5D1.N46" )
			)
			( pin "@baseboard_fab2_lib.baseboard_fab2(sch_1):page24_i172:ddr1_cs_n(3)"
				( attribute "PN" "V47"
					( Origin gPackager )
				)
				( objectStatus "U5D1.V47" )
			)
			( pin "@baseboard_fab2_lib.baseboard_fab2(sch_1):page24_i172:ddr1_cs_n(4)"
				( attribute "PN" "J50"
					( Origin gPackager )
				)
				( objectStatus "U5D1.J50" )
			)
			( pin "@baseboard_fab2_lib.baseboard_fab2(sch_1):page24_i172:ddr1_cs_n(5)"
				( attribute "PN" "T49"
					( Origin gPackager )
				)
				( objectStatus "U5D1.T49" )
			)
			( pin "@baseboard_fab2_lib.baseboard_fab2(sch_1):page24_i172:ddr1_cs_n(6)"
				( attribute "PN" "M45"
					( Origin gPackager )
				)
				( objectStatus "U5D1.M45" )
			)
			( pin "@baseboard_fab2_lib.baseboard_fab2(sch_1):page24_i172:ddr1_cs_n(7)"
				( attribute "PN" "R46"
					( Origin gPackager )
				)
				( objectStatus "U5D1.R46" )
			)
			( pin "@baseboard_fab2_lib.baseboard_fab2(sch_1):page24_i172:ddr1_dq(0)"
				( attribute "PN" "AV81"
					( Origin gPackager )
				)
				( objectStatus "U5D1.AV81" )
			)
			( pin "@baseboard_fab2_lib.baseboard_fab2(sch_1):page24_i172:ddr1_dq(1)"
				( attribute "PN" "AT79"
					( Origin gPackager )
				)
				( objectStatus "U5D1.AT79" )
			)
			( pin "@baseboard_fab2_lib.baseboard_fab2(sch_1):page24_i172:ddr1_dq(2)"
				( attribute "PN" "AN82"
					( Origin gPackager )
				)
				( objectStatus "U5D1.AN82" )
			)
			( pin "@baseboard_fab2_lib.baseboard_fab2(sch_1):page24_i172:ddr1_dq(3)"
				( attribute "PN" "AM81"
					( Origin gPackager )
				)
				( objectStatus "U5D1.AM81" )
			)
			( pin "@baseboard_fab2_lib.baseboard_fab2(sch_1):page24_i172:ddr1_dq(4)"
				( attribute "PN" "AW80"
					( Origin gPackager )
				)
				( objectStatus "U5D1.AW80" )
			)
			( pin "@baseboard_fab2_lib.baseboard_fab2(sch_1):page24_i172:ddr1_dq(5)"
				( attribute "PN" "AV79"
					( Origin gPackager )
				)
				( objectStatus "U5D1.AV79" )
			)
			( pin "@baseboard_fab2_lib.baseboard_fab2(sch_1):page24_i172:ddr1_dq(6)"
				( attribute "PN" "AR82"
					( Origin gPackager )
				)
				( objectStatus "U5D1.AR82" )
			)
			( pin "@baseboard_fab2_lib.baseboard_fab2(sch_1):page24_i172:ddr1_dq(7)"
				( attribute "PN" "AN80"
					( Origin gPackager )
				)
				( objectStatus "U5D1.AN80" )
			)
			( pin "@baseboard_fab2_lib.baseboard_fab2(sch_1):page24_i172:ddr1_dq(8)"
				( attribute "PN" "AH81"
					( Origin gPackager )
				)
				( objectStatus "U5D1.AH81" )
			)
			( pin "@baseboard_fab2_lib.baseboard_fab2(sch_1):page24_i172:ddr1_dq(9)"
				( attribute "PN" "AF79"
					( Origin gPackager )
				)
				( objectStatus "U5D1.AF79" )
			)
			( pin "@baseboard_fab2_lib.baseboard_fab2(sch_1):page24_i172:ddr1_dq(10)"
				( attribute "PN" "AC82"
					( Origin gPackager )
				)
				( objectStatus "U5D1.AC82" )
			)
			( pin "@baseboard_fab2_lib.baseboard_fab2(sch_1):page24_i172:ddr1_dq(11)"
				( attribute "PN" "AB81"
					( Origin gPackager )
				)
				( objectStatus "U5D1.AB81" )
			)
			( pin "@baseboard_fab2_lib.baseboard_fab2(sch_1):page24_i172:ddr1_dq(12)"
				( attribute "PN" "AJ80"
					( Origin gPackager )
				)
				( objectStatus "U5D1.AJ80" )
			)
			( pin "@baseboard_fab2_lib.baseboard_fab2(sch_1):page24_i172:ddr1_dq(13)"
				( attribute "PN" "AH79"
					( Origin gPackager )
				)
				( objectStatus "U5D1.AH79" )
			)
			( pin "@baseboard_fab2_lib.baseboard_fab2(sch_1):page24_i172:ddr1_dq(14)"
				( attribute "PN" "AE82"
					( Origin gPackager )
				)
				( objectStatus "U5D1.AE82" )
			)
			( pin "@baseboard_fab2_lib.baseboard_fab2(sch_1):page24_i172:ddr1_dq(15)"
				( attribute "PN" "AC80"
					( Origin gPackager )
				)
				( objectStatus "U5D1.AC80" )
			)
			( pin "@baseboard_fab2_lib.baseboard_fab2(sch_1):page24_i172:ddr1_dq(16)"
				( attribute "PN" "E80"
					( Origin gPackager )
				)
				( objectStatus "U5D1.E80" )
			)
			( pin "@baseboard_fab2_lib.baseboard_fab2(sch_1):page24_i172:ddr1_dq(17)"
				( attribute "PN" "J80"
					( Origin gPackager )
				)
				( objectStatus "U5D1.J80" )
			)
			( pin "@baseboard_fab2_lib.baseboard_fab2(sch_1):page24_i172:ddr1_dq(18)"
				( attribute "PN" "F77"
					( Origin gPackager )
				)
				( objectStatus "U5D1.F77" )
			)
			( pin "@baseboard_fab2_lib.baseboard_fab2(sch_1):page24_i172:ddr1_dq(19)"
				( attribute "PN" "H77"
					( Origin gPackager )
				)
				( objectStatus "U5D1.H77" )
			)
			( pin "@baseboard_fab2_lib.baseboard_fab2(sch_1):page24_i172:ddr1_dq(20)"
				( attribute "PN" "F81"
					( Origin gPackager )
				)
				( objectStatus "U5D1.F81" )
			)
			( pin "@baseboard_fab2_lib.baseboard_fab2(sch_1):page24_i172:ddr1_dq(21)"
				( attribute "PN" "H81"
					( Origin gPackager )
				)
				( objectStatus "U5D1.H81" )
			)
			( pin "@baseboard_fab2_lib.baseboard_fab2(sch_1):page24_i172:ddr1_dq(22)"
				( attribute "PN" "E78"
					( Origin gPackager )
				)
				( objectStatus "U5D1.E78" )
			)
			( pin "@baseboard_fab2_lib.baseboard_fab2(sch_1):page24_i172:ddr1_dq(23)"
				( attribute "PN" "J78"
					( Origin gPackager )
				)
				( objectStatus "U5D1.J78" )
			)
			( pin "@baseboard_fab2_lib.baseboard_fab2(sch_1):page24_i172:ddr1_dq(24)"
				( attribute "PN" "D75"
					( Origin gPackager )
				)
				( objectStatus "U5D1.D75" )
			)
			( pin "@baseboard_fab2_lib.baseboard_fab2(sch_1):page24_i172:ddr1_dq(25)"
				( attribute "PN" "C74"
					( Origin gPackager )
				)
				( objectStatus "U5D1.C74" )
			)
			( pin "@baseboard_fab2_lib.baseboard_fab2(sch_1):page24_i172:ddr1_dq(26)"
				( attribute "PN" "D71"
					( Origin gPackager )
				)
				( objectStatus "U5D1.D71" )
			)
			( pin "@baseboard_fab2_lib.baseboard_fab2(sch_1):page24_i172:ddr1_dq(27)"
				( attribute "PN" "F71"
					( Origin gPackager )
				)
				( objectStatus "U5D1.F71" )
			)
			( pin "@baseboard_fab2_lib.baseboard_fab2(sch_1):page24_i172:ddr1_dq(28)"
				( attribute "PN" "F75"
					( Origin gPackager )
				)
				( objectStatus "U5D1.F75" )
			)
			( pin "@baseboard_fab2_lib.baseboard_fab2(sch_1):page24_i172:ddr1_dq(29)"
				( attribute "PN" "G74"
					( Origin gPackager )
				)
				( objectStatus "U5D1.G74" )
			)
			( pin "@baseboard_fab2_lib.baseboard_fab2(sch_1):page24_i172:ddr1_dq(30)"
				( attribute "PN" "C72"
					( Origin gPackager )
				)
				( objectStatus "U5D1.C72" )
			)
			( pin "@baseboard_fab2_lib.baseboard_fab2(sch_1):page24_i172:ddr1_dq(31)"
				( attribute "PN" "G72"
					( Origin gPackager )
				)
				( objectStatus "U5D1.G72" )
			)
			( pin "@baseboard_fab2_lib.baseboard_fab2(sch_1):page24_i172:ddr1_dq(32)"
				( attribute "PN" "K43"
					( Origin gPackager )
				)
				( objectStatus "U5D1.K43" )
			)
			( pin "@baseboard_fab2_lib.baseboard_fab2(sch_1):page24_i172:ddr1_dq(33)"
				( attribute "PN" "H43"
					( Origin gPackager )
				)
				( objectStatus "U5D1.H43" )
			)
			( pin "@baseboard_fab2_lib.baseboard_fab2(sch_1):page24_i172:ddr1_dq(34)"
				( attribute "PN" "L40"
					( Origin gPackager )
				)
				( objectStatus "U5D1.L40" )
			)
			( pin "@baseboard_fab2_lib.baseboard_fab2(sch_1):page24_i172:ddr1_dq(35)"
				( attribute "PN" "N40"
					( Origin gPackager )
				)
				( objectStatus "U5D1.N40" )
			)
			( pin "@baseboard_fab2_lib.baseboard_fab2(sch_1):page24_i172:ddr1_dq(36)"
				( attribute "PN" "P43"
					( Origin gPackager )
				)
				( objectStatus "U5D1.P43" )
			)
			( pin "@baseboard_fab2_lib.baseboard_fab2(sch_1):page24_i172:ddr1_dq(37)"
				( attribute "PN" "T43"
					( Origin gPackager )
				)
				( objectStatus "U5D1.T43" )
			)
			( pin "@baseboard_fab2_lib.baseboard_fab2(sch_1):page24_i172:ddr1_dq(38)"
				( attribute "PN" "K41"
					( Origin gPackager )
				)
				( objectStatus "U5D1.K41" )
			)
			( pin "@baseboard_fab2_lib.baseboard_fab2(sch_1):page24_i172:ddr1_dq(39)"
				( attribute "PN" "P41"
					( Origin gPackager )
				)
				( objectStatus "U5D1.P41" )
			)
			( pin "@baseboard_fab2_lib.baseboard_fab2(sch_1):page24_i172:ddr1_dq(40)"
				( attribute "PN" "C36"
					( Origin gPackager )
				)
				( objectStatus "U5D1.C36" )
			)
			( pin "@baseboard_fab2_lib.baseboard_fab2(sch_1):page24_i172:ddr1_dq(41)"
				( attribute "PN" "B35"
					( Origin gPackager )
				)
				( objectStatus "U5D1.B35" )
			)
			( pin "@baseboard_fab2_lib.baseboard_fab2(sch_1):page24_i172:ddr1_dq(42)"
				( attribute "PN" "C32"
					( Origin gPackager )
				)
				( objectStatus "U5D1.C32" )
			)
			( pin "@baseboard_fab2_lib.baseboard_fab2(sch_1):page24_i172:ddr1_dq(43)"
				( attribute "PN" "E32"
					( Origin gPackager )
				)
				( objectStatus "U5D1.E32" )
			)
			( pin "@baseboard_fab2_lib.baseboard_fab2(sch_1):page24_i172:ddr1_dq(44)"
				( attribute "PN" "E36"
					( Origin gPackager )
				)
				( objectStatus "U5D1.E36" )
			)
			( pin "@baseboard_fab2_lib.baseboard_fab2(sch_1):page24_i172:ddr1_dq(45)"
				( attribute "PN" "F35"
					( Origin gPackager )
				)
				( objectStatus "U5D1.F35" )
			)
			( pin "@baseboard_fab2_lib.baseboard_fab2(sch_1):page24_i172:ddr1_dq(46)"
				( attribute "PN" "B33"
					( Origin gPackager )
				)
				( objectStatus "U5D1.B33" )
			)
			( pin "@baseboard_fab2_lib.baseboard_fab2(sch_1):page24_i172:ddr1_dq(47)"
				( attribute "PN" "F33"
					( Origin gPackager )
				)
				( objectStatus "U5D1.F33" )
			)
			( pin "@baseboard_fab2_lib.baseboard_fab2(sch_1):page24_i172:ddr1_dq(48)"
				( attribute "PN" "C30"
					( Origin gPackager )
				)
				( objectStatus "U5D1.C30" )
			)
			( pin "@baseboard_fab2_lib.baseboard_fab2(sch_1):page24_i172:ddr1_dq(49)"
				( attribute "PN" "B29"
					( Origin gPackager )
				)
				( objectStatus "U5D1.B29" )
			)
			( pin "@baseboard_fab2_lib.baseboard_fab2(sch_1):page24_i172:ddr1_dq(50)"
				( attribute "PN" "C26"
					( Origin gPackager )
				)
				( objectStatus "U5D1.C26" )
			)
			( pin "@baseboard_fab2_lib.baseboard_fab2(sch_1):page24_i172:ddr1_dq(51)"
				( attribute "PN" "E26"
					( Origin gPackager )
				)
				( objectStatus "U5D1.E26" )
			)
			( pin "@baseboard_fab2_lib.baseboard_fab2(sch_1):page24_i172:ddr1_dq(52)"
				( attribute "PN" "E30"
					( Origin gPackager )
				)
				( objectStatus "U5D1.E30" )
			)
			( pin "@baseboard_fab2_lib.baseboard_fab2(sch_1):page24_i172:ddr1_dq(53)"
				( attribute "PN" "F29"
					( Origin gPackager )
				)
				( objectStatus "U5D1.F29" )
			)
			( pin "@baseboard_fab2_lib.baseboard_fab2(sch_1):page24_i172:ddr1_dq(54)"
				( attribute "PN" "B27"
					( Origin gPackager )
				)
				( objectStatus "U5D1.B27" )
			)
			( pin "@baseboard_fab2_lib.baseboard_fab2(sch_1):page24_i172:ddr1_dq(55)"
				( attribute "PN" "F27"
					( Origin gPackager )
				)
				( objectStatus "U5D1.F27" )
			)
			( pin "@baseboard_fab2_lib.baseboard_fab2(sch_1):page24_i172:ddr1_dq(56)"
				( attribute "PN" "U28"
					( Origin gPackager )
				)
				( objectStatus "U5D1.U28" )
			)
			( pin "@baseboard_fab2_lib.baseboard_fab2(sch_1):page24_i172:ddr1_dq(57)"
				( attribute "PN" "AA28"
					( Origin gPackager )
				)
				( objectStatus "U5D1.AA28" )
			)
			( pin "@baseboard_fab2_lib.baseboard_fab2(sch_1):page24_i172:ddr1_dq(58)"
				( attribute "PN" "V25"
					( Origin gPackager )
				)
				( objectStatus "U5D1.V25" )
			)
			( pin "@baseboard_fab2_lib.baseboard_fab2(sch_1):page24_i172:ddr1_dq(59)"
				( attribute "PN" "Y25"
					( Origin gPackager )
				)
				( objectStatus "U5D1.Y25" )
			)
			( pin "@baseboard_fab2_lib.baseboard_fab2(sch_1):page24_i172:ddr1_dq(60)"
				( attribute "PN" "V29"
					( Origin gPackager )
				)
				( objectStatus "U5D1.V29" )
			)
			( pin "@baseboard_fab2_lib.baseboard_fab2(sch_1):page24_i172:ddr1_dq(61)"
				( attribute "PN" "Y29"
					( Origin gPackager )
				)
				( objectStatus "U5D1.Y29" )
			)
			( pin "@baseboard_fab2_lib.baseboard_fab2(sch_1):page24_i172:ddr1_dq(62)"
				( attribute "PN" "U26"
					( Origin gPackager )
				)
				( objectStatus "U5D1.U26" )
			)
			( pin "@baseboard_fab2_lib.baseboard_fab2(sch_1):page24_i172:ddr1_dq(63)"
				( attribute "PN" "AA26"
					( Origin gPackager )
				)
				( objectStatus "U5D1.AA26" )
			)
			( pin "@baseboard_fab2_lib.baseboard_fab2(sch_1):page24_i172:ddr1_dqs_dn(0)"
				( attribute "PN" "AP79"
					( Origin gPackager )
				)
				( objectStatus "U5D1.AP79" )
			)
			( pin "@baseboard_fab2_lib.baseboard_fab2(sch_1):page24_i172:ddr1_dqs_dn(1)"
				( attribute "PN" "AD79"
					( Origin gPackager )
				)
				( objectStatus "U5D1.AD79" )
			)
			( pin "@baseboard_fab2_lib.baseboard_fab2(sch_1):page24_i172:ddr1_dqs_dn(2)"
				( attribute "PN" "K79"
					( Origin gPackager )
				)
				( objectStatus "U5D1.K79" )
			)
			( pin "@baseboard_fab2_lib.baseboard_fab2(sch_1):page24_i172:ddr1_dqs_dn(3)"
				( attribute "PN" "H73"
					( Origin gPackager )
				)
				( objectStatus "U5D1.H73" )
			)
			( pin "@baseboard_fab2_lib.baseboard_fab2(sch_1):page24_i172:ddr1_dqs_dn(4)"
				( attribute "PN" "N42"
					( Origin gPackager )
				)
				( objectStatus "U5D1.N42" )
			)
			( pin "@baseboard_fab2_lib.baseboard_fab2(sch_1):page24_i172:ddr1_dqs_dn(5)"
				( attribute "PN" "G34"
					( Origin gPackager )
				)
				( objectStatus "U5D1.G34" )
			)
			( pin "@baseboard_fab2_lib.baseboard_fab2(sch_1):page24_i172:ddr1_dqs_dn(6)"
				( attribute "PN" "G28"
					( Origin gPackager )
				)
				( objectStatus "U5D1.G28" )
			)
			( pin "@baseboard_fab2_lib.baseboard_fab2(sch_1):page24_i172:ddr1_dqs_dn(7)"
				( attribute "PN" "AB27"
					( Origin gPackager )
				)
				( objectStatus "U5D1.AB27" )
			)
			( pin "@baseboard_fab2_lib.baseboard_fab2(sch_1):page24_i172:ddr1_dqs_dn(8)"
				( attribute "PN" "N68"
					( Origin gPackager )
				)
				( objectStatus "U5D1.N68" )
			)
			( pin "@baseboard_fab2_lib.baseboard_fab2(sch_1):page24_i172:ddr1_dqs_dn(9)"
				( attribute "PN" "AU82"
					( Origin gPackager )
				)
				( objectStatus "U5D1.AU82" )
			)
			( pin "@baseboard_fab2_lib.baseboard_fab2(sch_1):page24_i172:ddr1_dqs_dn(10)"
				( attribute "PN" "AG82"
					( Origin gPackager )
				)
				( objectStatus "U5D1.AG82" )
			)
			( pin "@baseboard_fab2_lib.baseboard_fab2(sch_1):page24_i172:ddr1_dqs_dn(11)"
				( attribute "PN" "D79"
					( Origin gPackager )
				)
				( objectStatus "U5D1.D79" )
			)
			( pin "@baseboard_fab2_lib.baseboard_fab2(sch_1):page24_i172:ddr1_dqs_dn(12)"
				( attribute "PN" "B73"
					( Origin gPackager )
				)
				( objectStatus "U5D1.B73" )
			)
			( pin "@baseboard_fab2_lib.baseboard_fab2(sch_1):page24_i172:ddr1_dqs_dn(13)"
				( attribute "PN" "J42"
					( Origin gPackager )
				)
				( objectStatus "U5D1.J42" )
			)
			( pin "@baseboard_fab2_lib.baseboard_fab2(sch_1):page24_i172:ddr1_dqs_dn(14)"
				( attribute "PN" "A34"
					( Origin gPackager )
				)
				( objectStatus "U5D1.A34" )
			)
			( pin "@baseboard_fab2_lib.baseboard_fab2(sch_1):page24_i172:ddr1_dqs_dn(15)"
				( attribute "PN" "A28"
					( Origin gPackager )
				)
				( objectStatus "U5D1.A28" )
			)
			( pin "@baseboard_fab2_lib.baseboard_fab2(sch_1):page24_i172:ddr1_dqs_dn(16)"
				( attribute "PN" "T27"
					( Origin gPackager )
				)
				( objectStatus "U5D1.T27" )
			)
			( pin "@baseboard_fab2_lib.baseboard_fab2(sch_1):page24_i172:ddr1_dqs_dn(17)"
				( attribute "PN" "G68"
					( Origin gPackager )
				)
				( objectStatus "U5D1.G68" )
			)
			( pin "@baseboard_fab2_lib.baseboard_fab2(sch_1):page24_i172:ddr1_dqs_dp(0)"
				( attribute "PN" "AR80"
					( Origin gPackager )
				)
				( objectStatus "U5D1.AR80" )
			)
			( pin "@baseboard_fab2_lib.baseboard_fab2(sch_1):page24_i172:ddr1_dqs_dp(1)"
				( attribute "PN" "AE80"
					( Origin gPackager )
				)
				( objectStatus "U5D1.AE80" )
			)
			( pin "@baseboard_fab2_lib.baseboard_fab2(sch_1):page24_i172:ddr1_dqs_dp(2)"
				( attribute "PN" "H79"
					( Origin gPackager )
				)
				( objectStatus "U5D1.H79" )
			)
			( pin "@baseboard_fab2_lib.baseboard_fab2(sch_1):page24_i172:ddr1_dqs_dp(3)"
				( attribute "PN" "F73"
					( Origin gPackager )
				)
				( objectStatus "U5D1.F73" )
			)
			( pin "@baseboard_fab2_lib.baseboard_fab2(sch_1):page24_i172:ddr1_dqs_dp(4)"
				( attribute "PN" "R42"
					( Origin gPackager )
				)
				( objectStatus "U5D1.R42" )
			)
			( pin "@baseboard_fab2_lib.baseboard_fab2(sch_1):page24_i172:ddr1_dqs_dp(5)"
				( attribute "PN" "E34"
					( Origin gPackager )
				)
				( objectStatus "U5D1.E34" )
			)
			( pin "@baseboard_fab2_lib.baseboard_fab2(sch_1):page24_i172:ddr1_dqs_dp(6)"
				( attribute "PN" "E28"
					( Origin gPackager )
				)
				( objectStatus "U5D1.E28" )
			)
			( pin "@baseboard_fab2_lib.baseboard_fab2(sch_1):page24_i172:ddr1_dqs_dp(7)"
				( attribute "PN" "Y27"
					( Origin gPackager )
				)
				( objectStatus "U5D1.Y27" )
			)
			( pin "@baseboard_fab2_lib.baseboard_fab2(sch_1):page24_i172:ddr1_dqs_dp(8)"
				( attribute "PN" "L68"
					( Origin gPackager )
				)
				( objectStatus "U5D1.L68" )
			)
			( pin "@baseboard_fab2_lib.baseboard_fab2(sch_1):page24_i172:ddr1_dqs_dp(9)"
				( attribute "PN" "AT81"
					( Origin gPackager )
				)
				( objectStatus "U5D1.AT81" )
			)
			( pin "@baseboard_fab2_lib.baseboard_fab2(sch_1):page24_i172:ddr1_dqs_dp(10)"
				( attribute "PN" "AF81"
					( Origin gPackager )
				)
				( objectStatus "U5D1.AF81" )
			)
			( pin "@baseboard_fab2_lib.baseboard_fab2(sch_1):page24_i172:ddr1_dqs_dp(11)"
				( attribute "PN" "F79"
					( Origin gPackager )
				)
				( objectStatus "U5D1.F79" )
			)
			( pin "@baseboard_fab2_lib.baseboard_fab2(sch_1):page24_i172:ddr1_dqs_dp(12)"
				( attribute "PN" "D73"
					( Origin gPackager )
				)
				( objectStatus "U5D1.D73" )
			)
			( pin "@baseboard_fab2_lib.baseboard_fab2(sch_1):page24_i172:ddr1_dqs_dp(13)"
				( attribute "PN" "L42"
					( Origin gPackager )
				)
				( objectStatus "U5D1.L42" )
			)
			( pin "@baseboard_fab2_lib.baseboard_fab2(sch_1):page24_i172:ddr1_dqs_dp(14)"
				( attribute "PN" "C34"
					( Origin gPackager )
				)
				( objectStatus "U5D1.C34" )
			)
			( pin "@baseboard_fab2_lib.baseboard_fab2(sch_1):page24_i172:ddr1_dqs_dp(15)"
				( attribute "PN" "C28"
					( Origin gPackager )
				)
				( objectStatus "U5D1.C28" )
			)
			( pin "@baseboard_fab2_lib.baseboard_fab2(sch_1):page24_i172:ddr1_dqs_dp(16)"
				( attribute "PN" "V27"
					( Origin gPackager )
				)
				( objectStatus "U5D1.V27" )
			)
			( pin "@baseboard_fab2_lib.baseboard_fab2(sch_1):page24_i172:ddr1_dqs_dp(17)"
				( attribute "PN" "J68"
					( Origin gPackager )
				)
				( objectStatus "U5D1.J68" )
			)
			( pin "@baseboard_fab2_lib.baseboard_fab2(sch_1):page24_i172:ddr1_ecc(0)"
				( attribute "PN" "J70"
					( Origin gPackager )
				)
				( objectStatus "U5D1.J70" )
			)
			( pin "@baseboard_fab2_lib.baseboard_fab2(sch_1):page24_i172:ddr1_ecc(1)"
				( attribute "PN" "H69"
					( Origin gPackager )
				)
				( objectStatus "U5D1.H69" )
			)
			( pin "@baseboard_fab2_lib.baseboard_fab2(sch_1):page24_i172:ddr1_ecc(2)"
				( attribute "PN" "J66"
					( Origin gPackager )
				)
				( objectStatus "U5D1.J66" )
			)
			( pin "@baseboard_fab2_lib.baseboard_fab2(sch_1):page24_i172:ddr1_ecc(3)"
				( attribute "PN" "L66"
					( Origin gPackager )
				)
				( objectStatus "U5D1.L66" )
			)
			( pin "@baseboard_fab2_lib.baseboard_fab2(sch_1):page24_i172:ddr1_ecc(4)"
				( attribute "PN" "L70"
					( Origin gPackager )
				)
				( objectStatus "U5D1.L70" )
			)
			( pin "@baseboard_fab2_lib.baseboard_fab2(sch_1):page24_i172:ddr1_ecc(5)"
				( attribute "PN" "M69"
					( Origin gPackager )
				)
				( objectStatus "U5D1.M69" )
			)
			( pin "@baseboard_fab2_lib.baseboard_fab2(sch_1):page24_i172:ddr1_ecc(6)"
				( attribute "PN" "H67"
					( Origin gPackager )
				)
				( objectStatus "U5D1.H67" )
			)
			( pin "@baseboard_fab2_lib.baseboard_fab2(sch_1):page24_i172:ddr1_ecc(7)"
				( attribute "PN" "M67"
					( Origin gPackager )
				)
				( objectStatus "U5D1.M67" )
			)
			( pin "@baseboard_fab2_lib.baseboard_fab2(sch_1):page24_i172:ddr1_ma(0)"
				( attribute "PN" "J52"
					( Origin gPackager )
				)
				( objectStatus "U5D1.J52" )
			)
			( pin "@baseboard_fab2_lib.baseboard_fab2(sch_1):page24_i172:ddr1_ma(1)"
				( attribute "PN" "J58"
					( Origin gPackager )
				)
				( objectStatus "U5D1.J58" )
			)
			( pin "@baseboard_fab2_lib.baseboard_fab2(sch_1):page24_i172:ddr1_ma(2)"
				( attribute "PN" "K57"
					( Origin gPackager )
				)
				( objectStatus "U5D1.K57" )
			)
			( pin "@baseboard_fab2_lib.baseboard_fab2(sch_1):page24_i172:ddr1_ma(3)"
				( attribute "PN" "N58"
					( Origin gPackager )
				)
				( objectStatus "U5D1.N58" )
			)
			( pin "@baseboard_fab2_lib.baseboard_fab2(sch_1):page24_i172:ddr1_ma(4)"
				( attribute "PN" "M59"
					( Origin gPackager )
				)
				( objectStatus "U5D1.M59" )
			)
			( pin "@baseboard_fab2_lib.baseboard_fab2(sch_1):page24_i172:ddr1_ma(5)"
				( attribute "PN" "R58"
					( Origin gPackager )
				)
				( objectStatus "U5D1.R58" )
			)
			( pin "@baseboard_fab2_lib.baseboard_fab2(sch_1):page24_i172:ddr1_ma(6)"
				( attribute "PN" "T59"
					( Origin gPackager )
				)
				( objectStatus "U5D1.T59" )
			)
			( pin "@baseboard_fab2_lib.baseboard_fab2(sch_1):page24_i172:ddr1_ma(7)"
				( attribute "PN" "V61"
					( Origin gPackager )
				)
				( objectStatus "U5D1.V61" )
			)
			( pin "@baseboard_fab2_lib.baseboard_fab2(sch_1):page24_i172:ddr1_ma(8)"
				( attribute "PN" "W60"
					( Origin gPackager )
				)
				( objectStatus "U5D1.W60" )
			)
			( pin "@baseboard_fab2_lib.baseboard_fab2(sch_1):page24_i172:ddr1_ma(9)"
				( attribute "PN" "K59"
					( Origin gPackager )
				)
				( objectStatus "U5D1.K59" )
			)
			( pin "@baseboard_fab2_lib.baseboard_fab2(sch_1):page24_i172:ddr1_ma(10)"
				( attribute "PN" "M55"
					( Origin gPackager )
				)
				( objectStatus "U5D1.M55" )
			)
			( pin "@baseboard_fab2_lib.baseboard_fab2(sch_1):page24_i172:ddr1_ma(11)"
				( attribute "PN" "R60"
					( Origin gPackager )
				)
				( objectStatus "U5D1.R60" )
			)
			( pin "@baseboard_fab2_lib.baseboard_fab2(sch_1):page24_i172:ddr1_ma(12)"
				( attribute "PN" "T61"
					( Origin gPackager )
				)
				( objectStatus "U5D1.T61" )
			)
			( pin "@baseboard_fab2_lib.baseboard_fab2(sch_1):page24_i172:ddr1_ma(13)"
				( attribute "PN" "M51"
					( Origin gPackager )
				)
				( objectStatus "U5D1.M51" )
			)
			( pin "@baseboard_fab2_lib.baseboard_fab2(sch_1):page24_i172:ddr1_ma(14)"
				( attribute "PN" "T51"
					( Origin gPackager )
				)
				( objectStatus "U5D1.T51" )
			)
			( pin "@baseboard_fab2_lib.baseboard_fab2(sch_1):page24_i172:ddr1_ma(15)"
				( attribute "PN" "N52"
					( Origin gPackager )
				)
				( objectStatus "U5D1.N52" )
			)
			( pin "@baseboard_fab2_lib.baseboard_fab2(sch_1):page24_i172:ddr1_ma(16)"
				( attribute "PN" "R52"
					( Origin gPackager )
				)
				( objectStatus "U5D1.R52" )
			)
			( pin "@baseboard_fab2_lib.baseboard_fab2(sch_1):page24_i172:ddr1_ma(17)"
				( attribute "PN" "N48"
					( Origin gPackager )
				)
				( objectStatus "U5D1.N48" )
			)
			( pin "@baseboard_fab2_lib.baseboard_fab2(sch_1):page24_i172:ddr1_odt(0)"
				( attribute "PN" "N50"
					( Origin gPackager )
				)
				( objectStatus "U5D1.N50" )
			)
			( pin "@baseboard_fab2_lib.baseboard_fab2(sch_1):page24_i172:ddr1_odt(1)"
				( attribute "PN" "R48"
					( Origin gPackager )
				)
				( objectStatus "U5D1.R48" )
			)
			( pin "@baseboard_fab2_lib.baseboard_fab2(sch_1):page24_i172:ddr1_odt(2)"
				( attribute "PN" "M49"
					( Origin gPackager )
				)
				( objectStatus "U5D1.M49" )
			)
			( pin "@baseboard_fab2_lib.baseboard_fab2(sch_1):page24_i172:ddr1_odt(3)"
				( attribute "PN" "T47"
					( Origin gPackager )
				)
				( objectStatus "U5D1.T47" )
			)
			( pin "@baseboard_fab2_lib.baseboard_fab2(sch_1):page24_i172:ddr1_par"
				( attribute "PN" "K53"
					( Origin gPackager )
				)
				( objectStatus "U5D1.K53" )
			)
			( pin "@baseboard_fab2_lib.baseboard_fab2(sch_1):page25_i172:ddr2_act_n"
				( attribute "PN" "AB61"
					( Origin gPackager )
				)
				( objectStatus "U5D1.AB61" )
			)
			( pin "@baseboard_fab2_lib.baseboard_fab2(sch_1):page25_i172:ddr2_alert_n"
				( attribute "PN" "AD61"
					( Origin gPackager )
				)
				( objectStatus "U5D1.AD61" )
			)
			( pin "@baseboard_fab2_lib.baseboard_fab2(sch_1):page25_i172:ddr2_ba(0)"
				( attribute "PN" "W52"
					( Origin gPackager )
				)
				( objectStatus "U5D1.W52" )
			)
			( pin "@baseboard_fab2_lib.baseboard_fab2(sch_1):page25_i172:ddr2_ba(1)"
				( attribute "PN" "AE56"
					( Origin gPackager )
				)
				( objectStatus "U5D1.AE56" )
			)
			( pin "@baseboard_fab2_lib.baseboard_fab2(sch_1):page25_i172:ddr2_bg(0)"
				( attribute "PN" "AA60"
					( Origin gPackager )
				)
				( objectStatus "U5D1.AA60" )
			)
			( pin "@baseboard_fab2_lib.baseboard_fab2(sch_1):page25_i172:ddr2_bg(1)"
				( attribute "PN" "AE62"
					( Origin gPackager )
				)
				( objectStatus "U5D1.AE62" )
			)
			( pin "@baseboard_fab2_lib.baseboard_fab2(sch_1):page25_i172:ddr2_cid(2)"
				( attribute "PN" "AB45"
					( Origin gPackager )
				)
				( objectStatus "U5D1.AB45" )
			)
			( pin "@baseboard_fab2_lib.baseboard_fab2(sch_1):page25_i172:ddr2_cke(0)"
				( attribute "PN" "AA62"
					( Origin gPackager )
				)
				( objectStatus "U5D1.AA62" )
			)
			( pin "@baseboard_fab2_lib.baseboard_fab2(sch_1):page25_i172:ddr2_cke(1)"
				( attribute "PN" "AD63"
					( Origin gPackager )
				)
				( objectStatus "U5D1.AD63" )
			)
			( pin "@baseboard_fab2_lib.baseboard_fab2(sch_1):page25_i172:ddr2_cke(2)"
				( attribute "PN" "V63"
					( Origin gPackager )
				)
				( objectStatus "U5D1.V63" )
			)
			( pin "@baseboard_fab2_lib.baseboard_fab2(sch_1):page25_i172:ddr2_cke(3)"
				( attribute "PN" "AB63"
					( Origin gPackager )
				)
				( objectStatus "U5D1.AB63" )
			)
			( pin "@baseboard_fab2_lib.baseboard_fab2(sch_1):page25_i172:ddr2_clk_dn(0)"
				( attribute "PN" "AA54"
					( Origin gPackager )
				)
				( objectStatus "U5D1.AA54" )
			)
			( pin "@baseboard_fab2_lib.baseboard_fab2(sch_1):page25_i172:ddr2_clk_dn(1)"
				( attribute "PN" "W54"
					( Origin gPackager )
				)
				( objectStatus "U5D1.W54" )
			)
			( pin "@baseboard_fab2_lib.baseboard_fab2(sch_1):page25_i172:ddr2_clk_dn(2)"
				( attribute "PN" "AA56"
					( Origin gPackager )
				)
				( objectStatus "U5D1.AA56" )
			)
			( pin "@baseboard_fab2_lib.baseboard_fab2(sch_1):page25_i172:ddr2_clk_dn(3)"
				( attribute "PN" "W56"
					( Origin gPackager )
				)
				( objectStatus "U5D1.W56" )
			)
			( pin "@baseboard_fab2_lib.baseboard_fab2(sch_1):page25_i172:ddr2_clk_dp(0)"
				( attribute "PN" "AB55"
					( Origin gPackager )
				)
				( objectStatus "U5D1.AB55" )
			)
			( pin "@baseboard_fab2_lib.baseboard_fab2(sch_1):page25_i172:ddr2_clk_dp(1)"
				( attribute "PN" "V55"
					( Origin gPackager )
				)
				( objectStatus "U5D1.V55" )
			)
			( pin "@baseboard_fab2_lib.baseboard_fab2(sch_1):page25_i172:ddr2_clk_dp(2)"
				( attribute "PN" "AB57"
					( Origin gPackager )
				)
				( objectStatus "U5D1.AB57" )
			)
			( pin "@baseboard_fab2_lib.baseboard_fab2(sch_1):page25_i172:ddr2_clk_dp(3)"
				( attribute "PN" "V57"
					( Origin gPackager )
				)
				( objectStatus "U5D1.V57" )
			)
			( pin "@baseboard_fab2_lib.baseboard_fab2(sch_1):page25_i172:ddr2_cs_n(0)"
				( attribute "PN" "V51"
					( Origin gPackager )
				)
				( objectStatus "U5D1.V51" )
			)
			( pin "@baseboard_fab2_lib.baseboard_fab2(sch_1):page25_i172:ddr2_cs_n(1)"
				( attribute "PN" "AB49"
					( Origin gPackager )
				)
				( objectStatus "U5D1.AB49" )
			)
			( pin "@baseboard_fab2_lib.baseboard_fab2(sch_1):page25_i172:ddr2_cs_n(2)"
				( attribute "PN" "W46"
					( Origin gPackager )
				)
				( objectStatus "U5D1.W46" )
			)
			( pin "@baseboard_fab2_lib.baseboard_fab2(sch_1):page25_i172:ddr2_cs_n(3)"
				( attribute "PN" "AA46"
					( Origin gPackager )
				)
				( objectStatus "U5D1.AA46" )
			)
			( pin "@baseboard_fab2_lib.baseboard_fab2(sch_1):page25_i172:ddr2_cs_n(4)"
				( attribute "PN" "AB51"
					( Origin gPackager )
				)
				( objectStatus "U5D1.AB51" )
			)
			( pin "@baseboard_fab2_lib.baseboard_fab2(sch_1):page25_i172:ddr2_cs_n(5)"
				( attribute "PN" "W48"
					( Origin gPackager )
				)
				( objectStatus "U5D1.W48" )
			)
			( pin "@baseboard_fab2_lib.baseboard_fab2(sch_1):page25_i172:ddr2_cs_n(6)"
				( attribute "PN" "T45"
					( Origin gPackager )
				)
				( objectStatus "U5D1.T45" )
			)
			( pin "@baseboard_fab2_lib.baseboard_fab2(sch_1):page25_i172:ddr2_cs_n(7)"
				( attribute "PN" "V45"
					( Origin gPackager )
				)
				( objectStatus "U5D1.V45" )
			)
			( pin "@baseboard_fab2_lib.baseboard_fab2(sch_1):page25_i172:ddr2_dq(0)"
				( attribute "PN" "AR76"
					( Origin gPackager )
				)
				( objectStatus "U5D1.AR76" )
			)
			( pin "@baseboard_fab2_lib.baseboard_fab2(sch_1):page25_i172:ddr2_dq(1)"
				( attribute "PN" "AN74"
					( Origin gPackager )
				)
				( objectStatus "U5D1.AN74" )
			)
			( pin "@baseboard_fab2_lib.baseboard_fab2(sch_1):page25_i172:ddr2_dq(2)"
				( attribute "PN" "AK77"
					( Origin gPackager )
				)
				( objectStatus "U5D1.AK77" )
			)
			( pin "@baseboard_fab2_lib.baseboard_fab2(sch_1):page25_i172:ddr2_dq(3)"
				( attribute "PN" "AJ76"
					( Origin gPackager )
				)
				( objectStatus "U5D1.AJ76" )
			)
			( pin "@baseboard_fab2_lib.baseboard_fab2(sch_1):page25_i172:ddr2_dq(4)"
				( attribute "PN" "AT75"
					( Origin gPackager )
				)
				( objectStatus "U5D1.AT75" )
			)
			( pin "@baseboard_fab2_lib.baseboard_fab2(sch_1):page25_i172:ddr2_dq(5)"
				( attribute "PN" "AR74"
					( Origin gPackager )
				)
				( objectStatus "U5D1.AR74" )
			)
			( pin "@baseboard_fab2_lib.baseboard_fab2(sch_1):page25_i172:ddr2_dq(6)"
				( attribute "PN" "AM77"
					( Origin gPackager )
				)
				( objectStatus "U5D1.AM77" )
			)
			( pin "@baseboard_fab2_lib.baseboard_fab2(sch_1):page25_i172:ddr2_dq(7)"
				( attribute "PN" "AK75"
					( Origin gPackager )
				)
				( objectStatus "U5D1.AK75" )
			)
			( pin "@baseboard_fab2_lib.baseboard_fab2(sch_1):page25_i172:ddr2_dq(8)"
				( attribute "PN" "AE76"
					( Origin gPackager )
				)
				( objectStatus "U5D1.AE76" )
			)
			( pin "@baseboard_fab2_lib.baseboard_fab2(sch_1):page25_i172:ddr2_dq(9)"
				( attribute "PN" "AC74"
					( Origin gPackager )
				)
				( objectStatus "U5D1.AC74" )
			)
			( pin "@baseboard_fab2_lib.baseboard_fab2(sch_1):page25_i172:ddr2_dq(10)"
				( attribute "PN" "Y77"
					( Origin gPackager )
				)
				( objectStatus "U5D1.Y77" )
			)
			( pin "@baseboard_fab2_lib.baseboard_fab2(sch_1):page25_i172:ddr2_dq(11)"
				( attribute "PN" "W76"
					( Origin gPackager )
				)
				( objectStatus "U5D1.W76" )
			)
			( pin "@baseboard_fab2_lib.baseboard_fab2(sch_1):page25_i172:ddr2_dq(12)"
				( attribute "PN" "AF75"
					( Origin gPackager )
				)
				( objectStatus "U5D1.AF75" )
			)
			( pin "@baseboard_fab2_lib.baseboard_fab2(sch_1):page25_i172:ddr2_dq(13)"
				( attribute "PN" "AE74"
					( Origin gPackager )
				)
				( objectStatus "U5D1.AE74" )
			)
			( pin "@baseboard_fab2_lib.baseboard_fab2(sch_1):page25_i172:ddr2_dq(14)"
				( attribute "PN" "AB77"
					( Origin gPackager )
				)
				( objectStatus "U5D1.AB77" )
			)
			( pin "@baseboard_fab2_lib.baseboard_fab2(sch_1):page25_i172:ddr2_dq(15)"
				( attribute "PN" "Y75"
					( Origin gPackager )
				)
				( objectStatus "U5D1.Y75" )
			)
			( pin "@baseboard_fab2_lib.baseboard_fab2(sch_1):page25_i172:ddr2_dq(16)"
				( attribute "PN" "W72"
					( Origin gPackager )
				)
				( objectStatus "U5D1.W72" )
			)
			( pin "@baseboard_fab2_lib.baseboard_fab2(sch_1):page25_i172:ddr2_dq(17)"
				( attribute "PN" "AA70"
					( Origin gPackager )
				)
				( objectStatus "U5D1.AA70" )
			)
			( pin "@baseboard_fab2_lib.baseboard_fab2(sch_1):page25_i172:ddr2_dq(18)"
				( attribute "PN" "R70"
					( Origin gPackager )
				)
				( objectStatus "U5D1.R70" )
			)
			( pin "@baseboard_fab2_lib.baseboard_fab2(sch_1):page25_i172:ddr2_dq(19)"
				( attribute "PN" "T69"
					( Origin gPackager )
				)
				( objectStatus "U5D1.T69" )
			)
			( pin "@baseboard_fab2_lib.baseboard_fab2(sch_1):page25_i172:ddr2_dq(20)"
				( attribute "PN" "AA72"
					( Origin gPackager )
				)
				( objectStatus "U5D1.AA72" )
			)
			( pin "@baseboard_fab2_lib.baseboard_fab2(sch_1):page25_i172:ddr2_dq(21)"
				( attribute "PN" "AB71"
					( Origin gPackager )
				)
				( objectStatus "U5D1.AB71" )
			)
			( pin "@baseboard_fab2_lib.baseboard_fab2(sch_1):page25_i172:ddr2_dq(22)"
				( attribute "PN" "T71"
					( Origin gPackager )
				)
				( objectStatus "U5D1.T71" )
			)
			( pin "@baseboard_fab2_lib.baseboard_fab2(sch_1):page25_i172:ddr2_dq(23)"
				( attribute "PN" "V69"
					( Origin gPackager )
				)
				( objectStatus "U5D1.V69" )
			)
			( pin "@baseboard_fab2_lib.baseboard_fab2(sch_1):page25_i172:ddr2_dq(24)"
				( attribute "PN" "AM67"
					( Origin gPackager )
				)
				( objectStatus "U5D1.AM67" )
			)
			( pin "@baseboard_fab2_lib.baseboard_fab2(sch_1):page25_i172:ddr2_dq(25)"
				( attribute "PN" "AT67"
					( Origin gPackager )
				)
				( objectStatus "U5D1.AT67" )
			)
			( pin "@baseboard_fab2_lib.baseboard_fab2(sch_1):page25_i172:ddr2_dq(26)"
				( attribute "PN" "AN64"
					( Origin gPackager )
				)
				( objectStatus "U5D1.AN64" )
			)
			( pin "@baseboard_fab2_lib.baseboard_fab2(sch_1):page25_i172:ddr2_dq(27)"
				( attribute "PN" "AR64"
					( Origin gPackager )
				)
				( objectStatus "U5D1.AR64" )
			)
			( pin "@baseboard_fab2_lib.baseboard_fab2(sch_1):page25_i172:ddr2_dq(28)"
				( attribute "PN" "AN68"
					( Origin gPackager )
				)
				( objectStatus "U5D1.AN68" )
			)
			( pin "@baseboard_fab2_lib.baseboard_fab2(sch_1):page25_i172:ddr2_dq(29)"
				( attribute "PN" "AR68"
					( Origin gPackager )
				)
				( objectStatus "U5D1.AR68" )
			)
			( pin "@baseboard_fab2_lib.baseboard_fab2(sch_1):page25_i172:ddr2_dq(30)"
				( attribute "PN" "AM65"
					( Origin gPackager )
				)
				( objectStatus "U5D1.AM65" )
			)
			( pin "@baseboard_fab2_lib.baseboard_fab2(sch_1):page25_i172:ddr2_dq(31)"
				( attribute "PN" "AT65"
					( Origin gPackager )
				)
				( objectStatus "U5D1.AT65" )
			)
			( pin "@baseboard_fab2_lib.baseboard_fab2(sch_1):page25_i172:ddr2_dq(32)"
				( attribute "PN" "U40"
					( Origin gPackager )
				)
				( objectStatus "U5D1.U40" )
			)
			( pin "@baseboard_fab2_lib.baseboard_fab2(sch_1):page25_i172:ddr2_dq(33)"
				( attribute "PN" "AA40"
					( Origin gPackager )
				)
				( objectStatus "U5D1.AA40" )
			)
			( pin "@baseboard_fab2_lib.baseboard_fab2(sch_1):page25_i172:ddr2_dq(34)"
				( attribute "PN" "V37"
					( Origin gPackager )
				)
				( objectStatus "U5D1.V37" )
			)
			( pin "@baseboard_fab2_lib.baseboard_fab2(sch_1):page25_i172:ddr2_dq(35)"
				( attribute "PN" "Y37"
					( Origin gPackager )
				)
				( objectStatus "U5D1.Y37" )
			)
			( pin "@baseboard_fab2_lib.baseboard_fab2(sch_1):page25_i172:ddr2_dq(36)"
				( attribute "PN" "V41"
					( Origin gPackager )
				)
				( objectStatus "U5D1.V41" )
			)
			( pin "@baseboard_fab2_lib.baseboard_fab2(sch_1):page25_i172:ddr2_dq(37)"
				( attribute "PN" "Y41"
					( Origin gPackager )
				)
				( objectStatus "U5D1.Y41" )
			)
			( pin "@baseboard_fab2_lib.baseboard_fab2(sch_1):page25_i172:ddr2_dq(38)"
				( attribute "PN" "U38"
					( Origin gPackager )
				)
				( objectStatus "U5D1.U38" )
			)
			( pin "@baseboard_fab2_lib.baseboard_fab2(sch_1):page25_i172:ddr2_dq(39)"
				( attribute "PN" "AA38"
					( Origin gPackager )
				)
				( objectStatus "U5D1.AA38" )
			)
			( pin "@baseboard_fab2_lib.baseboard_fab2(sch_1):page25_i172:ddr2_dq(40)"
				( attribute "PN" "U34"
					( Origin gPackager )
				)
				( objectStatus "U5D1.U34" )
			)
			( pin "@baseboard_fab2_lib.baseboard_fab2(sch_1):page25_i172:ddr2_dq(41)"
				( attribute "PN" "AA34"
					( Origin gPackager )
				)
				( objectStatus "U5D1.AA34" )
			)
			( pin "@baseboard_fab2_lib.baseboard_fab2(sch_1):page25_i172:ddr2_dq(42)"
				( attribute "PN" "V31"
					( Origin gPackager )
				)
				( objectStatus "U5D1.V31" )
			)
			( pin "@baseboard_fab2_lib.baseboard_fab2(sch_1):page25_i172:ddr2_dq(43)"
				( attribute "PN" "Y31"
					( Origin gPackager )
				)
				( objectStatus "U5D1.Y31" )
			)
			( pin "@baseboard_fab2_lib.baseboard_fab2(sch_1):page25_i172:ddr2_dq(44)"
				( attribute "PN" "V35"
					( Origin gPackager )
				)
				( objectStatus "U5D1.V35" )
			)
			( pin "@baseboard_fab2_lib.baseboard_fab2(sch_1):page25_i172:ddr2_dq(45)"
				( attribute "PN" "Y35"
					( Origin gPackager )
				)
				( objectStatus "U5D1.Y35" )
			)
			( pin "@baseboard_fab2_lib.baseboard_fab2(sch_1):page25_i172:ddr2_dq(46)"
				( attribute "PN" "U32"
					( Origin gPackager )
				)
				( objectStatus "U5D1.U32" )
			)
			( pin "@baseboard_fab2_lib.baseboard_fab2(sch_1):page25_i172:ddr2_dq(47)"
				( attribute "PN" "AA32"
					( Origin gPackager )
				)
				( objectStatus "U5D1.AA32" )
			)
			( pin "@baseboard_fab2_lib.baseboard_fab2(sch_1):page25_i172:ddr2_dq(48)"
				( attribute "PN" "AD31"
					( Origin gPackager )
				)
				( objectStatus "U5D1.AD31" )
			)
			( pin "@baseboard_fab2_lib.baseboard_fab2(sch_1):page25_i172:ddr2_dq(49)"
				( attribute "PN" "AH31"
					( Origin gPackager )
				)
				( objectStatus "U5D1.AH31" )
			)
			( pin "@baseboard_fab2_lib.baseboard_fab2(sch_1):page25_i172:ddr2_dq(50)"
				( attribute "PN" "AE28"
					( Origin gPackager )
				)
				( objectStatus "U5D1.AE28" )
			)
			( pin "@baseboard_fab2_lib.baseboard_fab2(sch_1):page25_i172:ddr2_dq(51)"
				( attribute "PN" "AG28"
					( Origin gPackager )
				)
				( objectStatus "U5D1.AG28" )
			)
			( pin "@baseboard_fab2_lib.baseboard_fab2(sch_1):page25_i172:ddr2_dq(52)"
				( attribute "PN" "AE32"
					( Origin gPackager )
				)
				( objectStatus "U5D1.AE32" )
			)
			( pin "@baseboard_fab2_lib.baseboard_fab2(sch_1):page25_i172:ddr2_dq(53)"
				( attribute "PN" "AG32"
					( Origin gPackager )
				)
				( objectStatus "U5D1.AG32" )
			)
			( pin "@baseboard_fab2_lib.baseboard_fab2(sch_1):page25_i172:ddr2_dq(54)"
				( attribute "PN" "AD29"
					( Origin gPackager )
				)
				( objectStatus "U5D1.AD29" )
			)
			( pin "@baseboard_fab2_lib.baseboard_fab2(sch_1):page25_i172:ddr2_dq(55)"
				( attribute "PN" "AH29"
					( Origin gPackager )
				)
				( objectStatus "U5D1.AH29" )
			)
			( pin "@baseboard_fab2_lib.baseboard_fab2(sch_1):page25_i172:ddr2_dq(56)"
				( attribute "PN" "AD25"
					( Origin gPackager )
				)
				( objectStatus "U5D1.AD25" )
			)
			( pin "@baseboard_fab2_lib.baseboard_fab2(sch_1):page25_i172:ddr2_dq(57)"
				( attribute "PN" "AH25"
					( Origin gPackager )
				)
				( objectStatus "U5D1.AH25" )
			)
			( pin "@baseboard_fab2_lib.baseboard_fab2(sch_1):page25_i172:ddr2_dq(58)"
				( attribute "PN" "AE22"
					( Origin gPackager )
				)
				( objectStatus "U5D1.AE22" )
			)
			( pin "@baseboard_fab2_lib.baseboard_fab2(sch_1):page25_i172:ddr2_dq(59)"
				( attribute "PN" "AG22"
					( Origin gPackager )
				)
				( objectStatus "U5D1.AG22" )
			)
			( pin "@baseboard_fab2_lib.baseboard_fab2(sch_1):page25_i172:ddr2_dq(60)"
				( attribute "PN" "AE26"
					( Origin gPackager )
				)
				( objectStatus "U5D1.AE26" )
			)
			( pin "@baseboard_fab2_lib.baseboard_fab2(sch_1):page25_i172:ddr2_dq(61)"
				( attribute "PN" "AG26"
					( Origin gPackager )
				)
				( objectStatus "U5D1.AG26" )
			)
			( pin "@baseboard_fab2_lib.baseboard_fab2(sch_1):page25_i172:ddr2_dq(62)"
				( attribute "PN" "AD23"
					( Origin gPackager )
				)
				( objectStatus "U5D1.AD23" )
			)
			( pin "@baseboard_fab2_lib.baseboard_fab2(sch_1):page25_i172:ddr2_dq(63)"
				( attribute "PN" "AH23"
					( Origin gPackager )
				)
				( objectStatus "U5D1.AH23" )
			)
			( pin "@baseboard_fab2_lib.baseboard_fab2(sch_1):page25_i172:ddr2_dqs_dn(0)"
				( attribute "PN" "AL74"
					( Origin gPackager )
				)
				( objectStatus "U5D1.AL74" )
			)
			( pin "@baseboard_fab2_lib.baseboard_fab2(sch_1):page25_i172:ddr2_dqs_dn(1)"
				( attribute "PN" "AA74"
					( Origin gPackager )
				)
				( objectStatus "U5D1.AA74" )
			)
			( pin "@baseboard_fab2_lib.baseboard_fab2(sch_1):page25_i172:ddr2_dqs_dn(2)"
				( attribute "PN" "Y69"
					( Origin gPackager )
				)
				( objectStatus "U5D1.Y69" )
			)
			( pin "@baseboard_fab2_lib.baseboard_fab2(sch_1):page25_i172:ddr2_dqs_dn(3)"
				( attribute "PN" "AU66"
					( Origin gPackager )
				)
				( objectStatus "U5D1.AU66" )
			)
			( pin "@baseboard_fab2_lib.baseboard_fab2(sch_1):page25_i172:ddr2_dqs_dn(4)"
				( attribute "PN" "AB39"
					( Origin gPackager )
				)
				( objectStatus "U5D1.AB39" )
			)
			( pin "@baseboard_fab2_lib.baseboard_fab2(sch_1):page25_i172:ddr2_dqs_dn(5)"
				( attribute "PN" "AB33"
					( Origin gPackager )
				)
				( objectStatus "U5D1.AB33" )
			)
			( pin "@baseboard_fab2_lib.baseboard_fab2(sch_1):page25_i172:ddr2_dqs_dn(6)"
				( attribute "PN" "AJ30"
					( Origin gPackager )
				)
				( objectStatus "U5D1.AJ30" )
			)
			( pin "@baseboard_fab2_lib.baseboard_fab2(sch_1):page25_i172:ddr2_dqs_dn(7)"
				( attribute "PN" "AJ24"
					( Origin gPackager )
				)
				( objectStatus "U5D1.AJ24" )
			)
			( pin "@baseboard_fab2_lib.baseboard_fab2(sch_1):page25_i172:ddr2_dqs_dn(8)"
				( attribute "PN" "BB71"
					( Origin gPackager )
				)
				( objectStatus "U5D1.BB71" )
			)
			( pin "@baseboard_fab2_lib.baseboard_fab2(sch_1):page25_i172:ddr2_dqs_dn(9)"
				( attribute "PN" "AP77"
					( Origin gPackager )
				)
				( objectStatus "U5D1.AP77" )
			)
			( pin "@baseboard_fab2_lib.baseboard_fab2(sch_1):page25_i172:ddr2_dqs_dn(10)"
				( attribute "PN" "AD77"
					( Origin gPackager )
				)
				( objectStatus "U5D1.AD77" )
			)
			( pin "@baseboard_fab2_lib.baseboard_fab2(sch_1):page25_i172:ddr2_dqs_dn(11)"
				( attribute "PN" "U72"
					( Origin gPackager )
				)
				( objectStatus "U5D1.U72" )
			)
			( pin "@baseboard_fab2_lib.baseboard_fab2(sch_1):page25_i172:ddr2_dqs_dn(12)"
				( attribute "PN" "AL66"
					( Origin gPackager )
				)
				( objectStatus "U5D1.AL66" )
			)
			( pin "@baseboard_fab2_lib.baseboard_fab2(sch_1):page25_i172:ddr2_dqs_dn(13)"
				( attribute "PN" "T39"
					( Origin gPackager )
				)
				( objectStatus "U5D1.T39" )
			)
			( pin "@baseboard_fab2_lib.baseboard_fab2(sch_1):page25_i172:ddr2_dqs_dn(14)"
				( attribute "PN" "T33"
					( Origin gPackager )
				)
				( objectStatus "U5D1.T33" )
			)
			( pin "@baseboard_fab2_lib.baseboard_fab2(sch_1):page25_i172:ddr2_dqs_dn(15)"
				( attribute "PN" "AC30"
					( Origin gPackager )
				)
				( objectStatus "U5D1.AC30" )
			)
			( pin "@baseboard_fab2_lib.baseboard_fab2(sch_1):page25_i172:ddr2_dqs_dn(16)"
				( attribute "PN" "AC24"
					( Origin gPackager )
				)
				( objectStatus "U5D1.AC24" )
			)
			( pin "@baseboard_fab2_lib.baseboard_fab2(sch_1):page25_i172:ddr2_dqs_dn(17)"
				( attribute "PN" "AT71"
					( Origin gPackager )
				)
				( objectStatus "U5D1.AT71" )
			)
			( pin "@baseboard_fab2_lib.baseboard_fab2(sch_1):page25_i172:ddr2_dqs_dp(0)"
				( attribute "PN" "AM75"
					( Origin gPackager )
				)
				( objectStatus "U5D1.AM75" )
			)
			( pin "@baseboard_fab2_lib.baseboard_fab2(sch_1):page25_i172:ddr2_dqs_dp(1)"
				( attribute "PN" "AB75"
					( Origin gPackager )
				)
				( objectStatus "U5D1.AB75" )
			)
			( pin "@baseboard_fab2_lib.baseboard_fab2(sch_1):page25_i172:ddr2_dqs_dp(2)"
				( attribute "PN" "W70"
					( Origin gPackager )
				)
				( objectStatus "U5D1.W70" )
			)
			( pin "@baseboard_fab2_lib.baseboard_fab2(sch_1):page25_i172:ddr2_dqs_dp(3)"
				( attribute "PN" "AR66"
					( Origin gPackager )
				)
				( objectStatus "U5D1.AR66" )
			)
			( pin "@baseboard_fab2_lib.baseboard_fab2(sch_1):page25_i172:ddr2_dqs_dp(4)"
				( attribute "PN" "Y39"
					( Origin gPackager )
				)
				( objectStatus "U5D1.Y39" )
			)
			( pin "@baseboard_fab2_lib.baseboard_fab2(sch_1):page25_i172:ddr2_dqs_dp(5)"
				( attribute "PN" "Y33"
					( Origin gPackager )
				)
				( objectStatus "U5D1.Y33" )
			)
			( pin "@baseboard_fab2_lib.baseboard_fab2(sch_1):page25_i172:ddr2_dqs_dp(6)"
				( attribute "PN" "AG30"
					( Origin gPackager )
				)
				( objectStatus "U5D1.AG30" )
			)
			( pin "@baseboard_fab2_lib.baseboard_fab2(sch_1):page25_i172:ddr2_dqs_dp(7)"
				( attribute "PN" "AG24"
					( Origin gPackager )
				)
				( objectStatus "U5D1.AG24" )
			)
			( pin "@baseboard_fab2_lib.baseboard_fab2(sch_1):page25_i172:ddr2_dqs_dp(8)"
				( attribute "PN" "AY71"
					( Origin gPackager )
				)
				( objectStatus "U5D1.AY71" )
			)
			( pin "@baseboard_fab2_lib.baseboard_fab2(sch_1):page25_i172:ddr2_dqs_dp(9)"
				( attribute "PN" "AN76"
					( Origin gPackager )
				)
				( objectStatus "U5D1.AN76" )
			)
			( pin "@baseboard_fab2_lib.baseboard_fab2(sch_1):page25_i172:ddr2_dqs_dp(10)"
				( attribute "PN" "AC76"
					( Origin gPackager )
				)
				( objectStatus "U5D1.AC76" )
			)
			( pin "@baseboard_fab2_lib.baseboard_fab2(sch_1):page25_i172:ddr2_dqs_dp(11)"
				( attribute "PN" "V71"
					( Origin gPackager )
				)
				( objectStatus "U5D1.V71" )
			)
			( pin "@baseboard_fab2_lib.baseboard_fab2(sch_1):page25_i172:ddr2_dqs_dp(12)"
				( attribute "PN" "AN66"
					( Origin gPackager )
				)
				( objectStatus "U5D1.AN66" )
			)
			( pin "@baseboard_fab2_lib.baseboard_fab2(sch_1):page25_i172:ddr2_dqs_dp(13)"
				( attribute "PN" "V39"
					( Origin gPackager )
				)
				( objectStatus "U5D1.V39" )
			)
			( pin "@baseboard_fab2_lib.baseboard_fab2(sch_1):page25_i172:ddr2_dqs_dp(14)"
				( attribute "PN" "V33"
					( Origin gPackager )
				)
				( objectStatus "U5D1.V33" )
			)
			( pin "@baseboard_fab2_lib.baseboard_fab2(sch_1):page25_i172:ddr2_dqs_dp(15)"
				( attribute "PN" "AE30"
					( Origin gPackager )
				)
				( objectStatus "U5D1.AE30" )
			)
			( pin "@baseboard_fab2_lib.baseboard_fab2(sch_1):page25_i172:ddr2_dqs_dp(16)"
				( attribute "PN" "AE24"
					( Origin gPackager )
				)
				( objectStatus "U5D1.AE24" )
			)
			( pin "@baseboard_fab2_lib.baseboard_fab2(sch_1):page25_i172:ddr2_dqs_dp(17)"
				( attribute "PN" "AV71"
					( Origin gPackager )
				)
				( objectStatus "U5D1.AV71" )
			)
			( pin "@baseboard_fab2_lib.baseboard_fab2(sch_1):page25_i172:ddr2_ecc(0)"
				( attribute "PN" "AU72"
					( Origin gPackager )
				)
				( objectStatus "U5D1.AU72" )
			)
			( pin "@baseboard_fab2_lib.baseboard_fab2(sch_1):page25_i172:ddr2_ecc(1)"
				( attribute "PN" "BA72"
					( Origin gPackager )
				)
				( objectStatus "U5D1.BA72" )
			)
			( pin "@baseboard_fab2_lib.baseboard_fab2(sch_1):page25_i172:ddr2_ecc(2)"
				( attribute "PN" "AV69"
					( Origin gPackager )
				)
				( objectStatus "U5D1.AV69" )
			)
			( pin "@baseboard_fab2_lib.baseboard_fab2(sch_1):page25_i172:ddr2_ecc(3)"
				( attribute "PN" "AY69"
					( Origin gPackager )
				)
				( objectStatus "U5D1.AY69" )
			)
			( pin "@baseboard_fab2_lib.baseboard_fab2(sch_1):page25_i172:ddr2_ecc(4)"
				( attribute "PN" "AV73"
					( Origin gPackager )
				)
				( objectStatus "U5D1.AV73" )
			)
			( pin "@baseboard_fab2_lib.baseboard_fab2(sch_1):page25_i172:ddr2_ecc(5)"
				( attribute "PN" "AY73"
					( Origin gPackager )
				)
				( objectStatus "U5D1.AY73" )
			)
			( pin "@baseboard_fab2_lib.baseboard_fab2(sch_1):page25_i172:ddr2_ecc(6)"
				( attribute "PN" "AU70"
					( Origin gPackager )
				)
				( objectStatus "U5D1.AU70" )
			)
			( pin "@baseboard_fab2_lib.baseboard_fab2(sch_1):page25_i172:ddr2_ecc(7)"
				( attribute "PN" "BA70"
					( Origin gPackager )
				)
				( objectStatus "U5D1.BA70" )
			)
			( pin "@baseboard_fab2_lib.baseboard_fab2(sch_1):page25_i172:ddr2_ma(0)"
				( attribute "PN" "AB53"
					( Origin gPackager )
				)
				( objectStatus "U5D1.AB53" )
			)
			( pin "@baseboard_fab2_lib.baseboard_fab2(sch_1):page25_i172:ddr2_ma(1)"
				( attribute "PN" "AE58"
					( Origin gPackager )
				)
				( objectStatus "U5D1.AE58" )
			)
			( pin "@baseboard_fab2_lib.baseboard_fab2(sch_1):page25_i172:ddr2_ma(2)"
				( attribute "PN" "AD57"
					( Origin gPackager )
				)
				( objectStatus "U5D1.AD57" )
			)
			( pin "@baseboard_fab2_lib.baseboard_fab2(sch_1):page25_i172:ddr2_ma(3)"
				( attribute "PN" "W58"
					( Origin gPackager )
				)
				( objectStatus "U5D1.W58" )
			)
			( pin "@baseboard_fab2_lib.baseboard_fab2(sch_1):page25_i172:ddr2_ma(4)"
				( attribute "PN" "AA58"
					( Origin gPackager )
				)
				( objectStatus "U5D1.AA58" )
			)
			( pin "@baseboard_fab2_lib.baseboard_fab2(sch_1):page25_i172:ddr2_ma(5)"
				( attribute "PN" "V59"
					( Origin gPackager )
				)
				( objectStatus "U5D1.V59" )
			)
			( pin "@baseboard_fab2_lib.baseboard_fab2(sch_1):page25_i172:ddr2_ma(6)"
				( attribute "PN" "AB59"
					( Origin gPackager )
				)
				( objectStatus "U5D1.AB59" )
			)
			( pin "@baseboard_fab2_lib.baseboard_fab2(sch_1):page25_i172:ddr2_ma(7)"
				( attribute "PN" "AE60"
					( Origin gPackager )
				)
				( objectStatus "U5D1.AE60" )
			)
			( pin "@baseboard_fab2_lib.baseboard_fab2(sch_1):page25_i172:ddr2_ma(8)"
				( attribute "PN" "AD59"
					( Origin gPackager )
				)
				( objectStatus "U5D1.AD59" )
			)
			( pin "@baseboard_fab2_lib.baseboard_fab2(sch_1):page25_i172:ddr2_ma(9)"
				( attribute "PN" "AG58"
					( Origin gPackager )
				)
				( objectStatus "U5D1.AG58" )
			)
			( pin "@baseboard_fab2_lib.baseboard_fab2(sch_1):page25_i172:ddr2_ma(10)"
				( attribute "PN" "AD55"
					( Origin gPackager )
				)
				( objectStatus "U5D1.AD55" )
			)
			( pin "@baseboard_fab2_lib.baseboard_fab2(sch_1):page25_i172:ddr2_ma(11)"
				( attribute "PN" "AG60"
					( Origin gPackager )
				)
				( objectStatus "U5D1.AG60" )
			)
			( pin "@baseboard_fab2_lib.baseboard_fab2(sch_1):page25_i172:ddr2_ma(12)"
				( attribute "PN" "AG62"
					( Origin gPackager )
				)
				( objectStatus "U5D1.AG62" )
			)
			( pin "@baseboard_fab2_lib.baseboard_fab2(sch_1):page25_i172:ddr2_ma(13)"
				( attribute "PN" "AD53"
					( Origin gPackager )
				)
				( objectStatus "U5D1.AD53" )
			)
			( pin "@baseboard_fab2_lib.baseboard_fab2(sch_1):page25_i172:ddr2_ma(14)"
				( attribute "PN" "W50"
					( Origin gPackager )
				)
				( objectStatus "U5D1.W50" )
			)
			( pin "@baseboard_fab2_lib.baseboard_fab2(sch_1):page25_i172:ddr2_ma(15)"
				( attribute "PN" "AE54"
					( Origin gPackager )
				)
				( objectStatus "U5D1.AE54" )
			)
			( pin "@baseboard_fab2_lib.baseboard_fab2(sch_1):page25_i172:ddr2_ma(16)"
				( attribute "PN" "AA52"
					( Origin gPackager )
				)
				( objectStatus "U5D1.AA52" )
			)
			( pin "@baseboard_fab2_lib.baseboard_fab2(sch_1):page25_i172:ddr2_ma(17)"
				( attribute "PN" "AC46"
					( Origin gPackager )
				)
				( objectStatus "U5D1.AC46" )
			)
			( pin "@baseboard_fab2_lib.baseboard_fab2(sch_1):page25_i172:ddr2_odt(0)"
				( attribute "PN" "AA50"
					( Origin gPackager )
				)
				( objectStatus "U5D1.AA50" )
			)
			( pin "@baseboard_fab2_lib.baseboard_fab2(sch_1):page25_i172:ddr2_odt(1)"
				( attribute "PN" "AA48"
					( Origin gPackager )
				)
				( objectStatus "U5D1.AA48" )
			)
			( pin "@baseboard_fab2_lib.baseboard_fab2(sch_1):page25_i172:ddr2_odt(2)"
				( attribute "PN" "V49"
					( Origin gPackager )
				)
				( objectStatus "U5D1.V49" )
			)
			( pin "@baseboard_fab2_lib.baseboard_fab2(sch_1):page25_i172:ddr2_odt(3)"
				( attribute "PN" "AB47"
					( Origin gPackager )
				)
				( objectStatus "U5D1.AB47" )
			)
			( pin "@baseboard_fab2_lib.baseboard_fab2(sch_1):page25_i172:ddr2_par"
				( attribute "PN" "V53"
					( Origin gPackager )
				)
				( objectStatus "U5D1.V53" )
			)
			( pin "@baseboard_fab2_lib.baseboard_fab2(sch_1):page26_i172:ddr3_act_n"
				( attribute "PN" "DW60"
					( Origin gPackager )
				)
				( objectStatus "U5D1.DW60" )
			)
			( pin "@baseboard_fab2_lib.baseboard_fab2(sch_1):page26_i172:ddr3_alert_n"
				( attribute "PN" "ED63"
					( Origin gPackager )
				)
				( objectStatus "U5D1.ED63" )
			)
			( pin "@baseboard_fab2_lib.baseboard_fab2(sch_1):page26_i172:ddr3_ba(0)"
				( attribute "PN" "EE52"
					( Origin gPackager )
				)
				( objectStatus "U5D1.EE52" )
			)
			( pin "@baseboard_fab2_lib.baseboard_fab2(sch_1):page26_i172:ddr3_ba(1)"
				( attribute "PN" "EA54"
					( Origin gPackager )
				)
				( objectStatus "U5D1.EA54" )
			)
			( pin "@baseboard_fab2_lib.baseboard_fab2(sch_1):page26_i172:ddr3_bg(0)"
				( attribute "PN" "ED61"
					( Origin gPackager )
				)
				( objectStatus "U5D1.ED61" )
			)
			( pin "@baseboard_fab2_lib.baseboard_fab2(sch_1):page26_i172:ddr3_bg(1)"
				( attribute "PN" "DW62"
					( Origin gPackager )
				)
				( objectStatus "U5D1.DW62" )
			)
			( pin "@baseboard_fab2_lib.baseboard_fab2(sch_1):page26_i172:ddr3_cid(2)"
				( attribute "PN" "DV47"
					( Origin gPackager )
				)
				( objectStatus "U5D1.DV47" )
			)
			( pin "@baseboard_fab2_lib.baseboard_fab2(sch_1):page26_i172:ddr3_cke(0)"
				( attribute "PN" "EE62"
					( Origin gPackager )
				)
				( objectStatus "U5D1.EE62" )
			)
			( pin "@baseboard_fab2_lib.baseboard_fab2(sch_1):page26_i172:ddr3_cke(1)"
				( attribute "PN" "EF63"
					( Origin gPackager )
				)
				( objectStatus "U5D1.EF63" )
			)
			( pin "@baseboard_fab2_lib.baseboard_fab2(sch_1):page26_i172:ddr3_cke(2)"
				( attribute "PN" "EA62"
					( Origin gPackager )
				)
				( objectStatus "U5D1.EA62" )
			)
			( pin "@baseboard_fab2_lib.baseboard_fab2(sch_1):page26_i172:ddr3_cke(3)"
				( attribute "PN" "EB63"
					( Origin gPackager )
				)
				( objectStatus "U5D1.EB63" )
			)
			( pin "@baseboard_fab2_lib.baseboard_fab2(sch_1):page26_i172:ddr3_clk_dn(0)"
				( attribute "PN" "ED55"
					( Origin gPackager )
				)
				( objectStatus "U5D1.ED55" )
			)
			( pin "@baseboard_fab2_lib.baseboard_fab2(sch_1):page26_i172:ddr3_clk_dn(1)"
				( attribute "PN" "EF55"
					( Origin gPackager )
				)
				( objectStatus "U5D1.EF55" )
			)
			( pin "@baseboard_fab2_lib.baseboard_fab2(sch_1):page26_i172:ddr3_clk_dn(2)"
				( attribute "PN" "DW56"
					( Origin gPackager )
				)
				( objectStatus "U5D1.DW56" )
			)
			( pin "@baseboard_fab2_lib.baseboard_fab2(sch_1):page26_i172:ddr3_clk_dn(3)"
				( attribute "PN" "EF57"
					( Origin gPackager )
				)
				( objectStatus "U5D1.EF57" )
			)
			( pin "@baseboard_fab2_lib.baseboard_fab2(sch_1):page26_i172:ddr3_clk_dp(0)"
				( attribute "PN" "EB55"
					( Origin gPackager )
				)
				( objectStatus "U5D1.EB55" )
			)
			( pin "@baseboard_fab2_lib.baseboard_fab2(sch_1):page26_i172:ddr3_clk_dp(1)"
				( attribute "PN" "EE54"
					( Origin gPackager )
				)
				( objectStatus "U5D1.EE54" )
			)
			( pin "@baseboard_fab2_lib.baseboard_fab2(sch_1):page26_i172:ddr3_clk_dp(2)"
				( attribute "PN" "EA56"
					( Origin gPackager )
				)
				( objectStatus "U5D1.EA56" )
			)
			( pin "@baseboard_fab2_lib.baseboard_fab2(sch_1):page26_i172:ddr3_clk_dp(3)"
				( attribute "PN" "EE56"
					( Origin gPackager )
				)
				( objectStatus "U5D1.EE56" )
			)
			( pin "@baseboard_fab2_lib.baseboard_fab2(sch_1):page26_i172:ddr3_cs_n(0)"
				( attribute "PN" "EF51"
					( Origin gPackager )
				)
				( objectStatus "U5D1.EF51" )
			)
			( pin "@baseboard_fab2_lib.baseboard_fab2(sch_1):page26_i172:ddr3_cs_n(1)"
				( attribute "PN" "ED49"
					( Origin gPackager )
				)
				( objectStatus "U5D1.ED49" )
			)
			( pin "@baseboard_fab2_lib.baseboard_fab2(sch_1):page26_i172:ddr3_cs_n(2)"
				( attribute "PN" "ED47"
					( Origin gPackager )
				)
				( objectStatus "U5D1.ED47" )
			)
			( pin "@baseboard_fab2_lib.baseboard_fab2(sch_1):page26_i172:ddr3_cs_n(3)"
				( attribute "PN" "EB47"
					( Origin gPackager )
				)
				( objectStatus "U5D1.EB47" )
			)
			( pin "@baseboard_fab2_lib.baseboard_fab2(sch_1):page26_i172:ddr3_cs_n(4)"
				( attribute "PN" "EB51"
					( Origin gPackager )
				)
				( objectStatus "U5D1.EB51" )
			)
			( pin "@baseboard_fab2_lib.baseboard_fab2(sch_1):page26_i172:ddr3_cs_n(5)"
				( attribute "PN" "EB49"
					( Origin gPackager )
				)
				( objectStatus "U5D1.EB49" )
			)
			( pin "@baseboard_fab2_lib.baseboard_fab2(sch_1):page26_i172:ddr3_cs_n(6)"
				( attribute "PN" "DV45"
					( Origin gPackager )
				)
				( objectStatus "U5D1.DV45" )
			)
			( pin "@baseboard_fab2_lib.baseboard_fab2(sch_1):page26_i172:ddr3_cs_n(7)"
				( attribute "PN" "EB45"
					( Origin gPackager )
				)
				( objectStatus "U5D1.EB45" )
			)
			( pin "@baseboard_fab2_lib.baseboard_fab2(sch_1):page26_i172:ddr3_dq(0)"
				( attribute "PN" "CN84"
					( Origin gPackager )
				)
				( objectStatus "U5D1.CN84" )
			)
			( pin "@baseboard_fab2_lib.baseboard_fab2(sch_1):page26_i172:ddr3_dq(1)"
				( attribute "PN" "CN86"
					( Origin gPackager )
				)
				( objectStatus "U5D1.CN86" )
			)
			( pin "@baseboard_fab2_lib.baseboard_fab2(sch_1):page26_i172:ddr3_dq(2)"
				( attribute "PN" "DA86"
					( Origin gPackager )
				)
				( objectStatus "U5D1.DA86" )
			)
			( pin "@baseboard_fab2_lib.baseboard_fab2(sch_1):page26_i172:ddr3_dq(3)"
				( attribute "PN" "DA84"
					( Origin gPackager )
				)
				( objectStatus "U5D1.DA84" )
			)
			( pin "@baseboard_fab2_lib.baseboard_fab2(sch_1):page26_i172:ddr3_dq(4)"
				( attribute "PN" "CL84"
					( Origin gPackager )
				)
				( objectStatus "U5D1.CL84" )
			)
			( pin "@baseboard_fab2_lib.baseboard_fab2(sch_1):page26_i172:ddr3_dq(5)"
				( attribute "PN" "CL86"
					( Origin gPackager )
				)
				( objectStatus "U5D1.CL86" )
			)
			( pin "@baseboard_fab2_lib.baseboard_fab2(sch_1):page26_i172:ddr3_dq(6)"
				( attribute "PN" "CW86"
					( Origin gPackager )
				)
				( objectStatus "U5D1.CW86" )
			)
			( pin "@baseboard_fab2_lib.baseboard_fab2(sch_1):page26_i172:ddr3_dq(7)"
				( attribute "PN" "CW84"
					( Origin gPackager )
				)
				( objectStatus "U5D1.CW84" )
			)
			( pin "@baseboard_fab2_lib.baseboard_fab2(sch_1):page26_i172:ddr3_dq(8)"
				( attribute "PN" "DG84"
					( Origin gPackager )
				)
				( objectStatus "U5D1.DG84" )
			)
			( pin "@baseboard_fab2_lib.baseboard_fab2(sch_1):page26_i172:ddr3_dq(9)"
				( attribute "PN" "DH85"
					( Origin gPackager )
				)
				( objectStatus "U5D1.DH85" )
			)
			( pin "@baseboard_fab2_lib.baseboard_fab2(sch_1):page26_i172:ddr3_dq(10)"
				( attribute "PN" "DV83"
					( Origin gPackager )
				)
				( objectStatus "U5D1.DV83" )
			)
			( pin "@baseboard_fab2_lib.baseboard_fab2(sch_1):page26_i172:ddr3_dq(11)"
				( attribute "PN" "DY83"
					( Origin gPackager )
				)
				( objectStatus "U5D1.DY83" )
			)
			( pin "@baseboard_fab2_lib.baseboard_fab2(sch_1):page26_i172:ddr3_dq(12)"
				( attribute "PN" "DD85"
					( Origin gPackager )
				)
				( objectStatus "U5D1.DD85" )
			)
			( pin "@baseboard_fab2_lib.baseboard_fab2(sch_1):page26_i172:ddr3_dq(13)"
				( attribute "PN" "DE84"
					( Origin gPackager )
				)
				( objectStatus "U5D1.DE84" )
			)
			( pin "@baseboard_fab2_lib.baseboard_fab2(sch_1):page26_i172:ddr3_dq(14)"
				( attribute "PN" "DR84"
					( Origin gPackager )
				)
				( objectStatus "U5D1.DR84" )
			)
			( pin "@baseboard_fab2_lib.baseboard_fab2(sch_1):page26_i172:ddr3_dq(15)"
				( attribute "PN" "DV85"
					( Origin gPackager )
				)
				( objectStatus "U5D1.DV85" )
			)
			( pin "@baseboard_fab2_lib.baseboard_fab2(sch_1):page26_i172:ddr3_dq(16)"
				( attribute "PN" "DM79"
					( Origin gPackager )
				)
				( objectStatus "U5D1.DM79" )
			)
			( pin "@baseboard_fab2_lib.baseboard_fab2(sch_1):page26_i172:ddr3_dq(17)"
				( attribute "PN" "DK81"
					( Origin gPackager )
				)
				( objectStatus "U5D1.DK81" )
			)
			( pin "@baseboard_fab2_lib.baseboard_fab2(sch_1):page26_i172:ddr3_dq(18)"
				( attribute "PN" "DT81"
					( Origin gPackager )
				)
				( objectStatus "U5D1.DT81" )
			)
			( pin "@baseboard_fab2_lib.baseboard_fab2(sch_1):page26_i172:ddr3_dq(19)"
				( attribute "PN" "DR82"
					( Origin gPackager )
				)
				( objectStatus "U5D1.DR82" )
			)
			( pin "@baseboard_fab2_lib.baseboard_fab2(sch_1):page26_i172:ddr3_dq(20)"
				( attribute "PN" "DK79"
					( Origin gPackager )
				)
				( objectStatus "U5D1.DK79" )
			)
			( pin "@baseboard_fab2_lib.baseboard_fab2(sch_1):page26_i172:ddr3_dq(21)"
				( attribute "PN" "DJ80"
					( Origin gPackager )
				)
				( objectStatus "U5D1.DJ80" )
			)
			( pin "@baseboard_fab2_lib.baseboard_fab2(sch_1):page26_i172:ddr3_dq(22)"
				( attribute "PN" "DR80"
					( Origin gPackager )
				)
				( objectStatus "U5D1.DR80" )
			)
			( pin "@baseboard_fab2_lib.baseboard_fab2(sch_1):page26_i172:ddr3_dq(23)"
				( attribute "PN" "DN82"
					( Origin gPackager )
				)
				( objectStatus "U5D1.DN82" )
			)
			( pin "@baseboard_fab2_lib.baseboard_fab2(sch_1):page26_i172:ddr3_dq(24)"
				( attribute "PN" "DN76"
					( Origin gPackager )
				)
				( objectStatus "U5D1.DN76" )
			)
			( pin "@baseboard_fab2_lib.baseboard_fab2(sch_1):page26_i172:ddr3_dq(25)"
				( attribute "PN" "DU76"
					( Origin gPackager )
				)
				( objectStatus "U5D1.DU76" )
			)
			( pin "@baseboard_fab2_lib.baseboard_fab2(sch_1):page26_i172:ddr3_dq(26)"
				( attribute "PN" "DP73"
					( Origin gPackager )
				)
				( objectStatus "U5D1.DP73" )
			)
			( pin "@baseboard_fab2_lib.baseboard_fab2(sch_1):page26_i172:ddr3_dq(27)"
				( attribute "PN" "DT73"
					( Origin gPackager )
				)
				( objectStatus "U5D1.DT73" )
			)
			( pin "@baseboard_fab2_lib.baseboard_fab2(sch_1):page26_i172:ddr3_dq(28)"
				( attribute "PN" "DP77"
					( Origin gPackager )
				)
				( objectStatus "U5D1.DP77" )
			)
			( pin "@baseboard_fab2_lib.baseboard_fab2(sch_1):page26_i172:ddr3_dq(29)"
				( attribute "PN" "DT77"
					( Origin gPackager )
				)
				( objectStatus "U5D1.DT77" )
			)
			( pin "@baseboard_fab2_lib.baseboard_fab2(sch_1):page26_i172:ddr3_dq(30)"
				( attribute "PN" "DN74"
					( Origin gPackager )
				)
				( objectStatus "U5D1.DN74" )
			)
			( pin "@baseboard_fab2_lib.baseboard_fab2(sch_1):page26_i172:ddr3_dq(31)"
				( attribute "PN" "DU74"
					( Origin gPackager )
				)
				( objectStatus "U5D1.DU74" )
			)
			( pin "@baseboard_fab2_lib.baseboard_fab2(sch_1):page26_i172:ddr3_dq(32)"
				( attribute "PN" "EC40"
					( Origin gPackager )
				)
				( objectStatus "U5D1.EC40" )
			)
			( pin "@baseboard_fab2_lib.baseboard_fab2(sch_1):page26_i172:ddr3_dq(33)"
				( attribute "PN" "ED39"
					( Origin gPackager )
				)
				( objectStatus "U5D1.ED39" )
			)
			( pin "@baseboard_fab2_lib.baseboard_fab2(sch_1):page26_i172:ddr3_dq(34)"
				( attribute "PN" "EA36"
					( Origin gPackager )
				)
				( objectStatus "U5D1.EA36" )
			)
			( pin "@baseboard_fab2_lib.baseboard_fab2(sch_1):page26_i172:ddr3_dq(35)"
				( attribute "PN" "EC36"
					( Origin gPackager )
				)
				( objectStatus "U5D1.EC36" )
			)
			( pin "@baseboard_fab2_lib.baseboard_fab2(sch_1):page26_i172:ddr3_dq(36)"
				( attribute "PN" "DY39"
					( Origin gPackager )
				)
				( objectStatus "U5D1.DY39" )
			)
			( pin "@baseboard_fab2_lib.baseboard_fab2(sch_1):page26_i172:ddr3_dq(37)"
				( attribute "PN" "EA40"
					( Origin gPackager )
				)
				( objectStatus "U5D1.EA40" )
			)
			( pin "@baseboard_fab2_lib.baseboard_fab2(sch_1):page26_i172:ddr3_dq(38)"
				( attribute "PN" "DY37"
					( Origin gPackager )
				)
				( objectStatus "U5D1.DY37" )
			)
			( pin "@baseboard_fab2_lib.baseboard_fab2(sch_1):page26_i172:ddr3_dq(39)"
				( attribute "PN" "ED37"
					( Origin gPackager )
				)
				( objectStatus "U5D1.ED37" )
			)
			( pin "@baseboard_fab2_lib.baseboard_fab2(sch_1):page26_i172:ddr3_dq(40)"
				( attribute "PN" "DN36"
					( Origin gPackager )
				)
				( objectStatus "U5D1.DN36" )
			)
			( pin "@baseboard_fab2_lib.baseboard_fab2(sch_1):page26_i172:ddr3_dq(41)"
				( attribute "PN" "DU36"
					( Origin gPackager )
				)
				( objectStatus "U5D1.DU36" )
			)
			( pin "@baseboard_fab2_lib.baseboard_fab2(sch_1):page26_i172:ddr3_dq(42)"
				( attribute "PN" "DP33"
					( Origin gPackager )
				)
				( objectStatus "U5D1.DP33" )
			)
			( pin "@baseboard_fab2_lib.baseboard_fab2(sch_1):page26_i172:ddr3_dq(43)"
				( attribute "PN" "DT33"
					( Origin gPackager )
				)
				( objectStatus "U5D1.DT33" )
			)
			( pin "@baseboard_fab2_lib.baseboard_fab2(sch_1):page26_i172:ddr3_dq(44)"
				( attribute "PN" "DP37"
					( Origin gPackager )
				)
				( objectStatus "U5D1.DP37" )
			)
			( pin "@baseboard_fab2_lib.baseboard_fab2(sch_1):page26_i172:ddr3_dq(45)"
				( attribute "PN" "DT37"
					( Origin gPackager )
				)
				( objectStatus "U5D1.DT37" )
			)
			( pin "@baseboard_fab2_lib.baseboard_fab2(sch_1):page26_i172:ddr3_dq(46)"
				( attribute "PN" "DN34"
					( Origin gPackager )
				)
				( objectStatus "U5D1.DN34" )
			)
			( pin "@baseboard_fab2_lib.baseboard_fab2(sch_1):page26_i172:ddr3_dq(47)"
				( attribute "PN" "DU34"
					( Origin gPackager )
				)
				( objectStatus "U5D1.DU34" )
			)
			( pin "@baseboard_fab2_lib.baseboard_fab2(sch_1):page26_i172:ddr3_dq(48)"
				( attribute "PN" "DN30"
					( Origin gPackager )
				)
				( objectStatus "U5D1.DN30" )
			)
			( pin "@baseboard_fab2_lib.baseboard_fab2(sch_1):page26_i172:ddr3_dq(49)"
				( attribute "PN" "DU30"
					( Origin gPackager )
				)
				( objectStatus "U5D1.DU30" )
			)
			( pin "@baseboard_fab2_lib.baseboard_fab2(sch_1):page26_i172:ddr3_dq(50)"
				( attribute "PN" "DP27"
					( Origin gPackager )
				)
				( objectStatus "U5D1.DP27" )
			)
			( pin "@baseboard_fab2_lib.baseboard_fab2(sch_1):page26_i172:ddr3_dq(51)"
				( attribute "PN" "DT27"
					( Origin gPackager )
				)
				( objectStatus "U5D1.DT27" )
			)
			( pin "@baseboard_fab2_lib.baseboard_fab2(sch_1):page26_i172:ddr3_dq(52)"
				( attribute "PN" "DP31"
					( Origin gPackager )
				)
				( objectStatus "U5D1.DP31" )
			)
			( pin "@baseboard_fab2_lib.baseboard_fab2(sch_1):page26_i172:ddr3_dq(53)"
				( attribute "PN" "DT31"
					( Origin gPackager )
				)
				( objectStatus "U5D1.DT31" )
			)
			( pin "@baseboard_fab2_lib.baseboard_fab2(sch_1):page26_i172:ddr3_dq(54)"
				( attribute "PN" "DN28"
					( Origin gPackager )
				)
				( objectStatus "U5D1.DN28" )
			)
			( pin "@baseboard_fab2_lib.baseboard_fab2(sch_1):page26_i172:ddr3_dq(55)"
				( attribute "PN" "DU28"
					( Origin gPackager )
				)
				( objectStatus "U5D1.DU28" )
			)
			( pin "@baseboard_fab2_lib.baseboard_fab2(sch_1):page26_i172:ddr3_dq(56)"
				( attribute "PN" "DN24"
					( Origin gPackager )
				)
				( objectStatus "U5D1.DN24" )
			)
			( pin "@baseboard_fab2_lib.baseboard_fab2(sch_1):page26_i172:ddr3_dq(57)"
				( attribute "PN" "DU24"
					( Origin gPackager )
				)
				( objectStatus "U5D1.DU24" )
			)
			( pin "@baseboard_fab2_lib.baseboard_fab2(sch_1):page26_i172:ddr3_dq(58)"
				( attribute "PN" "DY21"
					( Origin gPackager )
				)
				( objectStatus "U5D1.DY21" )
			)
			( pin "@baseboard_fab2_lib.baseboard_fab2(sch_1):page26_i172:ddr3_dq(59)"
				( attribute "PN" "EB21"
					( Origin gPackager )
				)
				( objectStatus "U5D1.EB21" )
			)
			( pin "@baseboard_fab2_lib.baseboard_fab2(sch_1):page26_i172:ddr3_dq(60)"
				( attribute "PN" "DP25"
					( Origin gPackager )
				)
				( objectStatus "U5D1.DP25" )
			)
			( pin "@baseboard_fab2_lib.baseboard_fab2(sch_1):page26_i172:ddr3_dq(61)"
				( attribute "PN" "DT25"
					( Origin gPackager )
				)
				( objectStatus "U5D1.DT25" )
			)
			( pin "@baseboard_fab2_lib.baseboard_fab2(sch_1):page26_i172:ddr3_dq(62)"
				( attribute "PN" "EC22"
					( Origin gPackager )
				)
				( objectStatus "U5D1.EC22" )
			)
			( pin "@baseboard_fab2_lib.baseboard_fab2(sch_1):page26_i172:ddr3_dq(63)"
				( attribute "PN" "DW22"
					( Origin gPackager )
				)
				( objectStatus "U5D1.DW22" )
			)
			( pin "@baseboard_fab2_lib.baseboard_fab2(sch_1):page26_i172:ddr3_dqs_dn(0)"
				( attribute "PN" "CU84"
					( Origin gPackager )
				)
				( objectStatus "U5D1.CU84" )
			)
			( pin "@baseboard_fab2_lib.baseboard_fab2(sch_1):page26_i172:ddr3_dqs_dn(1)"
				( attribute "PN" "DN84"
					( Origin gPackager )
				)
				( objectStatus "U5D1.DN84" )
			)
			( pin "@baseboard_fab2_lib.baseboard_fab2(sch_1):page26_i172:ddr3_dqs_dn(2)"
				( attribute "PN" "DL82"
					( Origin gPackager )
				)
				( objectStatus "U5D1.DL82" )
			)
			( pin "@baseboard_fab2_lib.baseboard_fab2(sch_1):page26_i172:ddr3_dqs_dn(3)"
				( attribute "PN" "DV75"
					( Origin gPackager )
				)
				( objectStatus "U5D1.DV75" )
			)
			( pin "@baseboard_fab2_lib.baseboard_fab2(sch_1):page26_i172:ddr3_dqs_dn(4)"
				( attribute "PN" "EE38"
					( Origin gPackager )
				)
				( objectStatus "U5D1.EE38" )
			)
			( pin "@baseboard_fab2_lib.baseboard_fab2(sch_1):page26_i172:ddr3_dqs_dn(5)"
				( attribute "PN" "DV35"
					( Origin gPackager )
				)
				( objectStatus "U5D1.DV35" )
			)
			( pin "@baseboard_fab2_lib.baseboard_fab2(sch_1):page26_i172:ddr3_dqs_dn(6)"
				( attribute "PN" "DV29"
					( Origin gPackager )
				)
				( objectStatus "U5D1.DV29" )
			)
			( pin "@baseboard_fab2_lib.baseboard_fab2(sch_1):page26_i172:ddr3_dqs_dn(7)"
				( attribute "PN" "DV23"
					( Origin gPackager )
				)
				( objectStatus "U5D1.DV23" )
			)
			( pin "@baseboard_fab2_lib.baseboard_fab2(sch_1):page26_i172:ddr3_dqs_dn(8)"
				( attribute "PN" "DF67"
					( Origin gPackager )
				)
				( objectStatus "U5D1.DF67" )
			)
			( pin "@baseboard_fab2_lib.baseboard_fab2(sch_1):page26_i172:ddr3_dqs_dn(9)"
				( attribute "PN" "CR84"
					( Origin gPackager )
				)
				( objectStatus "U5D1.CR84" )
			)
			( pin "@baseboard_fab2_lib.baseboard_fab2(sch_1):page26_i172:ddr3_dqs_dn(10)"
				( attribute "PN" "DM85"
					( Origin gPackager )
				)
				( objectStatus "U5D1.DM85" )
			)
			( pin "@baseboard_fab2_lib.baseboard_fab2(sch_1):page26_i172:ddr3_dqs_dn(11)"
				( attribute "PN" "DN80"
					( Origin gPackager )
				)
				( objectStatus "U5D1.DN80" )
			)
			( pin "@baseboard_fab2_lib.baseboard_fab2(sch_1):page26_i172:ddr3_dqs_dn(12)"
				( attribute "PN" "DP75"
					( Origin gPackager )
				)
				( objectStatus "U5D1.DP75" )
			)
			( pin "@baseboard_fab2_lib.baseboard_fab2(sch_1):page26_i172:ddr3_dqs_dn(13)"
				( attribute "PN" "EA38"
					( Origin gPackager )
				)
				( objectStatus "U5D1.EA38" )
			)
			( pin "@baseboard_fab2_lib.baseboard_fab2(sch_1):page26_i172:ddr3_dqs_dn(14)"
				( attribute "PN" "DP35"
					( Origin gPackager )
				)
				( objectStatus "U5D1.DP35" )
			)
			( pin "@baseboard_fab2_lib.baseboard_fab2(sch_1):page26_i172:ddr3_dqs_dn(15)"
				( attribute "PN" "DM29"
					( Origin gPackager )
				)
				( objectStatus "U5D1.DM29" )
			)
			( pin "@baseboard_fab2_lib.baseboard_fab2(sch_1):page26_i172:ddr3_dqs_dn(16)"
				( attribute "PN" "DM23"
					( Origin gPackager )
				)
				( objectStatus "U5D1.DM23" )
			)
			( pin "@baseboard_fab2_lib.baseboard_fab2(sch_1):page26_i172:ddr3_dqs_dn(17)"
				( attribute "PN" "DB67"
					( Origin gPackager )
				)
				( objectStatus "U5D1.DB67" )
			)
			( pin "@baseboard_fab2_lib.baseboard_fab2(sch_1):page26_i172:ddr3_dqs_dp(0)"
				( attribute "PN" "CV85"
					( Origin gPackager )
				)
				( objectStatus "U5D1.CV85" )
			)
			( pin "@baseboard_fab2_lib.baseboard_fab2(sch_1):page26_i172:ddr3_dqs_dp(1)"
				( attribute "PN" "DP85"
					( Origin gPackager )
				)
				( objectStatus "U5D1.DP85" )
			)
			( pin "@baseboard_fab2_lib.baseboard_fab2(sch_1):page26_i172:ddr3_dqs_dp(2)"
				( attribute "PN" "DM81"
					( Origin gPackager )
				)
				( objectStatus "U5D1.DM81" )
			)
			( pin "@baseboard_fab2_lib.baseboard_fab2(sch_1):page26_i172:ddr3_dqs_dp(3)"
				( attribute "PN" "DT75"
					( Origin gPackager )
				)
				( objectStatus "U5D1.DT75" )
			)
			( pin "@baseboard_fab2_lib.baseboard_fab2(sch_1):page26_i172:ddr3_dqs_dp(4)"
				( attribute "PN" "EC38"
					( Origin gPackager )
				)
				( objectStatus "U5D1.EC38" )
			)
			( pin "@baseboard_fab2_lib.baseboard_fab2(sch_1):page26_i172:ddr3_dqs_dp(5)"
				( attribute "PN" "DT35"
					( Origin gPackager )
				)
				( objectStatus "U5D1.DT35" )
			)
			( pin "@baseboard_fab2_lib.baseboard_fab2(sch_1):page26_i172:ddr3_dqs_dp(6)"
				( attribute "PN" "DT29"
					( Origin gPackager )
				)
				( objectStatus "U5D1.DT29" )
			)
			( pin "@baseboard_fab2_lib.baseboard_fab2(sch_1):page26_i172:ddr3_dqs_dp(7)"
				( attribute "PN" "DT23"
					( Origin gPackager )
				)
				( objectStatus "U5D1.DT23" )
			)
			( pin "@baseboard_fab2_lib.baseboard_fab2(sch_1):page26_i172:ddr3_dqs_dp(8)"
				( attribute "PN" "DD67"
					( Origin gPackager )
				)
				( objectStatus "U5D1.DD67" )
			)
			( pin "@baseboard_fab2_lib.baseboard_fab2(sch_1):page26_i172:ddr3_dqs_dp(9)"
				( attribute "PN" "CP85"
					( Origin gPackager )
				)
				( objectStatus "U5D1.CP85" )
			)
			( pin "@baseboard_fab2_lib.baseboard_fab2(sch_1):page26_i172:ddr3_dqs_dp(10)"
				( attribute "PN" "DL84"
					( Origin gPackager )
				)
				( objectStatus "U5D1.DL84" )
			)
			( pin "@baseboard_fab2_lib.baseboard_fab2(sch_1):page26_i172:ddr3_dqs_dp(11)"
				( attribute "PN" "DP79"
					( Origin gPackager )
				)
				( objectStatus "U5D1.DP79" )
			)
			( pin "@baseboard_fab2_lib.baseboard_fab2(sch_1):page26_i172:ddr3_dqs_dp(12)"
				( attribute "PN" "DM75"
					( Origin gPackager )
				)
				( objectStatus "U5D1.DM75" )
			)
			( pin "@baseboard_fab2_lib.baseboard_fab2(sch_1):page26_i172:ddr3_dqs_dp(13)"
				( attribute "PN" "DW38"
					( Origin gPackager )
				)
				( objectStatus "U5D1.DW38" )
			)
			( pin "@baseboard_fab2_lib.baseboard_fab2(sch_1):page26_i172:ddr3_dqs_dp(14)"
				( attribute "PN" "DM35"
					( Origin gPackager )
				)
				( objectStatus "U5D1.DM35" )
			)
			( pin "@baseboard_fab2_lib.baseboard_fab2(sch_1):page26_i172:ddr3_dqs_dp(15)"
				( attribute "PN" "DP29"
					( Origin gPackager )
				)
				( objectStatus "U5D1.DP29" )
			)
			( pin "@baseboard_fab2_lib.baseboard_fab2(sch_1):page26_i172:ddr3_dqs_dp(16)"
				( attribute "PN" "DP23"
					( Origin gPackager )
				)
				( objectStatus "U5D1.DP23" )
			)
			( pin "@baseboard_fab2_lib.baseboard_fab2(sch_1):page26_i172:ddr3_dqs_dp(17)"
				( attribute "PN" "CY67"
					( Origin gPackager )
				)
				( objectStatus "U5D1.CY67" )
			)
			( pin "@baseboard_fab2_lib.baseboard_fab2(sch_1):page26_i172:ddr3_ecc(0)"
				( attribute "PN" "DA68"
					( Origin gPackager )
				)
				( objectStatus "U5D1.DA68" )
			)
			( pin "@baseboard_fab2_lib.baseboard_fab2(sch_1):page26_i172:ddr3_ecc(1)"
				( attribute "PN" "DE68"
					( Origin gPackager )
				)
				( objectStatus "U5D1.DE68" )
			)
			( pin "@baseboard_fab2_lib.baseboard_fab2(sch_1):page26_i172:ddr3_ecc(2)"
				( attribute "PN" "DB65"
					( Origin gPackager )
				)
				( objectStatus "U5D1.DB65" )
			)
			( pin "@baseboard_fab2_lib.baseboard_fab2(sch_1):page26_i172:ddr3_ecc(3)"
				( attribute "PN" "DD65"
					( Origin gPackager )
				)
				( objectStatus "U5D1.DD65" )
			)
			( pin "@baseboard_fab2_lib.baseboard_fab2(sch_1):page26_i172:ddr3_ecc(4)"
				( attribute "PN" "DB69"
					( Origin gPackager )
				)
				( objectStatus "U5D1.DB69" )
			)
			( pin "@baseboard_fab2_lib.baseboard_fab2(sch_1):page26_i172:ddr3_ecc(5)"
				( attribute "PN" "DD69"
					( Origin gPackager )
				)
				( objectStatus "U5D1.DD69" )
			)
			( pin "@baseboard_fab2_lib.baseboard_fab2(sch_1):page26_i172:ddr3_ecc(6)"
				( attribute "PN" "DA66"
					( Origin gPackager )
				)
				( objectStatus "U5D1.DA66" )
			)
			( pin "@baseboard_fab2_lib.baseboard_fab2(sch_1):page26_i172:ddr3_ecc(7)"
				( attribute "PN" "DE66"
					( Origin gPackager )
				)
				( objectStatus "U5D1.DE66" )
			)
			( pin "@baseboard_fab2_lib.baseboard_fab2(sch_1):page26_i172:ddr3_ma(0)"
				( attribute "PN" "EB53"
					( Origin gPackager )
				)
				( objectStatus "U5D1.EB53" )
			)
			( pin "@baseboard_fab2_lib.baseboard_fab2(sch_1):page26_i172:ddr3_ma(1)"
				( attribute "PN" "ED57"
					( Origin gPackager )
				)
				( objectStatus "U5D1.ED57" )
			)
			( pin "@baseboard_fab2_lib.baseboard_fab2(sch_1):page26_i172:ddr3_ma(2)"
				( attribute "PN" "EE58"
					( Origin gPackager )
				)
				( objectStatus "U5D1.EE58" )
			)
			( pin "@baseboard_fab2_lib.baseboard_fab2(sch_1):page26_i172:ddr3_ma(3)"
				( attribute "PN" "EB57"
					( Origin gPackager )
				)
				( objectStatus "U5D1.EB57" )
			)
			( pin "@baseboard_fab2_lib.baseboard_fab2(sch_1):page26_i172:ddr3_ma(4)"
				( attribute "PN" "ED59"
					( Origin gPackager )
				)
				( objectStatus "U5D1.ED59" )
			)
			( pin "@baseboard_fab2_lib.baseboard_fab2(sch_1):page26_i172:ddr3_ma(5)"
				( attribute "PN" "EA58"
					( Origin gPackager )
				)
				( objectStatus "U5D1.EA58" )
			)
			( pin "@baseboard_fab2_lib.baseboard_fab2(sch_1):page26_i172:ddr3_ma(6)"
				( attribute "PN" "EE60"
					( Origin gPackager )
				)
				( objectStatus "U5D1.EE60" )
			)
			( pin "@baseboard_fab2_lib.baseboard_fab2(sch_1):page26_i172:ddr3_ma(7)"
				( attribute "PN" "EA60"
					( Origin gPackager )
				)
				( objectStatus "U5D1.EA60" )
			)
			( pin "@baseboard_fab2_lib.baseboard_fab2(sch_1):page26_i172:ddr3_ma(8)"
				( attribute "PN" "EB59"
					( Origin gPackager )
				)
				( objectStatus "U5D1.EB59" )
			)
			( pin "@baseboard_fab2_lib.baseboard_fab2(sch_1):page26_i172:ddr3_ma(9)"
				( attribute "PN" "EF61"
					( Origin gPackager )
				)
				( objectStatus "U5D1.EF61" )
			)
			( pin "@baseboard_fab2_lib.baseboard_fab2(sch_1):page26_i172:ddr3_ma(10)"
				( attribute "PN" "DW54"
					( Origin gPackager )
				)
				( objectStatus "U5D1.DW54" )
			)
			( pin "@baseboard_fab2_lib.baseboard_fab2(sch_1):page26_i172:ddr3_ma(11)"
				( attribute "PN" "EB61"
					( Origin gPackager )
				)
				( objectStatus "U5D1.EB61" )
			)
			( pin "@baseboard_fab2_lib.baseboard_fab2(sch_1):page26_i172:ddr3_ma(12)"
				( attribute "PN" "DT63"
					( Origin gPackager )
				)
				( objectStatus "U5D1.DT63" )
			)
			( pin "@baseboard_fab2_lib.baseboard_fab2(sch_1):page26_i172:ddr3_ma(13)"
				( attribute "PN" "DW48"
					( Origin gPackager )
				)
				( objectStatus "U5D1.DW48" )
			)
			( pin "@baseboard_fab2_lib.baseboard_fab2(sch_1):page26_i172:ddr3_ma(14)"
				( attribute "PN" "ED51"
					( Origin gPackager )
				)
				( objectStatus "U5D1.ED51" )
			)
			( pin "@baseboard_fab2_lib.baseboard_fab2(sch_1):page26_i172:ddr3_ma(15)"
				( attribute "PN" "DV49"
					( Origin gPackager )
				)
				( objectStatus "U5D1.DV49" )
			)
			( pin "@baseboard_fab2_lib.baseboard_fab2(sch_1):page26_i172:ddr3_ma(16)"
				( attribute "PN" "EA52"
					( Origin gPackager )
				)
				( objectStatus "U5D1.EA52" )
			)
			( pin "@baseboard_fab2_lib.baseboard_fab2(sch_1):page26_i172:ddr3_ma(17)"
				( attribute "PN" "EA46"
					( Origin gPackager )
				)
				( objectStatus "U5D1.EA46" )
			)
			( pin "@baseboard_fab2_lib.baseboard_fab2(sch_1):page26_i172:ddr3_odt(0)"
				( attribute "PN" "EE50"
					( Origin gPackager )
				)
				( objectStatus "U5D1.EE50" )
			)
			( pin "@baseboard_fab2_lib.baseboard_fab2(sch_1):page26_i172:ddr3_odt(1)"
				( attribute "PN" "EE48"
					( Origin gPackager )
				)
				( objectStatus "U5D1.EE48" )
			)
			( pin "@baseboard_fab2_lib.baseboard_fab2(sch_1):page26_i172:ddr3_odt(2)"
				( attribute "PN" "EA50"
					( Origin gPackager )
				)
				( objectStatus "U5D1.EA50" )
			)
			( pin "@baseboard_fab2_lib.baseboard_fab2(sch_1):page26_i172:ddr3_odt(3)"
				( attribute "PN" "EA48"
					( Origin gPackager )
				)
				( objectStatus "U5D1.EA48" )
			)
			( pin "@baseboard_fab2_lib.baseboard_fab2(sch_1):page26_i172:ddr3_par"
				( attribute "PN" "ED53"
					( Origin gPackager )
				)
				( objectStatus "U5D1.ED53" )
			)
			( pin "@baseboard_fab2_lib.baseboard_fab2(sch_1):page27_i172:ddr4_act_n"
				( attribute "PN" "DR62"
					( Origin gPackager )
				)
				( objectStatus "U5D1.DR62" )
			)
			( pin "@baseboard_fab2_lib.baseboard_fab2(sch_1):page27_i172:ddr4_alert_n"
				( attribute "PN" "DT61"
					( Origin gPackager )
				)
				( objectStatus "U5D1.DT61" )
			)
			( pin "@baseboard_fab2_lib.baseboard_fab2(sch_1):page27_i172:ddr4_ba(0)"
				( attribute "PN" "DM53"
					( Origin gPackager )
				)
				( objectStatus "U5D1.DM53" )
			)
			( pin "@baseboard_fab2_lib.baseboard_fab2(sch_1):page27_i172:ddr4_ba(1)"
				( attribute "PN" "DV55"
					( Origin gPackager )
				)
				( objectStatus "U5D1.DV55" )
			)
			( pin "@baseboard_fab2_lib.baseboard_fab2(sch_1):page27_i172:ddr4_bg(0)"
				( attribute "PN" "DJ62"
					( Origin gPackager )
				)
				( objectStatus "U5D1.DJ62" )
			)
			( pin "@baseboard_fab2_lib.baseboard_fab2(sch_1):page27_i172:ddr4_bg(1)"
				( attribute "PN" "DM61"
					( Origin gPackager )
				)
				( objectStatus "U5D1.DM61" )
			)
			( pin "@baseboard_fab2_lib.baseboard_fab2(sch_1):page27_i172:ddr4_cid(2)"
				( attribute "PN" "DT47"
					( Origin gPackager )
				)
				( objectStatus "U5D1.DT47" )
			)
			( pin "@baseboard_fab2_lib.baseboard_fab2(sch_1):page27_i172:ddr4_cke(0)"
				( attribute "PN" "DM63"
					( Origin gPackager )
				)
				( objectStatus "U5D1.DM63" )
			)
			( pin "@baseboard_fab2_lib.baseboard_fab2(sch_1):page27_i172:ddr4_cke(1)"
				( attribute "PN" "DN64"
					( Origin gPackager )
				)
				( objectStatus "U5D1.DN64" )
			)
			( pin "@baseboard_fab2_lib.baseboard_fab2(sch_1):page27_i172:ddr4_cke(2)"
				( attribute "PN" "DL64"
					( Origin gPackager )
				)
				( objectStatus "U5D1.DL64" )
			)
			( pin "@baseboard_fab2_lib.baseboard_fab2(sch_1):page27_i172:ddr4_cke(3)"
				( attribute "PN" "DR64"
					( Origin gPackager )
				)
				( objectStatus "U5D1.DR64" )
			)
			( pin "@baseboard_fab2_lib.baseboard_fab2(sch_1):page27_i172:ddr4_clk_dn(0)"
				( attribute "PN" "DM55"
					( Origin gPackager )
				)
				( objectStatus "U5D1.DM55" )
			)
			( pin "@baseboard_fab2_lib.baseboard_fab2(sch_1):page27_i172:ddr4_clk_dn(1)"
				( attribute "PN" "DR54"
					( Origin gPackager )
				)
				( objectStatus "U5D1.DR54" )
			)
			( pin "@baseboard_fab2_lib.baseboard_fab2(sch_1):page27_i172:ddr4_clk_dn(2)"
				( attribute "PN" "DM57"
					( Origin gPackager )
				)
				( objectStatus "U5D1.DM57" )
			)
			( pin "@baseboard_fab2_lib.baseboard_fab2(sch_1):page27_i172:ddr4_clk_dn(3)"
				( attribute "PN" "DT57"
					( Origin gPackager )
				)
				( objectStatus "U5D1.DT57" )
			)
			( pin "@baseboard_fab2_lib.baseboard_fab2(sch_1):page27_i172:ddr4_clk_dp(0)"
				( attribute "PN" "DN54"
					( Origin gPackager )
				)
				( objectStatus "U5D1.DN54" )
			)
			( pin "@baseboard_fab2_lib.baseboard_fab2(sch_1):page27_i172:ddr4_clk_dp(1)"
				( attribute "PN" "DT53"
					( Origin gPackager )
				)
				( objectStatus "U5D1.DT53" )
			)
			( pin "@baseboard_fab2_lib.baseboard_fab2(sch_1):page27_i172:ddr4_clk_dp(2)"
				( attribute "PN" "DN56"
					( Origin gPackager )
				)
				( objectStatus "U5D1.DN56" )
			)
			( pin "@baseboard_fab2_lib.baseboard_fab2(sch_1):page27_i172:ddr4_clk_dp(3)"
				( attribute "PN" "DR56"
					( Origin gPackager )
				)
				( objectStatus "U5D1.DR56" )
			)
			( pin "@baseboard_fab2_lib.baseboard_fab2(sch_1):page27_i172:ddr4_cs_n(0)"
				( attribute "PN" "DV51"
					( Origin gPackager )
				)
				( objectStatus "U5D1.DV51" )
			)
			( pin "@baseboard_fab2_lib.baseboard_fab2(sch_1):page27_i172:ddr4_cs_n(1)"
				( attribute "PN" "DN50"
					( Origin gPackager )
				)
				( objectStatus "U5D1.DN50" )
			)
			( pin "@baseboard_fab2_lib.baseboard_fab2(sch_1):page27_i172:ddr4_cs_n(2)"
				( attribute "PN" "DR46"
					( Origin gPackager )
				)
				( objectStatus "U5D1.DR46" )
			)
			( pin "@baseboard_fab2_lib.baseboard_fab2(sch_1):page27_i172:ddr4_cs_n(3)"
				( attribute "PN" "DK47"
					( Origin gPackager )
				)
				( objectStatus "U5D1.DK47" )
			)
			( pin "@baseboard_fab2_lib.baseboard_fab2(sch_1):page27_i172:ddr4_cs_n(4)"
				( attribute "PN" "DW50"
					( Origin gPackager )
				)
				( objectStatus "U5D1.DW50" )
			)
			( pin "@baseboard_fab2_lib.baseboard_fab2(sch_1):page27_i172:ddr4_cs_n(5)"
				( attribute "PN" "DM49"
					( Origin gPackager )
				)
				( objectStatus "U5D1.DM49" )
			)
			( pin "@baseboard_fab2_lib.baseboard_fab2(sch_1):page27_i172:ddr4_cs_n(6)"
				( attribute "PN" "DT45"
					( Origin gPackager )
				)
				( objectStatus "U5D1.DT45" )
			)
			( pin "@baseboard_fab2_lib.baseboard_fab2(sch_1):page27_i172:ddr4_cs_n(7)"
				( attribute "PN" "DN46"
					( Origin gPackager )
				)
				( objectStatus "U5D1.DN46" )
			)
			( pin "@baseboard_fab2_lib.baseboard_fab2(sch_1):page27_i172:ddr4_dq(0)"
				( attribute "PN" "CM79"
					( Origin gPackager )
				)
				( objectStatus "U5D1.CM79" )
			)
			( pin "@baseboard_fab2_lib.baseboard_fab2(sch_1):page27_i172:ddr4_dq(1)"
				( attribute "PN" "CK81"
					( Origin gPackager )
				)
				( objectStatus "U5D1.CK81" )
			)
			( pin "@baseboard_fab2_lib.baseboard_fab2(sch_1):page27_i172:ddr4_dq(2)"
				( attribute "PN" "CT81"
					( Origin gPackager )
				)
				( objectStatus "U5D1.CT81" )
			)
			( pin "@baseboard_fab2_lib.baseboard_fab2(sch_1):page27_i172:ddr4_dq(3)"
				( attribute "PN" "CR82"
					( Origin gPackager )
				)
				( objectStatus "U5D1.CR82" )
			)
			( pin "@baseboard_fab2_lib.baseboard_fab2(sch_1):page27_i172:ddr4_dq(4)"
				( attribute "PN" "CK79"
					( Origin gPackager )
				)
				( objectStatus "U5D1.CK79" )
			)
			( pin "@baseboard_fab2_lib.baseboard_fab2(sch_1):page27_i172:ddr4_dq(5)"
				( attribute "PN" "CJ80"
					( Origin gPackager )
				)
				( objectStatus "U5D1.CJ80" )
			)
			( pin "@baseboard_fab2_lib.baseboard_fab2(sch_1):page27_i172:ddr4_dq(6)"
				( attribute "PN" "CR80"
					( Origin gPackager )
				)
				( objectStatus "U5D1.CR80" )
			)
			( pin "@baseboard_fab2_lib.baseboard_fab2(sch_1):page27_i172:ddr4_dq(7)"
				( attribute "PN" "CN82"
					( Origin gPackager )
				)
				( objectStatus "U5D1.CN82" )
			)
			( pin "@baseboard_fab2_lib.baseboard_fab2(sch_1):page27_i172:ddr4_dq(8)"
				( attribute "PN" "DB79"
					( Origin gPackager )
				)
				( objectStatus "U5D1.DB79" )
			)
			( pin "@baseboard_fab2_lib.baseboard_fab2(sch_1):page27_i172:ddr4_dq(9)"
				( attribute "PN" "CY81"
					( Origin gPackager )
				)
				( objectStatus "U5D1.CY81" )
			)
			( pin "@baseboard_fab2_lib.baseboard_fab2(sch_1):page27_i172:ddr4_dq(10)"
				( attribute "PN" "DE80"
					( Origin gPackager )
				)
				( objectStatus "U5D1.DE80" )
			)
			( pin "@baseboard_fab2_lib.baseboard_fab2(sch_1):page27_i172:ddr4_dq(11)"
				( attribute "PN" "DF81"
					( Origin gPackager )
				)
				( objectStatus "U5D1.DF81" )
			)
			( pin "@baseboard_fab2_lib.baseboard_fab2(sch_1):page27_i172:ddr4_dq(12)"
				( attribute "PN" "CY79"
					( Origin gPackager )
				)
				( objectStatus "U5D1.CY79" )
			)
			( pin "@baseboard_fab2_lib.baseboard_fab2(sch_1):page27_i172:ddr4_dq(13)"
				( attribute "PN" "CW80"
					( Origin gPackager )
				)
				( objectStatus "U5D1.CW80" )
			)
			( pin "@baseboard_fab2_lib.baseboard_fab2(sch_1):page27_i172:ddr4_dq(14)"
				( attribute "PN" "DC82"
					( Origin gPackager )
				)
				( objectStatus "U5D1.DC82" )
			)
			( pin "@baseboard_fab2_lib.baseboard_fab2(sch_1):page27_i172:ddr4_dq(15)"
				( attribute "PN" "DE82"
					( Origin gPackager )
				)
				( objectStatus "U5D1.DE82" )
			)
			( pin "@baseboard_fab2_lib.baseboard_fab2(sch_1):page27_i172:ddr4_dq(16)"
				( attribute "PN" "DW80"
					( Origin gPackager )
				)
				( objectStatus "U5D1.DW80" )
			)
			( pin "@baseboard_fab2_lib.baseboard_fab2(sch_1):page27_i172:ddr4_dq(17)"
				( attribute "PN" "EC80"
					( Origin gPackager )
				)
				( objectStatus "U5D1.EC80" )
			)
			( pin "@baseboard_fab2_lib.baseboard_fab2(sch_1):page27_i172:ddr4_dq(18)"
				( attribute "PN" "DY77"
					( Origin gPackager )
				)
				( objectStatus "U5D1.DY77" )
			)
			( pin "@baseboard_fab2_lib.baseboard_fab2(sch_1):page27_i172:ddr4_dq(19)"
				( attribute "PN" "EB77"
					( Origin gPackager )
				)
				( objectStatus "U5D1.EB77" )
			)
			( pin "@baseboard_fab2_lib.baseboard_fab2(sch_1):page27_i172:ddr4_dq(20)"
				( attribute "PN" "DY81"
					( Origin gPackager )
				)
				( objectStatus "U5D1.DY81" )
			)
			( pin "@baseboard_fab2_lib.baseboard_fab2(sch_1):page27_i172:ddr4_dq(21)"
				( attribute "PN" "EB81"
					( Origin gPackager )
				)
				( objectStatus "U5D1.EB81" )
			)
			( pin "@baseboard_fab2_lib.baseboard_fab2(sch_1):page27_i172:ddr4_dq(22)"
				( attribute "PN" "DW78"
					( Origin gPackager )
				)
				( objectStatus "U5D1.DW78" )
			)
			( pin "@baseboard_fab2_lib.baseboard_fab2(sch_1):page27_i172:ddr4_dq(23)"
				( attribute "PN" "EC78"
					( Origin gPackager )
				)
				( objectStatus "U5D1.EC78" )
			)
			( pin "@baseboard_fab2_lib.baseboard_fab2(sch_1):page27_i172:ddr4_dq(24)"
				( attribute "PN" "ED75"
					( Origin gPackager )
				)
				( objectStatus "U5D1.ED75" )
			)
			( pin "@baseboard_fab2_lib.baseboard_fab2(sch_1):page27_i172:ddr4_dq(25)"
				( attribute "PN" "EE74"
					( Origin gPackager )
				)
				( objectStatus "U5D1.EE74" )
			)
			( pin "@baseboard_fab2_lib.baseboard_fab2(sch_1):page27_i172:ddr4_dq(26)"
				( attribute "PN" "EB71"
					( Origin gPackager )
				)
				( objectStatus "U5D1.EB71" )
			)
			( pin "@baseboard_fab2_lib.baseboard_fab2(sch_1):page27_i172:ddr4_dq(27)"
				( attribute "PN" "ED71"
					( Origin gPackager )
				)
				( objectStatus "U5D1.ED71" )
			)
			( pin "@baseboard_fab2_lib.baseboard_fab2(sch_1):page27_i172:ddr4_dq(28)"
				( attribute "PN" "EA74"
					( Origin gPackager )
				)
				( objectStatus "U5D1.EA74" )
			)
			( pin "@baseboard_fab2_lib.baseboard_fab2(sch_1):page27_i172:ddr4_dq(29)"
				( attribute "PN" "EB75"
					( Origin gPackager )
				)
				( objectStatus "U5D1.EB75" )
			)
			( pin "@baseboard_fab2_lib.baseboard_fab2(sch_1):page27_i172:ddr4_dq(30)"
				( attribute "PN" "EA72"
					( Origin gPackager )
				)
				( objectStatus "U5D1.EA72" )
			)
			( pin "@baseboard_fab2_lib.baseboard_fab2(sch_1):page27_i172:ddr4_dq(31)"
				( attribute "PN" "EE72"
					( Origin gPackager )
				)
				( objectStatus "U5D1.EE72" )
			)
			( pin "@baseboard_fab2_lib.baseboard_fab2(sch_1):page27_i172:ddr4_dq(32)"
				( attribute "PN" "DU42"
					( Origin gPackager )
				)
				( objectStatus "U5D1.DU42" )
			)
			( pin "@baseboard_fab2_lib.baseboard_fab2(sch_1):page27_i172:ddr4_dq(33)"
				( attribute "PN" "DW42"
					( Origin gPackager )
				)
				( objectStatus "U5D1.DW42" )
			)
			( pin "@baseboard_fab2_lib.baseboard_fab2(sch_1):page27_i172:ddr4_dq(34)"
				( attribute "PN" "DP39"
					( Origin gPackager )
				)
				( objectStatus "U5D1.DP39" )
			)
			( pin "@baseboard_fab2_lib.baseboard_fab2(sch_1):page27_i172:ddr4_dq(35)"
				( attribute "PN" "DT39"
					( Origin gPackager )
				)
				( objectStatus "U5D1.DT39" )
			)
			( pin "@baseboard_fab2_lib.baseboard_fab2(sch_1):page27_i172:ddr4_dq(36)"
				( attribute "PN" "DL42"
					( Origin gPackager )
				)
				( objectStatus "U5D1.DL42" )
			)
			( pin "@baseboard_fab2_lib.baseboard_fab2(sch_1):page27_i172:ddr4_dq(37)"
				( attribute "PN" "DN42"
					( Origin gPackager )
				)
				( objectStatus "U5D1.DN42" )
			)
			( pin "@baseboard_fab2_lib.baseboard_fab2(sch_1):page27_i172:ddr4_dq(38)"
				( attribute "PN" "DN40"
					( Origin gPackager )
				)
				( objectStatus "U5D1.DN40" )
			)
			( pin "@baseboard_fab2_lib.baseboard_fab2(sch_1):page27_i172:ddr4_dq(39)"
				( attribute "PN" "DU40"
					( Origin gPackager )
				)
				( objectStatus "U5D1.DU40" )
			)
			( pin "@baseboard_fab2_lib.baseboard_fab2(sch_1):page27_i172:ddr4_dq(40)"
				( attribute "PN" "EC34"
					( Origin gPackager )
				)
				( objectStatus "U5D1.EC34" )
			)
			( pin "@baseboard_fab2_lib.baseboard_fab2(sch_1):page27_i172:ddr4_dq(41)"
				( attribute "PN" "ED33"
					( Origin gPackager )
				)
				( objectStatus "U5D1.ED33" )
			)
			( pin "@baseboard_fab2_lib.baseboard_fab2(sch_1):page27_i172:ddr4_dq(42)"
				( attribute "PN" "EA30"
					( Origin gPackager )
				)
				( objectStatus "U5D1.EA30" )
			)
			( pin "@baseboard_fab2_lib.baseboard_fab2(sch_1):page27_i172:ddr4_dq(43)"
				( attribute "PN" "EC30"
					( Origin gPackager )
				)
				( objectStatus "U5D1.EC30" )
			)
			( pin "@baseboard_fab2_lib.baseboard_fab2(sch_1):page27_i172:ddr4_dq(44)"
				( attribute "PN" "DY33"
					( Origin gPackager )
				)
				( objectStatus "U5D1.DY33" )
			)
			( pin "@baseboard_fab2_lib.baseboard_fab2(sch_1):page27_i172:ddr4_dq(45)"
				( attribute "PN" "EA34"
					( Origin gPackager )
				)
				( objectStatus "U5D1.EA34" )
			)
			( pin "@baseboard_fab2_lib.baseboard_fab2(sch_1):page27_i172:ddr4_dq(46)"
				( attribute "PN" "DY31"
					( Origin gPackager )
				)
				( objectStatus "U5D1.DY31" )
			)
			( pin "@baseboard_fab2_lib.baseboard_fab2(sch_1):page27_i172:ddr4_dq(47)"
				( attribute "PN" "ED31"
					( Origin gPackager )
				)
				( objectStatus "U5D1.ED31" )
			)
			( pin "@baseboard_fab2_lib.baseboard_fab2(sch_1):page27_i172:ddr4_dq(48)"
				( attribute "PN" "EC28"
					( Origin gPackager )
				)
				( objectStatus "U5D1.EC28" )
			)
			( pin "@baseboard_fab2_lib.baseboard_fab2(sch_1):page27_i172:ddr4_dq(49)"
				( attribute "PN" "ED27"
					( Origin gPackager )
				)
				( objectStatus "U5D1.ED27" )
			)
			( pin "@baseboard_fab2_lib.baseboard_fab2(sch_1):page27_i172:ddr4_dq(50)"
				( attribute "PN" "EA24"
					( Origin gPackager )
				)
				( objectStatus "U5D1.EA24" )
			)
			( pin "@baseboard_fab2_lib.baseboard_fab2(sch_1):page27_i172:ddr4_dq(51)"
				( attribute "PN" "EC24"
					( Origin gPackager )
				)
				( objectStatus "U5D1.EC24" )
			)
			( pin "@baseboard_fab2_lib.baseboard_fab2(sch_1):page27_i172:ddr4_dq(52)"
				( attribute "PN" "DY27"
					( Origin gPackager )
				)
				( objectStatus "U5D1.DY27" )
			)
			( pin "@baseboard_fab2_lib.baseboard_fab2(sch_1):page27_i172:ddr4_dq(53)"
				( attribute "PN" "EA28"
					( Origin gPackager )
				)
				( objectStatus "U5D1.EA28" )
			)
			( pin "@baseboard_fab2_lib.baseboard_fab2(sch_1):page27_i172:ddr4_dq(54)"
				( attribute "PN" "DY25"
					( Origin gPackager )
				)
				( objectStatus "U5D1.DY25" )
			)
			( pin "@baseboard_fab2_lib.baseboard_fab2(sch_1):page27_i172:ddr4_dq(55)"
				( attribute "PN" "ED25"
					( Origin gPackager )
				)
				( objectStatus "U5D1.ED25" )
			)
			( pin "@baseboard_fab2_lib.baseboard_fab2(sch_1):page27_i172:ddr4_dq(56)"
				( attribute "PN" "DF27"
					( Origin gPackager )
				)
				( objectStatus "U5D1.DF27" )
			)
			( pin "@baseboard_fab2_lib.baseboard_fab2(sch_1):page27_i172:ddr4_dq(57)"
				( attribute "PN" "DK27"
					( Origin gPackager )
				)
				( objectStatus "U5D1.DK27" )
			)
			( pin "@baseboard_fab2_lib.baseboard_fab2(sch_1):page27_i172:ddr4_dq(58)"
				( attribute "PN" "DD25"
					( Origin gPackager )
				)
				( objectStatus "U5D1.DD25" )
			)
			( pin "@baseboard_fab2_lib.baseboard_fab2(sch_1):page27_i172:ddr4_dq(59)"
				( attribute "PN" "DJ24"
					( Origin gPackager )
				)
				( objectStatus "U5D1.DJ24" )
			)
			( pin "@baseboard_fab2_lib.baseboard_fab2(sch_1):page27_i172:ddr4_dq(60)"
				( attribute "PN" "DG28"
					( Origin gPackager )
				)
				( objectStatus "U5D1.DG28" )
			)
			( pin "@baseboard_fab2_lib.baseboard_fab2(sch_1):page27_i172:ddr4_dq(61)"
				( attribute "PN" "DJ28"
					( Origin gPackager )
				)
				( objectStatus "U5D1.DJ28" )
			)
			( pin "@baseboard_fab2_lib.baseboard_fab2(sch_1):page27_i172:ddr4_dq(62)"
				( attribute "PN" "DF25"
					( Origin gPackager )
				)
				( objectStatus "U5D1.DF25" )
			)
			( pin "@baseboard_fab2_lib.baseboard_fab2(sch_1):page27_i172:ddr4_dq(63)"
				( attribute "PN" "DK25"
					( Origin gPackager )
				)
				( objectStatus "U5D1.DK25" )
			)
			( pin "@baseboard_fab2_lib.baseboard_fab2(sch_1):page27_i172:ddr4_dqs_dn(0)"
				( attribute "PN" "CL82"
					( Origin gPackager )
				)
				( objectStatus "U5D1.CL82" )
			)
			( pin "@baseboard_fab2_lib.baseboard_fab2(sch_1):page27_i172:ddr4_dqs_dn(1)"
				( attribute "PN" "DA82"
					( Origin gPackager )
				)
				( objectStatus "U5D1.DA82" )
			)
			( pin "@baseboard_fab2_lib.baseboard_fab2(sch_1):page27_i172:ddr4_dqs_dn(2)"
				( attribute "PN" "ED79"
					( Origin gPackager )
				)
				( objectStatus "U5D1.ED79" )
			)
			( pin "@baseboard_fab2_lib.baseboard_fab2(sch_1):page27_i172:ddr4_dqs_dn(3)"
				( attribute "PN" "EF73"
					( Origin gPackager )
				)
				( objectStatus "U5D1.EF73" )
			)
			( pin "@baseboard_fab2_lib.baseboard_fab2(sch_1):page27_i172:ddr4_dqs_dn(4)"
				( attribute "PN" "DV41"
					( Origin gPackager )
				)
				( objectStatus "U5D1.DV41" )
			)
			( pin "@baseboard_fab2_lib.baseboard_fab2(sch_1):page27_i172:ddr4_dqs_dn(5)"
				( attribute "PN" "EE32"
					( Origin gPackager )
				)
				( objectStatus "U5D1.EE32" )
			)
			( pin "@baseboard_fab2_lib.baseboard_fab2(sch_1):page27_i172:ddr4_dqs_dn(6)"
				( attribute "PN" "EE26"
					( Origin gPackager )
				)
				( objectStatus "U5D1.EE26" )
			)
			( pin "@baseboard_fab2_lib.baseboard_fab2(sch_1):page27_i172:ddr4_dqs_dn(7)"
				( attribute "PN" "DL26"
					( Origin gPackager )
				)
				( objectStatus "U5D1.DL26" )
			)
			( pin "@baseboard_fab2_lib.baseboard_fab2(sch_1):page27_i172:ddr4_dqs_dn(8)"
				( attribute "PN" "EB67"
					( Origin gPackager )
				)
				( objectStatus "U5D1.EB67" )
			)
			( pin "@baseboard_fab2_lib.baseboard_fab2(sch_1):page27_i172:ddr4_dqs_dn(9)"
				( attribute "PN" "CN80"
					( Origin gPackager )
				)
				( objectStatus "U5D1.CN80" )
			)
			( pin "@baseboard_fab2_lib.baseboard_fab2(sch_1):page27_i172:ddr4_dqs_dn(10)"
				( attribute "PN" "DC80"
					( Origin gPackager )
				)
				( objectStatus "U5D1.DC80" )
			)
			( pin "@baseboard_fab2_lib.baseboard_fab2(sch_1):page27_i172:ddr4_dqs_dn(11)"
				( attribute "PN" "DY79"
					( Origin gPackager )
				)
				( objectStatus "U5D1.DY79" )
			)
			( pin "@baseboard_fab2_lib.baseboard_fab2(sch_1):page27_i172:ddr4_dqs_dn(12)"
				( attribute "PN" "EB73"
					( Origin gPackager )
				)
				( objectStatus "U5D1.EB73" )
			)
			( pin "@baseboard_fab2_lib.baseboard_fab2(sch_1):page27_i172:ddr4_dqs_dn(13)"
				( attribute "PN" "DP41"
					( Origin gPackager )
				)
				( objectStatus "U5D1.DP41" )
			)
			( pin "@baseboard_fab2_lib.baseboard_fab2(sch_1):page27_i172:ddr4_dqs_dn(14)"
				( attribute "PN" "EA32"
					( Origin gPackager )
				)
				( objectStatus "U5D1.EA32" )
			)
			( pin "@baseboard_fab2_lib.baseboard_fab2(sch_1):page27_i172:ddr4_dqs_dn(15)"
				( attribute "PN" "EA26"
					( Origin gPackager )
				)
				( objectStatus "U5D1.EA26" )
			)
			( pin "@baseboard_fab2_lib.baseboard_fab2(sch_1):page27_i172:ddr4_dqs_dn(16)"
				( attribute "PN" "DG26"
					( Origin gPackager )
				)
				( objectStatus "U5D1.DG26" )
			)
			( pin "@baseboard_fab2_lib.baseboard_fab2(sch_1):page27_i172:ddr4_dqs_dn(17)"
				( attribute "PN" "DV67"
					( Origin gPackager )
				)
				( objectStatus "U5D1.DV67" )
			)
			( pin "@baseboard_fab2_lib.baseboard_fab2(sch_1):page27_i172:ddr4_dqs_dp(0)"
				( attribute "PN" "CM81"
					( Origin gPackager )
				)
				( objectStatus "U5D1.CM81" )
			)
			( pin "@baseboard_fab2_lib.baseboard_fab2(sch_1):page27_i172:ddr4_dqs_dp(1)"
				( attribute "PN" "DB81"
					( Origin gPackager )
				)
				( objectStatus "U5D1.DB81" )
			)
			( pin "@baseboard_fab2_lib.baseboard_fab2(sch_1):page27_i172:ddr4_dqs_dp(2)"
				( attribute "PN" "EB79"
					( Origin gPackager )
				)
				( objectStatus "U5D1.EB79" )
			)
			( pin "@baseboard_fab2_lib.baseboard_fab2(sch_1):page27_i172:ddr4_dqs_dp(3)"
				( attribute "PN" "ED73"
					( Origin gPackager )
				)
				( objectStatus "U5D1.ED73" )
			)
			( pin "@baseboard_fab2_lib.baseboard_fab2(sch_1):page27_i172:ddr4_dqs_dp(4)"
				( attribute "PN" "DT41"
					( Origin gPackager )
				)
				( objectStatus "U5D1.DT41" )
			)
			( pin "@baseboard_fab2_lib.baseboard_fab2(sch_1):page27_i172:ddr4_dqs_dp(5)"
				( attribute "PN" "EC32"
					( Origin gPackager )
				)
				( objectStatus "U5D1.EC32" )
			)
			( pin "@baseboard_fab2_lib.baseboard_fab2(sch_1):page27_i172:ddr4_dqs_dp(6)"
				( attribute "PN" "EC26"
					( Origin gPackager )
				)
				( objectStatus "U5D1.EC26" )
			)
			( pin "@baseboard_fab2_lib.baseboard_fab2(sch_1):page27_i172:ddr4_dqs_dp(7)"
				( attribute "PN" "DJ26"
					( Origin gPackager )
				)
				( objectStatus "U5D1.DJ26" )
			)
			( pin "@baseboard_fab2_lib.baseboard_fab2(sch_1):page27_i172:ddr4_dqs_dp(8)"
				( attribute "PN" "DY67"
					( Origin gPackager )
				)
				( objectStatus "U5D1.DY67" )
			)
			( pin "@baseboard_fab2_lib.baseboard_fab2(sch_1):page27_i172:ddr4_dqs_dp(9)"
				( attribute "PN" "CP79"
					( Origin gPackager )
				)
				( objectStatus "U5D1.CP79" )
			)
			( pin "@baseboard_fab2_lib.baseboard_fab2(sch_1):page27_i172:ddr4_dqs_dp(10)"
				( attribute "PN" "DD79"
					( Origin gPackager )
				)
				( objectStatus "U5D1.DD79" )
			)
			( pin "@baseboard_fab2_lib.baseboard_fab2(sch_1):page27_i172:ddr4_dqs_dp(11)"
				( attribute "PN" "DV79"
					( Origin gPackager )
				)
				( objectStatus "U5D1.DV79" )
			)
			( pin "@baseboard_fab2_lib.baseboard_fab2(sch_1):page27_i172:ddr4_dqs_dp(12)"
				( attribute "PN" "DY73"
					( Origin gPackager )
				)
				( objectStatus "U5D1.DY73" )
			)
			( pin "@baseboard_fab2_lib.baseboard_fab2(sch_1):page27_i172:ddr4_dqs_dp(13)"
				( attribute "PN" "DM41"
					( Origin gPackager )
				)
				( objectStatus "U5D1.DM41" )
			)
			( pin "@baseboard_fab2_lib.baseboard_fab2(sch_1):page27_i172:ddr4_dqs_dp(14)"
				( attribute "PN" "DW32"
					( Origin gPackager )
				)
				( objectStatus "U5D1.DW32" )
			)
			( pin "@baseboard_fab2_lib.baseboard_fab2(sch_1):page27_i172:ddr4_dqs_dp(15)"
				( attribute "PN" "DW26"
					( Origin gPackager )
				)
				( objectStatus "U5D1.DW26" )
			)
			( pin "@baseboard_fab2_lib.baseboard_fab2(sch_1):page27_i172:ddr4_dqs_dp(16)"
				( attribute "PN" "DE26"
					( Origin gPackager )
				)
				( objectStatus "U5D1.DE26" )
			)
			( pin "@baseboard_fab2_lib.baseboard_fab2(sch_1):page27_i172:ddr4_dqs_dp(17)"
				( attribute "PN" "DT67"
					( Origin gPackager )
				)
				( objectStatus "U5D1.DT67" )
			)
			( pin "@baseboard_fab2_lib.baseboard_fab2(sch_1):page27_i172:ddr4_ecc(0)"
				( attribute "PN" "DY69"
					( Origin gPackager )
				)
				( objectStatus "U5D1.DY69" )
			)
			( pin "@baseboard_fab2_lib.baseboard_fab2(sch_1):page27_i172:ddr4_ecc(1)"
				( attribute "PN" "EA68"
					( Origin gPackager )
				)
				( objectStatus "U5D1.EA68" )
			)
			( pin "@baseboard_fab2_lib.baseboard_fab2(sch_1):page27_i172:ddr4_ecc(2)"
				( attribute "PN" "DV65"
					( Origin gPackager )
				)
				( objectStatus "U5D1.DV65" )
			)
			( pin "@baseboard_fab2_lib.baseboard_fab2(sch_1):page27_i172:ddr4_ecc(3)"
				( attribute "PN" "DY65"
					( Origin gPackager )
				)
				( objectStatus "U5D1.DY65" )
			)
			( pin "@baseboard_fab2_lib.baseboard_fab2(sch_1):page27_i172:ddr4_ecc(4)"
				( attribute "PN" "DU68"
					( Origin gPackager )
				)
				( objectStatus "U5D1.DU68" )
			)
			( pin "@baseboard_fab2_lib.baseboard_fab2(sch_1):page27_i172:ddr4_ecc(5)"
				( attribute "PN" "DV69"
					( Origin gPackager )
				)
				( objectStatus "U5D1.DV69" )
			)
			( pin "@baseboard_fab2_lib.baseboard_fab2(sch_1):page27_i172:ddr4_ecc(6)"
				( attribute "PN" "DU66"
					( Origin gPackager )
				)
				( objectStatus "U5D1.DU66" )
			)
			( pin "@baseboard_fab2_lib.baseboard_fab2(sch_1):page27_i172:ddr4_ecc(7)"
				( attribute "PN" "EA66"
					( Origin gPackager )
				)
				( objectStatus "U5D1.EA66" )
			)
			( pin "@baseboard_fab2_lib.baseboard_fab2(sch_1):page27_i172:ddr4_ma(0)"
				( attribute "PN" "DW52"
					( Origin gPackager )
				)
				( objectStatus "U5D1.DW52" )
			)
			( pin "@baseboard_fab2_lib.baseboard_fab2(sch_1):page27_i172:ddr4_ma(1)"
				( attribute "PN" "DW58"
					( Origin gPackager )
				)
				( objectStatus "U5D1.DW58" )
			)
			( pin "@baseboard_fab2_lib.baseboard_fab2(sch_1):page27_i172:ddr4_ma(2)"
				( attribute "PN" "DV57"
					( Origin gPackager )
				)
				( objectStatus "U5D1.DV57" )
			)
			( pin "@baseboard_fab2_lib.baseboard_fab2(sch_1):page27_i172:ddr4_ma(3)"
				( attribute "PN" "DR58"
					( Origin gPackager )
				)
				( objectStatus "U5D1.DR58" )
			)
			( pin "@baseboard_fab2_lib.baseboard_fab2(sch_1):page27_i172:ddr4_ma(4)"
				( attribute "PN" "DT59"
					( Origin gPackager )
				)
				( objectStatus "U5D1.DT59" )
			)
			( pin "@baseboard_fab2_lib.baseboard_fab2(sch_1):page27_i172:ddr4_ma(5)"
				( attribute "PN" "DN58"
					( Origin gPackager )
				)
				( objectStatus "U5D1.DN58" )
			)
			( pin "@baseboard_fab2_lib.baseboard_fab2(sch_1):page27_i172:ddr4_ma(6)"
				( attribute "PN" "DM59"
					( Origin gPackager )
				)
				( objectStatus "U5D1.DM59" )
			)
			( pin "@baseboard_fab2_lib.baseboard_fab2(sch_1):page27_i172:ddr4_ma(7)"
				( attribute "PN" "DK61"
					( Origin gPackager )
				)
				( objectStatus "U5D1.DK61" )
			)
			( pin "@baseboard_fab2_lib.baseboard_fab2(sch_1):page27_i172:ddr4_ma(8)"
				( attribute "PN" "DJ60"
					( Origin gPackager )
				)
				( objectStatus "U5D1.DJ60" )
			)
			( pin "@baseboard_fab2_lib.baseboard_fab2(sch_1):page27_i172:ddr4_ma(9)"
				( attribute "PN" "DV59"
					( Origin gPackager )
				)
				( objectStatus "U5D1.DV59" )
			)
			( pin "@baseboard_fab2_lib.baseboard_fab2(sch_1):page27_i172:ddr4_ma(10)"
				( attribute "PN" "DT55"
					( Origin gPackager )
				)
				( objectStatus "U5D1.DT55" )
			)
			( pin "@baseboard_fab2_lib.baseboard_fab2(sch_1):page27_i172:ddr4_ma(11)"
				( attribute "PN" "DR60"
					( Origin gPackager )
				)
				( objectStatus "U5D1.DR60" )
			)
			( pin "@baseboard_fab2_lib.baseboard_fab2(sch_1):page27_i172:ddr4_ma(12)"
				( attribute "PN" "DN60"
					( Origin gPackager )
				)
				( objectStatus "U5D1.DN60" )
			)
			( pin "@baseboard_fab2_lib.baseboard_fab2(sch_1):page27_i172:ddr4_ma(13)"
				( attribute "PN" "DT51"
					( Origin gPackager )
				)
				( objectStatus "U5D1.DT51" )
			)
			( pin "@baseboard_fab2_lib.baseboard_fab2(sch_1):page27_i172:ddr4_ma(14)"
				( attribute "PN" "DM51"
					( Origin gPackager )
				)
				( objectStatus "U5D1.DM51" )
			)
			( pin "@baseboard_fab2_lib.baseboard_fab2(sch_1):page27_i172:ddr4_ma(15)"
				( attribute "PN" "DR52"
					( Origin gPackager )
				)
				( objectStatus "U5D1.DR52" )
			)
			( pin "@baseboard_fab2_lib.baseboard_fab2(sch_1):page27_i172:ddr4_ma(16)"
				( attribute "PN" "DN52"
					( Origin gPackager )
				)
				( objectStatus "U5D1.DN52" )
			)
			( pin "@baseboard_fab2_lib.baseboard_fab2(sch_1):page27_i172:ddr4_ma(17)"
				( attribute "PN" "DR48"
					( Origin gPackager )
				)
				( objectStatus "U5D1.DR48" )
			)
			( pin "@baseboard_fab2_lib.baseboard_fab2(sch_1):page27_i172:ddr4_odt(0)"
				( attribute "PN" "DR50"
					( Origin gPackager )
				)
				( objectStatus "U5D1.DR50" )
			)
			( pin "@baseboard_fab2_lib.baseboard_fab2(sch_1):page27_i172:ddr4_odt(1)"
				( attribute "PN" "DN48"
					( Origin gPackager )
				)
				( objectStatus "U5D1.DN48" )
			)
			( pin "@baseboard_fab2_lib.baseboard_fab2(sch_1):page27_i172:ddr4_odt(2)"
				( attribute "PN" "DT49"
					( Origin gPackager )
				)
				( objectStatus "U5D1.DT49" )
			)
			( pin "@baseboard_fab2_lib.baseboard_fab2(sch_1):page27_i172:ddr4_odt(3)"
				( attribute "PN" "DM47"
					( Origin gPackager )
				)
				( objectStatus "U5D1.DM47" )
			)
			( pin "@baseboard_fab2_lib.baseboard_fab2(sch_1):page27_i172:ddr4_par"
				( attribute "PN" "DV53"
					( Origin gPackager )
				)
				( objectStatus "U5D1.DV53" )
			)
			( pin "@baseboard_fab2_lib.baseboard_fab2(sch_1):page28_i172:ddr5_act_n"
				( attribute "PN" "DC62"
					( Origin gPackager )
				)
				( objectStatus "U5D1.DC62" )
			)
			( pin "@baseboard_fab2_lib.baseboard_fab2(sch_1):page28_i172:ddr5_alert_n"
				( attribute "PN" "DD61"
					( Origin gPackager )
				)
				( objectStatus "U5D1.DD61" )
			)
			( pin "@baseboard_fab2_lib.baseboard_fab2(sch_1):page28_i172:ddr5_ba(0)"
				( attribute "PN" "DJ52"
					( Origin gPackager )
				)
				( objectStatus "U5D1.DJ52" )
			)
			( pin "@baseboard_fab2_lib.baseboard_fab2(sch_1):page28_i172:ddr5_ba(1)"
				( attribute "PN" "DC56"
					( Origin gPackager )
				)
				( objectStatus "U5D1.DC56" )
			)
			( pin "@baseboard_fab2_lib.baseboard_fab2(sch_1):page28_i172:ddr5_bg(0)"
				( attribute "PN" "DA62"
					( Origin gPackager )
				)
				( objectStatus "U5D1.DA62" )
			)
			( pin "@baseboard_fab2_lib.baseboard_fab2(sch_1):page28_i172:ddr5_bg(1)"
				( attribute "PN" "DF61"
					( Origin gPackager )
				)
				( objectStatus "U5D1.DF61" )
			)
			( pin "@baseboard_fab2_lib.baseboard_fab2(sch_1):page28_i172:ddr5_cid(2)"
				( attribute "PN" "DF45"
					( Origin gPackager )
				)
				( objectStatus "U5D1.DF45" )
			)
			( pin "@baseboard_fab2_lib.baseboard_fab2(sch_1):page28_i172:ddr5_cke(0)"
				( attribute "PN" "DG62"
					( Origin gPackager )
				)
				( objectStatus "U5D1.DG62" )
			)
			( pin "@baseboard_fab2_lib.baseboard_fab2(sch_1):page28_i172:ddr5_cke(1)"
				( attribute "PN" "DD63"
					( Origin gPackager )
				)
				( objectStatus "U5D1.DD63" )
			)
			( pin "@baseboard_fab2_lib.baseboard_fab2(sch_1):page28_i172:ddr5_cke(2)"
				( attribute "PN" "DK63"
					( Origin gPackager )
				)
				( objectStatus "U5D1.DK63" )
			)
			( pin "@baseboard_fab2_lib.baseboard_fab2(sch_1):page28_i172:ddr5_cke(3)"
				( attribute "PN" "DF63"
					( Origin gPackager )
				)
				( objectStatus "U5D1.DF63" )
			)
			( pin "@baseboard_fab2_lib.baseboard_fab2(sch_1):page28_i172:ddr5_clk_dn(0)"
				( attribute "PN" "DK55"
					( Origin gPackager )
				)
				( objectStatus "U5D1.DK55" )
			)
			( pin "@baseboard_fab2_lib.baseboard_fab2(sch_1):page28_i172:ddr5_clk_dn(1)"
				( attribute "PN" "DF55"
					( Origin gPackager )
				)
				( objectStatus "U5D1.DF55" )
			)
			( pin "@baseboard_fab2_lib.baseboard_fab2(sch_1):page28_i172:ddr5_clk_dn(2)"
				( attribute "PN" "DK57"
					( Origin gPackager )
				)
				( objectStatus "U5D1.DK57" )
			)
			( pin "@baseboard_fab2_lib.baseboard_fab2(sch_1):page28_i172:ddr5_clk_dn(3)"
				( attribute "PN" "DF57"
					( Origin gPackager )
				)
				( objectStatus "U5D1.DF57" )
			)
			( pin "@baseboard_fab2_lib.baseboard_fab2(sch_1):page28_i172:ddr5_clk_dp(0)"
				( attribute "PN" "DJ54"
					( Origin gPackager )
				)
				( objectStatus "U5D1.DJ54" )
			)
			( pin "@baseboard_fab2_lib.baseboard_fab2(sch_1):page28_i172:ddr5_clk_dp(1)"
				( attribute "PN" "DG54"
					( Origin gPackager )
				)
				( objectStatus "U5D1.DG54" )
			)
			( pin "@baseboard_fab2_lib.baseboard_fab2(sch_1):page28_i172:ddr5_clk_dp(2)"
				( attribute "PN" "DJ56"
					( Origin gPackager )
				)
				( objectStatus "U5D1.DJ56" )
			)
			( pin "@baseboard_fab2_lib.baseboard_fab2(sch_1):page28_i172:ddr5_clk_dp(3)"
				( attribute "PN" "DG56"
					( Origin gPackager )
				)
				( objectStatus "U5D1.DG56" )
			)
			( pin "@baseboard_fab2_lib.baseboard_fab2(sch_1):page28_i172:ddr5_cs_n(0)"
				( attribute "PN" "DK51"
					( Origin gPackager )
				)
				( objectStatus "U5D1.DK51" )
			)
			( pin "@baseboard_fab2_lib.baseboard_fab2(sch_1):page28_i172:ddr5_cs_n(1)"
				( attribute "PN" "DF49"
					( Origin gPackager )
				)
				( objectStatus "U5D1.DF49" )
			)
			( pin "@baseboard_fab2_lib.baseboard_fab2(sch_1):page28_i172:ddr5_cs_n(2)"
				( attribute "PN" "DJ46"
					( Origin gPackager )
				)
				( objectStatus "U5D1.DJ46" )
			)
			( pin "@baseboard_fab2_lib.baseboard_fab2(sch_1):page28_i172:ddr5_cs_n(3)"
				( attribute "PN" "DG46"
					( Origin gPackager )
				)
				( objectStatus "U5D1.DG46" )
			)
			( pin "@baseboard_fab2_lib.baseboard_fab2(sch_1):page28_i172:ddr5_cs_n(4)"
				( attribute "PN" "DF51"
					( Origin gPackager )
				)
				( objectStatus "U5D1.DF51" )
			)
			( pin "@baseboard_fab2_lib.baseboard_fab2(sch_1):page28_i172:ddr5_cs_n(5)"
				( attribute "PN" "DJ48"
					( Origin gPackager )
				)
				( objectStatus "U5D1.DJ48" )
			)
			( pin "@baseboard_fab2_lib.baseboard_fab2(sch_1):page28_i172:ddr5_cs_n(6)"
				( attribute "PN" "DM45"
					( Origin gPackager )
				)
				( objectStatus "U5D1.DM45" )
			)
			( pin "@baseboard_fab2_lib.baseboard_fab2(sch_1):page28_i172:ddr5_cs_n(7)"
				( attribute "PN" "DK45"
					( Origin gPackager )
				)
				( objectStatus "U5D1.DK45" )
			)
			( pin "@baseboard_fab2_lib.baseboard_fab2(sch_1):page28_i172:ddr5_dq(0)"
				( attribute "PN" "CR74"
					( Origin gPackager )
				)
				( objectStatus "U5D1.CR74" )
			)
			( pin "@baseboard_fab2_lib.baseboard_fab2(sch_1):page28_i172:ddr5_dq(1)"
				( attribute "PN" "CN76"
					( Origin gPackager )
				)
				( objectStatus "U5D1.CN76" )
			)
			( pin "@baseboard_fab2_lib.baseboard_fab2(sch_1):page28_i172:ddr5_dq(2)"
				( attribute "PN" "CW76"
					( Origin gPackager )
				)
				( objectStatus "U5D1.CW76" )
			)
			( pin "@baseboard_fab2_lib.baseboard_fab2(sch_1):page28_i172:ddr5_dq(3)"
				( attribute "PN" "CV77"
					( Origin gPackager )
				)
				( objectStatus "U5D1.CV77" )
			)
			( pin "@baseboard_fab2_lib.baseboard_fab2(sch_1):page28_i172:ddr5_dq(4)"
				( attribute "PN" "CN74"
					( Origin gPackager )
				)
				( objectStatus "U5D1.CN74" )
			)
			( pin "@baseboard_fab2_lib.baseboard_fab2(sch_1):page28_i172:ddr5_dq(5)"
				( attribute "PN" "CM75"
					( Origin gPackager )
				)
				( objectStatus "U5D1.CM75" )
			)
			( pin "@baseboard_fab2_lib.baseboard_fab2(sch_1):page28_i172:ddr5_dq(6)"
				( attribute "PN" "CV75"
					( Origin gPackager )
				)
				( objectStatus "U5D1.CV75" )
			)
			( pin "@baseboard_fab2_lib.baseboard_fab2(sch_1):page28_i172:ddr5_dq(7)"
				( attribute "PN" "CT77"
					( Origin gPackager )
				)
				( objectStatus "U5D1.CT77" )
			)
			( pin "@baseboard_fab2_lib.baseboard_fab2(sch_1):page28_i172:ddr5_dq(8)"
				( attribute "PN" "DE74"
					( Origin gPackager )
				)
				( objectStatus "U5D1.DE74" )
			)
			( pin "@baseboard_fab2_lib.baseboard_fab2(sch_1):page28_i172:ddr5_dq(9)"
				( attribute "PN" "DC76"
					( Origin gPackager )
				)
				( objectStatus "U5D1.DC76" )
			)
			( pin "@baseboard_fab2_lib.baseboard_fab2(sch_1):page28_i172:ddr5_dq(10)"
				( attribute "PN" "DH75"
					( Origin gPackager )
				)
				( objectStatus "U5D1.DH75" )
			)
			( pin "@baseboard_fab2_lib.baseboard_fab2(sch_1):page28_i172:ddr5_dq(11)"
				( attribute "PN" "DJ76"
					( Origin gPackager )
				)
				( objectStatus "U5D1.DJ76" )
			)
			( pin "@baseboard_fab2_lib.baseboard_fab2(sch_1):page28_i172:ddr5_dq(12)"
				( attribute "PN" "DC74"
					( Origin gPackager )
				)
				( objectStatus "U5D1.DC74" )
			)
			( pin "@baseboard_fab2_lib.baseboard_fab2(sch_1):page28_i172:ddr5_dq(13)"
				( attribute "PN" "DB75"
					( Origin gPackager )
				)
				( objectStatus "U5D1.DB75" )
			)
			( pin "@baseboard_fab2_lib.baseboard_fab2(sch_1):page28_i172:ddr5_dq(14)"
				( attribute "PN" "DF77"
					( Origin gPackager )
				)
				( objectStatus "U5D1.DF77" )
			)
			( pin "@baseboard_fab2_lib.baseboard_fab2(sch_1):page28_i172:ddr5_dq(15)"
				( attribute "PN" "DH77"
					( Origin gPackager )
				)
				( objectStatus "U5D1.DH77" )
			)
			( pin "@baseboard_fab2_lib.baseboard_fab2(sch_1):page28_i172:ddr5_dq(16)"
				( attribute "PN" "DG70"
					( Origin gPackager )
				)
				( objectStatus "U5D1.DG70" )
			)
			( pin "@baseboard_fab2_lib.baseboard_fab2(sch_1):page28_i172:ddr5_dq(17)"
				( attribute "PN" "DJ72"
					( Origin gPackager )
				)
				( objectStatus "U5D1.DJ72" )
			)
			( pin "@baseboard_fab2_lib.baseboard_fab2(sch_1):page28_i172:ddr5_dq(18)"
				( attribute "PN" "DM69"
					( Origin gPackager )
				)
				( objectStatus "U5D1.DM69" )
			)
			( pin "@baseboard_fab2_lib.baseboard_fab2(sch_1):page28_i172:ddr5_dq(19)"
				( attribute "PN" "DN70"
					( Origin gPackager )
				)
				( objectStatus "U5D1.DN70" )
			)
			( pin "@baseboard_fab2_lib.baseboard_fab2(sch_1):page28_i172:ddr5_dq(20)"
				( attribute "PN" "DF71"
					( Origin gPackager )
				)
				( objectStatus "U5D1.DF71" )
			)
			( pin "@baseboard_fab2_lib.baseboard_fab2(sch_1):page28_i172:ddr5_dq(21)"
				( attribute "PN" "DG72"
					( Origin gPackager )
				)
				( objectStatus "U5D1.DG72" )
			)
			( pin "@baseboard_fab2_lib.baseboard_fab2(sch_1):page28_i172:ddr5_dq(22)"
				( attribute "PN" "DK69"
					( Origin gPackager )
				)
				( objectStatus "U5D1.DK69" )
			)
			( pin "@baseboard_fab2_lib.baseboard_fab2(sch_1):page28_i172:ddr5_dq(23)"
				( attribute "PN" "DM71"
					( Origin gPackager )
				)
				( objectStatus "U5D1.DM71" )
			)
			( pin "@baseboard_fab2_lib.baseboard_fab2(sch_1):page28_i172:ddr5_dq(24)"
				( attribute "PN" "CN66"
					( Origin gPackager )
				)
				( objectStatus "U5D1.CN66" )
			)
			( pin "@baseboard_fab2_lib.baseboard_fab2(sch_1):page28_i172:ddr5_dq(25)"
				( attribute "PN" "CU66"
					( Origin gPackager )
				)
				( objectStatus "U5D1.CU66" )
			)
			( pin "@baseboard_fab2_lib.baseboard_fab2(sch_1):page28_i172:ddr5_dq(26)"
				( attribute "PN" "CP63"
					( Origin gPackager )
				)
				( objectStatus "U5D1.CP63" )
			)
			( pin "@baseboard_fab2_lib.baseboard_fab2(sch_1):page28_i172:ddr5_dq(27)"
				( attribute "PN" "CT63"
					( Origin gPackager )
				)
				( objectStatus "U5D1.CT63" )
			)
			( pin "@baseboard_fab2_lib.baseboard_fab2(sch_1):page28_i172:ddr5_dq(28)"
				( attribute "PN" "CP67"
					( Origin gPackager )
				)
				( objectStatus "U5D1.CP67" )
			)
			( pin "@baseboard_fab2_lib.baseboard_fab2(sch_1):page28_i172:ddr5_dq(29)"
				( attribute "PN" "CT67"
					( Origin gPackager )
				)
				( objectStatus "U5D1.CT67" )
			)
			( pin "@baseboard_fab2_lib.baseboard_fab2(sch_1):page28_i172:ddr5_dq(30)"
				( attribute "PN" "CN64"
					( Origin gPackager )
				)
				( objectStatus "U5D1.CN64" )
			)
			( pin "@baseboard_fab2_lib.baseboard_fab2(sch_1):page28_i172:ddr5_dq(31)"
				( attribute "PN" "CU64"
					( Origin gPackager )
				)
				( objectStatus "U5D1.CU64" )
			)
			( pin "@baseboard_fab2_lib.baseboard_fab2(sch_1):page28_i172:ddr5_dq(32)"
				( attribute "PN" "DD41"
					( Origin gPackager )
				)
				( objectStatus "U5D1.DD41" )
			)
			( pin "@baseboard_fab2_lib.baseboard_fab2(sch_1):page28_i172:ddr5_dq(33)"
				( attribute "PN" "DG42"
					( Origin gPackager )
				)
				( objectStatus "U5D1.DG42" )
			)
			( pin "@baseboard_fab2_lib.baseboard_fab2(sch_1):page28_i172:ddr5_dq(34)"
				( attribute "PN" "DE38"
					( Origin gPackager )
				)
				( objectStatus "U5D1.DE38" )
			)
			( pin "@baseboard_fab2_lib.baseboard_fab2(sch_1):page28_i172:ddr5_dq(35)"
				( attribute "PN" "DG38"
					( Origin gPackager )
				)
				( objectStatus "U5D1.DG38" )
			)
			( pin "@baseboard_fab2_lib.baseboard_fab2(sch_1):page28_i172:ddr5_dq(36)"
				( attribute "PN" "DA42"
					( Origin gPackager )
				)
				( objectStatus "U5D1.DA42" )
			)
			( pin "@baseboard_fab2_lib.baseboard_fab2(sch_1):page28_i172:ddr5_dq(37)"
				( attribute "PN" "DE42"
					( Origin gPackager )
				)
				( objectStatus "U5D1.DE42" )
			)
			( pin "@baseboard_fab2_lib.baseboard_fab2(sch_1):page28_i172:ddr5_dq(38)"
				( attribute "PN" "DD39"
					( Origin gPackager )
				)
				( objectStatus "U5D1.DD39" )
			)
			( pin "@baseboard_fab2_lib.baseboard_fab2(sch_1):page28_i172:ddr5_dq(39)"
				( attribute "PN" "DH39"
					( Origin gPackager )
				)
				( objectStatus "U5D1.DH39" )
			)
			( pin "@baseboard_fab2_lib.baseboard_fab2(sch_1):page28_i172:ddr5_dq(40)"
				( attribute "PN" "DF33"
					( Origin gPackager )
				)
				( objectStatus "U5D1.DF33" )
			)
			( pin "@baseboard_fab2_lib.baseboard_fab2(sch_1):page28_i172:ddr5_dq(41)"
				( attribute "PN" "DK33"
					( Origin gPackager )
				)
				( objectStatus "U5D1.DK33" )
			)
			( pin "@baseboard_fab2_lib.baseboard_fab2(sch_1):page28_i172:ddr5_dq(42)"
				( attribute "PN" "DG30"
					( Origin gPackager )
				)
				( objectStatus "U5D1.DG30" )
			)
			( pin "@baseboard_fab2_lib.baseboard_fab2(sch_1):page28_i172:ddr5_dq(43)"
				( attribute "PN" "DJ30"
					( Origin gPackager )
				)
				( objectStatus "U5D1.DJ30" )
			)
			( pin "@baseboard_fab2_lib.baseboard_fab2(sch_1):page28_i172:ddr5_dq(44)"
				( attribute "PN" "DG34"
					( Origin gPackager )
				)
				( objectStatus "U5D1.DG34" )
			)
			( pin "@baseboard_fab2_lib.baseboard_fab2(sch_1):page28_i172:ddr5_dq(45)"
				( attribute "PN" "DJ34"
					( Origin gPackager )
				)
				( objectStatus "U5D1.DJ34" )
			)
			( pin "@baseboard_fab2_lib.baseboard_fab2(sch_1):page28_i172:ddr5_dq(46)"
				( attribute "PN" "DF31"
					( Origin gPackager )
				)
				( objectStatus "U5D1.DF31" )
			)
			( pin "@baseboard_fab2_lib.baseboard_fab2(sch_1):page28_i172:ddr5_dq(47)"
				( attribute "PN" "DK31"
					( Origin gPackager )
				)
				( objectStatus "U5D1.DK31" )
			)
			( pin "@baseboard_fab2_lib.baseboard_fab2(sch_1):page28_i172:ddr5_dq(48)"
				( attribute "PN" "CW36"
					( Origin gPackager )
				)
				( objectStatus "U5D1.CW36" )
			)
			( pin "@baseboard_fab2_lib.baseboard_fab2(sch_1):page28_i172:ddr5_dq(49)"
				( attribute "PN" "DC36"
					( Origin gPackager )
				)
				( objectStatus "U5D1.DC36" )
			)
			( pin "@baseboard_fab2_lib.baseboard_fab2(sch_1):page28_i172:ddr5_dq(50)"
				( attribute "PN" "CY33"
					( Origin gPackager )
				)
				( objectStatus "U5D1.CY33" )
			)
			( pin "@baseboard_fab2_lib.baseboard_fab2(sch_1):page28_i172:ddr5_dq(51)"
				( attribute "PN" "DB33"
					( Origin gPackager )
				)
				( objectStatus "U5D1.DB33" )
			)
			( pin "@baseboard_fab2_lib.baseboard_fab2(sch_1):page28_i172:ddr5_dq(52)"
				( attribute "PN" "CY37"
					( Origin gPackager )
				)
				( objectStatus "U5D1.CY37" )
			)
			( pin "@baseboard_fab2_lib.baseboard_fab2(sch_1):page28_i172:ddr5_dq(53)"
				( attribute "PN" "DB37"
					( Origin gPackager )
				)
				( objectStatus "U5D1.DB37" )
			)
			( pin "@baseboard_fab2_lib.baseboard_fab2(sch_1):page28_i172:ddr5_dq(54)"
				( attribute "PN" "CW34"
					( Origin gPackager )
				)
				( objectStatus "U5D1.CW34" )
			)
			( pin "@baseboard_fab2_lib.baseboard_fab2(sch_1):page28_i172:ddr5_dq(55)"
				( attribute "PN" "DC34"
					( Origin gPackager )
				)
				( objectStatus "U5D1.DC34" )
			)
			( pin "@baseboard_fab2_lib.baseboard_fab2(sch_1):page28_i172:ddr5_dq(56)"
				( attribute "PN" "CW30"
					( Origin gPackager )
				)
				( objectStatus "U5D1.CW30" )
			)
			( pin "@baseboard_fab2_lib.baseboard_fab2(sch_1):page28_i172:ddr5_dq(57)"
				( attribute "PN" "DC30"
					( Origin gPackager )
				)
				( objectStatus "U5D1.DC30" )
			)
			( pin "@baseboard_fab2_lib.baseboard_fab2(sch_1):page28_i172:ddr5_dq(58)"
				( attribute "PN" "CY27"
					( Origin gPackager )
				)
				( objectStatus "U5D1.CY27" )
			)
			( pin "@baseboard_fab2_lib.baseboard_fab2(sch_1):page28_i172:ddr5_dq(59)"
				( attribute "PN" "DB27"
					( Origin gPackager )
				)
				( objectStatus "U5D1.DB27" )
			)
			( pin "@baseboard_fab2_lib.baseboard_fab2(sch_1):page28_i172:ddr5_dq(60)"
				( attribute "PN" "CY31"
					( Origin gPackager )
				)
				( objectStatus "U5D1.CY31" )
			)
			( pin "@baseboard_fab2_lib.baseboard_fab2(sch_1):page28_i172:ddr5_dq(61)"
				( attribute "PN" "DB31"
					( Origin gPackager )
				)
				( objectStatus "U5D1.DB31" )
			)
			( pin "@baseboard_fab2_lib.baseboard_fab2(sch_1):page28_i172:ddr5_dq(62)"
				( attribute "PN" "CW28"
					( Origin gPackager )
				)
				( objectStatus "U5D1.CW28" )
			)
			( pin "@baseboard_fab2_lib.baseboard_fab2(sch_1):page28_i172:ddr5_dq(63)"
				( attribute "PN" "DC28"
					( Origin gPackager )
				)
				( objectStatus "U5D1.DC28" )
			)
			( pin "@baseboard_fab2_lib.baseboard_fab2(sch_1):page28_i172:ddr5_dqs_dn(0)"
				( attribute "PN" "CP77"
					( Origin gPackager )
				)
				( objectStatus "U5D1.CP77" )
			)
			( pin "@baseboard_fab2_lib.baseboard_fab2(sch_1):page28_i172:ddr5_dqs_dn(1)"
				( attribute "PN" "DD77"
					( Origin gPackager )
				)
				( objectStatus "U5D1.DD77" )
			)
			( pin "@baseboard_fab2_lib.baseboard_fab2(sch_1):page28_i172:ddr5_dqs_dn(2)"
				( attribute "PN" "DL72"
					( Origin gPackager )
				)
				( objectStatus "U5D1.DL72" )
			)
			( pin "@baseboard_fab2_lib.baseboard_fab2(sch_1):page28_i172:ddr5_dqs_dn(3)"
				( attribute "PN" "CV65"
					( Origin gPackager )
				)
				( objectStatus "U5D1.CV65" )
			)
			( pin "@baseboard_fab2_lib.baseboard_fab2(sch_1):page28_i172:ddr5_dqs_dn(4)"
				( attribute "PN" "DG40"
					( Origin gPackager )
				)
				( objectStatus "U5D1.DG40" )
			)
			( pin "@baseboard_fab2_lib.baseboard_fab2(sch_1):page28_i172:ddr5_dqs_dn(5)"
				( attribute "PN" "DL32"
					( Origin gPackager )
				)
				( objectStatus "U5D1.DL32" )
			)
			( pin "@baseboard_fab2_lib.baseboard_fab2(sch_1):page28_i172:ddr5_dqs_dn(6)"
				( attribute "PN" "DD35"
					( Origin gPackager )
				)
				( objectStatus "U5D1.DD35" )
			)
			( pin "@baseboard_fab2_lib.baseboard_fab2(sch_1):page28_i172:ddr5_dqs_dn(7)"
				( attribute "PN" "DD29"
					( Origin gPackager )
				)
				( objectStatus "U5D1.DD29" )
			)
			( pin "@baseboard_fab2_lib.baseboard_fab2(sch_1):page28_i172:ddr5_dqs_dn(8)"
				( attribute "PN" "CN70"
					( Origin gPackager )
				)
				( objectStatus "U5D1.CN70" )
			)
			( pin "@baseboard_fab2_lib.baseboard_fab2(sch_1):page28_i172:ddr5_dqs_dn(9)"
				( attribute "PN" "CT75"
					( Origin gPackager )
				)
				( objectStatus "U5D1.CT75" )
			)
			( pin "@baseboard_fab2_lib.baseboard_fab2(sch_1):page28_i172:ddr5_dqs_dn(10)"
				( attribute "PN" "DF75"
					( Origin gPackager )
				)
				( objectStatus "U5D1.DF75" )
			)
			( pin "@baseboard_fab2_lib.baseboard_fab2(sch_1):page28_i172:ddr5_dqs_dn(11)"
				( attribute "PN" "DJ70"
					( Origin gPackager )
				)
				( objectStatus "U5D1.DJ70" )
			)
			( pin "@baseboard_fab2_lib.baseboard_fab2(sch_1):page28_i172:ddr5_dqs_dn(12)"
				( attribute "PN" "CP65"
					( Origin gPackager )
				)
				( objectStatus "U5D1.CP65" )
			)
			( pin "@baseboard_fab2_lib.baseboard_fab2(sch_1):page28_i172:ddr5_dqs_dn(13)"
				( attribute "PN" "DE40"
					( Origin gPackager )
				)
				( objectStatus "U5D1.DE40" )
			)
			( pin "@baseboard_fab2_lib.baseboard_fab2(sch_1):page28_i172:ddr5_dqs_dn(14)"
				( attribute "PN" "DG32"
					( Origin gPackager )
				)
				( objectStatus "U5D1.DG32" )
			)
			( pin "@baseboard_fab2_lib.baseboard_fab2(sch_1):page28_i172:ddr5_dqs_dn(15)"
				( attribute "PN" "CY35"
					( Origin gPackager )
				)
				( objectStatus "U5D1.CY35" )
			)
			( pin "@baseboard_fab2_lib.baseboard_fab2(sch_1):page28_i172:ddr5_dqs_dn(16)"
				( attribute "PN" "CY29"
					( Origin gPackager )
				)
				( objectStatus "U5D1.CY29" )
			)
			( pin "@baseboard_fab2_lib.baseboard_fab2(sch_1):page28_i172:ddr5_dqs_dn(17)"
				( attribute "PN" "CJ70"
					( Origin gPackager )
				)
				( objectStatus "U5D1.CJ70" )
			)
			( pin "@baseboard_fab2_lib.baseboard_fab2(sch_1):page28_i172:ddr5_dqs_dp(0)"
				( attribute "PN" "CR76"
					( Origin gPackager )
				)
				( objectStatus "U5D1.CR76" )
			)
			( pin "@baseboard_fab2_lib.baseboard_fab2(sch_1):page28_i172:ddr5_dqs_dp(1)"
				( attribute "PN" "DE76"
					( Origin gPackager )
				)
				( objectStatus "U5D1.DE76" )
			)
			( pin "@baseboard_fab2_lib.baseboard_fab2(sch_1):page28_i172:ddr5_dqs_dp(2)"
				( attribute "PN" "DK71"
					( Origin gPackager )
				)
				( objectStatus "U5D1.DK71" )
			)
			( pin "@baseboard_fab2_lib.baseboard_fab2(sch_1):page28_i172:ddr5_dqs_dp(3)"
				( attribute "PN" "CT65"
					( Origin gPackager )
				)
				( objectStatus "U5D1.CT65" )
			)
			( pin "@baseboard_fab2_lib.baseboard_fab2(sch_1):page28_i172:ddr5_dqs_dp(4)"
				( attribute "PN" "DJ40"
					( Origin gPackager )
				)
				( objectStatus "U5D1.DJ40" )
			)
			( pin "@baseboard_fab2_lib.baseboard_fab2(sch_1):page28_i172:ddr5_dqs_dp(5)"
				( attribute "PN" "DJ32"
					( Origin gPackager )
				)
				( objectStatus "U5D1.DJ32" )
			)
			( pin "@baseboard_fab2_lib.baseboard_fab2(sch_1):page28_i172:ddr5_dqs_dp(6)"
				( attribute "PN" "DB35"
					( Origin gPackager )
				)
				( objectStatus "U5D1.DB35" )
			)
			( pin "@baseboard_fab2_lib.baseboard_fab2(sch_1):page28_i172:ddr5_dqs_dp(7)"
				( attribute "PN" "DB29"
					( Origin gPackager )
				)
				( objectStatus "U5D1.DB29" )
			)
			( pin "@baseboard_fab2_lib.baseboard_fab2(sch_1):page28_i172:ddr5_dqs_dp(8)"
				( attribute "PN" "CL70"
					( Origin gPackager )
				)
				( objectStatus "U5D1.CL70" )
			)
			( pin "@baseboard_fab2_lib.baseboard_fab2(sch_1):page28_i172:ddr5_dqs_dp(9)"
				( attribute "PN" "CU74"
					( Origin gPackager )
				)
				( objectStatus "U5D1.CU74" )
			)
			( pin "@baseboard_fab2_lib.baseboard_fab2(sch_1):page28_i172:ddr5_dqs_dp(10)"
				( attribute "PN" "DG74"
					( Origin gPackager )
				)
				( objectStatus "U5D1.DG74" )
			)
			( pin "@baseboard_fab2_lib.baseboard_fab2(sch_1):page28_i172:ddr5_dqs_dp(11)"
				( attribute "PN" "DH69"
					( Origin gPackager )
				)
				( objectStatus "U5D1.DH69" )
			)
			( pin "@baseboard_fab2_lib.baseboard_fab2(sch_1):page28_i172:ddr5_dqs_dp(12)"
				( attribute "PN" "CM65"
					( Origin gPackager )
				)
				( objectStatus "U5D1.CM65" )
			)
			( pin "@baseboard_fab2_lib.baseboard_fab2(sch_1):page28_i172:ddr5_dqs_dp(13)"
				( attribute "PN" "DC40"
					( Origin gPackager )
				)
				( objectStatus "U5D1.DC40" )
			)
			( pin "@baseboard_fab2_lib.baseboard_fab2(sch_1):page28_i172:ddr5_dqs_dp(14)"
				( attribute "PN" "DE32"
					( Origin gPackager )
				)
				( objectStatus "U5D1.DE32" )
			)
			( pin "@baseboard_fab2_lib.baseboard_fab2(sch_1):page28_i172:ddr5_dqs_dp(15)"
				( attribute "PN" "CV35"
					( Origin gPackager )
				)
				( objectStatus "U5D1.CV35" )
			)
			( pin "@baseboard_fab2_lib.baseboard_fab2(sch_1):page28_i172:ddr5_dqs_dp(16)"
				( attribute "PN" "CV29"
					( Origin gPackager )
				)
				( objectStatus "U5D1.CV29" )
			)
			( pin "@baseboard_fab2_lib.baseboard_fab2(sch_1):page28_i172:ddr5_dqs_dp(17)"
				( attribute "PN" "CG70"
					( Origin gPackager )
				)
				( objectStatus "U5D1.CG70" )
			)
			( pin "@baseboard_fab2_lib.baseboard_fab2(sch_1):page28_i172:ddr5_ecc(0)"
				( attribute "PN" "CH71"
					( Origin gPackager )
				)
				( objectStatus "U5D1.CH71" )
			)
			( pin "@baseboard_fab2_lib.baseboard_fab2(sch_1):page28_i172:ddr5_ecc(1)"
				( attribute "PN" "CM71"
					( Origin gPackager )
				)
				( objectStatus "U5D1.CM71" )
			)
			( pin "@baseboard_fab2_lib.baseboard_fab2(sch_1):page28_i172:ddr5_ecc(2)"
				( attribute "PN" "CJ68"
					( Origin gPackager )
				)
				( objectStatus "U5D1.CJ68" )
			)
			( pin "@baseboard_fab2_lib.baseboard_fab2(sch_1):page28_i172:ddr5_ecc(3)"
				( attribute "PN" "CL68"
					( Origin gPackager )
				)
				( objectStatus "U5D1.CL68" )
			)
			( pin "@baseboard_fab2_lib.baseboard_fab2(sch_1):page28_i172:ddr5_ecc(4)"
				( attribute "PN" "CJ72"
					( Origin gPackager )
				)
				( objectStatus "U5D1.CJ72" )
			)
			( pin "@baseboard_fab2_lib.baseboard_fab2(sch_1):page28_i172:ddr5_ecc(5)"
				( attribute "PN" "CL72"
					( Origin gPackager )
				)
				( objectStatus "U5D1.CL72" )
			)
			( pin "@baseboard_fab2_lib.baseboard_fab2(sch_1):page28_i172:ddr5_ecc(6)"
				( attribute "PN" "CH69"
					( Origin gPackager )
				)
				( objectStatus "U5D1.CH69" )
			)
			( pin "@baseboard_fab2_lib.baseboard_fab2(sch_1):page28_i172:ddr5_ecc(7)"
				( attribute "PN" "CM69"
					( Origin gPackager )
				)
				( objectStatus "U5D1.CM69" )
			)
			( pin "@baseboard_fab2_lib.baseboard_fab2(sch_1):page28_i172:ddr5_ma(0)"
				( attribute "PN" "DF53"
					( Origin gPackager )
				)
				( objectStatus "U5D1.DF53" )
			)
			( pin "@baseboard_fab2_lib.baseboard_fab2(sch_1):page28_i172:ddr5_ma(1)"
				( attribute "PN" "DC58"
					( Origin gPackager )
				)
				( objectStatus "U5D1.DC58" )
			)
			( pin "@baseboard_fab2_lib.baseboard_fab2(sch_1):page28_i172:ddr5_ma(2)"
				( attribute "PN" "DD57"
					( Origin gPackager )
				)
				( objectStatus "U5D1.DD57" )
			)
			( pin "@baseboard_fab2_lib.baseboard_fab2(sch_1):page28_i172:ddr5_ma(3)"
				( attribute "PN" "DG58"
					( Origin gPackager )
				)
				( objectStatus "U5D1.DG58" )
			)
			( pin "@baseboard_fab2_lib.baseboard_fab2(sch_1):page28_i172:ddr5_ma(4)"
				( attribute "PN" "DJ58"
					( Origin gPackager )
				)
				( objectStatus "U5D1.DJ58" )
			)
			( pin "@baseboard_fab2_lib.baseboard_fab2(sch_1):page28_i172:ddr5_ma(5)"
				( attribute "PN" "DF59"
					( Origin gPackager )
				)
				( objectStatus "U5D1.DF59" )
			)
			( pin "@baseboard_fab2_lib.baseboard_fab2(sch_1):page28_i172:ddr5_ma(6)"
				( attribute "PN" "DK59"
					( Origin gPackager )
				)
				( objectStatus "U5D1.DK59" )
			)
			( pin "@baseboard_fab2_lib.baseboard_fab2(sch_1):page28_i172:ddr5_ma(7)"
				( attribute "PN" "DC60"
					( Origin gPackager )
				)
				( objectStatus "U5D1.DC60" )
			)
			( pin "@baseboard_fab2_lib.baseboard_fab2(sch_1):page28_i172:ddr5_ma(8)"
				( attribute "PN" "DD59"
					( Origin gPackager )
				)
				( objectStatus "U5D1.DD59" )
			)
			( pin "@baseboard_fab2_lib.baseboard_fab2(sch_1):page28_i172:ddr5_ma(9)"
				( attribute "PN" "DA58"
					( Origin gPackager )
				)
				( objectStatus "U5D1.DA58" )
			)
			( pin "@baseboard_fab2_lib.baseboard_fab2(sch_1):page28_i172:ddr5_ma(10)"
				( attribute "PN" "DD55"
					( Origin gPackager )
				)
				( objectStatus "U5D1.DD55" )
			)
			( pin "@baseboard_fab2_lib.baseboard_fab2(sch_1):page28_i172:ddr5_ma(11)"
				( attribute "PN" "DA60"
					( Origin gPackager )
				)
				( objectStatus "U5D1.DA60" )
			)
			( pin "@baseboard_fab2_lib.baseboard_fab2(sch_1):page28_i172:ddr5_ma(12)"
				( attribute "PN" "DG60"
					( Origin gPackager )
				)
				( objectStatus "U5D1.DG60" )
			)
			( pin "@baseboard_fab2_lib.baseboard_fab2(sch_1):page28_i172:ddr5_ma(13)"
				( attribute "PN" "DD53"
					( Origin gPackager )
				)
				( objectStatus "U5D1.DD53" )
			)
			( pin "@baseboard_fab2_lib.baseboard_fab2(sch_1):page28_i172:ddr5_ma(14)"
				( attribute "PN" "DJ50"
					( Origin gPackager )
				)
				( objectStatus "U5D1.DJ50" )
			)
			( pin "@baseboard_fab2_lib.baseboard_fab2(sch_1):page28_i172:ddr5_ma(15)"
				( attribute "PN" "DC54"
					( Origin gPackager )
				)
				( objectStatus "U5D1.DC54" )
			)
			( pin "@baseboard_fab2_lib.baseboard_fab2(sch_1):page28_i172:ddr5_ma(16)"
				( attribute "PN" "DG52"
					( Origin gPackager )
				)
				( objectStatus "U5D1.DG52" )
			)
			( pin "@baseboard_fab2_lib.baseboard_fab2(sch_1):page28_i172:ddr5_ma(17)"
				( attribute "PN" "DE46"
					( Origin gPackager )
				)
				( objectStatus "U5D1.DE46" )
			)
			( pin "@baseboard_fab2_lib.baseboard_fab2(sch_1):page28_i172:ddr5_odt(0)"
				( attribute "PN" "DG50"
					( Origin gPackager )
				)
				( objectStatus "U5D1.DG50" )
			)
			( pin "@baseboard_fab2_lib.baseboard_fab2(sch_1):page28_i172:ddr5_odt(1)"
				( attribute "PN" "DG48"
					( Origin gPackager )
				)
				( objectStatus "U5D1.DG48" )
			)
			( pin "@baseboard_fab2_lib.baseboard_fab2(sch_1):page28_i172:ddr5_odt(2)"
				( attribute "PN" "DK49"
					( Origin gPackager )
				)
				( objectStatus "U5D1.DK49" )
			)
			( pin "@baseboard_fab2_lib.baseboard_fab2(sch_1):page28_i172:ddr5_odt(3)"
				( attribute "PN" "DF47"
					( Origin gPackager )
				)
				( objectStatus "U5D1.DF47" )
			)
			( pin "@baseboard_fab2_lib.baseboard_fab2(sch_1):page28_i172:ddr5_par"
				( attribute "PN" "DK53"
					( Origin gPackager )
				)
				( objectStatus "U5D1.DK53" )
			)
			( pin "@baseboard_fab2_lib.baseboard_fab2(sch_1):page29_i61:cd_hfi0_i2cclk"
				( attribute "PN" "BN22"
					( Origin gPackager )
				)
				( objectStatus "U5D1.BN22" )
			)
			( pin "@baseboard_fab2_lib.baseboard_fab2(sch_1):page29_i61:cd_hfi0_i2cdat"
				( attribute "PN" "BP23"
					( Origin gPackager )
				)
				( objectStatus "U5D1.BP23" )
			)
			( pin "@baseboard_fab2_lib.baseboard_fab2(sch_1):page29_i61:cd_hfi0_int_n"
				( attribute "PN" "BP19"
					( Origin gPackager )
				)
				( objectStatus "U5D1.BP19" )
			)
			( pin "@baseboard_fab2_lib.baseboard_fab2(sch_1):page29_i61:cd_hfi0_led_n"
				( attribute "PN" "BK21"
					( Origin gPackager )
				)
				( objectStatus "U5D1.BK21" )
			)
			( pin "@baseboard_fab2_lib.baseboard_fab2(sch_1):page29_i61:cd_hfi0_modprst_n"
				( attribute "PN" "BR20"
					( Origin gPackager )
				)
				( objectStatus "U5D1.BR20" )
			)
			( pin "@baseboard_fab2_lib.baseboard_fab2(sch_1):page29_i61:cd_hfi0_reset_n"
				( attribute "PN" "BN24"
					( Origin gPackager )
				)
				( objectStatus "U5D1.BN24" )
			)
			( pin "@baseboard_fab2_lib.baseboard_fab2(sch_1):page29_i61:cd_hfi1_i2cclk"
				( attribute "PN" "BJ22"
					( Origin gPackager )
				)
				( objectStatus "U5D1.BJ22" )
			)
			( pin "@baseboard_fab2_lib.baseboard_fab2(sch_1):page29_i61:cd_hfi1_i2cdat"
				( attribute "PN" "BH23"
					( Origin gPackager )
				)
				( objectStatus "U5D1.BH23" )
			)
			( pin "@baseboard_fab2_lib.baseboard_fab2(sch_1):page29_i61:cd_hfi1_int_n"
				( attribute "PN" "BM21"
					( Origin gPackager )
				)
				( objectStatus "U5D1.BM21" )
			)
			( pin "@baseboard_fab2_lib.baseboard_fab2(sch_1):page29_i61:cd_hfi1_led_n"
				( attribute "PN" "BM23"
					( Origin gPackager )
				)
				( objectStatus "U5D1.BM23" )
			)
			( pin "@baseboard_fab2_lib.baseboard_fab2(sch_1):page29_i61:cd_hfi1_modprst_n"
				( attribute "PN" "BT19"
					( Origin gPackager )
				)
				( objectStatus "U5D1.BT19" )
			)
			( pin "@baseboard_fab2_lib.baseboard_fab2(sch_1):page29_i61:cd_hfi1_reset_n"
				( attribute "PN" "BK23"
					( Origin gPackager )
				)
				( objectStatus "U5D1.BK23" )
			)
			( pin "@baseboard_fab2_lib.baseboard_fab2(sch_1):page29_i61:cd_hfi_refclk_dn"
				( attribute "PN" "BE16"
					( Origin gPackager )
				)
				( objectStatus "U5D1.BE16" )
			)
			( pin "@baseboard_fab2_lib.baseboard_fab2(sch_1):page29_i61:cd_hfi_refclk_dp"
				( attribute "PN" "BG16"
					( Origin gPackager )
				)
				( objectStatus "U5D1.BG16" )
			)
			( pin "@baseboard_fab2_lib.baseboard_fab2(sch_1):page29_i61:cd_pe_refclk_dn"
				( attribute "PN" "BU24"
					( Origin gPackager )
				)
				( objectStatus "U5D1.BU24" )
			)
			( pin "@baseboard_fab2_lib.baseboard_fab2(sch_1):page29_i61:cd_pe_refclk_dp"
				( attribute "PN" "BW24"
					( Origin gPackager )
				)
				( objectStatus "U5D1.BW24" )
			)
			( pin "@baseboard_fab2_lib.baseboard_fab2(sch_1):page29_i61:cd_por_n"
				( attribute "PN" "CF25"
					( Origin gPackager )
				)
				( objectStatus "U5D1.CF25" )
			)
			( pin "@baseboard_fab2_lib.baseboard_fab2(sch_1):page29_i61:cd_tclk"
				( attribute "PN" "CB23"
					( Origin gPackager )
				)
				( objectStatus "U5D1.CB23" )
			)
			( pin "@baseboard_fab2_lib.baseboard_fab2(sch_1):page29_i61:cd_tdi"
				( attribute "PN" "BY21"
					( Origin gPackager )
				)
				( objectStatus "U5D1.BY21" )
			)
			( pin "@baseboard_fab2_lib.baseboard_fab2(sch_1):page29_i61:cd_tdo"
				( attribute "PN" "CC22"
					( Origin gPackager )
				)
				( objectStatus "U5D1.CC22" )
			)
			( pin "@baseboard_fab2_lib.baseboard_fab2(sch_1):page29_i61:cd_tms"
				( attribute "PN" "CE24"
					( Origin gPackager )
				)
				( objectStatus "U5D1.CE24" )
			)
			( pin "@baseboard_fab2_lib.baseboard_fab2(sch_1):page29_i61:cd_trst_n"
				( attribute "PN" "CD23"
					( Origin gPackager )
				)
				( objectStatus "U5D1.CD23" )
			)
			( pin "@baseboard_fab2_lib.baseboard_fab2(sch_1):page29_i61:dmi_rx_dn(0)"
				( attribute "PN" "CK9"
					( Origin gPackager )
				)
				( objectStatus "U5D1.CK9" )
			)
			( pin "@baseboard_fab2_lib.baseboard_fab2(sch_1):page29_i61:dmi_rx_dn(1)"
				( attribute "PN" "CM11"
					( Origin gPackager )
				)
				( objectStatus "U5D1.CM11" )
			)
			( pin "@baseboard_fab2_lib.baseboard_fab2(sch_1):page29_i61:dmi_rx_dn(2)"
				( attribute "PN" "CR12"
					( Origin gPackager )
				)
				( objectStatus "U5D1.CR12" )
			)
			( pin "@baseboard_fab2_lib.baseboard_fab2(sch_1):page29_i61:dmi_rx_dn(3)"
				( attribute "PN" "CT11"
					( Origin gPackager )
				)
				( objectStatus "U5D1.CT11" )
			)
			( pin "@baseboard_fab2_lib.baseboard_fab2(sch_1):page29_i61:dmi_rx_dp(0)"
				( attribute "PN" "CL10"
					( Origin gPackager )
				)
				( objectStatus "U5D1.CL10" )
			)
			( pin "@baseboard_fab2_lib.baseboard_fab2(sch_1):page29_i61:dmi_rx_dp(1)"
				( attribute "PN" "CN10"
					( Origin gPackager )
				)
				( objectStatus "U5D1.CN10" )
			)
			( pin "@baseboard_fab2_lib.baseboard_fab2(sch_1):page29_i61:dmi_rx_dp(2)"
				( attribute "PN" "CP11"
					( Origin gPackager )
				)
				( objectStatus "U5D1.CP11" )
			)
			( pin "@baseboard_fab2_lib.baseboard_fab2(sch_1):page29_i61:dmi_rx_dp(3)"
				( attribute "PN" "CV11"
					( Origin gPackager )
				)
				( objectStatus "U5D1.CV11" )
			)
			( pin "@baseboard_fab2_lib.baseboard_fab2(sch_1):page29_i61:dmi_tx_dn(0)"
				( attribute "PN" "CG4"
					( Origin gPackager )
				)
				( objectStatus "U5D1.CG4" )
			)
			( pin "@baseboard_fab2_lib.baseboard_fab2(sch_1):page29_i61:dmi_tx_dn(1)"
				( attribute "PN" "CJ4"
					( Origin gPackager )
				)
				( objectStatus "U5D1.CJ4" )
			)
			( pin "@baseboard_fab2_lib.baseboard_fab2(sch_1):page29_i61:dmi_tx_dn(2)"
				( attribute "PN" "CN4"
					( Origin gPackager )
				)
				( objectStatus "U5D1.CN4" )
			)
			( pin "@baseboard_fab2_lib.baseboard_fab2(sch_1):page29_i61:dmi_tx_dn(3)"
				( attribute "PN" "CP5"
					( Origin gPackager )
				)
				( objectStatus "U5D1.CP5" )
			)
			( pin "@baseboard_fab2_lib.baseboard_fab2(sch_1):page29_i61:dmi_tx_dp(0)"
				( attribute "PN" "CH5"
					( Origin gPackager )
				)
				( objectStatus "U5D1.CH5" )
			)
			( pin "@baseboard_fab2_lib.baseboard_fab2(sch_1):page29_i61:dmi_tx_dp(1)"
				( attribute "PN" "CL4"
					( Origin gPackager )
				)
				( objectStatus "U5D1.CL4" )
			)
			( pin "@baseboard_fab2_lib.baseboard_fab2(sch_1):page29_i61:dmi_tx_dp(2)"
				( attribute "PN" "CM3"
					( Origin gPackager )
				)
				( objectStatus "U5D1.CM3" )
			)
			( pin "@baseboard_fab2_lib.baseboard_fab2(sch_1):page29_i61:dmi_tx_dp(3)"
				( attribute "PN" "CR4"
					( Origin gPackager )
				)
				( objectStatus "U5D1.CR4" )
			)
			( pin "@baseboard_fab2_lib.baseboard_fab2(sch_1):page29_i61:rsvd(172)"
				( attribute "PN" "BA76"
					( Origin gPackager )
				)
				( objectStatus "U5D1.BA76" )
			)
			( pin "@baseboard_fab2_lib.baseboard_fab2(sch_1):page29_i61:rsvd(173)"
				( attribute "PN" "BA66"
					( Origin gPackager )
				)
				( objectStatus "U5D1.BA66" )
			)
			( pin "@baseboard_fab2_lib.baseboard_fab2(sch_1):page29_i61:rsvd(174)"
				( attribute "PN" "BA64"
					( Origin gPackager )
				)
				( objectStatus "U5D1.BA64" )
			)
			( pin "@baseboard_fab2_lib.baseboard_fab2(sch_1):page29_i61:rsvd(175)"
				( attribute "PN" "BA22"
					( Origin gPackager )
				)
				( objectStatus "U5D1.BA22" )
			)
			( pin "@baseboard_fab2_lib.baseboard_fab2(sch_1):page29_i61:rsvd(176)"
				( attribute "PN" "BA18"
					( Origin gPackager )
				)
				( objectStatus "U5D1.BA18" )
			)
			( pin "@baseboard_fab2_lib.baseboard_fab2(sch_1):page29_i61:rsvd(177)"
				( attribute "PN" "BA16"
					( Origin gPackager )
				)
				( objectStatus "U5D1.BA16" )
			)
			( pin "@baseboard_fab2_lib.baseboard_fab2(sch_1):page29_i61:rsvd(178)"
				( attribute "PN" "BA14"
					( Origin gPackager )
				)
				( objectStatus "U5D1.BA14" )
			)
			( pin "@baseboard_fab2_lib.baseboard_fab2(sch_1):page29_i61:rsvd(179)"
				( attribute "PN" "AY77"
					( Origin gPackager )
				)
				( objectStatus "U5D1.AY77" )
			)
			( pin "@baseboard_fab2_lib.baseboard_fab2(sch_1):page29_i61:rsvd(180)"
				( attribute "PN" "AY75"
					( Origin gPackager )
				)
				( objectStatus "U5D1.AY75" )
			)
			( pin "@baseboard_fab2_lib.baseboard_fab2(sch_1):page29_i61:rsvd(181)"
				( attribute "PN" "AY67"
					( Origin gPackager )
				)
				( objectStatus "U5D1.AY67" )
			)
			( pin "@baseboard_fab2_lib.baseboard_fab2(sch_1):page29_i61:rsvd(182)"
				( attribute "PN" "AY65"
					( Origin gPackager )
				)
				( objectStatus "U5D1.AY65" )
			)
			( pin "@baseboard_fab2_lib.baseboard_fab2(sch_1):page29_i61:rsvd(183)"
				( attribute "PN" "AW76"
					( Origin gPackager )
				)
				( objectStatus "U5D1.AW76" )
			)
			( pin "@baseboard_fab2_lib.baseboard_fab2(sch_1):page29_i61:rsvd(184)"
				( attribute "PN" "AW64"
					( Origin gPackager )
				)
				( objectStatus "U5D1.AW64" )
			)
			( pin "@baseboard_fab2_lib.baseboard_fab2(sch_1):page29_i61:rsvd(185)"
				( attribute "CDS_NOT_ON_SYM" "TRUE"
					( Origin gFrontEnd )
				)
			)
			( pin "@baseboard_fab2_lib.baseboard_fab2(sch_1):page29_i61:rsvd(186)"
				( attribute "PN" "AV77"
					( Origin gPackager )
				)
				( objectStatus "U5D1.AV77" )
			)
			( pin "@baseboard_fab2_lib.baseboard_fab2(sch_1):page29_i61:rsvd(187)"
				( attribute "PN" "AT25"
					( Origin gPackager )
				)
				( objectStatus "U5D1.AT25" )
			)
			( pin "@baseboard_fab2_lib.baseboard_fab2(sch_1):page29_i61:rsvd(188)"
				( attribute "PN" "AT23"
					( Origin gPackager )
				)
				( objectStatus "U5D1.AT23" )
			)
			( pin "@baseboard_fab2_lib.baseboard_fab2(sch_1):page29_i61:rsvd(189)"
				( attribute "PN" "AT13"
					( Origin gPackager )
				)
				( objectStatus "U5D1.AT13" )
			)
			( pin "@baseboard_fab2_lib.baseboard_fab2(sch_1):page29_i61:rsvd(190)"
				( attribute "PN" "AR62"
					( Origin gPackager )
				)
				( objectStatus "U5D1.AR62" )
			)
			( pin "@baseboard_fab2_lib.baseboard_fab2(sch_1):page29_i61:rsvd(191)"
				( attribute "PN" "AR26"
					( Origin gPackager )
				)
				( objectStatus "U5D1.AR26" )
			)
			( pin "@baseboard_fab2_lib.baseboard_fab2(sch_1):page29_i61:rsvd(192)"
				( attribute "PN" "AR22"
					( Origin gPackager )
				)
				( objectStatus "U5D1.AR22" )
			)
			( pin "@baseboard_fab2_lib.baseboard_fab2(sch_1):page29_i61:rsvd(193)"
				( attribute "PN" "AR20"
					( Origin gPackager )
				)
				( objectStatus "U5D1.AR20" )
			)
			( pin "@baseboard_fab2_lib.baseboard_fab2(sch_1):page30_i84:pe1_rx_dn(0)"
				( attribute "PN" "CW8"
					( Origin gPackager )
				)
				( objectStatus "U5D1.CW8" )
			)
			( pin "@baseboard_fab2_lib.baseboard_fab2(sch_1):page30_i84:pe1_rx_dn(1)"
				( attribute "PN" "DA8"
					( Origin gPackager )
				)
				( objectStatus "U5D1.DA8" )
			)
			( pin "@baseboard_fab2_lib.baseboard_fab2(sch_1):page30_i84:pe1_rx_dn(2)"
				( attribute "PN" "DC8"
					( Origin gPackager )
				)
				( objectStatus "U5D1.DC8" )
			)
			( pin "@baseboard_fab2_lib.baseboard_fab2(sch_1):page30_i84:pe1_rx_dn(3)"
				( attribute "PN" "DC10"
					( Origin gPackager )
				)
				( objectStatus "U5D1.DC10" )
			)
			( pin "@baseboard_fab2_lib.baseboard_fab2(sch_1):page30_i84:pe1_rx_dn(4)"
				( attribute "PN" "DE10"
					( Origin gPackager )
				)
				( objectStatus "U5D1.DE10" )
			)
			( pin "@baseboard_fab2_lib.baseboard_fab2(sch_1):page30_i84:pe1_rx_dn(5)"
				( attribute "PN" "DH9"
					( Origin gPackager )
				)
				( objectStatus "U5D1.DH9" )
			)
			( pin "@baseboard_fab2_lib.baseboard_fab2(sch_1):page30_i84:pe1_rx_dn(6)"
				( attribute "PN" "DK9"
					( Origin gPackager )
				)
				( objectStatus "U5D1.DK9" )
			)
			( pin "@baseboard_fab2_lib.baseboard_fab2(sch_1):page30_i84:pe1_rx_dn(7)"
				( attribute "PN" "DM9"
					( Origin gPackager )
				)
				( objectStatus "U5D1.DM9" )
			)
			( pin "@baseboard_fab2_lib.baseboard_fab2(sch_1):page30_i84:pe1_rx_dn(8)"
				( attribute "PN" "DM11"
					( Origin gPackager )
				)
				( objectStatus "U5D1.DM11" )
			)
			( pin "@baseboard_fab2_lib.baseboard_fab2(sch_1):page30_i84:pe1_rx_dn(9)"
				( attribute "PN" "DP11"
					( Origin gPackager )
				)
				( objectStatus "U5D1.DP11" )
			)
			( pin "@baseboard_fab2_lib.baseboard_fab2(sch_1):page30_i84:pe1_rx_dn(10)"
				( attribute "PN" "DT11"
					( Origin gPackager )
				)
				( objectStatus "U5D1.DT11" )
			)
			( pin "@baseboard_fab2_lib.baseboard_fab2(sch_1):page30_i84:pe1_rx_dn(11)"
				( attribute "PN" "DT13"
					( Origin gPackager )
				)
				( objectStatus "U5D1.DT13" )
			)
			( pin "@baseboard_fab2_lib.baseboard_fab2(sch_1):page30_i84:pe1_rx_dn(12)"
				( attribute "PN" "DV13"
					( Origin gPackager )
				)
				( objectStatus "U5D1.DV13" )
			)
			( pin "@baseboard_fab2_lib.baseboard_fab2(sch_1):page30_i84:pe1_rx_dn(13)"
				( attribute "PN" "DW14"
					( Origin gPackager )
				)
				( objectStatus "U5D1.DW14" )
			)
			( pin "@baseboard_fab2_lib.baseboard_fab2(sch_1):page30_i84:pe1_rx_dn(14)"
				( attribute "PN" "DY15"
					( Origin gPackager )
				)
				( objectStatus "U5D1.DY15" )
			)
			( pin "@baseboard_fab2_lib.baseboard_fab2(sch_1):page30_i84:pe1_rx_dn(15)"
				( attribute "PN" "DU16"
					( Origin gPackager )
				)
				( objectStatus "U5D1.DU16" )
			)
			( pin "@baseboard_fab2_lib.baseboard_fab2(sch_1):page30_i84:pe1_rx_dp(0)"
				( attribute "PN" "CU8"
					( Origin gPackager )
				)
				( objectStatus "U5D1.CU8" )
			)
			( pin "@baseboard_fab2_lib.baseboard_fab2(sch_1):page30_i84:pe1_rx_dp(1)"
				( attribute "PN" "CY7"
					( Origin gPackager )
				)
				( objectStatus "U5D1.CY7" )
			)
			( pin "@baseboard_fab2_lib.baseboard_fab2(sch_1):page30_i84:pe1_rx_dp(2)"
				( attribute "PN" "DB9"
					( Origin gPackager )
				)
				( objectStatus "U5D1.DB9" )
			)
			( pin "@baseboard_fab2_lib.baseboard_fab2(sch_1):page30_i84:pe1_rx_dp(3)"
				( attribute "PN" "DA10"
					( Origin gPackager )
				)
				( objectStatus "U5D1.DA10" )
			)
			( pin "@baseboard_fab2_lib.baseboard_fab2(sch_1):page30_i84:pe1_rx_dp(4)"
				( attribute "PN" "DD9"
					( Origin gPackager )
				)
				( objectStatus "U5D1.DD9" )
			)
			( pin "@baseboard_fab2_lib.baseboard_fab2(sch_1):page30_i84:pe1_rx_dp(5)"
				( attribute "PN" "DF9"
					( Origin gPackager )
				)
				( objectStatus "U5D1.DF9" )
			)
			( pin "@baseboard_fab2_lib.baseboard_fab2(sch_1):page30_i84:pe1_rx_dp(6)"
				( attribute "PN" "DJ8"
					( Origin gPackager )
				)
				( objectStatus "U5D1.DJ8" )
			)
			( pin "@baseboard_fab2_lib.baseboard_fab2(sch_1):page30_i84:pe1_rx_dp(7)"
				( attribute "PN" "DL10"
					( Origin gPackager )
				)
				( objectStatus "U5D1.DL10" )
			)
			( pin "@baseboard_fab2_lib.baseboard_fab2(sch_1):page30_i84:pe1_rx_dp(8)"
				( attribute "PN" "DK11"
					( Origin gPackager )
				)
				( objectStatus "U5D1.DK11" )
			)
			( pin "@baseboard_fab2_lib.baseboard_fab2(sch_1):page30_i84:pe1_rx_dp(9)"
				( attribute "PN" "DN10"
					( Origin gPackager )
				)
				( objectStatus "U5D1.DN10" )
			)
			( pin "@baseboard_fab2_lib.baseboard_fab2(sch_1):page30_i84:pe1_rx_dp(10)"
				( attribute "PN" "DR12"
					( Origin gPackager )
				)
				( objectStatus "U5D1.DR12" )
			)
			( pin "@baseboard_fab2_lib.baseboard_fab2(sch_1):page30_i84:pe1_rx_dp(11)"
				( attribute "PN" "DP13"
					( Origin gPackager )
				)
				( objectStatus "U5D1.DP13" )
			)
			( pin "@baseboard_fab2_lib.baseboard_fab2(sch_1):page30_i84:pe1_rx_dp(12)"
				( attribute "PN" "DU12"
					( Origin gPackager )
				)
				( objectStatus "U5D1.DU12" )
			)
			( pin "@baseboard_fab2_lib.baseboard_fab2(sch_1):page30_i84:pe1_rx_dp(13)"
				( attribute "PN" "DY13"
					( Origin gPackager )
				)
				( objectStatus "U5D1.DY13" )
			)
			( pin "@baseboard_fab2_lib.baseboard_fab2(sch_1):page30_i84:pe1_rx_dp(14)"
				( attribute "PN" "DV15"
					( Origin gPackager )
				)
				( objectStatus "U5D1.DV15" )
			)
			( pin "@baseboard_fab2_lib.baseboard_fab2(sch_1):page30_i84:pe1_rx_dp(15)"
				( attribute "PN" "DT15"
					( Origin gPackager )
				)
				( objectStatus "U5D1.DT15" )
			)
			( pin "@baseboard_fab2_lib.baseboard_fab2(sch_1):page30_i84:pe1_tx_dn(0)"
				( attribute "PN" "DA2"
					( Origin gPackager )
				)
				( objectStatus "U5D1.DA2" )
			)
			( pin "@baseboard_fab2_lib.baseboard_fab2(sch_1):page30_i84:pe1_tx_dn(1)"
				( attribute "PN" "DC2"
					( Origin gPackager )
				)
				( objectStatus "U5D1.DC2" )
			)
			( pin "@baseboard_fab2_lib.baseboard_fab2(sch_1):page30_i84:pe1_tx_dn(2)"
				( attribute "PN" "DE2"
					( Origin gPackager )
				)
				( objectStatus "U5D1.DE2" )
			)
			( pin "@baseboard_fab2_lib.baseboard_fab2(sch_1):page30_i84:pe1_tx_dn(3)"
				( attribute "PN" "DE4"
					( Origin gPackager )
				)
				( objectStatus "U5D1.DE4" )
			)
			( pin "@baseboard_fab2_lib.baseboard_fab2(sch_1):page30_i84:pe1_tx_dn(4)"
				( attribute "PN" "DG4"
					( Origin gPackager )
				)
				( objectStatus "U5D1.DG4" )
			)
			( pin "@baseboard_fab2_lib.baseboard_fab2(sch_1):page30_i84:pe1_tx_dn(5)"
				( attribute "PN" "DK3"
					( Origin gPackager )
				)
				( objectStatus "U5D1.DK3" )
			)
			( pin "@baseboard_fab2_lib.baseboard_fab2(sch_1):page30_i84:pe1_tx_dn(6)"
				( attribute "PN" "DM3"
					( Origin gPackager )
				)
				( objectStatus "U5D1.DM3" )
			)
			( pin "@baseboard_fab2_lib.baseboard_fab2(sch_1):page30_i84:pe1_tx_dn(7)"
				( attribute "PN" "DN4"
					( Origin gPackager )
				)
				( objectStatus "U5D1.DN4" )
			)
			( pin "@baseboard_fab2_lib.baseboard_fab2(sch_1):page30_i84:pe1_tx_dn(8)"
				( attribute "PN" "DT5"
					( Origin gPackager )
				)
				( objectStatus "U5D1.DT5" )
			)
			( pin "@baseboard_fab2_lib.baseboard_fab2(sch_1):page30_i84:pe1_tx_dn(9)"
				( attribute "PN" "DV3"
					( Origin gPackager )
				)
				( objectStatus "U5D1.DV3" )
			)
			( pin "@baseboard_fab2_lib.baseboard_fab2(sch_1):page30_i84:pe1_tx_dn(10)"
				( attribute "PN" "DW4"
					( Origin gPackager )
				)
				( objectStatus "U5D1.DW4" )
			)
			( pin "@baseboard_fab2_lib.baseboard_fab2(sch_1):page30_i84:pe1_tx_dn(11)"
				( attribute "PN" "DU6"
					( Origin gPackager )
				)
				( objectStatus "U5D1.DU6" )
			)
			( pin "@baseboard_fab2_lib.baseboard_fab2(sch_1):page30_i84:pe1_tx_dn(12)"
				( attribute "PN" "DV7"
					( Origin gPackager )
				)
				( objectStatus "U5D1.DV7" )
			)
			( pin "@baseboard_fab2_lib.baseboard_fab2(sch_1):page30_i84:pe1_tx_dn(13)"
				( attribute "PN" "DY7"
					( Origin gPackager )
				)
				( objectStatus "U5D1.DY7" )
			)
			( pin "@baseboard_fab2_lib.baseboard_fab2(sch_1):page30_i84:pe1_tx_dn(14)"
				( attribute "PN" "EA8"
					( Origin gPackager )
				)
				( objectStatus "U5D1.EA8" )
			)
			( pin "@baseboard_fab2_lib.baseboard_fab2(sch_1):page30_i84:pe1_tx_dn(15)"
				( attribute "PN" "ED9"
					( Origin gPackager )
				)
				( objectStatus "U5D1.ED9" )
			)
			( pin "@baseboard_fab2_lib.baseboard_fab2(sch_1):page30_i84:pe1_tx_dp(0)"
				( attribute "PN" "CW2"
					( Origin gPackager )
				)
				( objectStatus "U5D1.CW2" )
			)
			( pin "@baseboard_fab2_lib.baseboard_fab2(sch_1):page30_i84:pe1_tx_dp(1)"
				( attribute "PN" "DB1"
					( Origin gPackager )
				)
				( objectStatus "U5D1.DB1" )
			)
			( pin "@baseboard_fab2_lib.baseboard_fab2(sch_1):page30_i84:pe1_tx_dp(2)"
				( attribute "PN" "DD3"
					( Origin gPackager )
				)
				( objectStatus "U5D1.DD3" )
			)
			( pin "@baseboard_fab2_lib.baseboard_fab2(sch_1):page30_i84:pe1_tx_dp(3)"
				( attribute "PN" "DC4"
					( Origin gPackager )
				)
				( objectStatus "U5D1.DC4" )
			)
			( pin "@baseboard_fab2_lib.baseboard_fab2(sch_1):page30_i84:pe1_tx_dp(4)"
				( attribute "PN" "DF3"
					( Origin gPackager )
				)
				( objectStatus "U5D1.DF3" )
			)
			( pin "@baseboard_fab2_lib.baseboard_fab2(sch_1):page30_i84:pe1_tx_dp(5)"
				( attribute "PN" "DH3"
					( Origin gPackager )
				)
				( objectStatus "U5D1.DH3" )
			)
			( pin "@baseboard_fab2_lib.baseboard_fab2(sch_1):page30_i84:pe1_tx_dp(6)"
				( attribute "PN" "DL2"
					( Origin gPackager )
				)
				( objectStatus "U5D1.DL2" )
			)
			( pin "@baseboard_fab2_lib.baseboard_fab2(sch_1):page30_i84:pe1_tx_dp(7)"
				( attribute "PN" "DP3"
					( Origin gPackager )
				)
				( objectStatus "U5D1.DP3" )
			)
			( pin "@baseboard_fab2_lib.baseboard_fab2(sch_1):page30_i84:pe1_tx_dp(8)"
				( attribute "PN" "DR4"
					( Origin gPackager )
				)
				( objectStatus "U5D1.DR4" )
			)
			( pin "@baseboard_fab2_lib.baseboard_fab2(sch_1):page30_i84:pe1_tx_dp(9)"
				( attribute "PN" "DU2"
					( Origin gPackager )
				)
				( objectStatus "U5D1.DU2" )
			)
			( pin "@baseboard_fab2_lib.baseboard_fab2(sch_1):page30_i84:pe1_tx_dp(10)"
				( attribute "PN" "DU4"
					( Origin gPackager )
				)
				( objectStatus "U5D1.DU4" )
			)
			( pin "@baseboard_fab2_lib.baseboard_fab2(sch_1):page30_i84:pe1_tx_dp(11)"
				( attribute "PN" "DV5"
					( Origin gPackager )
				)
				( objectStatus "U5D1.DV5" )
			)
			( pin "@baseboard_fab2_lib.baseboard_fab2(sch_1):page30_i84:pe1_tx_dp(12)"
				( attribute "PN" "DT7"
					( Origin gPackager )
				)
				( objectStatus "U5D1.DT7" )
			)
			( pin "@baseboard_fab2_lib.baseboard_fab2(sch_1):page30_i84:pe1_tx_dp(13)"
				( attribute "PN" "DW6"
					( Origin gPackager )
				)
				( objectStatus "U5D1.DW6" )
			)
			( pin "@baseboard_fab2_lib.baseboard_fab2(sch_1):page30_i84:pe1_tx_dp(14)"
				( attribute "PN" "EB7"
					( Origin gPackager )
				)
				( objectStatus "U5D1.EB7" )
			)
			( pin "@baseboard_fab2_lib.baseboard_fab2(sch_1):page30_i84:pe1_tx_dp(15)"
				( attribute "PN" "EC8"
					( Origin gPackager )
				)
				( objectStatus "U5D1.EC8" )
			)
			( pin "@baseboard_fab2_lib.baseboard_fab2(sch_1):page31_i106:pe2_rx_dn(0)"
				( attribute "PN" "CT9"
					( Origin gPackager )
				)
				( objectStatus "U5D1.CT9" )
			)
			( pin "@baseboard_fab2_lib.baseboard_fab2(sch_1):page31_i106:pe2_rx_dn(1)"
				( attribute "PN" "CP9"
					( Origin gPackager )
				)
				( objectStatus "U5D1.CP9" )
			)
			( pin "@baseboard_fab2_lib.baseboard_fab2(sch_1):page31_i106:pe2_rx_dn(2)"
				( attribute "PN" "CP7"
					( Origin gPackager )
				)
				( objectStatus "U5D1.CP7" )
			)
			( pin "@baseboard_fab2_lib.baseboard_fab2(sch_1):page31_i106:pe2_rx_dn(3)"
				( attribute "PN" "CM7"
					( Origin gPackager )
				)
				( objectStatus "U5D1.CM7" )
			)
			( pin "@baseboard_fab2_lib.baseboard_fab2(sch_1):page31_i106:pe2_rx_dn(4)"
				( attribute "PN" "CK7"
					( Origin gPackager )
				)
				( objectStatus "U5D1.CK7" )
			)
			( pin "@baseboard_fab2_lib.baseboard_fab2(sch_1):page31_i106:pe2_rx_dn(5)"
				( attribute "PN" "CG8"
					( Origin gPackager )
				)
				( objectStatus "U5D1.CG8" )
			)
			( pin "@baseboard_fab2_lib.baseboard_fab2(sch_1):page31_i106:pe2_rx_dn(6)"
				( attribute "PN" "CE6"
					( Origin gPackager )
				)
				( objectStatus "U5D1.CE6" )
			)
			( pin "@baseboard_fab2_lib.baseboard_fab2(sch_1):page31_i106:pe2_rx_dn(7)"
				( attribute "PN" "CE8"
					( Origin gPackager )
				)
				( objectStatus "U5D1.CE8" )
			)
			( pin "@baseboard_fab2_lib.baseboard_fab2(sch_1):page31_i106:pe2_rx_dn(8)"
				( attribute "PN" "BY9"
					( Origin gPackager )
				)
				( objectStatus "U5D1.BY9" )
			)
			( pin "@baseboard_fab2_lib.baseboard_fab2(sch_1):page31_i106:pe2_rx_dn(9)"
				( attribute "PN" "BY7"
					( Origin gPackager )
				)
				( objectStatus "U5D1.BY7" )
			)
			( pin "@baseboard_fab2_lib.baseboard_fab2(sch_1):page31_i106:pe2_rx_dn(10)"
				( attribute "PN" "BV7"
					( Origin gPackager )
				)
				( objectStatus "U5D1.BV7" )
			)
			( pin "@baseboard_fab2_lib.baseboard_fab2(sch_1):page31_i106:pe2_rx_dn(11)"
				( attribute "PN" "BT7"
					( Origin gPackager )
				)
				( objectStatus "U5D1.BT7" )
			)
			( pin "@baseboard_fab2_lib.baseboard_fab2(sch_1):page31_i106:pe2_rx_dn(12)"
				( attribute "PN" "BR8"
					( Origin gPackager )
				)
				( objectStatus "U5D1.BR8" )
			)
			( pin "@baseboard_fab2_lib.baseboard_fab2(sch_1):page31_i106:pe2_rx_dn(13)"
				( attribute "PN" "BN8"
					( Origin gPackager )
				)
				( objectStatus "U5D1.BN8" )
			)
			( pin "@baseboard_fab2_lib.baseboard_fab2(sch_1):page31_i106:pe2_rx_dn(14)"
				( attribute "PN" "BL8"
					( Origin gPackager )
				)
				( objectStatus "U5D1.BL8" )
			)
			( pin "@baseboard_fab2_lib.baseboard_fab2(sch_1):page31_i106:pe2_rx_dn(15)"
				( attribute "PN" "BK9"
					( Origin gPackager )
				)
				( objectStatus "U5D1.BK9" )
			)
			( pin "@baseboard_fab2_lib.baseboard_fab2(sch_1):page31_i106:pe2_rx_dp(0)"
				( attribute "PN" "CR8"
					( Origin gPackager )
				)
				( objectStatus "U5D1.CR8" )
			)
			( pin "@baseboard_fab2_lib.baseboard_fab2(sch_1):page31_i106:pe2_rx_dp(1)"
				( attribute "PN" "CM9"
					( Origin gPackager )
				)
				( objectStatus "U5D1.CM9" )
			)
			( pin "@baseboard_fab2_lib.baseboard_fab2(sch_1):page31_i106:pe2_rx_dp(2)"
				( attribute "PN" "CN8"
					( Origin gPackager )
				)
				( objectStatus "U5D1.CN8" )
			)
			( pin "@baseboard_fab2_lib.baseboard_fab2(sch_1):page31_i106:pe2_rx_dp(3)"
				( attribute "PN" "CL6"
					( Origin gPackager )
				)
				( objectStatus "U5D1.CL6" )
			)
			( pin "@baseboard_fab2_lib.baseboard_fab2(sch_1):page31_i106:pe2_rx_dp(4)"
				( attribute "PN" "CH7"
					( Origin gPackager )
				)
				( objectStatus "U5D1.CH7" )
			)
			( pin "@baseboard_fab2_lib.baseboard_fab2(sch_1):page31_i106:pe2_rx_dp(5)"
				( attribute "PN" "CF7"
					( Origin gPackager )
				)
				( objectStatus "U5D1.CF7" )
			)
			( pin "@baseboard_fab2_lib.baseboard_fab2(sch_1):page31_i106:pe2_rx_dp(6)"
				( attribute "PN" "CD7"
					( Origin gPackager )
				)
				( objectStatus "U5D1.CD7" )
			)
			( pin "@baseboard_fab2_lib.baseboard_fab2(sch_1):page31_i106:pe2_rx_dp(7)"
				( attribute "PN" "CC8"
					( Origin gPackager )
				)
				( objectStatus "U5D1.CC8" )
			)
			( pin "@baseboard_fab2_lib.baseboard_fab2(sch_1):page31_i106:pe2_rx_dp(8)"
				( attribute "PN" "BV9"
					( Origin gPackager )
				)
				( objectStatus "U5D1.BV9" )
			)
			( pin "@baseboard_fab2_lib.baseboard_fab2(sch_1):page31_i106:pe2_rx_dp(9)"
				( attribute "PN" "BW8"
					( Origin gPackager )
				)
				( objectStatus "U5D1.BW8" )
			)
			( pin "@baseboard_fab2_lib.baseboard_fab2(sch_1):page31_i106:pe2_rx_dp(10)"
				( attribute "PN" "BU6"
					( Origin gPackager )
				)
				( objectStatus "U5D1.BU6" )
			)
			( pin "@baseboard_fab2_lib.baseboard_fab2(sch_1):page31_i106:pe2_rx_dp(11)"
				( attribute "PN" "BP7"
					( Origin gPackager )
				)
				( objectStatus "U5D1.BP7" )
			)
			( pin "@baseboard_fab2_lib.baseboard_fab2(sch_1):page31_i106:pe2_rx_dp(12)"
				( attribute "PN" "BP9"
					( Origin gPackager )
				)
				( objectStatus "U5D1.BP9" )
			)
			( pin "@baseboard_fab2_lib.baseboard_fab2(sch_1):page31_i106:pe2_rx_dp(13)"
				( attribute "PN" "BM7"
					( Origin gPackager )
				)
				( objectStatus "U5D1.BM7" )
			)
			( pin "@baseboard_fab2_lib.baseboard_fab2(sch_1):page31_i106:pe2_rx_dp(14)"
				( attribute "PN" "BJ8"
					( Origin gPackager )
				)
				( objectStatus "U5D1.BJ8" )
			)
			( pin "@baseboard_fab2_lib.baseboard_fab2(sch_1):page31_i106:pe2_rx_dp(15)"
				( attribute "PN" "BJ10"
					( Origin gPackager )
				)
				( objectStatus "U5D1.BJ10" )
			)
			( pin "@baseboard_fab2_lib.baseboard_fab2(sch_1):page31_i106:pe2_tx_dn(0)"
				( attribute "PN" "CY3"
					( Origin gPackager )
				)
				( objectStatus "U5D1.CY3" )
			)
			( pin "@baseboard_fab2_lib.baseboard_fab2(sch_1):page31_i106:pe2_tx_dn(1)"
				( attribute "PN" "CV3"
					( Origin gPackager )
				)
				( objectStatus "U5D1.CV3" )
			)
			( pin "@baseboard_fab2_lib.baseboard_fab2(sch_1):page31_i106:pe2_tx_dn(2)"
				( attribute "PN" "CT1"
					( Origin gPackager )
				)
				( objectStatus "U5D1.CT1" )
			)
			( pin "@baseboard_fab2_lib.baseboard_fab2(sch_1):page31_i106:pe2_tx_dn(3)"
				( attribute "PN" "CT3"
					( Origin gPackager )
				)
				( objectStatus "U5D1.CT3" )
			)
			( pin "@baseboard_fab2_lib.baseboard_fab2(sch_1):page31_i106:pe2_tx_dn(4)"
				( attribute "PN" "CM1"
					( Origin gPackager )
				)
				( objectStatus "U5D1.CM1" )
			)
			( pin "@baseboard_fab2_lib.baseboard_fab2(sch_1):page31_i106:pe2_tx_dn(5)"
				( attribute "PN" "CL2"
					( Origin gPackager )
				)
				( objectStatus "U5D1.CL2" )
			)
			( pin "@baseboard_fab2_lib.baseboard_fab2(sch_1):page31_i106:pe2_tx_dn(6)"
				( attribute "PN" "CG2"
					( Origin gPackager )
				)
				( objectStatus "U5D1.CG2" )
			)
			( pin "@baseboard_fab2_lib.baseboard_fab2(sch_1):page31_i106:pe2_tx_dn(7)"
				( attribute "PN" "CF3"
					( Origin gPackager )
				)
				( objectStatus "U5D1.CF3" )
			)
			( pin "@baseboard_fab2_lib.baseboard_fab2(sch_1):page31_i106:pe2_tx_dn(8)"
				( attribute "PN" "CC2"
					( Origin gPackager )
				)
				( objectStatus "U5D1.CC2" )
			)
			( pin "@baseboard_fab2_lib.baseboard_fab2(sch_1):page31_i106:pe2_tx_dn(9)"
				( attribute "PN" "CB3"
					( Origin gPackager )
				)
				( objectStatus "U5D1.CB3" )
			)
			( pin "@baseboard_fab2_lib.baseboard_fab2(sch_1):page31_i106:pe2_tx_dn(10)"
				( attribute "PN" "CA4"
					( Origin gPackager )
				)
				( objectStatus "U5D1.CA4" )
			)
			( pin "@baseboard_fab2_lib.baseboard_fab2(sch_1):page31_i106:pe2_tx_dn(11)"
				( attribute "PN" "BW4"
					( Origin gPackager )
				)
				( objectStatus "U5D1.BW4" )
			)
			( pin "@baseboard_fab2_lib.baseboard_fab2(sch_1):page31_i106:pe2_tx_dn(12)"
				( attribute "PN" "BU4"
					( Origin gPackager )
				)
				( objectStatus "U5D1.BU4" )
			)
			( pin "@baseboard_fab2_lib.baseboard_fab2(sch_1):page31_i106:pe2_tx_dn(13)"
				( attribute "PN" "BP5"
					( Origin gPackager )
				)
				( objectStatus "U5D1.BP5" )
			)
			( pin "@baseboard_fab2_lib.baseboard_fab2(sch_1):page31_i106:pe2_tx_dn(14)"
				( attribute "PN" "BL4"
					( Origin gPackager )
				)
				( objectStatus "U5D1.BL4" )
			)
			( pin "@baseboard_fab2_lib.baseboard_fab2(sch_1):page31_i106:pe2_tx_dn(15)"
				( attribute "PN" "BM5"
					( Origin gPackager )
				)
				( objectStatus "U5D1.BM5" )
			)
			( pin "@baseboard_fab2_lib.baseboard_fab2(sch_1):page31_i106:pe2_tx_dp(0)"
				( attribute "PN" "CW4"
					( Origin gPackager )
				)
				( objectStatus "U5D1.CW4" )
			)
			( pin "@baseboard_fab2_lib.baseboard_fab2(sch_1):page31_i106:pe2_tx_dp(1)"
				( attribute "PN" "CU2"
					( Origin gPackager )
				)
				( objectStatus "U5D1.CU2" )
			)
			( pin "@baseboard_fab2_lib.baseboard_fab2(sch_1):page31_i106:pe2_tx_dp(2)"
				( attribute "PN" "CR2"
					( Origin gPackager )
				)
				( objectStatus "U5D1.CR2" )
			)
			( pin "@baseboard_fab2_lib.baseboard_fab2(sch_1):page31_i106:pe2_tx_dp(3)"
				( attribute "PN" "CP3"
					( Origin gPackager )
				)
				( objectStatus "U5D1.CP3" )
			)
			( pin "@baseboard_fab2_lib.baseboard_fab2(sch_1):page31_i106:pe2_tx_dp(4)"
				( attribute "PN" "CK1"
					( Origin gPackager )
				)
				( objectStatus "U5D1.CK1" )
			)
			( pin "@baseboard_fab2_lib.baseboard_fab2(sch_1):page31_i106:pe2_tx_dp(5)"
				( attribute "PN" "CK3"
					( Origin gPackager )
				)
				( objectStatus "U5D1.CK3" )
			)
			( pin "@baseboard_fab2_lib.baseboard_fab2(sch_1):page31_i106:pe2_tx_dp(6)"
				( attribute "PN" "CE2"
					( Origin gPackager )
				)
				( objectStatus "U5D1.CE2" )
			)
			( pin "@baseboard_fab2_lib.baseboard_fab2(sch_1):page31_i106:pe2_tx_dp(7)"
				( attribute "PN" "CE4"
					( Origin gPackager )
				)
				( objectStatus "U5D1.CE4" )
			)
			( pin "@baseboard_fab2_lib.baseboard_fab2(sch_1):page31_i106:pe2_tx_dp(8)"
				( attribute "PN" "CD3"
					( Origin gPackager )
				)
				( objectStatus "U5D1.CD3" )
			)
			( pin "@baseboard_fab2_lib.baseboard_fab2(sch_1):page31_i106:pe2_tx_dp(9)"
				( attribute "PN" "BY3"
					( Origin gPackager )
				)
				( objectStatus "U5D1.BY3" )
			)
			( pin "@baseboard_fab2_lib.baseboard_fab2(sch_1):page31_i106:pe2_tx_dp(10)"
				( attribute "PN" "BY5"
					( Origin gPackager )
				)
				( objectStatus "U5D1.BY5" )
			)
			( pin "@baseboard_fab2_lib.baseboard_fab2(sch_1):page31_i106:pe2_tx_dp(11)"
				( attribute "PN" "BV3"
					( Origin gPackager )
				)
				( objectStatus "U5D1.BV3" )
			)
			( pin "@baseboard_fab2_lib.baseboard_fab2(sch_1):page31_i106:pe2_tx_dp(12)"
				( attribute "PN" "BR4"
					( Origin gPackager )
				)
				( objectStatus "U5D1.BR4" )
			)
			( pin "@baseboard_fab2_lib.baseboard_fab2(sch_1):page31_i106:pe2_tx_dp(13)"
				( attribute "PN" "BN4"
					( Origin gPackager )
				)
				( objectStatus "U5D1.BN4" )
			)
			( pin "@baseboard_fab2_lib.baseboard_fab2(sch_1):page31_i106:pe2_tx_dp(14)"
				( attribute "PN" "BM3"
					( Origin gPackager )
				)
				( objectStatus "U5D1.BM3" )
			)
			( pin "@baseboard_fab2_lib.baseboard_fab2(sch_1):page31_i106:pe2_tx_dp(15)"
				( attribute "PN" "BK5"
					( Origin gPackager )
				)
				( objectStatus "U5D1.BK5" )
			)
			( pin "@baseboard_fab2_lib.baseboard_fab2(sch_1):page32_i89:pe3_rx_dn(0)"
				( attribute "PN" "EA18"
					( Origin gPackager )
				)
				( objectStatus "U5D1.EA18" )
			)
			( pin "@baseboard_fab2_lib.baseboard_fab2(sch_1):page32_i89:pe3_rx_dn(1)"
				( attribute "PN" "DW18"
					( Origin gPackager )
				)
				( objectStatus "U5D1.DW18" )
			)
			( pin "@baseboard_fab2_lib.baseboard_fab2(sch_1):page32_i89:pe3_rx_dn(2)"
				( attribute "PN" "DW16"
					( Origin gPackager )
				)
				( objectStatus "U5D1.DW16" )
			)
			( pin "@baseboard_fab2_lib.baseboard_fab2(sch_1):page32_i89:pe3_rx_dn(3)"
				( attribute "PN" "DT19"
					( Origin gPackager )
				)
				( objectStatus "U5D1.DT19" )
			)
			( pin "@baseboard_fab2_lib.baseboard_fab2(sch_1):page32_i89:pe3_rx_dn(4)"
				( attribute "PN" "DR16"
					( Origin gPackager )
				)
				( objectStatus "U5D1.DR16" )
			)
			( pin "@baseboard_fab2_lib.baseboard_fab2(sch_1):page32_i89:pe3_rx_dn(5)"
				( attribute "PN" "DR14"
					( Origin gPackager )
				)
				( objectStatus "U5D1.DR14" )
			)
			( pin "@baseboard_fab2_lib.baseboard_fab2(sch_1):page32_i89:pe3_rx_dn(6)"
				( attribute "PN" "DN14"
					( Origin gPackager )
				)
				( objectStatus "U5D1.DN14" )
			)
			( pin "@baseboard_fab2_lib.baseboard_fab2(sch_1):page32_i89:pe3_rx_dn(7)"
				( attribute "PN" "DL14"
					( Origin gPackager )
				)
				( objectStatus "U5D1.DL14" )
			)
			( pin "@baseboard_fab2_lib.baseboard_fab2(sch_1):page32_i89:pe3_rx_dn(8)"
				( attribute "PN" "DL12"
					( Origin gPackager )
				)
				( objectStatus "U5D1.DL12" )
			)
			( pin "@baseboard_fab2_lib.baseboard_fab2(sch_1):page32_i89:pe3_rx_dn(9)"
				( attribute "PN" "DJ12"
					( Origin gPackager )
				)
				( objectStatus "U5D1.DJ12" )
			)
			( pin "@baseboard_fab2_lib.baseboard_fab2(sch_1):page32_i89:pe3_rx_dn(10)"
				( attribute "PN" "DG12"
					( Origin gPackager )
				)
				( objectStatus "U5D1.DG12" )
			)
			( pin "@baseboard_fab2_lib.baseboard_fab2(sch_1):page32_i89:pe3_rx_dn(11)"
				( attribute "PN" "DG10"
					( Origin gPackager )
				)
				( objectStatus "U5D1.DG10" )
			)
			( pin "@baseboard_fab2_lib.baseboard_fab2(sch_1):page32_i89:pe3_rx_dn(12)"
				( attribute "PN" "DD13"
					( Origin gPackager )
				)
				( objectStatus "U5D1.DD13" )
			)
			( pin "@baseboard_fab2_lib.baseboard_fab2(sch_1):page32_i89:pe3_rx_dn(13)"
				( attribute "PN" "DB11"
					( Origin gPackager )
				)
				( objectStatus "U5D1.DB11" )
			)
			( pin "@baseboard_fab2_lib.baseboard_fab2(sch_1):page32_i89:pe3_rx_dn(14)"
				( attribute "PN" "CY11"
					( Origin gPackager )
				)
				( objectStatus "U5D1.CY11" )
			)
			( pin "@baseboard_fab2_lib.baseboard_fab2(sch_1):page32_i89:pe3_rx_dn(15)"
				( attribute "PN" "CV9"
					( Origin gPackager )
				)
				( objectStatus "U5D1.CV9" )
			)
			( pin "@baseboard_fab2_lib.baseboard_fab2(sch_1):page32_i89:pe3_rx_dp(0)"
				( attribute "PN" "DY17"
					( Origin gPackager )
				)
				( objectStatus "U5D1.DY17" )
			)
			( pin "@baseboard_fab2_lib.baseboard_fab2(sch_1):page32_i89:pe3_rx_dp(1)"
				( attribute "PN" "DU18"
					( Origin gPackager )
				)
				( objectStatus "U5D1.DU18" )
			)
			( pin "@baseboard_fab2_lib.baseboard_fab2(sch_1):page32_i89:pe3_rx_dp(2)"
				( attribute "PN" "DV17"
					( Origin gPackager )
				)
				( objectStatus "U5D1.DV17" )
			)
			( pin "@baseboard_fab2_lib.baseboard_fab2(sch_1):page32_i89:pe3_rx_dp(3)"
				( attribute "PN" "DR18"
					( Origin gPackager )
				)
				( objectStatus "U5D1.DR18" )
			)
			( pin "@baseboard_fab2_lib.baseboard_fab2(sch_1):page32_i89:pe3_rx_dp(4)"
				( attribute "PN" "DN16"
					( Origin gPackager )
				)
				( objectStatus "U5D1.DN16" )
			)
			( pin "@baseboard_fab2_lib.baseboard_fab2(sch_1):page32_i89:pe3_rx_dp(5)"
				( attribute "PN" "DP15"
					( Origin gPackager )
				)
				( objectStatus "U5D1.DP15" )
			)
			( pin "@baseboard_fab2_lib.baseboard_fab2(sch_1):page32_i89:pe3_rx_dp(6)"
				( attribute "PN" "DM13"
					( Origin gPackager )
				)
				( objectStatus "U5D1.DM13" )
			)
			( pin "@baseboard_fab2_lib.baseboard_fab2(sch_1):page32_i89:pe3_rx_dp(7)"
				( attribute "PN" "DJ14"
					( Origin gPackager )
				)
				( objectStatus "U5D1.DJ14" )
			)
			( pin "@baseboard_fab2_lib.baseboard_fab2(sch_1):page32_i89:pe3_rx_dp(8)"
				( attribute "PN" "DK13"
					( Origin gPackager )
				)
				( objectStatus "U5D1.DK13" )
			)
			( pin "@baseboard_fab2_lib.baseboard_fab2(sch_1):page32_i89:pe3_rx_dp(9)"
				( attribute "PN" "DH11"
					( Origin gPackager )
				)
				( objectStatus "U5D1.DH11" )
			)
			( pin "@baseboard_fab2_lib.baseboard_fab2(sch_1):page32_i89:pe3_rx_dp(10)"
				( attribute "PN" "DE12"
					( Origin gPackager )
				)
				( objectStatus "U5D1.DE12" )
			)
			( pin "@baseboard_fab2_lib.baseboard_fab2(sch_1):page32_i89:pe3_rx_dp(11)"
				( attribute "PN" "DF11"
					( Origin gPackager )
				)
				( objectStatus "U5D1.DF11" )
			)
			( pin "@baseboard_fab2_lib.baseboard_fab2(sch_1):page32_i89:pe3_rx_dp(12)"
				( attribute "PN" "DC12"
					( Origin gPackager )
				)
				( objectStatus "U5D1.DC12" )
			)
			( pin "@baseboard_fab2_lib.baseboard_fab2(sch_1):page32_i89:pe3_rx_dp(13)"
				( attribute "PN" "DA12"
					( Origin gPackager )
				)
				( objectStatus "U5D1.DA12" )
			)
			( pin "@baseboard_fab2_lib.baseboard_fab2(sch_1):page32_i89:pe3_rx_dp(14)"
				( attribute "PN" "CW10"
					( Origin gPackager )
				)
				( objectStatus "U5D1.CW10" )
			)
			( pin "@baseboard_fab2_lib.baseboard_fab2(sch_1):page32_i89:pe3_rx_dp(15)"
				( attribute "PN" "CU10"
					( Origin gPackager )
				)
				( objectStatus "U5D1.CU10" )
			)
			( pin "@baseboard_fab2_lib.baseboard_fab2(sch_1):page32_i89:pe3_tx_dn(0)"
				( attribute "PN" "EE14"
					( Origin gPackager )
				)
				( objectStatus "U5D1.EE14" )
			)
			( pin "@baseboard_fab2_lib.baseboard_fab2(sch_1):page32_i89:pe3_tx_dn(1)"
				( attribute "PN" "EE12"
					( Origin gPackager )
				)
				( objectStatus "U5D1.EE12" )
			)
			( pin "@baseboard_fab2_lib.baseboard_fab2(sch_1):page32_i89:pe3_tx_dn(2)"
				( attribute "PN" "EC12"
					( Origin gPackager )
				)
				( objectStatus "U5D1.EC12" )
			)
			( pin "@baseboard_fab2_lib.baseboard_fab2(sch_1):page32_i89:pe3_tx_dn(3)"
				( attribute "PN" "DY11"
					( Origin gPackager )
				)
				( objectStatus "U5D1.DY11" )
			)
			( pin "@baseboard_fab2_lib.baseboard_fab2(sch_1):page32_i89:pe3_tx_dn(4)"
				( attribute "PN" "EB9"
					( Origin gPackager )
				)
				( objectStatus "U5D1.EB9" )
			)
			( pin "@baseboard_fab2_lib.baseboard_fab2(sch_1):page32_i89:pe3_tx_dn(5)"
				( attribute "PN" "DW10"
					( Origin gPackager )
				)
				( objectStatus "U5D1.DW10" )
			)
			( pin "@baseboard_fab2_lib.baseboard_fab2(sch_1):page32_i89:pe3_tx_dn(6)"
				( attribute "PN" "DU8"
					( Origin gPackager )
				)
				( objectStatus "U5D1.DU8" )
			)
			( pin "@baseboard_fab2_lib.baseboard_fab2(sch_1):page32_i89:pe3_tx_dn(7)"
				( attribute "PN" "DR8"
					( Origin gPackager )
				)
				( objectStatus "U5D1.DR8" )
			)
			( pin "@baseboard_fab2_lib.baseboard_fab2(sch_1):page32_i89:pe3_tx_dn(8)"
				( attribute "PN" "DM7"
					( Origin gPackager )
				)
				( objectStatus "U5D1.DM7" )
			)
			( pin "@baseboard_fab2_lib.baseboard_fab2(sch_1):page32_i89:pe3_tx_dn(9)"
				( attribute "PN" "DP5"
					( Origin gPackager )
				)
				( objectStatus "U5D1.DP5" )
			)
			( pin "@baseboard_fab2_lib.baseboard_fab2(sch_1):page32_i89:pe3_tx_dn(10)"
				( attribute "PN" "DL6"
					( Origin gPackager )
				)
				( objectStatus "U5D1.DL6" )
			)
			( pin "@baseboard_fab2_lib.baseboard_fab2(sch_1):page32_i89:pe3_tx_dn(11)"
				( attribute "PN" "DJ4"
					( Origin gPackager )
				)
				( objectStatus "U5D1.DJ4" )
			)
			( pin "@baseboard_fab2_lib.baseboard_fab2(sch_1):page32_i89:pe3_tx_dn(12)"
				( attribute "PN" "DJ6"
					( Origin gPackager )
				)
				( objectStatus "U5D1.DJ6" )
			)
			( pin "@baseboard_fab2_lib.baseboard_fab2(sch_1):page32_i89:pe3_tx_dn(13)"
				( attribute "PN" "DD5"
					( Origin gPackager )
				)
				( objectStatus "U5D1.DD5" )
			)
			( pin "@baseboard_fab2_lib.baseboard_fab2(sch_1):page32_i89:pe3_tx_dn(14)"
				( attribute "PN" "DB5"
					( Origin gPackager )
				)
				( objectStatus "U5D1.DB5" )
			)
			( pin "@baseboard_fab2_lib.baseboard_fab2(sch_1):page32_i89:pe3_tx_dn(15)"
				( attribute "PN" "CY5"
					( Origin gPackager )
				)
				( objectStatus "U5D1.CY5" )
			)
			( pin "@baseboard_fab2_lib.baseboard_fab2(sch_1):page32_i89:pe3_tx_dp(0)"
				( attribute "PN" "EC14"
					( Origin gPackager )
				)
				( objectStatus "U5D1.EC14" )
			)
			( pin "@baseboard_fab2_lib.baseboard_fab2(sch_1):page32_i89:pe3_tx_dp(1)"
				( attribute "PN" "ED13"
					( Origin gPackager )
				)
				( objectStatus "U5D1.ED13" )
			)
			( pin "@baseboard_fab2_lib.baseboard_fab2(sch_1):page32_i89:pe3_tx_dp(2)"
				( attribute "PN" "EB11"
					( Origin gPackager )
				)
				( objectStatus "U5D1.EB11" )
			)
			( pin "@baseboard_fab2_lib.baseboard_fab2(sch_1):page32_i89:pe3_tx_dp(3)"
				( attribute "PN" "EA10"
					( Origin gPackager )
				)
				( objectStatus "U5D1.EA10" )
			)
			( pin "@baseboard_fab2_lib.baseboard_fab2(sch_1):page32_i89:pe3_tx_dp(4)"
				( attribute "PN" "DY9"
					( Origin gPackager )
				)
				( objectStatus "U5D1.DY9" )
			)
			( pin "@baseboard_fab2_lib.baseboard_fab2(sch_1):page32_i89:pe3_tx_dp(5)"
				( attribute "PN" "DV9"
					( Origin gPackager )
				)
				( objectStatus "U5D1.DV9" )
			)
			( pin "@baseboard_fab2_lib.baseboard_fab2(sch_1):page32_i89:pe3_tx_dp(6)"
				( attribute "PN" "DT9"
					( Origin gPackager )
				)
				( objectStatus "U5D1.DT9" )
			)
			( pin "@baseboard_fab2_lib.baseboard_fab2(sch_1):page32_i89:pe3_tx_dp(7)"
				( attribute "PN" "DP7"
					( Origin gPackager )
				)
				( objectStatus "U5D1.DP7" )
			)
			( pin "@baseboard_fab2_lib.baseboard_fab2(sch_1):page32_i89:pe3_tx_dp(8)"
				( attribute "PN" "DN6"
					( Origin gPackager )
				)
				( objectStatus "U5D1.DN6" )
			)
			( pin "@baseboard_fab2_lib.baseboard_fab2(sch_1):page32_i89:pe3_tx_dp(9)"
				( attribute "PN" "DM5"
					( Origin gPackager )
				)
				( objectStatus "U5D1.DM5" )
			)
			( pin "@baseboard_fab2_lib.baseboard_fab2(sch_1):page32_i89:pe3_tx_dp(10)"
				( attribute "PN" "DK5"
					( Origin gPackager )
				)
				( objectStatus "U5D1.DK5" )
			)
			( pin "@baseboard_fab2_lib.baseboard_fab2(sch_1):page32_i89:pe3_tx_dp(11)"
				( attribute "PN" "DH5"
					( Origin gPackager )
				)
				( objectStatus "U5D1.DH5" )
			)
			( pin "@baseboard_fab2_lib.baseboard_fab2(sch_1):page32_i89:pe3_tx_dp(12)"
				( attribute "PN" "DG6"
					( Origin gPackager )
				)
				( objectStatus "U5D1.DG6" )
			)
			( pin "@baseboard_fab2_lib.baseboard_fab2(sch_1):page32_i89:pe3_tx_dp(13)"
				( attribute "PN" "DC6"
					( Origin gPackager )
				)
				( objectStatus "U5D1.DC6" )
			)
			( pin "@baseboard_fab2_lib.baseboard_fab2(sch_1):page32_i89:pe3_tx_dp(14)"
				( attribute "PN" "DA4"
					( Origin gPackager )
				)
				( objectStatus "U5D1.DA4" )
			)
			( pin "@baseboard_fab2_lib.baseboard_fab2(sch_1):page32_i89:pe3_tx_dp(15)"
				( attribute "PN" "CV5"
					( Origin gPackager )
				)
				( objectStatus "U5D1.CV5" )
			)
			( pin "@baseboard_fab2_lib.baseboard_fab2(sch_1):page33_i86:upi0_rx_dn(0)"
				( attribute "PN" "AC10"
					( Origin gPackager )
				)
				( objectStatus "U5D1.AC10" )
			)
			( pin "@baseboard_fab2_lib.baseboard_fab2(sch_1):page33_i86:upi0_rx_dn(1)"
				( attribute "PN" "AA8"
					( Origin gPackager )
				)
				( objectStatus "U5D1.AA8" )
			)
			( pin "@baseboard_fab2_lib.baseboard_fab2(sch_1):page33_i86:upi0_rx_dn(2)"
				( attribute "PN" "AB7"
					( Origin gPackager )
				)
				( objectStatus "U5D1.AB7" )
			)
			( pin "@baseboard_fab2_lib.baseboard_fab2(sch_1):page33_i86:upi0_rx_dn(3)"
				( attribute "PN" "AD5"
					( Origin gPackager )
				)
				( objectStatus "U5D1.AD5" )
			)
			( pin "@baseboard_fab2_lib.baseboard_fab2(sch_1):page33_i86:upi0_rx_dn(4)"
				( attribute "PN" "AE6"
					( Origin gPackager )
				)
				( objectStatus "U5D1.AE6" )
			)
			( pin "@baseboard_fab2_lib.baseboard_fab2(sch_1):page33_i86:upi0_rx_dn(5)"
				( attribute "PN" "AG8"
					( Origin gPackager )
				)
				( objectStatus "U5D1.AG8" )
			)
			( pin "@baseboard_fab2_lib.baseboard_fab2(sch_1):page33_i86:upi0_rx_dn(6)"
				( attribute "PN" "AJ6"
					( Origin gPackager )
				)
				( objectStatus "U5D1.AJ6" )
			)
			( pin "@baseboard_fab2_lib.baseboard_fab2(sch_1):page33_i86:upi0_rx_dn(7)"
				( attribute "PN" "AL6"
					( Origin gPackager )
				)
				( objectStatus "U5D1.AL6" )
			)
			( pin "@baseboard_fab2_lib.baseboard_fab2(sch_1):page33_i86:upi0_rx_dn(8)"
				( attribute "PN" "AK7"
					( Origin gPackager )
				)
				( objectStatus "U5D1.AK7" )
			)
			( pin "@baseboard_fab2_lib.baseboard_fab2(sch_1):page33_i86:upi0_rx_dn(9)"
				( attribute "PN" "AM9"
					( Origin gPackager )
				)
				( objectStatus "U5D1.AM9" )
			)
			( pin "@baseboard_fab2_lib.baseboard_fab2(sch_1):page33_i86:upi0_rx_dn(10)"
				( attribute "PN" "AP7"
					( Origin gPackager )
				)
				( objectStatus "U5D1.AP7" )
			)
			( pin "@baseboard_fab2_lib.baseboard_fab2(sch_1):page33_i86:upi0_rx_dn(11)"
				( attribute "PN" "AR8"
					( Origin gPackager )
				)
				( objectStatus "U5D1.AR8" )
			)
			( pin "@baseboard_fab2_lib.baseboard_fab2(sch_1):page33_i86:upi0_rx_dn(12)"
				( attribute "PN" "AU10"
					( Origin gPackager )
				)
				( objectStatus "U5D1.AU10" )
			)
			( pin "@baseboard_fab2_lib.baseboard_fab2(sch_1):page33_i86:upi0_rx_dn(13)"
				( attribute "PN" "BA8"
					( Origin gPackager )
				)
				( objectStatus "U5D1.BA8" )
			)
			( pin "@baseboard_fab2_lib.baseboard_fab2(sch_1):page33_i86:upi0_rx_dn(14)"
				( attribute "PN" "BC6"
					( Origin gPackager )
				)
				( objectStatus "U5D1.BC6" )
			)
			( pin "@baseboard_fab2_lib.baseboard_fab2(sch_1):page33_i86:upi0_rx_dn(15)"
				( attribute "PN" "BD7"
					( Origin gPackager )
				)
				( objectStatus "U5D1.BD7" )
			)
			( pin "@baseboard_fab2_lib.baseboard_fab2(sch_1):page33_i86:upi0_rx_dn(16)"
				( attribute "PN" "AW8"
					( Origin gPackager )
				)
				( objectStatus "U5D1.AW8" )
			)
			( pin "@baseboard_fab2_lib.baseboard_fab2(sch_1):page33_i86:upi0_rx_dn(17)"
				( attribute "PN" "AY9"
					( Origin gPackager )
				)
				( objectStatus "U5D1.AY9" )
			)
			( pin "@baseboard_fab2_lib.baseboard_fab2(sch_1):page33_i86:upi0_rx_dn(18)"
				( attribute "PN" "BD9"
					( Origin gPackager )
				)
				( objectStatus "U5D1.BD9" )
			)
			( pin "@baseboard_fab2_lib.baseboard_fab2(sch_1):page33_i86:upi0_rx_dn(19)"
				( attribute "PN" "BB11"
					( Origin gPackager )
				)
				( objectStatus "U5D1.BB11" )
			)
			( pin "@baseboard_fab2_lib.baseboard_fab2(sch_1):page33_i86:upi0_rx_dp(0)"
				( attribute "PN" "AB9"
					( Origin gPackager )
				)
				( objectStatus "U5D1.AB9" )
			)
			( pin "@baseboard_fab2_lib.baseboard_fab2(sch_1):page33_i86:upi0_rx_dp(1)"
				( attribute "PN" "AC8"
					( Origin gPackager )
				)
				( objectStatus "U5D1.AC8" )
			)
			( pin "@baseboard_fab2_lib.baseboard_fab2(sch_1):page33_i86:upi0_rx_dp(2)"
				( attribute "PN" "AA6"
					( Origin gPackager )
				)
				( objectStatus "U5D1.AA6" )
			)
			( pin "@baseboard_fab2_lib.baseboard_fab2(sch_1):page33_i86:upi0_rx_dp(3)"
				( attribute "PN" "AC6"
					( Origin gPackager )
				)
				( objectStatus "U5D1.AC6" )
			)
			( pin "@baseboard_fab2_lib.baseboard_fab2(sch_1):page33_i86:upi0_rx_dp(4)"
				( attribute "PN" "AG6"
					( Origin gPackager )
				)
				( objectStatus "U5D1.AG6" )
			)
			( pin "@baseboard_fab2_lib.baseboard_fab2(sch_1):page33_i86:upi0_rx_dp(5)"
				( attribute "PN" "AF7"
					( Origin gPackager )
				)
				( objectStatus "U5D1.AF7" )
			)
			( pin "@baseboard_fab2_lib.baseboard_fab2(sch_1):page33_i86:upi0_rx_dp(6)"
				( attribute "PN" "AH7"
					( Origin gPackager )
				)
				( objectStatus "U5D1.AH7" )
			)
			( pin "@baseboard_fab2_lib.baseboard_fab2(sch_1):page33_i86:upi0_rx_dp(7)"
				( attribute "PN" "AK5"
					( Origin gPackager )
				)
				( objectStatus "U5D1.AK5" )
			)
			( pin "@baseboard_fab2_lib.baseboard_fab2(sch_1):page33_i86:upi0_rx_dp(8)"
				( attribute "PN" "AM7"
					( Origin gPackager )
				)
				( objectStatus "U5D1.AM7" )
			)
			( pin "@baseboard_fab2_lib.baseboard_fab2(sch_1):page33_i86:upi0_rx_dp(9)"
				( attribute "PN" "AL8"
					( Origin gPackager )
				)
				( objectStatus "U5D1.AL8" )
			)
			( pin "@baseboard_fab2_lib.baseboard_fab2(sch_1):page33_i86:upi0_rx_dp(10)"
				( attribute "PN" "AN8"
					( Origin gPackager )
				)
				( objectStatus "U5D1.AN8" )
			)
			( pin "@baseboard_fab2_lib.baseboard_fab2(sch_1):page33_i86:upi0_rx_dp(11)"
				( attribute "PN" "AU8"
					( Origin gPackager )
				)
				( objectStatus "U5D1.AU8" )
			)
			( pin "@baseboard_fab2_lib.baseboard_fab2(sch_1):page33_i86:upi0_rx_dp(12)"
				( attribute "PN" "AT9"
					( Origin gPackager )
				)
				( objectStatus "U5D1.AT9" )
			)
			( pin "@baseboard_fab2_lib.baseboard_fab2(sch_1):page33_i86:upi0_rx_dp(13)"
				( attribute "PN" "AY7"
					( Origin gPackager )
				)
				( objectStatus "U5D1.AY7" )
			)
			( pin "@baseboard_fab2_lib.baseboard_fab2(sch_1):page33_i86:upi0_rx_dp(14)"
				( attribute "PN" "BB7"
					( Origin gPackager )
				)
				( objectStatus "U5D1.BB7" )
			)
			( pin "@baseboard_fab2_lib.baseboard_fab2(sch_1):page33_i86:upi0_rx_dp(15)"
				( attribute "PN" "BF7"
					( Origin gPackager )
				)
				( objectStatus "U5D1.BF7" )
			)
			( pin "@baseboard_fab2_lib.baseboard_fab2(sch_1):page33_i86:upi0_rx_dp(16)"
				( attribute "PN" "AV9"
					( Origin gPackager )
				)
				( objectStatus "U5D1.AV9" )
			)
			( pin "@baseboard_fab2_lib.baseboard_fab2(sch_1):page33_i86:upi0_rx_dp(17)"
				( attribute "PN" "BB9"
					( Origin gPackager )
				)
				( objectStatus "U5D1.BB9" )
			)
			( pin "@baseboard_fab2_lib.baseboard_fab2(sch_1):page33_i86:upi0_rx_dp(18)"
				( attribute "PN" "BC10"
					( Origin gPackager )
				)
				( objectStatus "U5D1.BC10" )
			)
			( pin "@baseboard_fab2_lib.baseboard_fab2(sch_1):page33_i86:upi0_rx_dp(19)"
				( attribute "PN" "BA10"
					( Origin gPackager )
				)
				( objectStatus "U5D1.BA10" )
			)
			( pin "@baseboard_fab2_lib.baseboard_fab2(sch_1):page33_i86:upi0_tx_dn(0)"
				( attribute "PN" "N2"
					( Origin gPackager )
				)
				( objectStatus "U5D1.N2" )
			)
			( pin "@baseboard_fab2_lib.baseboard_fab2(sch_1):page33_i86:upi0_tx_dn(1)"
				( attribute "PN" "P1"
					( Origin gPackager )
				)
				( objectStatus "U5D1.P1" )
			)
			( pin "@baseboard_fab2_lib.baseboard_fab2(sch_1):page33_i86:upi0_tx_dn(2)"
				( attribute "PN" "V3"
					( Origin gPackager )
				)
				( objectStatus "U5D1.V3" )
			)
			( pin "@baseboard_fab2_lib.baseboard_fab2(sch_1):page33_i86:upi0_tx_dn(3)"
				( attribute "PN" "Y1"
					( Origin gPackager )
				)
				( objectStatus "U5D1.Y1" )
			)
			( pin "@baseboard_fab2_lib.baseboard_fab2(sch_1):page33_i86:upi0_tx_dn(4)"
				( attribute "PN" "AB3"
					( Origin gPackager )
				)
				( objectStatus "U5D1.AB3" )
			)
			( pin "@baseboard_fab2_lib.baseboard_fab2(sch_1):page33_i86:upi0_tx_dn(5)"
				( attribute "PN" "AC2"
					( Origin gPackager )
				)
				( objectStatus "U5D1.AC2" )
			)
			( pin "@baseboard_fab2_lib.baseboard_fab2(sch_1):page33_i86:upi0_tx_dn(6)"
				( attribute "PN" "AG4"
					( Origin gPackager )
				)
				( objectStatus "U5D1.AG4" )
			)
			( pin "@baseboard_fab2_lib.baseboard_fab2(sch_1):page33_i86:upi0_tx_dn(7)"
				( attribute "PN" "AE2"
					( Origin gPackager )
				)
				( objectStatus "U5D1.AE2" )
			)
			( pin "@baseboard_fab2_lib.baseboard_fab2(sch_1):page33_i86:upi0_tx_dn(8)"
				( attribute "PN" "AH3"
					( Origin gPackager )
				)
				( objectStatus "U5D1.AH3" )
			)
			( pin "@baseboard_fab2_lib.baseboard_fab2(sch_1):page33_i86:upi0_tx_dn(9)"
				( attribute "PN" "AL2"
					( Origin gPackager )
				)
				( objectStatus "U5D1.AL2" )
			)
			( pin "@baseboard_fab2_lib.baseboard_fab2(sch_1):page33_i86:upi0_tx_dn(10)"
				( attribute "PN" "AM3"
					( Origin gPackager )
				)
				( objectStatus "U5D1.AM3" )
			)
			( pin "@baseboard_fab2_lib.baseboard_fab2(sch_1):page33_i86:upi0_tx_dn(11)"
				( attribute "PN" "AN4"
					( Origin gPackager )
				)
				( objectStatus "U5D1.AN4" )
			)
			( pin "@baseboard_fab2_lib.baseboard_fab2(sch_1):page33_i86:upi0_tx_dn(12)"
				( attribute "PN" "AT1"
					( Origin gPackager )
				)
				( objectStatus "U5D1.AT1" )
			)
			( pin "@baseboard_fab2_lib.baseboard_fab2(sch_1):page33_i86:upi0_tx_dn(13)"
				( attribute "PN" "AT3"
					( Origin gPackager )
				)
				( objectStatus "U5D1.AT3" )
			)
			( pin "@baseboard_fab2_lib.baseboard_fab2(sch_1):page33_i86:upi0_tx_dn(14)"
				( attribute "PN" "AU4"
					( Origin gPackager )
				)
				( objectStatus "U5D1.AU4" )
			)
			( pin "@baseboard_fab2_lib.baseboard_fab2(sch_1):page33_i86:upi0_tx_dn(15)"
				( attribute "PN" "AV5"
					( Origin gPackager )
				)
				( objectStatus "U5D1.AV5" )
			)
			( pin "@baseboard_fab2_lib.baseboard_fab2(sch_1):page33_i86:upi0_tx_dn(16)"
				( attribute "PN" "BA4"
					( Origin gPackager )
				)
				( objectStatus "U5D1.BA4" )
			)
			( pin "@baseboard_fab2_lib.baseboard_fab2(sch_1):page33_i86:upi0_tx_dn(17)"
				( attribute "PN" "BB3"
					( Origin gPackager )
				)
				( objectStatus "U5D1.BB3" )
			)
			( pin "@baseboard_fab2_lib.baseboard_fab2(sch_1):page33_i86:upi0_tx_dn(18)"
				( attribute "PN" "BF3"
					( Origin gPackager )
				)
				( objectStatus "U5D1.BF3" )
			)
			( pin "@baseboard_fab2_lib.baseboard_fab2(sch_1):page33_i86:upi0_tx_dn(19)"
				( attribute "PN" "BG4"
					( Origin gPackager )
				)
				( objectStatus "U5D1.BG4" )
			)
			( pin "@baseboard_fab2_lib.baseboard_fab2(sch_1):page33_i86:upi0_tx_dp(0)"
				( attribute "PN" "M1"
					( Origin gPackager )
				)
				( objectStatus "U5D1.M1" )
			)
			( pin "@baseboard_fab2_lib.baseboard_fab2(sch_1):page33_i86:upi0_tx_dp(1)"
				( attribute "PN" "T1"
					( Origin gPackager )
				)
				( objectStatus "U5D1.T1" )
			)
			( pin "@baseboard_fab2_lib.baseboard_fab2(sch_1):page33_i86:upi0_tx_dp(2)"
				( attribute "PN" "Y3"
					( Origin gPackager )
				)
				( objectStatus "U5D1.Y3" )
			)
			( pin "@baseboard_fab2_lib.baseboard_fab2(sch_1):page33_i86:upi0_tx_dp(3)"
				( attribute "PN" "W2"
					( Origin gPackager )
				)
				( objectStatus "U5D1.W2" )
			)
			( pin "@baseboard_fab2_lib.baseboard_fab2(sch_1):page33_i86:upi0_tx_dp(4)"
				( attribute "PN" "AA2"
					( Origin gPackager )
				)
				( objectStatus "U5D1.AA2" )
			)
			( pin "@baseboard_fab2_lib.baseboard_fab2(sch_1):page33_i86:upi0_tx_dp(5)"
				( attribute "PN" "AD1"
					( Origin gPackager )
				)
				( objectStatus "U5D1.AD1" )
			)
			( pin "@baseboard_fab2_lib.baseboard_fab2(sch_1):page33_i86:upi0_tx_dp(6)"
				( attribute "PN" "AF3"
					( Origin gPackager )
				)
				( objectStatus "U5D1.AF3" )
			)
			( pin "@baseboard_fab2_lib.baseboard_fab2(sch_1):page33_i86:upi0_tx_dp(7)"
				( attribute "PN" "AG2"
					( Origin gPackager )
				)
				( objectStatus "U5D1.AG2" )
			)
			( pin "@baseboard_fab2_lib.baseboard_fab2(sch_1):page33_i86:upi0_tx_dp(8)"
				( attribute "PN" "AJ2"
					( Origin gPackager )
				)
				( objectStatus "U5D1.AJ2" )
			)
			( pin "@baseboard_fab2_lib.baseboard_fab2(sch_1):page33_i86:upi0_tx_dp(9)"
				( attribute "PN" "AK1"
					( Origin gPackager )
				)
				( objectStatus "U5D1.AK1" )
			)
			( pin "@baseboard_fab2_lib.baseboard_fab2(sch_1):page33_i86:upi0_tx_dp(10)"
				( attribute "PN" "AK3"
					( Origin gPackager )
				)
				( objectStatus "U5D1.AK3" )
			)
			( pin "@baseboard_fab2_lib.baseboard_fab2(sch_1):page33_i86:upi0_tx_dp(11)"
				( attribute "PN" "AP3"
					( Origin gPackager )
				)
				( objectStatus "U5D1.AP3" )
			)
			( pin "@baseboard_fab2_lib.baseboard_fab2(sch_1):page33_i86:upi0_tx_dp(12)"
				( attribute "PN" "AP1"
					( Origin gPackager )
				)
				( objectStatus "U5D1.AP1" )
			)
			( pin "@baseboard_fab2_lib.baseboard_fab2(sch_1):page33_i86:upi0_tx_dp(13)"
				( attribute "PN" "AR2"
					( Origin gPackager )
				)
				( objectStatus "U5D1.AR2" )
			)
			( pin "@baseboard_fab2_lib.baseboard_fab2(sch_1):page33_i86:upi0_tx_dp(14)"
				( attribute "PN" "AR4"
					( Origin gPackager )
				)
				( objectStatus "U5D1.AR4" )
			)
			( pin "@baseboard_fab2_lib.baseboard_fab2(sch_1):page33_i86:upi0_tx_dp(15)"
				( attribute "PN" "AW4"
					( Origin gPackager )
				)
				( objectStatus "U5D1.AW4" )
			)
			( pin "@baseboard_fab2_lib.baseboard_fab2(sch_1):page33_i86:upi0_tx_dp(16)"
				( attribute "PN" "AY3"
					( Origin gPackager )
				)
				( objectStatus "U5D1.AY3" )
			)
			( pin "@baseboard_fab2_lib.baseboard_fab2(sch_1):page33_i86:upi0_tx_dp(17)"
				( attribute "PN" "BC2"
					( Origin gPackager )
				)
				( objectStatus "U5D1.BC2" )
			)
			( pin "@baseboard_fab2_lib.baseboard_fab2(sch_1):page33_i86:upi0_tx_dp(18)"
				( attribute "PN" "BD3"
					( Origin gPackager )
				)
				( objectStatus "U5D1.BD3" )
			)
			( pin "@baseboard_fab2_lib.baseboard_fab2(sch_1):page33_i86:upi0_tx_dp(19)"
				( attribute "PN" "BH3"
					( Origin gPackager )
				)
				( objectStatus "U5D1.BH3" )
			)
			( pin "@baseboard_fab2_lib.baseboard_fab2(sch_1):page34_i86:upi1_rx_dn(0)"
				( attribute "PN" "T5"
					( Origin gPackager )
				)
				( objectStatus "U5D1.T5" )
			)
			( pin "@baseboard_fab2_lib.baseboard_fab2(sch_1):page34_i86:upi1_rx_dn(1)"
				( attribute "PN" "P7"
					( Origin gPackager )
				)
				( objectStatus "U5D1.P7" )
			)
			( pin "@baseboard_fab2_lib.baseboard_fab2(sch_1):page34_i86:upi1_rx_dn(2)"
				( attribute "PN" "V7"
					( Origin gPackager )
				)
				( objectStatus "U5D1.V7" )
			)
			( pin "@baseboard_fab2_lib.baseboard_fab2(sch_1):page34_i86:upi1_rx_dn(3)"
				( attribute "PN" "T9"
					( Origin gPackager )
				)
				( objectStatus "U5D1.T9" )
			)
			( pin "@baseboard_fab2_lib.baseboard_fab2(sch_1):page34_i86:upi1_rx_dn(4)"
				( attribute "PN" "P9"
					( Origin gPackager )
				)
				( objectStatus "U5D1.P9" )
			)
			( pin "@baseboard_fab2_lib.baseboard_fab2(sch_1):page34_i86:upi1_rx_dn(5)"
				( attribute "PN" "R10"
					( Origin gPackager )
				)
				( objectStatus "U5D1.R10" )
			)
			( pin "@baseboard_fab2_lib.baseboard_fab2(sch_1):page34_i86:upi1_rx_dn(6)"
				( attribute "PN" "U12"
					( Origin gPackager )
				)
				( objectStatus "U5D1.U12" )
			)
			( pin "@baseboard_fab2_lib.baseboard_fab2(sch_1):page34_i86:upi1_rx_dn(7)"
				( attribute "PN" "L12"
					( Origin gPackager )
				)
				( objectStatus "U5D1.L12" )
			)
			( pin "@baseboard_fab2_lib.baseboard_fab2(sch_1):page34_i86:upi1_rx_dn(8)"
				( attribute "PN" "N14"
					( Origin gPackager )
				)
				( objectStatus "U5D1.N14" )
			)
			( pin "@baseboard_fab2_lib.baseboard_fab2(sch_1):page34_i86:upi1_rx_dn(9)"
				( attribute "PN" "R12"
					( Origin gPackager )
				)
				( objectStatus "U5D1.R12" )
			)
			( pin "@baseboard_fab2_lib.baseboard_fab2(sch_1):page34_i86:upi1_rx_dn(10)"
				( attribute "PN" "R16"
					( Origin gPackager )
				)
				( objectStatus "U5D1.R16" )
			)
			( pin "@baseboard_fab2_lib.baseboard_fab2(sch_1):page34_i86:upi1_rx_dn(11)"
				( attribute "PN" "P17"
					( Origin gPackager )
				)
				( objectStatus "U5D1.P17" )
			)
			( pin "@baseboard_fab2_lib.baseboard_fab2(sch_1):page34_i86:upi1_rx_dn(12)"
				( attribute "PN" "U16"
					( Origin gPackager )
				)
				( objectStatus "U5D1.U16" )
			)
			( pin "@baseboard_fab2_lib.baseboard_fab2(sch_1):page34_i86:upi1_rx_dn(13)"
				( attribute "PN" "W18"
					( Origin gPackager )
				)
				( objectStatus "U5D1.W18" )
			)
			( pin "@baseboard_fab2_lib.baseboard_fab2(sch_1):page34_i86:upi1_rx_dn(14)"
				( attribute "PN" "R20"
					( Origin gPackager )
				)
				( objectStatus "U5D1.R20" )
			)
			( pin "@baseboard_fab2_lib.baseboard_fab2(sch_1):page34_i86:upi1_rx_dn(15)"
				( attribute "PN" "U18"
					( Origin gPackager )
				)
				( objectStatus "U5D1.U18" )
			)
			( pin "@baseboard_fab2_lib.baseboard_fab2(sch_1):page34_i86:upi1_rx_dn(16)"
				( attribute "PN" "P21"
					( Origin gPackager )
				)
				( objectStatus "U5D1.P21" )
			)
			( pin "@baseboard_fab2_lib.baseboard_fab2(sch_1):page34_i86:upi1_rx_dn(17)"
				( attribute "PN" "V19"
					( Origin gPackager )
				)
				( objectStatus "U5D1.V19" )
			)
			( pin "@baseboard_fab2_lib.baseboard_fab2(sch_1):page34_i86:upi1_rx_dn(18)"
				( attribute "PN" "Y21"
					( Origin gPackager )
				)
				( objectStatus "U5D1.Y21" )
			)
			( pin "@baseboard_fab2_lib.baseboard_fab2(sch_1):page34_i86:upi1_rx_dn(19)"
				( attribute "PN" "AB19"
					( Origin gPackager )
				)
				( objectStatus "U5D1.AB19" )
			)
			( pin "@baseboard_fab2_lib.baseboard_fab2(sch_1):page34_i86:upi1_rx_dp(0)"
				( attribute "PN" "R6"
					( Origin gPackager )
				)
				( objectStatus "U5D1.R6" )
			)
			( pin "@baseboard_fab2_lib.baseboard_fab2(sch_1):page34_i86:upi1_rx_dp(1)"
				( attribute "PN" "T7"
					( Origin gPackager )
				)
				( objectStatus "U5D1.T7" )
			)
			( pin "@baseboard_fab2_lib.baseboard_fab2(sch_1):page34_i86:upi1_rx_dp(2)"
				( attribute "PN" "U8"
					( Origin gPackager )
				)
				( objectStatus "U5D1.U8" )
			)
			( pin "@baseboard_fab2_lib.baseboard_fab2(sch_1):page34_i86:upi1_rx_dp(3)"
				( attribute "PN" "R8"
					( Origin gPackager )
				)
				( objectStatus "U5D1.R8" )
			)
			( pin "@baseboard_fab2_lib.baseboard_fab2(sch_1):page34_i86:upi1_rx_dp(4)"
				( attribute "PN" "N10"
					( Origin gPackager )
				)
				( objectStatus "U5D1.N10" )
			)
			( pin "@baseboard_fab2_lib.baseboard_fab2(sch_1):page34_i86:upi1_rx_dp(5)"
				( attribute "PN" "U10"
					( Origin gPackager )
				)
				( objectStatus "U5D1.U10" )
			)
			( pin "@baseboard_fab2_lib.baseboard_fab2(sch_1):page34_i86:upi1_rx_dp(6)"
				( attribute "PN" "T11"
					( Origin gPackager )
				)
				( objectStatus "U5D1.T11" )
			)
			( pin "@baseboard_fab2_lib.baseboard_fab2(sch_1):page34_i86:upi1_rx_dp(7)"
				( attribute "PN" "N12"
					( Origin gPackager )
				)
				( objectStatus "U5D1.N12" )
			)
			( pin "@baseboard_fab2_lib.baseboard_fab2(sch_1):page34_i86:upi1_rx_dp(8)"
				( attribute "PN" "M13"
					( Origin gPackager )
				)
				( objectStatus "U5D1.M13" )
			)
			( pin "@baseboard_fab2_lib.baseboard_fab2(sch_1):page34_i86:upi1_rx_dp(9)"
				( attribute "PN" "P13"
					( Origin gPackager )
				)
				( objectStatus "U5D1.P13" )
			)
			( pin "@baseboard_fab2_lib.baseboard_fab2(sch_1):page34_i86:upi1_rx_dp(10)"
				( attribute "PN" "T15"
					( Origin gPackager )
				)
				( objectStatus "U5D1.T15" )
			)
			( pin "@baseboard_fab2_lib.baseboard_fab2(sch_1):page34_i86:upi1_rx_dp(11)"
				( attribute "PN" "N16"
					( Origin gPackager )
				)
				( objectStatus "U5D1.N16" )
			)
			( pin "@baseboard_fab2_lib.baseboard_fab2(sch_1):page34_i86:upi1_rx_dp(12)"
				( attribute "PN" "W16"
					( Origin gPackager )
				)
				( objectStatus "U5D1.W16" )
			)
			( pin "@baseboard_fab2_lib.baseboard_fab2(sch_1):page34_i86:upi1_rx_dp(13)"
				( attribute "PN" "V17"
					( Origin gPackager )
				)
				( objectStatus "U5D1.V17" )
			)
			( pin "@baseboard_fab2_lib.baseboard_fab2(sch_1):page34_i86:upi1_rx_dp(14)"
				( attribute "PN" "P19"
					( Origin gPackager )
				)
				( objectStatus "U5D1.P19" )
			)
			( pin "@baseboard_fab2_lib.baseboard_fab2(sch_1):page34_i86:upi1_rx_dp(15)"
				( attribute "PN" "T19"
					( Origin gPackager )
				)
				( objectStatus "U5D1.T19" )
			)
			( pin "@baseboard_fab2_lib.baseboard_fab2(sch_1):page34_i86:upi1_rx_dp(16)"
				( attribute "PN" "T21"
					( Origin gPackager )
				)
				( objectStatus "U5D1.T21" )
			)
			( pin "@baseboard_fab2_lib.baseboard_fab2(sch_1):page34_i86:upi1_rx_dp(17)"
				( attribute "PN" "Y19"
					( Origin gPackager )
				)
				( objectStatus "U5D1.Y19" )
			)
			( pin "@baseboard_fab2_lib.baseboard_fab2(sch_1):page34_i86:upi1_rx_dp(18)"
				( attribute "PN" "W20"
					( Origin gPackager )
				)
				( objectStatus "U5D1.W20" )
			)
			( pin "@baseboard_fab2_lib.baseboard_fab2(sch_1):page34_i86:upi1_rx_dp(19)"
				( attribute "PN" "AA20"
					( Origin gPackager )
				)
				( objectStatus "U5D1.AA20" )
			)
			( pin "@baseboard_fab2_lib.baseboard_fab2(sch_1):page34_i86:upi1_tx_dn(0)"
				( attribute "PN" "M3"
					( Origin gPackager )
				)
				( objectStatus "U5D1.M3" )
			)
			( pin "@baseboard_fab2_lib.baseboard_fab2(sch_1):page34_i86:upi1_tx_dn(1)"
				( attribute "PN" "L4"
					( Origin gPackager )
				)
				( objectStatus "U5D1.L4" )
			)
			( pin "@baseboard_fab2_lib.baseboard_fab2(sch_1):page34_i86:upi1_tx_dn(2)"
				( attribute "PN" "K5"
					( Origin gPackager )
				)
				( objectStatus "U5D1.K5" )
			)
			( pin "@baseboard_fab2_lib.baseboard_fab2(sch_1):page34_i86:upi1_tx_dn(3)"
				( attribute "PN" "J6"
					( Origin gPackager )
				)
				( objectStatus "U5D1.J6" )
			)
			( pin "@baseboard_fab2_lib.baseboard_fab2(sch_1):page34_i86:upi1_tx_dn(4)"
				( attribute "PN" "G6"
					( Origin gPackager )
				)
				( objectStatus "U5D1.G6" )
			)
			( pin "@baseboard_fab2_lib.baseboard_fab2(sch_1):page34_i86:upi1_tx_dn(5)"
				( attribute "PN" "H7"
					( Origin gPackager )
				)
				( objectStatus "U5D1.H7" )
			)
			( pin "@baseboard_fab2_lib.baseboard_fab2(sch_1):page34_i86:upi1_tx_dn(6)"
				( attribute "PN" "K9"
					( Origin gPackager )
				)
				( objectStatus "U5D1.K9" )
			)
			( pin "@baseboard_fab2_lib.baseboard_fab2(sch_1):page34_i86:upi1_tx_dn(7)"
				( attribute "PN" "D9"
					( Origin gPackager )
				)
				( objectStatus "U5D1.D9" )
			)
			( pin "@baseboard_fab2_lib.baseboard_fab2(sch_1):page34_i86:upi1_tx_dn(8)"
				( attribute "PN" "F11"
					( Origin gPackager )
				)
				( objectStatus "U5D1.F11" )
			)
			( pin "@baseboard_fab2_lib.baseboard_fab2(sch_1):page34_i86:upi1_tx_dn(9)"
				( attribute "PN" "G10"
					( Origin gPackager )
				)
				( objectStatus "U5D1.G10" )
			)
			( pin "@baseboard_fab2_lib.baseboard_fab2(sch_1):page34_i86:upi1_tx_dn(10)"
				( attribute "PN" "E12"
					( Origin gPackager )
				)
				( objectStatus "U5D1.E12" )
			)
			( pin "@baseboard_fab2_lib.baseboard_fab2(sch_1):page34_i86:upi1_tx_dn(11)"
				( attribute "PN" "G14"
					( Origin gPackager )
				)
				( objectStatus "U5D1.G14" )
			)
			( pin "@baseboard_fab2_lib.baseboard_fab2(sch_1):page34_i86:upi1_tx_dn(12)"
				( attribute "PN" "D15"
					( Origin gPackager )
				)
				( objectStatus "U5D1.D15" )
			)
			( pin "@baseboard_fab2_lib.baseboard_fab2(sch_1):page34_i86:upi1_tx_dn(13)"
				( attribute "PN" "F15"
					( Origin gPackager )
				)
				( objectStatus "U5D1.F15" )
			)
			( pin "@baseboard_fab2_lib.baseboard_fab2(sch_1):page34_i86:upi1_tx_dn(14)"
				( attribute "PN" "H17"
					( Origin gPackager )
				)
				( objectStatus "U5D1.H17" )
			)
			( pin "@baseboard_fab2_lib.baseboard_fab2(sch_1):page34_i86:upi1_tx_dn(15)"
				( attribute "PN" "K19"
					( Origin gPackager )
				)
				( objectStatus "U5D1.K19" )
			)
			( pin "@baseboard_fab2_lib.baseboard_fab2(sch_1):page34_i86:upi1_tx_dn(16)"
				( attribute "PN" "G18"
					( Origin gPackager )
				)
				( objectStatus "U5D1.G18" )
			)
			( pin "@baseboard_fab2_lib.baseboard_fab2(sch_1):page34_i86:upi1_tx_dn(17)"
				( attribute "PN" "J20"
					( Origin gPackager )
				)
				( objectStatus "U5D1.J20" )
			)
			( pin "@baseboard_fab2_lib.baseboard_fab2(sch_1):page34_i86:upi1_tx_dn(18)"
				( attribute "PN" "F21"
					( Origin gPackager )
				)
				( objectStatus "U5D1.F21" )
			)
			( pin "@baseboard_fab2_lib.baseboard_fab2(sch_1):page34_i86:upi1_tx_dn(19)"
				( attribute "PN" "H21"
					( Origin gPackager )
				)
				( objectStatus "U5D1.H21" )
			)
			( pin "@baseboard_fab2_lib.baseboard_fab2(sch_1):page34_i86:upi1_tx_dp(0)"
				( attribute "PN" "P3"
					( Origin gPackager )
				)
				( objectStatus "U5D1.P3" )
			)
			( pin "@baseboard_fab2_lib.baseboard_fab2(sch_1):page34_i86:upi1_tx_dp(1)"
				( attribute "PN" "K3"
					( Origin gPackager )
				)
				( objectStatus "U5D1.K3" )
			)
			( pin "@baseboard_fab2_lib.baseboard_fab2(sch_1):page34_i86:upi1_tx_dp(2)"
				( attribute "PN" "M5"
					( Origin gPackager )
				)
				( objectStatus "U5D1.M5" )
			)
			( pin "@baseboard_fab2_lib.baseboard_fab2(sch_1):page34_i86:upi1_tx_dp(3)"
				( attribute "PN" "H5"
					( Origin gPackager )
				)
				( objectStatus "U5D1.H5" )
			)
			( pin "@baseboard_fab2_lib.baseboard_fab2(sch_1):page34_i86:upi1_tx_dp(4)"
				( attribute "PN" "F7"
					( Origin gPackager )
				)
				( objectStatus "U5D1.F7" )
			)
			( pin "@baseboard_fab2_lib.baseboard_fab2(sch_1):page34_i86:upi1_tx_dp(5)"
				( attribute "PN" "K7"
					( Origin gPackager )
				)
				( objectStatus "U5D1.K7" )
			)
			( pin "@baseboard_fab2_lib.baseboard_fab2(sch_1):page34_i86:upi1_tx_dp(6)"
				( attribute "PN" "J8"
					( Origin gPackager )
				)
				( objectStatus "U5D1.J8" )
			)
			( pin "@baseboard_fab2_lib.baseboard_fab2(sch_1):page34_i86:upi1_tx_dp(7)"
				( attribute "PN" "F9"
					( Origin gPackager )
				)
				( objectStatus "U5D1.F9" )
			)
			( pin "@baseboard_fab2_lib.baseboard_fab2(sch_1):page34_i86:upi1_tx_dp(8)"
				( attribute "PN" "E10"
					( Origin gPackager )
				)
				( objectStatus "U5D1.E10" )
			)
			( pin "@baseboard_fab2_lib.baseboard_fab2(sch_1):page34_i86:upi1_tx_dp(9)"
				( attribute "PN" "H9"
					( Origin gPackager )
				)
				( objectStatus "U5D1.H9" )
			)
			( pin "@baseboard_fab2_lib.baseboard_fab2(sch_1):page34_i86:upi1_tx_dp(10)"
				( attribute "PN" "G12"
					( Origin gPackager )
				)
				( objectStatus "U5D1.G12" )
			)
			( pin "@baseboard_fab2_lib.baseboard_fab2(sch_1):page34_i86:upi1_tx_dp(11)"
				( attribute "PN" "F13"
					( Origin gPackager )
				)
				( objectStatus "U5D1.F13" )
			)
			( pin "@baseboard_fab2_lib.baseboard_fab2(sch_1):page34_i86:upi1_tx_dp(12)"
				( attribute "PN" "E14"
					( Origin gPackager )
				)
				( objectStatus "U5D1.E14" )
			)
			( pin "@baseboard_fab2_lib.baseboard_fab2(sch_1):page34_i86:upi1_tx_dp(13)"
				( attribute "PN" "H15"
					( Origin gPackager )
				)
				( objectStatus "U5D1.H15" )
			)
			( pin "@baseboard_fab2_lib.baseboard_fab2(sch_1):page34_i86:upi1_tx_dp(14)"
				( attribute "PN" "G16"
					( Origin gPackager )
				)
				( objectStatus "U5D1.G16" )
			)
			( pin "@baseboard_fab2_lib.baseboard_fab2(sch_1):page34_i86:upi1_tx_dp(15)"
				( attribute "PN" "L18"
					( Origin gPackager )
				)
				( objectStatus "U5D1.L18" )
			)
			( pin "@baseboard_fab2_lib.baseboard_fab2(sch_1):page34_i86:upi1_tx_dp(16)"
				( attribute "PN" "J18"
					( Origin gPackager )
				)
				( objectStatus "U5D1.J18" )
			)
			( pin "@baseboard_fab2_lib.baseboard_fab2(sch_1):page34_i86:upi1_tx_dp(17)"
				( attribute "PN" "H19"
					( Origin gPackager )
				)
				( objectStatus "U5D1.H19" )
			)
			( pin "@baseboard_fab2_lib.baseboard_fab2(sch_1):page34_i86:upi1_tx_dp(18)"
				( attribute "PN" "G20"
					( Origin gPackager )
				)
				( objectStatus "U5D1.G20" )
			)
			( pin "@baseboard_fab2_lib.baseboard_fab2(sch_1):page34_i86:upi1_tx_dp(19)"
				( attribute "PN" "K21"
					( Origin gPackager )
				)
				( objectStatus "U5D1.K21" )
			)
			( pin "@baseboard_fab2_lib.baseboard_fab2(sch_1):page35_i3:upi2_rx_dn(0)"
				( attribute "PN" "DF23"
					( Origin gPackager )
				)
				( objectStatus "U5D1.DF23" )
			)
			( pin "@baseboard_fab2_lib.baseboard_fab2(sch_1):page35_i3:upi2_rx_dn(1)"
				( attribute "PN" "DE22"
					( Origin gPackager )
				)
				( objectStatus "U5D1.DE22" )
			)
			( pin "@baseboard_fab2_lib.baseboard_fab2(sch_1):page35_i3:upi2_rx_dn(2)"
				( attribute "PN" "DC22"
					( Origin gPackager )
				)
				( objectStatus "U5D1.DC22" )
			)
			( pin "@baseboard_fab2_lib.baseboard_fab2(sch_1):page35_i3:upi2_rx_dn(3)"
				( attribute "PN" "DB21"
					( Origin gPackager )
				)
				( objectStatus "U5D1.DB21" )
			)
			( pin "@baseboard_fab2_lib.baseboard_fab2(sch_1):page35_i3:upi2_rx_dn(4)"
				( attribute "PN" "DD19"
					( Origin gPackager )
				)
				( objectStatus "U5D1.DD19" )
			)
			( pin "@baseboard_fab2_lib.baseboard_fab2(sch_1):page35_i3:upi2_rx_dn(5)"
				( attribute "PN" "DA20"
					( Origin gPackager )
				)
				( objectStatus "U5D1.DA20" )
			)
			( pin "@baseboard_fab2_lib.baseboard_fab2(sch_1):page35_i3:upi2_rx_dn(6)"
				( attribute "PN" "CW20"
					( Origin gPackager )
				)
				( objectStatus "U5D1.CW20" )
			)
			( pin "@baseboard_fab2_lib.baseboard_fab2(sch_1):page35_i3:upi2_rx_dn(7)"
				( attribute "PN" "CV19"
					( Origin gPackager )
				)
				( objectStatus "U5D1.CV19" )
			)
			( pin "@baseboard_fab2_lib.baseboard_fab2(sch_1):page35_i3:upi2_rx_dn(8)"
				( attribute "PN" "CT21"
					( Origin gPackager )
				)
				( objectStatus "U5D1.CT21" )
			)
			( pin "@baseboard_fab2_lib.baseboard_fab2(sch_1):page35_i3:upi2_rx_dn(9)"
				( attribute "PN" "CR18"
					( Origin gPackager )
				)
				( objectStatus "U5D1.CR18" )
			)
			( pin "@baseboard_fab2_lib.baseboard_fab2(sch_1):page35_i3:upi2_rx_dn(10)"
				( attribute "PN" "CN20"
					( Origin gPackager )
				)
				( objectStatus "U5D1.CN20" )
			)
			( pin "@baseboard_fab2_lib.baseboard_fab2(sch_1):page35_i3:upi2_rx_dn(11)"
				( attribute "PN" "CP21"
					( Origin gPackager )
				)
				( objectStatus "U5D1.CP21" )
			)
			( pin "@baseboard_fab2_lib.baseboard_fab2(sch_1):page35_i3:upi2_rx_dn(12)"
				( attribute "PN" "CL16"
					( Origin gPackager )
				)
				( objectStatus "U5D1.CL16" )
			)
			( pin "@baseboard_fab2_lib.baseboard_fab2(sch_1):page35_i3:upi2_rx_dn(13)"
				( attribute "PN" "CJ18"
					( Origin gPackager )
				)
				( objectStatus "U5D1.CJ18" )
			)
			( pin "@baseboard_fab2_lib.baseboard_fab2(sch_1):page35_i3:upi2_rx_dn(14)"
				( attribute "PN" "CH17"
					( Origin gPackager )
				)
				( objectStatus "U5D1.CH17" )
			)
			( pin "@baseboard_fab2_lib.baseboard_fab2(sch_1):page35_i3:upi2_rx_dn(15)"
				( attribute "PN" "CE16"
					( Origin gPackager )
				)
				( objectStatus "U5D1.CE16" )
			)
			( pin "@baseboard_fab2_lib.baseboard_fab2(sch_1):page35_i3:upi2_rx_dn(16)"
				( attribute "PN" "CD15"
					( Origin gPackager )
				)
				( objectStatus "U5D1.CD15" )
			)
			( pin "@baseboard_fab2_lib.baseboard_fab2(sch_1):page35_i3:upi2_rx_dn(17)"
				( attribute "PN" "CF17"
					( Origin gPackager )
				)
				( objectStatus "U5D1.CF17" )
			)
			( pin "@baseboard_fab2_lib.baseboard_fab2(sch_1):page35_i3:upi2_rx_dn(18)"
				( attribute "PN" "CB15"
					( Origin gPackager )
				)
				( objectStatus "U5D1.CB15" )
			)
			( pin "@baseboard_fab2_lib.baseboard_fab2(sch_1):page35_i3:upi2_rx_dn(19)"
				( attribute "PN" "BY17"
					( Origin gPackager )
				)
				( objectStatus "U5D1.BY17" )
			)
			( pin "@baseboard_fab2_lib.baseboard_fab2(sch_1):page35_i3:upi2_rx_dp(0)"
				( attribute "PN" "DG22"
					( Origin gPackager )
				)
				( objectStatus "U5D1.DG22" )
			)
			( pin "@baseboard_fab2_lib.baseboard_fab2(sch_1):page35_i3:upi2_rx_dp(1)"
				( attribute "PN" "DD21"
					( Origin gPackager )
				)
				( objectStatus "U5D1.DD21" )
			)
			( pin "@baseboard_fab2_lib.baseboard_fab2(sch_1):page35_i3:upi2_rx_dp(2)"
				( attribute "PN" "DA22"
					( Origin gPackager )
				)
				( objectStatus "U5D1.DA22" )
			)
			( pin "@baseboard_fab2_lib.baseboard_fab2(sch_1):page35_i3:upi2_rx_dp(3)"
				( attribute "PN" "DC20"
					( Origin gPackager )
				)
				( objectStatus "U5D1.DC20" )
			)
			( pin "@baseboard_fab2_lib.baseboard_fab2(sch_1):page35_i3:upi2_rx_dp(4)"
				( attribute "PN" "DB19"
					( Origin gPackager )
				)
				( objectStatus "U5D1.DB19" )
			)
			( pin "@baseboard_fab2_lib.baseboard_fab2(sch_1):page35_i3:upi2_rx_dp(5)"
				( attribute "PN" "CY19"
					( Origin gPackager )
				)
				( objectStatus "U5D1.CY19" )
			)
			( pin "@baseboard_fab2_lib.baseboard_fab2(sch_1):page35_i3:upi2_rx_dp(6)"
				( attribute "PN" "CU20"
					( Origin gPackager )
				)
				( objectStatus "U5D1.CU20" )
			)
			( pin "@baseboard_fab2_lib.baseboard_fab2(sch_1):page35_i3:upi2_rx_dp(7)"
				( attribute "PN" "CW18"
					( Origin gPackager )
				)
				( objectStatus "U5D1.CW18" )
			)
			( pin "@baseboard_fab2_lib.baseboard_fab2(sch_1):page35_i3:upi2_rx_dp(8)"
				( attribute "PN" "CR20"
					( Origin gPackager )
				)
				( objectStatus "U5D1.CR20" )
			)
			( pin "@baseboard_fab2_lib.baseboard_fab2(sch_1):page35_i3:upi2_rx_dp(9)"
				( attribute "PN" "CN18"
					( Origin gPackager )
				)
				( objectStatus "U5D1.CN18" )
			)
			( pin "@baseboard_fab2_lib.baseboard_fab2(sch_1):page35_i3:upi2_rx_dp(10)"
				( attribute "PN" "CP19"
					( Origin gPackager )
				)
				( objectStatus "U5D1.CP19" )
			)
			( pin "@baseboard_fab2_lib.baseboard_fab2(sch_1):page35_i3:upi2_rx_dp(11)"
				( attribute "PN" "CM21"
					( Origin gPackager )
				)
				( objectStatus "U5D1.CM21" )
			)
			( pin "@baseboard_fab2_lib.baseboard_fab2(sch_1):page35_i3:upi2_rx_dp(12)"
				( attribute "PN" "CJ16"
					( Origin gPackager )
				)
				( objectStatus "U5D1.CJ16" )
			)
			( pin "@baseboard_fab2_lib.baseboard_fab2(sch_1):page35_i3:upi2_rx_dp(13)"
				( attribute "PN" "CK17"
					( Origin gPackager )
				)
				( objectStatus "U5D1.CK17" )
			)
			( pin "@baseboard_fab2_lib.baseboard_fab2(sch_1):page35_i3:upi2_rx_dp(14)"
				( attribute "PN" "CG16"
					( Origin gPackager )
				)
				( objectStatus "U5D1.CG16" )
			)
			( pin "@baseboard_fab2_lib.baseboard_fab2(sch_1):page35_i3:upi2_rx_dp(15)"
				( attribute "PN" "CF15"
					( Origin gPackager )
				)
				( objectStatus "U5D1.CF15" )
			)
			( pin "@baseboard_fab2_lib.baseboard_fab2(sch_1):page35_i3:upi2_rx_dp(16)"
				( attribute "PN" "CC14"
					( Origin gPackager )
				)
				( objectStatus "U5D1.CC14" )
			)
			( pin "@baseboard_fab2_lib.baseboard_fab2(sch_1):page35_i3:upi2_rx_dp(17)"
				( attribute "PN" "CD17"
					( Origin gPackager )
				)
				( objectStatus "U5D1.CD17" )
			)
			( pin "@baseboard_fab2_lib.baseboard_fab2(sch_1):page35_i3:upi2_rx_dp(18)"
				( attribute "PN" "BY15"
					( Origin gPackager )
				)
				( objectStatus "U5D1.BY15" )
			)
			( pin "@baseboard_fab2_lib.baseboard_fab2(sch_1):page35_i3:upi2_rx_dp(19)"
				( attribute "PN" "CA16"
					( Origin gPackager )
				)
				( objectStatus "U5D1.CA16" )
			)
			( pin "@baseboard_fab2_lib.baseboard_fab2(sch_1):page35_i3:upi2_tx_dn(0)"
				( attribute "PN" "DT21"
					( Origin gPackager )
				)
				( objectStatus "U5D1.DT21" )
			)
			( pin "@baseboard_fab2_lib.baseboard_fab2(sch_1):page35_i3:upi2_tx_dn(1)"
				( attribute "PN" "DM21"
					( Origin gPackager )
				)
				( objectStatus "U5D1.DM21" )
			)
			( pin "@baseboard_fab2_lib.baseboard_fab2(sch_1):page35_i3:upi2_tx_dn(2)"
				( attribute "PN" "DL20"
					( Origin gPackager )
				)
				( objectStatus "U5D1.DL20" )
			)
			( pin "@baseboard_fab2_lib.baseboard_fab2(sch_1):page35_i3:upi2_tx_dn(3)"
				( attribute "PN" "DG20"
					( Origin gPackager )
				)
				( objectStatus "U5D1.DG20" )
			)
			( pin "@baseboard_fab2_lib.baseboard_fab2(sch_1):page35_i3:upi2_tx_dn(4)"
				( attribute "PN" "DH19"
					( Origin gPackager )
				)
				( objectStatus "U5D1.DH19" )
			)
			( pin "@baseboard_fab2_lib.baseboard_fab2(sch_1):page35_i3:upi2_tx_dn(5)"
				( attribute "PN" "DK17"
					( Origin gPackager )
				)
				( objectStatus "U5D1.DK17" )
			)
			( pin "@baseboard_fab2_lib.baseboard_fab2(sch_1):page35_i3:upi2_tx_dn(6)"
				( attribute "PN" "DG18"
					( Origin gPackager )
				)
				( objectStatus "U5D1.DG18" )
			)
			( pin "@baseboard_fab2_lib.baseboard_fab2(sch_1):page35_i3:upi2_tx_dn(7)"
				( attribute "PN" "DD17"
					( Origin gPackager )
				)
				( objectStatus "U5D1.DD17" )
			)
			( pin "@baseboard_fab2_lib.baseboard_fab2(sch_1):page35_i3:upi2_tx_dn(8)"
				( attribute "PN" "DF15"
					( Origin gPackager )
				)
				( objectStatus "U5D1.DF15" )
			)
			( pin "@baseboard_fab2_lib.baseboard_fab2(sch_1):page35_i3:upi2_tx_dn(9)"
				( attribute "PN" "DC16"
					( Origin gPackager )
				)
				( objectStatus "U5D1.DC16" )
			)
			( pin "@baseboard_fab2_lib.baseboard_fab2(sch_1):page35_i3:upi2_tx_dn(10)"
				( attribute "PN" "DA16"
					( Origin gPackager )
				)
				( objectStatus "U5D1.DA16" )
			)
			( pin "@baseboard_fab2_lib.baseboard_fab2(sch_1):page35_i3:upi2_tx_dn(11)"
				( attribute "PN" "CW14"
					( Origin gPackager )
				)
				( objectStatus "U5D1.CW14" )
			)
			( pin "@baseboard_fab2_lib.baseboard_fab2(sch_1):page35_i3:upi2_tx_dn(12)"
				( attribute "PN" "CU14"
					( Origin gPackager )
				)
				( objectStatus "U5D1.CU14" )
			)
			( pin "@baseboard_fab2_lib.baseboard_fab2(sch_1):page35_i3:upi2_tx_dn(13)"
				( attribute "PN" "CM13"
					( Origin gPackager )
				)
				( objectStatus "U5D1.CM13" )
			)
			( pin "@baseboard_fab2_lib.baseboard_fab2(sch_1):page35_i3:upi2_tx_dn(14)"
				( attribute "PN" "CJ14"
					( Origin gPackager )
				)
				( objectStatus "U5D1.CJ14" )
			)
			( pin "@baseboard_fab2_lib.baseboard_fab2(sch_1):page35_i3:upi2_tx_dn(15)"
				( attribute "PN" "CF13"
					( Origin gPackager )
				)
				( objectStatus "U5D1.CF13" )
			)
			( pin "@baseboard_fab2_lib.baseboard_fab2(sch_1):page35_i3:upi2_tx_dn(16)"
				( attribute "PN" "CH11"
					( Origin gPackager )
				)
				( objectStatus "U5D1.CH11" )
			)
			( pin "@baseboard_fab2_lib.baseboard_fab2(sch_1):page35_i3:upi2_tx_dn(17)"
				( attribute "PN" "CE12"
					( Origin gPackager )
				)
				( objectStatus "U5D1.CE12" )
			)
			( pin "@baseboard_fab2_lib.baseboard_fab2(sch_1):page35_i3:upi2_tx_dn(18)"
				( attribute "PN" "CC10"
					( Origin gPackager )
				)
				( objectStatus "U5D1.CC10" )
			)
			( pin "@baseboard_fab2_lib.baseboard_fab2(sch_1):page35_i3:upi2_tx_dn(19)"
				( attribute "PN" "CC12"
					( Origin gPackager )
				)
				( objectStatus "U5D1.CC12" )
			)
			( pin "@baseboard_fab2_lib.baseboard_fab2(sch_1):page35_i3:upi2_tx_dp(0)"
				( attribute "PN" "DP21"
					( Origin gPackager )
				)
				( objectStatus "U5D1.DP21" )
			)
			( pin "@baseboard_fab2_lib.baseboard_fab2(sch_1):page35_i3:upi2_tx_dp(1)"
				( attribute "PN" "DN20"
					( Origin gPackager )
				)
				( objectStatus "U5D1.DN20" )
			)
			( pin "@baseboard_fab2_lib.baseboard_fab2(sch_1):page35_i3:upi2_tx_dp(2)"
				( attribute "PN" "DK19"
					( Origin gPackager )
				)
				( objectStatus "U5D1.DK19" )
			)
			( pin "@baseboard_fab2_lib.baseboard_fab2(sch_1):page35_i3:upi2_tx_dp(3)"
				( attribute "PN" "DJ20"
					( Origin gPackager )
				)
				( objectStatus "U5D1.DJ20" )
			)
			( pin "@baseboard_fab2_lib.baseboard_fab2(sch_1):page35_i3:upi2_tx_dp(4)"
				( attribute "PN" "DJ18"
					( Origin gPackager )
				)
				( objectStatus "U5D1.DJ18" )
			)
			( pin "@baseboard_fab2_lib.baseboard_fab2(sch_1):page35_i3:upi2_tx_dp(5)"
				( attribute "PN" "DH17"
					( Origin gPackager )
				)
				( objectStatus "U5D1.DH17" )
			)
			( pin "@baseboard_fab2_lib.baseboard_fab2(sch_1):page35_i3:upi2_tx_dp(6)"
				( attribute "PN" "DF17"
					( Origin gPackager )
				)
				( objectStatus "U5D1.DF17" )
			)
			( pin "@baseboard_fab2_lib.baseboard_fab2(sch_1):page35_i3:upi2_tx_dp(7)"
				( attribute "PN" "DE16"
					( Origin gPackager )
				)
				( objectStatus "U5D1.DE16" )
			)
			( pin "@baseboard_fab2_lib.baseboard_fab2(sch_1):page35_i3:upi2_tx_dp(8)"
				( attribute "PN" "DD15"
					( Origin gPackager )
				)
				( objectStatus "U5D1.DD15" )
			)
			( pin "@baseboard_fab2_lib.baseboard_fab2(sch_1):page35_i3:upi2_tx_dp(9)"
				( attribute "PN" "DB15"
					( Origin gPackager )
				)
				( objectStatus "U5D1.DB15" )
			)
			( pin "@baseboard_fab2_lib.baseboard_fab2(sch_1):page35_i3:upi2_tx_dp(10)"
				( attribute "PN" "CW16"
					( Origin gPackager )
				)
				( objectStatus "U5D1.CW16" )
			)
			( pin "@baseboard_fab2_lib.baseboard_fab2(sch_1):page35_i3:upi2_tx_dp(11)"
				( attribute "PN" "CV13"
					( Origin gPackager )
				)
				( objectStatus "U5D1.CV13" )
			)
			( pin "@baseboard_fab2_lib.baseboard_fab2(sch_1):page35_i3:upi2_tx_dp(12)"
				( attribute "PN" "CR14"
					( Origin gPackager )
				)
				( objectStatus "U5D1.CR14" )
			)
			( pin "@baseboard_fab2_lib.baseboard_fab2(sch_1):page35_i3:upi2_tx_dp(13)"
				( attribute "PN" "CK13"
					( Origin gPackager )
				)
				( objectStatus "U5D1.CK13" )
			)
			( pin "@baseboard_fab2_lib.baseboard_fab2(sch_1):page35_i3:upi2_tx_dp(14)"
				( attribute "PN" "CH13"
					( Origin gPackager )
				)
				( objectStatus "U5D1.CH13" )
			)
			( pin "@baseboard_fab2_lib.baseboard_fab2(sch_1):page35_i3:upi2_tx_dp(15)"
				( attribute "PN" "CG12"
					( Origin gPackager )
				)
				( objectStatus "U5D1.CG12" )
			)
			( pin "@baseboard_fab2_lib.baseboard_fab2(sch_1):page35_i3:upi2_tx_dp(16)"
				( attribute "PN" "CF11"
					( Origin gPackager )
				)
				( objectStatus "U5D1.CF11" )
			)
			( pin "@baseboard_fab2_lib.baseboard_fab2(sch_1):page35_i3:upi2_tx_dp(17)"
				( attribute "PN" "CD11"
					( Origin gPackager )
				)
				( objectStatus "U5D1.CD11" )
			)
			( pin "@baseboard_fab2_lib.baseboard_fab2(sch_1):page35_i3:upi2_tx_dp(18)"
				( attribute "PN" "CB11"
					( Origin gPackager )
				)
				( objectStatus "U5D1.CB11" )
			)
			( pin "@baseboard_fab2_lib.baseboard_fab2(sch_1):page35_i3:upi2_tx_dp(19)"
				( attribute "PN" "CA12"
					( Origin gPackager )
				)
				( objectStatus "U5D1.CA12" )
			)
			( pin "@baseboard_fab2_lib.baseboard_fab2(sch_1):page36_i15:rsvd(92)"
				( attribute "PN" "CH23"
					( Origin gPackager )
				)
				( objectStatus "U5D1.CH23" )
			)
			( pin "@baseboard_fab2_lib.baseboard_fab2(sch_1):page36_i15:rsvd(93)"
				( attribute "PN" "CH21"
					( Origin gPackager )
				)
				( objectStatus "U5D1.CH21" )
			)
			( pin "@baseboard_fab2_lib.baseboard_fab2(sch_1):page36_i15:rsvd(94)"
				( attribute "PN" "CG82"
					( Origin gPackager )
				)
				( objectStatus "U5D1.CG82" )
			)
			( pin "@baseboard_fab2_lib.baseboard_fab2(sch_1):page36_i15:rsvd(95)"
				( attribute "PN" "CG78"
					( Origin gPackager )
				)
				( objectStatus "U5D1.CG78" )
			)
			( pin "@baseboard_fab2_lib.baseboard_fab2(sch_1):page36_i15:rsvd(96)"
				( attribute "PN" "CG26"
					( Origin gPackager )
				)
				( objectStatus "U5D1.CG26" )
			)
			( pin "@baseboard_fab2_lib.baseboard_fab2(sch_1):page36_i15:rsvd(97)"
				( attribute "PN" "CG24"
					( Origin gPackager )
				)
				( objectStatus "U5D1.CG24" )
			)
			( pin "@baseboard_fab2_lib.baseboard_fab2(sch_1):page36_i15:rsvd(98)"
				( attribute "PN" "CG20"
					( Origin gPackager )
				)
				( objectStatus "U5D1.CG20" )
			)
			( pin "@baseboard_fab2_lib.baseboard_fab2(sch_1):page36_i15:rsvd(99)"
				( attribute "PN" "CG10"
					( Origin gPackager )
				)
				( objectStatus "U5D1.CG10" )
			)
			( pin "@baseboard_fab2_lib.baseboard_fab2(sch_1):page36_i15:rsvd(100)"
				( attribute "PN" "CF81"
					( Origin gPackager )
				)
				( objectStatus "U5D1.CF81" )
			)
			( pin "@baseboard_fab2_lib.baseboard_fab2(sch_1):page36_i15:rsvd(101)"
				( attribute "PN" "CF79"
					( Origin gPackager )
				)
				( objectStatus "U5D1.CF79" )
			)
			( pin "@baseboard_fab2_lib.baseboard_fab2(sch_1):page36_i15:rsvd(102)"
				( attribute "PN" "CF23"
					( Origin gPackager )
				)
				( objectStatus "U5D1.CF23" )
			)
			( pin "@baseboard_fab2_lib.baseboard_fab2(sch_1):page36_i15:rsvd(103)"
				( attribute "PN" "CF21"
					( Origin gPackager )
				)
				( objectStatus "U5D1.CF21" )
			)
			( pin "@baseboard_fab2_lib.baseboard_fab2(sch_1):page36_i15:rsvd(104)"
				( attribute "PN" "CF19"
					( Origin gPackager )
				)
				( objectStatus "U5D1.CF19" )
			)
			( pin "@baseboard_fab2_lib.baseboard_fab2(sch_1):page36_i15:rsvd(105)"
				( attribute "PN" "CE80"
					( Origin gPackager )
				)
				( objectStatus "U5D1.CE80" )
			)
			( pin "@baseboard_fab2_lib.baseboard_fab2(sch_1):page36_i15:rsvd(106)"
				( attribute "PN" "CE78"
					( Origin gPackager )
				)
				( objectStatus "U5D1.CE78" )
			)
			( pin "@baseboard_fab2_lib.baseboard_fab2(sch_1):page36_i15:rsvd(107)"
				( attribute "PN" "CE22"
					( Origin gPackager )
				)
				( objectStatus "U5D1.CE22" )
			)
			( pin "@baseboard_fab2_lib.baseboard_fab2(sch_1):page36_i15:rsvd(108)"
				( attribute "PN" "CD25"
					( Origin gPackager )
				)
				( objectStatus "U5D1.CD25" )
			)
			( pin "@baseboard_fab2_lib.baseboard_fab2(sch_1):page36_i15:rsvd(109)"
				( attribute "PN" "CD21"
					( Origin gPackager )
				)
				( objectStatus "U5D1.CD21" )
			)
			( pin "@baseboard_fab2_lib.baseboard_fab2(sch_1):page36_i15:rsvd(110)"
				( attribute "PN" "CD19"
					( Origin gPackager )
				)
				( objectStatus "U5D1.CD19" )
			)
			( pin "@baseboard_fab2_lib.baseboard_fab2(sch_1):page36_i15:rsvd(111)"
				( attribute "PN" "CC6"
					( Origin gPackager )
				)
				( objectStatus "U5D1.CC6" )
			)
			( pin "@baseboard_fab2_lib.baseboard_fab2(sch_1):page36_i15:rsvd(112)"
				( attribute "PN" "CC20"
					( Origin gPackager )
				)
				( objectStatus "U5D1.CC20" )
			)
			( pin "@baseboard_fab2_lib.baseboard_fab2(sch_1):page36_i15:rsvd(113)"
				( attribute "PN" "CB5"
					( Origin gPackager )
				)
				( objectStatus "U5D1.CB5" )
			)
			( pin "@baseboard_fab2_lib.baseboard_fab2(sch_1):page36_i15:rsvd(114)"
				( attribute "PN" "CB25"
					( Origin gPackager )
				)
				( objectStatus "U5D1.CB25" )
			)
			( pin "@baseboard_fab2_lib.baseboard_fab2(sch_1):page36_i15:rsvd(115)"
				( attribute "PN" "CB21"
					( Origin gPackager )
				)
				( objectStatus "U5D1.CB21" )
			)
			( pin "@baseboard_fab2_lib.baseboard_fab2(sch_1):page36_i15:rsvd(116)"
				( attribute "PN" "CB19"
					( Origin gPackager )
				)
				( objectStatus "U5D1.CB19" )
			)
			( pin "@baseboard_fab2_lib.baseboard_fab2(sch_1):page36_i15:rsvd(117)"
				( attribute "PN" "CA24"
					( Origin gPackager )
				)
				( objectStatus "U5D1.CA24" )
			)
			( pin "@baseboard_fab2_lib.baseboard_fab2(sch_1):page36_i15:rsvd(118)"
				( attribute "PN" "CA22"
					( Origin gPackager )
				)
				( objectStatus "U5D1.CA22" )
			)
			( pin "@baseboard_fab2_lib.baseboard_fab2(sch_1):page36_i15:rsvd(119)"
				( attribute "PN" "BY25"
					( Origin gPackager )
				)
				( objectStatus "U5D1.BY25" )
			)
			( pin "@baseboard_fab2_lib.baseboard_fab2(sch_1):page36_i15:rsvd(120)"
				( attribute "PN" "BY19"
					( Origin gPackager )
				)
				( objectStatus "U5D1.BY19" )
			)
			( pin "@baseboard_fab2_lib.baseboard_fab2(sch_1):page36_i15:rsvd(121)"
				( attribute "PN" "BW22"
					( Origin gPackager )
				)
				( objectStatus "U5D1.BW22" )
			)
			( pin "@baseboard_fab2_lib.baseboard_fab2(sch_1):page36_i15:rsvd(122)"
				( attribute "PN" "BW20"
					( Origin gPackager )
				)
				( objectStatus "U5D1.BW20" )
			)
			( pin "@baseboard_fab2_lib.baseboard_fab2(sch_1):page36_i15:rsvd(123)"
				( attribute "PN" "BW10"
					( Origin gPackager )
				)
				( objectStatus "U5D1.BW10" )
			)
			( pin "@baseboard_fab2_lib.baseboard_fab2(sch_1):page36_i15:rsvd(124)"
				( attribute "PN" "BV23"
					( Origin gPackager )
				)
				( objectStatus "U5D1.BV23" )
			)
			( pin "@baseboard_fab2_lib.baseboard_fab2(sch_1):page36_i15:rsvd(125)"
				( attribute "PN" "BV21"
					( Origin gPackager )
				)
				( objectStatus "U5D1.BV21" )
			)
			( pin "@baseboard_fab2_lib.baseboard_fab2(sch_1):page36_i15:rsvd(126)"
				( attribute "PN" "BV19"
					( Origin gPackager )
				)
				( objectStatus "U5D1.BV19" )
			)
			( pin "@baseboard_fab2_lib.baseboard_fab2(sch_1):page36_i15:rsvd(127)"
				( attribute "PN" "BU22"
					( Origin gPackager )
				)
				( objectStatus "U5D1.BU22" )
			)
			( pin "@baseboard_fab2_lib.baseboard_fab2(sch_1):page36_i15:rsvd(128)"
				( attribute "PN" "BU20"
					( Origin gPackager )
				)
				( objectStatus "U5D1.BU20" )
			)
			( pin "@baseboard_fab2_lib.baseboard_fab2(sch_1):page36_i15:rsvd(129)"
				( attribute "PN" "BU18"
					( Origin gPackager )
				)
				( objectStatus "U5D1.BU18" )
			)
			( pin "@baseboard_fab2_lib.baseboard_fab2(sch_1):page36_i15:rsvd(130)"
				( attribute "PN" "BR24"
					( Origin gPackager )
				)
				( objectStatus "U5D1.BR24" )
			)
			( pin "@baseboard_fab2_lib.baseboard_fab2(sch_1):page36_i15:rsvd(131)"
				( attribute "PN" "BR22"
					( Origin gPackager )
				)
				( objectStatus "U5D1.BR22" )
			)
			( pin "@baseboard_fab2_lib.baseboard_fab2(sch_1):page36_i15:rsvd(132)"
				( attribute "PN" "BP21"
					( Origin gPackager )
				)
				( objectStatus "U5D1.BP21" )
			)
			( pin "@baseboard_fab2_lib.baseboard_fab2(sch_1):page36_i15:rsvd(133)"
				( attribute "PN" "BP17"
					( Origin gPackager )
				)
				( objectStatus "U5D1.BP17" )
			)
			( pin "@baseboard_fab2_lib.baseboard_fab2(sch_1):page36_i15:rsvd(134)"
				( attribute "PN" "BN18"
					( Origin gPackager )
				)
				( objectStatus "U5D1.BN18" )
			)
			( pin "@baseboard_fab2_lib.baseboard_fab2(sch_1):page36_i15:rsvd(135)"
				( attribute "PN" "BM19"
					( Origin gPackager )
				)
				( objectStatus "U5D1.BM19" )
			)
			( pin "@baseboard_fab2_lib.baseboard_fab2(sch_1):page36_i15:rsvd(136)"
				( attribute "PN" "BM17"
					( Origin gPackager )
				)
				( objectStatus "U5D1.BM17" )
			)
			( pin "@baseboard_fab2_lib.baseboard_fab2(sch_1):page36_i15:rsvd(137)"
				( attribute "PN" "BL20"
					( Origin gPackager )
				)
				( objectStatus "U5D1.BL20" )
			)
			( pin "@baseboard_fab2_lib.baseboard_fab2(sch_1):page36_i15:rsvd(138)"
				( attribute "PN" "BL18"
					( Origin gPackager )
				)
				( objectStatus "U5D1.BL18" )
			)
			( pin "@baseboard_fab2_lib.baseboard_fab2(sch_1):page36_i15:rsvd(139)"
				( attribute "PN" "BK17"
					( Origin gPackager )
				)
				( objectStatus "U5D1.BK17" )
			)
			( pin "@baseboard_fab2_lib.baseboard_fab2(sch_1):page36_i15:rsvd(140)"
				( attribute "PN" "BJ20"
					( Origin gPackager )
				)
				( objectStatus "U5D1.BJ20" )
			)
			( pin "@baseboard_fab2_lib.baseboard_fab2(sch_1):page36_i15:rsvd(141)"
				( attribute "PN" "BJ18"
					( Origin gPackager )
				)
				( objectStatus "U5D1.BJ18" )
			)
			( pin "@baseboard_fab2_lib.baseboard_fab2(sch_1):page36_i15:rsvd(142)"
				( attribute "PN" "BJ16"
					( Origin gPackager )
				)
				( objectStatus "U5D1.BJ16" )
			)
			( pin "@baseboard_fab2_lib.baseboard_fab2(sch_1):page36_i15:rsvd(143)"
				( attribute "PN" "BH19"
					( Origin gPackager )
				)
				( objectStatus "U5D1.BH19" )
			)
			( pin "@baseboard_fab2_lib.baseboard_fab2(sch_1):page36_i15:rsvd(144)"
				( attribute "PN" "BG20"
					( Origin gPackager )
				)
				( objectStatus "U5D1.BG20" )
			)
			( pin "@baseboard_fab2_lib.baseboard_fab2(sch_1):page36_i15:rsvd(145)"
				( attribute "PN" "BG18"
					( Origin gPackager )
				)
				( objectStatus "U5D1.BG18" )
			)
			( pin "@baseboard_fab2_lib.baseboard_fab2(sch_1):page36_i15:rsvd(146)"
				( attribute "PN" "BF21"
					( Origin gPackager )
				)
				( objectStatus "U5D1.BF21" )
			)
			( pin "@baseboard_fab2_lib.baseboard_fab2(sch_1):page36_i15:rsvd(147)"
				( attribute "PN" "BE22"
					( Origin gPackager )
				)
				( objectStatus "U5D1.BE22" )
			)
			( pin "@baseboard_fab2_lib.baseboard_fab2(sch_1):page36_i15:rsvd(148)"
				( attribute "PN" "BE20"
					( Origin gPackager )
				)
				( objectStatus "U5D1.BE20" )
			)
			( pin "@baseboard_fab2_lib.baseboard_fab2(sch_1):page36_i15:rsvd(149)"
				( attribute "PN" "BE18"
					( Origin gPackager )
				)
				( objectStatus "U5D1.BE18" )
			)
			( pin "@baseboard_fab2_lib.baseboard_fab2(sch_1):page36_i15:rsvd(150)"
				( attribute "PN" "BD69"
					( Origin gPackager )
				)
				( objectStatus "U5D1.BD69" )
			)
			( pin "@baseboard_fab2_lib.baseboard_fab2(sch_1):page36_i15:rsvd(151)"
				( attribute "PN" "BD67"
					( Origin gPackager )
				)
				( objectStatus "U5D1.BD67" )
			)
			( pin "@baseboard_fab2_lib.baseboard_fab2(sch_1):page36_i15:rsvd(152)"
				( attribute "PN" "BD65"
					( Origin gPackager )
				)
				( objectStatus "U5D1.BD65" )
			)
			( pin "@baseboard_fab2_lib.baseboard_fab2(sch_1):page36_i15:rsvd(153)"
				( attribute "PN" "BD25"
					( Origin gPackager )
				)
				( objectStatus "U5D1.BD25" )
			)
			( pin "@baseboard_fab2_lib.baseboard_fab2(sch_1):page36_i15:rsvd(154)"
				( attribute "PN" "BD19"
					( Origin gPackager )
				)
				( objectStatus "U5D1.BD19" )
			)
			( pin "@baseboard_fab2_lib.baseboard_fab2(sch_1):page36_i15:rsvd(155)"
				( attribute "PN" "BD17"
					( Origin gPackager )
				)
				( objectStatus "U5D1.BD17" )
			)
			( pin "@baseboard_fab2_lib.baseboard_fab2(sch_1):page36_i15:rsvd(156)"
				( attribute "PN" "BC68"
					( Origin gPackager )
				)
				( objectStatus "U5D1.BC68" )
			)
			( pin "@baseboard_fab2_lib.baseboard_fab2(sch_1):page36_i15:rsvd(157)"
				( attribute "PN" "BC66"
					( Origin gPackager )
				)
				( objectStatus "U5D1.BC66" )
			)
			( pin "@baseboard_fab2_lib.baseboard_fab2(sch_1):page36_i15:rsvd(158)"
				( attribute "PN" "BC64"
					( Origin gPackager )
				)
				( objectStatus "U5D1.BC64" )
			)
			( pin "@baseboard_fab2_lib.baseboard_fab2(sch_1):page36_i15:rsvd(159)"
				( attribute "PN" "BC22"
					( Origin gPackager )
				)
				( objectStatus "U5D1.BC22" )
			)
			( pin "@baseboard_fab2_lib.baseboard_fab2(sch_1):page36_i15:rsvd(160)"
				( attribute "PN" "BC20"
					( Origin gPackager )
				)
				( objectStatus "U5D1.BC20" )
			)
			( pin "@baseboard_fab2_lib.baseboard_fab2(sch_1):page36_i15:rsvd(161)"
				( attribute "PN" "BC18"
					( Origin gPackager )
				)
				( objectStatus "U5D1.BC18" )
			)
			( pin "@baseboard_fab2_lib.baseboard_fab2(sch_1):page36_i15:rsvd(162)"
				( attribute "PN" "BC14"
					( Origin gPackager )
				)
				( objectStatus "U5D1.BC14" )
			)
			( pin "@baseboard_fab2_lib.baseboard_fab2(sch_1):page36_i15:rsvd(163)"
				( attribute "PN" "BB67"
					( Origin gPackager )
				)
				( objectStatus "U5D1.BB67" )
			)
			( pin "@baseboard_fab2_lib.baseboard_fab2(sch_1):page36_i15:rsvd(164)"
				( attribute "PN" "BB65"
					( Origin gPackager )
				)
				( objectStatus "U5D1.BB65" )
			)
			( pin "@baseboard_fab2_lib.baseboard_fab2(sch_1):page36_i15:rsvd(165)"
				( attribute "PN" "BB25"
					( Origin gPackager )
				)
				( objectStatus "U5D1.BB25" )
			)
			( pin "@baseboard_fab2_lib.baseboard_fab2(sch_1):page36_i15:rsvd(166)"
				( attribute "PN" "BB21"
					( Origin gPackager )
				)
				( objectStatus "U5D1.BB21" )
			)
			( pin "@baseboard_fab2_lib.baseboard_fab2(sch_1):page36_i15:rsvd(167)"
				( attribute "PN" "BB17"
					( Origin gPackager )
				)
				( objectStatus "U5D1.BB17" )
			)
			( pin "@baseboard_fab2_lib.baseboard_fab2(sch_1):page36_i15:rsvd(168)"
				( attribute "PN" "BB15"
					( Origin gPackager )
				)
				( objectStatus "U5D1.BB15" )
			)
			( pin "@baseboard_fab2_lib.baseboard_fab2(sch_1):page36_i15:rsvd(169)"
				( attribute "PN" "BB13"
					( Origin gPackager )
				)
				( objectStatus "U5D1.BB13" )
			)
			( pin "@baseboard_fab2_lib.baseboard_fab2(sch_1):page36_i15:rsvd(170)"
				( attribute "PN" "BA82"
					( Origin gPackager )
				)
				( objectStatus "U5D1.BA82" )
			)
			( pin "@baseboard_fab2_lib.baseboard_fab2(sch_1):page36_i15:rsvd(171)"
				( attribute "PN" "BA78"
					( Origin gPackager )
				)
				( objectStatus "U5D1.BA78" )
			)
			( pin "@baseboard_fab2_lib.baseboard_fab2(sch_1):page36_i15:rsvd(172)"
				( attribute "CDS_NOT_ON_SYM" "TRUE"
					( Origin gFrontEnd )
				)
			)
			( pin "@baseboard_fab2_lib.baseboard_fab2(sch_1):page36_i15:rsvd(173)"
				( attribute "CDS_NOT_ON_SYM" "TRUE"
					( Origin gFrontEnd )
				)
			)
			( pin "@baseboard_fab2_lib.baseboard_fab2(sch_1):page36_i15:rsvd(174)"
				( attribute "CDS_NOT_ON_SYM" "TRUE"
					( Origin gFrontEnd )
				)
			)
			( pin "@baseboard_fab2_lib.baseboard_fab2(sch_1):page36_i15:rsvd(175)"
				( attribute "CDS_NOT_ON_SYM" "TRUE"
					( Origin gFrontEnd )
				)
			)
			( pin "@baseboard_fab2_lib.baseboard_fab2(sch_1):page36_i15:rsvd(176)"
				( attribute "CDS_NOT_ON_SYM" "TRUE"
					( Origin gFrontEnd )
				)
			)
			( pin "@baseboard_fab2_lib.baseboard_fab2(sch_1):page36_i15:rsvd(177)"
				( attribute "CDS_NOT_ON_SYM" "TRUE"
					( Origin gFrontEnd )
				)
			)
			( pin "@baseboard_fab2_lib.baseboard_fab2(sch_1):page36_i15:rsvd(178)"
				( attribute "CDS_NOT_ON_SYM" "TRUE"
					( Origin gFrontEnd )
				)
			)
			( pin "@baseboard_fab2_lib.baseboard_fab2(sch_1):page36_i15:rsvd(179)"
				( attribute "CDS_NOT_ON_SYM" "TRUE"
					( Origin gFrontEnd )
				)
			)
			( pin "@baseboard_fab2_lib.baseboard_fab2(sch_1):page36_i15:rsvd(180)"
				( attribute "CDS_NOT_ON_SYM" "TRUE"
					( Origin gFrontEnd )
				)
			)
			( pin "@baseboard_fab2_lib.baseboard_fab2(sch_1):page36_i15:rsvd(181)"
				( attribute "CDS_NOT_ON_SYM" "TRUE"
					( Origin gFrontEnd )
				)
			)
			( pin "@baseboard_fab2_lib.baseboard_fab2(sch_1):page36_i15:rsvd(182)"
				( attribute "CDS_NOT_ON_SYM" "TRUE"
					( Origin gFrontEnd )
				)
			)
			( pin "@baseboard_fab2_lib.baseboard_fab2(sch_1):page36_i15:rsvd(183)"
				( attribute "CDS_NOT_ON_SYM" "TRUE"
					( Origin gFrontEnd )
				)
			)
			( pin "@baseboard_fab2_lib.baseboard_fab2(sch_1):page36_i15:rsvd(184)"
				( attribute "CDS_NOT_ON_SYM" "TRUE"
					( Origin gFrontEnd )
				)
			)
			( pin "@baseboard_fab2_lib.baseboard_fab2(sch_1):page36_i15:rsvd(185)"
				( attribute "CDS_NOT_ON_SYM" "TRUE"
					( Origin gFrontEnd )
				)
			)
			( pin "@baseboard_fab2_lib.baseboard_fab2(sch_1):page36_i15:rsvd(186)"
				( attribute "CDS_NOT_ON_SYM" "TRUE"
					( Origin gFrontEnd )
				)
			)
			( pin "@baseboard_fab2_lib.baseboard_fab2(sch_1):page36_i15:rsvd(187)"
				( attribute "CDS_NOT_ON_SYM" "TRUE"
					( Origin gFrontEnd )
				)
			)
			( pin "@baseboard_fab2_lib.baseboard_fab2(sch_1):page36_i15:rsvd(188)"
				( attribute "CDS_NOT_ON_SYM" "TRUE"
					( Origin gFrontEnd )
				)
			)
			( pin "@baseboard_fab2_lib.baseboard_fab2(sch_1):page36_i15:rsvd(189)"
				( attribute "CDS_NOT_ON_SYM" "TRUE"
					( Origin gFrontEnd )
				)
			)
			( pin "@baseboard_fab2_lib.baseboard_fab2(sch_1):page36_i15:rsvd(190)"
				( attribute "CDS_NOT_ON_SYM" "TRUE"
					( Origin gFrontEnd )
				)
			)
			( pin "@baseboard_fab2_lib.baseboard_fab2(sch_1):page36_i15:rsvd(191)"
				( attribute "CDS_NOT_ON_SYM" "TRUE"
					( Origin gFrontEnd )
				)
			)
			( pin "@baseboard_fab2_lib.baseboard_fab2(sch_1):page36_i15:rsvd(192)"
				( attribute "CDS_NOT_ON_SYM" "TRUE"
					( Origin gFrontEnd )
				)
			)
			( pin "@baseboard_fab2_lib.baseboard_fab2(sch_1):page36_i15:rsvd(193)"
				( attribute "CDS_NOT_ON_SYM" "TRUE"
					( Origin gFrontEnd )
				)
			)
			( pin "@baseboard_fab2_lib.baseboard_fab2(sch_1):page36_i15:rsvd(194)"
				( attribute "CDS_NOT_ON_SYM" "TRUE"
					( Origin gFrontEnd )
				)
			)
			( pin "@baseboard_fab2_lib.baseboard_fab2(sch_1):page36_i15:rsvd(195)"
				( attribute "CDS_NOT_ON_SYM" "TRUE"
					( Origin gFrontEnd )
				)
			)
			( pin "@baseboard_fab2_lib.baseboard_fab2(sch_1):page36_i15:rsvd(196)"
				( attribute "CDS_NOT_ON_SYM" "TRUE"
					( Origin gFrontEnd )
				)
			)
			( pin "@baseboard_fab2_lib.baseboard_fab2(sch_1):page36_i15:rsvd(197)"
				( attribute "CDS_NOT_ON_SYM" "TRUE"
					( Origin gFrontEnd )
				)
			)
			( pin "@baseboard_fab2_lib.baseboard_fab2(sch_1):page36_i15:rsvd(198)"
				( attribute "CDS_NOT_ON_SYM" "TRUE"
					( Origin gFrontEnd )
				)
			)
			( pin "@baseboard_fab2_lib.baseboard_fab2(sch_1):page36_i15:rsvd(199)"
				( attribute "CDS_NOT_ON_SYM" "TRUE"
					( Origin gFrontEnd )
				)
			)
			( pin "@baseboard_fab2_lib.baseboard_fab2(sch_1):page36_i15:rsvd(200)"
				( attribute "CDS_NOT_ON_SYM" "TRUE"
					( Origin gFrontEnd )
				)
			)
			( pin "@baseboard_fab2_lib.baseboard_fab2(sch_1):page36_i15:rsvd(201)"
				( attribute "CDS_NOT_ON_SYM" "TRUE"
					( Origin gFrontEnd )
				)
			)
			( pin "@baseboard_fab2_lib.baseboard_fab2(sch_1):page36_i15:rsvd(202)"
				( attribute "CDS_NOT_ON_SYM" "TRUE"
					( Origin gFrontEnd )
				)
			)
			( pin "@baseboard_fab2_lib.baseboard_fab2(sch_1):page36_i15:rsvd(203)"
				( attribute "CDS_NOT_ON_SYM" "TRUE"
					( Origin gFrontEnd )
				)
			)
			( pin "@baseboard_fab2_lib.baseboard_fab2(sch_1):page36_i15:rsvd(204)"
				( attribute "CDS_NOT_ON_SYM" "TRUE"
					( Origin gFrontEnd )
				)
			)
			( pin "@baseboard_fab2_lib.baseboard_fab2(sch_1):page36_i15:rsvd(205)"
				( attribute "CDS_NOT_ON_SYM" "TRUE"
					( Origin gFrontEnd )
				)
			)
			( pin "@baseboard_fab2_lib.baseboard_fab2(sch_1):page36_i15:rsvd(206)"
				( attribute "CDS_NOT_ON_SYM" "TRUE"
					( Origin gFrontEnd )
				)
			)
			( pin "@baseboard_fab2_lib.baseboard_fab2(sch_1):page36_i15:rsvd(207)"
				( attribute "CDS_NOT_ON_SYM" "TRUE"
					( Origin gFrontEnd )
				)
			)
			( pin "@baseboard_fab2_lib.baseboard_fab2(sch_1):page36_i15:rsvd(208)"
				( attribute "CDS_NOT_ON_SYM" "TRUE"
					( Origin gFrontEnd )
				)
			)
			( pin "@baseboard_fab2_lib.baseboard_fab2(sch_1):page36_i15:rsvd(209)"
				( attribute "CDS_NOT_ON_SYM" "TRUE"
					( Origin gFrontEnd )
				)
			)
			( pin "@baseboard_fab2_lib.baseboard_fab2(sch_1):page36_i15:rsvd(210)"
				( attribute "CDS_NOT_ON_SYM" "TRUE"
					( Origin gFrontEnd )
				)
			)
			( pin "@baseboard_fab2_lib.baseboard_fab2(sch_1):page36_i15:rsvd(211)"
				( attribute "CDS_NOT_ON_SYM" "TRUE"
					( Origin gFrontEnd )
				)
			)
			( pin "@baseboard_fab2_lib.baseboard_fab2(sch_1):page36_i15:rsvd(212)"
				( attribute "CDS_NOT_ON_SYM" "TRUE"
					( Origin gFrontEnd )
				)
			)
			( pin "@baseboard_fab2_lib.baseboard_fab2(sch_1):page36_i15:rsvd(213)"
				( attribute "CDS_NOT_ON_SYM" "TRUE"
					( Origin gFrontEnd )
				)
			)
			( pin "@baseboard_fab2_lib.baseboard_fab2(sch_1):page36_i15:rsvd(214)"
				( attribute "CDS_NOT_ON_SYM" "TRUE"
					( Origin gFrontEnd )
				)
			)
			( pin "@baseboard_fab2_lib.baseboard_fab2(sch_1):page36_i15:rsvd(215)"
				( attribute "CDS_NOT_ON_SYM" "TRUE"
					( Origin gFrontEnd )
				)
			)
			( pin "@baseboard_fab2_lib.baseboard_fab2(sch_1):page36_i15:rsvd(216)"
				( attribute "CDS_NOT_ON_SYM" "TRUE"
					( Origin gFrontEnd )
				)
			)
			( pin "@baseboard_fab2_lib.baseboard_fab2(sch_1):page36_i15:rsvd(217)"
				( attribute "CDS_NOT_ON_SYM" "TRUE"
					( Origin gFrontEnd )
				)
			)
			( pin "@baseboard_fab2_lib.baseboard_fab2(sch_1):page36_i15:rsvd(218)"
				( attribute "CDS_NOT_ON_SYM" "TRUE"
					( Origin gFrontEnd )
				)
			)
			( pin "@baseboard_fab2_lib.baseboard_fab2(sch_1):page36_i15:rsvd(219)"
				( attribute "CDS_NOT_ON_SYM" "TRUE"
					( Origin gFrontEnd )
				)
			)
			( pin "@baseboard_fab2_lib.baseboard_fab2(sch_1):page36_i15:rsvd(220)"
				( attribute "CDS_NOT_ON_SYM" "TRUE"
					( Origin gFrontEnd )
				)
			)
			( pin "@baseboard_fab2_lib.baseboard_fab2(sch_1):page36_i15:rsvd(221)"
				( attribute "CDS_NOT_ON_SYM" "TRUE"
					( Origin gFrontEnd )
				)
			)
			( pin "@baseboard_fab2_lib.baseboard_fab2(sch_1):page36_i15:rsvd(222)"
				( attribute "CDS_NOT_ON_SYM" "TRUE"
					( Origin gFrontEnd )
				)
			)
			( pin "@baseboard_fab2_lib.baseboard_fab2(sch_1):page36_i15:rsvd(223)"
				( attribute "CDS_NOT_ON_SYM" "TRUE"
					( Origin gFrontEnd )
				)
			)
			( pin "@baseboard_fab2_lib.baseboard_fab2(sch_1):page36_i15:rsvd(224)"
				( attribute "CDS_NOT_ON_SYM" "TRUE"
					( Origin gFrontEnd )
				)
			)
			( pin "@baseboard_fab2_lib.baseboard_fab2(sch_1):page36_i15:rsvd(225)"
				( attribute "CDS_NOT_ON_SYM" "TRUE"
					( Origin gFrontEnd )
				)
			)
			( pin "@baseboard_fab2_lib.baseboard_fab2(sch_1):page36_i15:rsvd(226)"
				( attribute "CDS_NOT_ON_SYM" "TRUE"
					( Origin gFrontEnd )
				)
			)
			( pin "@baseboard_fab2_lib.baseboard_fab2(sch_1):page36_i15:rsvd(227)"
				( attribute "CDS_NOT_ON_SYM" "TRUE"
					( Origin gFrontEnd )
				)
			)
			( pin "@baseboard_fab2_lib.baseboard_fab2(sch_1):page36_i15:rsvd(228)"
				( attribute "CDS_NOT_ON_SYM" "TRUE"
					( Origin gFrontEnd )
				)
			)
			( pin "@baseboard_fab2_lib.baseboard_fab2(sch_1):page36_i15:rsvd(229)"
				( attribute "CDS_NOT_ON_SYM" "TRUE"
					( Origin gFrontEnd )
				)
			)
			( pin "@baseboard_fab2_lib.baseboard_fab2(sch_1):page36_i15:rsvd(230)"
				( attribute "CDS_NOT_ON_SYM" "TRUE"
					( Origin gFrontEnd )
				)
			)
			( pin "@baseboard_fab2_lib.baseboard_fab2(sch_1):page36_i15:rsvd(231)"
				( attribute "CDS_NOT_ON_SYM" "TRUE"
					( Origin gFrontEnd )
				)
			)
			( pin "@baseboard_fab2_lib.baseboard_fab2(sch_1):page36_i15:rsvd(232)"
				( attribute "CDS_NOT_ON_SYM" "TRUE"
					( Origin gFrontEnd )
				)
			)
			( pin "@baseboard_fab2_lib.baseboard_fab2(sch_1):page36_i15:rsvd(233)"
				( attribute "CDS_NOT_ON_SYM" "TRUE"
					( Origin gFrontEnd )
				)
			)
			( pin "@baseboard_fab2_lib.baseboard_fab2(sch_1):page36_i15:rsvd(234)"
				( attribute "CDS_NOT_ON_SYM" "TRUE"
					( Origin gFrontEnd )
				)
			)
			( pin "@baseboard_fab2_lib.baseboard_fab2(sch_1):page36_i15:rsvd(235)"
				( attribute "CDS_NOT_ON_SYM" "TRUE"
					( Origin gFrontEnd )
				)
			)
			( pin "@baseboard_fab2_lib.baseboard_fab2(sch_1):page36_i15:rsvd(236)"
				( attribute "CDS_NOT_ON_SYM" "TRUE"
					( Origin gFrontEnd )
				)
			)
			( pin "@baseboard_fab2_lib.baseboard_fab2(sch_1):page36_i15:rsvd(237)"
				( attribute "CDS_NOT_ON_SYM" "TRUE"
					( Origin gFrontEnd )
				)
			)
			( pin "@baseboard_fab2_lib.baseboard_fab2(sch_1):page36_i15:rsvd(238)"
				( attribute "CDS_NOT_ON_SYM" "TRUE"
					( Origin gFrontEnd )
				)
			)
			( pin "@baseboard_fab2_lib.baseboard_fab2(sch_1):page36_i15:rsvd(239)"
				( attribute "CDS_NOT_ON_SYM" "TRUE"
					( Origin gFrontEnd )
				)
			)
			( pin "@baseboard_fab2_lib.baseboard_fab2(sch_1):page36_i15:rsvd(240)"
				( attribute "CDS_NOT_ON_SYM" "TRUE"
					( Origin gFrontEnd )
				)
			)
			( pin "@baseboard_fab2_lib.baseboard_fab2(sch_1):page36_i15:rsvd(241)"
				( attribute "CDS_NOT_ON_SYM" "TRUE"
					( Origin gFrontEnd )
				)
			)
			( pin "@baseboard_fab2_lib.baseboard_fab2(sch_1):page36_i15:rsvd(242)"
				( attribute "CDS_NOT_ON_SYM" "TRUE"
					( Origin gFrontEnd )
				)
			)
			( pin "@baseboard_fab2_lib.baseboard_fab2(sch_1):page36_i15:rsvd(243)"
				( attribute "CDS_NOT_ON_SYM" "TRUE"
					( Origin gFrontEnd )
				)
			)
			( pin "@baseboard_fab2_lib.baseboard_fab2(sch_1):page36_i15:rsvd(244)"
				( attribute "CDS_NOT_ON_SYM" "TRUE"
					( Origin gFrontEnd )
				)
			)
			( pin "@baseboard_fab2_lib.baseboard_fab2(sch_1):page36_i15:rsvd(245)"
				( attribute "CDS_NOT_ON_SYM" "TRUE"
					( Origin gFrontEnd )
				)
			)
			( pin "@baseboard_fab2_lib.baseboard_fab2(sch_1):page36_i15:rsvd(246)"
				( attribute "CDS_NOT_ON_SYM" "TRUE"
					( Origin gFrontEnd )
				)
			)
			( pin "@baseboard_fab2_lib.baseboard_fab2(sch_1):page36_i15:rsvd(247)"
				( attribute "CDS_NOT_ON_SYM" "TRUE"
					( Origin gFrontEnd )
				)
			)
			( pin "@baseboard_fab2_lib.baseboard_fab2(sch_1):page36_i15:rsvd(248)"
				( attribute "CDS_NOT_ON_SYM" "TRUE"
					( Origin gFrontEnd )
				)
			)
			( pin "@baseboard_fab2_lib.baseboard_fab2(sch_1):page36_i15:rsvd(249)"
				( attribute "CDS_NOT_ON_SYM" "TRUE"
					( Origin gFrontEnd )
				)
			)
			( pin "@baseboard_fab2_lib.baseboard_fab2(sch_1):page36_i15:rsvd(250)"
				( attribute "CDS_NOT_ON_SYM" "TRUE"
					( Origin gFrontEnd )
				)
			)
			( pin "@baseboard_fab2_lib.baseboard_fab2(sch_1):page36_i15:rsvd(251)"
				( attribute "CDS_NOT_ON_SYM" "TRUE"
					( Origin gFrontEnd )
				)
			)
			( pin "@baseboard_fab2_lib.baseboard_fab2(sch_1):page36_i15:rsvd(252)"
				( attribute "CDS_NOT_ON_SYM" "TRUE"
					( Origin gFrontEnd )
				)
			)
			( pin "@baseboard_fab2_lib.baseboard_fab2(sch_1):page36_i15:rsvd(253)"
				( attribute "CDS_NOT_ON_SYM" "TRUE"
					( Origin gFrontEnd )
				)
			)
			( pin "@baseboard_fab2_lib.baseboard_fab2(sch_1):page36_i15:rsvd(254)"
				( attribute "CDS_NOT_ON_SYM" "TRUE"
					( Origin gFrontEnd )
				)
			)
			( pin "@baseboard_fab2_lib.baseboard_fab2(sch_1):page36_i15:rsvd(255)"
				( attribute "PN" "AY83"
					( Origin gPackager )
				)
				( objectStatus "U5D1.AY83" )
			)
			( pin "@baseboard_fab2_lib.baseboard_fab2(sch_1):page36_i16:rsvd(81)"
				( attribute "PN" "CL24"
					( Origin gPackager )
				)
				( objectStatus "U5D1.CL24" )
			)
			( pin "@baseboard_fab2_lib.baseboard_fab2(sch_1):page36_i16:rsvd(82)"
				( attribute "PN" "CK77"
					( Origin gPackager )
				)
				( objectStatus "U5D1.CK77" )
			)
			( pin "@baseboard_fab2_lib.baseboard_fab2(sch_1):page36_i16:rsvd(83)"
				( attribute "PN" "CK25"
					( Origin gPackager )
				)
				( objectStatus "U5D1.CK25" )
			)
			( pin "@baseboard_fab2_lib.baseboard_fab2(sch_1):page36_i16:rsvd(84)"
				( attribute "PN" "CK23"
					( Origin gPackager )
				)
				( objectStatus "U5D1.CK23" )
			)
			( pin "@baseboard_fab2_lib.baseboard_fab2(sch_1):page36_i16:rsvd(85)"
				( attribute "PN" "CK19"
					( Origin gPackager )
				)
				( objectStatus "U5D1.CK19" )
			)
			( pin "@baseboard_fab2_lib.baseboard_fab2(sch_1):page36_i16:rsvd(86)"
				( attribute "PN" "CJ26"
					( Origin gPackager )
				)
				( objectStatus "U5D1.CJ26" )
			)
			( pin "@baseboard_fab2_lib.baseboard_fab2(sch_1):page36_i16:rsvd(87)"
				( attribute "PN" "CJ24"
					( Origin gPackager )
				)
				( objectStatus "U5D1.CJ24" )
			)
			( pin "@baseboard_fab2_lib.baseboard_fab2(sch_1):page36_i16:rsvd(88)"
				( attribute "PN" "CJ22"
					( Origin gPackager )
				)
				( objectStatus "U5D1.CJ22" )
			)
			( pin "@baseboard_fab2_lib.baseboard_fab2(sch_1):page36_i16:rsvd(89)"
				( attribute "PN" "CJ20"
					( Origin gPackager )
				)
				( objectStatus "U5D1.CJ20" )
			)
			( pin "@baseboard_fab2_lib.baseboard_fab2(sch_1):page36_i16:rsvd(90)"
				( attribute "PN" "CH77"
					( Origin gPackager )
				)
				( objectStatus "U5D1.CH77" )
			)
			( pin "@baseboard_fab2_lib.baseboard_fab2(sch_1):page36_i16:rsvd(91)"
				( attribute "PN" "CH25"
					( Origin gPackager )
				)
				( objectStatus "U5D1.CH25" )
			)
			( pin "@baseboard_fab2_lib.baseboard_fab2(sch_1):page36_i16:test_6"
				( attribute "PN" "AR16"
					( Origin gPackager )
				)
				( objectStatus "U5D1.AR16" )
			)
			( pin "@baseboard_fab2_lib.baseboard_fab2(sch_1):page36_i16:test_7"
				( attribute "PN" "AU18"
					( Origin gPackager )
				)
				( objectStatus "U5D1.AU18" )
			)
			( pin "@baseboard_fab2_lib.baseboard_fab2(sch_1):page36_i16:test_8"
				( attribute "PN" "AW16"
					( Origin gPackager )
				)
				( objectStatus "U5D1.AW16" )
			)
			( pin "@baseboard_fab2_lib.baseboard_fab2(sch_1):page36_i16:test_9"
				( attribute "PN" "AW20"
					( Origin gPackager )
				)
				( objectStatus "U5D1.AW20" )
			)
			( pin "@baseboard_fab2_lib.baseboard_fab2(sch_1):page36_i16:test_10"
				( attribute "PN" "AW22"
					( Origin gPackager )
				)
				( objectStatus "U5D1.AW22" )
			)
			( pin "@baseboard_fab2_lib.baseboard_fab2(sch_1):page37_i303:a"
				( attribute "PN" "1"
					( Origin gPackager )
				)
				( objectStatus "R5D5.1" )
			)
			( pin "@baseboard_fab2_lib.baseboard_fab2(sch_1):page37_i303:b"
				( attribute "PN" "2"
					( Origin gPackager )
				)
				( objectStatus "R5D5.2" )
			)
			( pin "@baseboard_fab2_lib.baseboard_fab2(sch_1):page37_i309:a"
				( attribute "PN" "1"
					( Origin gPackager )
				)
				( objectStatus "R5P1.1" )
			)
			( pin "@baseboard_fab2_lib.baseboard_fab2(sch_1):page37_i309:b"
				( attribute "PN" "2"
					( Origin gPackager )
				)
				( objectStatus "R5P1.2" )
			)
			( pin "@baseboard_fab2_lib.baseboard_fab2(sch_1):page37_i310:vccin(130)"
				( attribute "PN" "BN78"
					( Origin gPackager )
				)
				( objectStatus "U5D1.BN78" )
			)
			( pin "@baseboard_fab2_lib.baseboard_fab2(sch_1):page37_i310:vccin(131)"
				( attribute "PN" "BN76"
					( Origin gPackager )
				)
				( objectStatus "U5D1.BN76" )
			)
			( pin "@baseboard_fab2_lib.baseboard_fab2(sch_1):page37_i310:vccin(132)"
				( attribute "PN" "BN74"
					( Origin gPackager )
				)
				( objectStatus "U5D1.BN74" )
			)
			( pin "@baseboard_fab2_lib.baseboard_fab2(sch_1):page37_i310:vccin(133)"
				( attribute "PN" "BN72"
					( Origin gPackager )
				)
				( objectStatus "U5D1.BN72" )
			)
			( pin "@baseboard_fab2_lib.baseboard_fab2(sch_1):page37_i310:vccin(134)"
				( attribute "PN" "BN70"
					( Origin gPackager )
				)
				( objectStatus "U5D1.BN70" )
			)
			( pin "@baseboard_fab2_lib.baseboard_fab2(sch_1):page37_i310:vccin(135)"
				( attribute "PN" "BN68"
					( Origin gPackager )
				)
				( objectStatus "U5D1.BN68" )
			)
			( pin "@baseboard_fab2_lib.baseboard_fab2(sch_1):page37_i310:vccin(136)"
				( attribute "PN" "BN66"
					( Origin gPackager )
				)
				( objectStatus "U5D1.BN66" )
			)
			( pin "@baseboard_fab2_lib.baseboard_fab2(sch_1):page37_i310:vccin(137)"
				( attribute "PN" "BN64"
					( Origin gPackager )
				)
				( objectStatus "U5D1.BN64" )
			)
			( pin "@baseboard_fab2_lib.baseboard_fab2(sch_1):page37_i310:vccin(138)"
				( attribute "PN" "BN62"
					( Origin gPackager )
				)
				( objectStatus "U5D1.BN62" )
			)
			( pin "@baseboard_fab2_lib.baseboard_fab2(sch_1):page37_i310:vccin(139)"
				( attribute "PN" "BN60"
					( Origin gPackager )
				)
				( objectStatus "U5D1.BN60" )
			)
			( pin "@baseboard_fab2_lib.baseboard_fab2(sch_1):page37_i310:vccin(140)"
				( attribute "PN" "BM83"
					( Origin gPackager )
				)
				( objectStatus "U5D1.BM83" )
			)
			( pin "@baseboard_fab2_lib.baseboard_fab2(sch_1):page37_i310:vccin(141)"
				( attribute "PN" "BM81"
					( Origin gPackager )
				)
				( objectStatus "U5D1.BM81" )
			)
			( pin "@baseboard_fab2_lib.baseboard_fab2(sch_1):page37_i310:vccin(142)"
				( attribute "PN" "BM79"
					( Origin gPackager )
				)
				( objectStatus "U5D1.BM79" )
			)
			( pin "@baseboard_fab2_lib.baseboard_fab2(sch_1):page37_i310:vccin(143)"
				( attribute "PN" "BM77"
					( Origin gPackager )
				)
				( objectStatus "U5D1.BM77" )
			)
			( pin "@baseboard_fab2_lib.baseboard_fab2(sch_1):page37_i310:vccin(144)"
				( attribute "PN" "BM75"
					( Origin gPackager )
				)
				( objectStatus "U5D1.BM75" )
			)
			( pin "@baseboard_fab2_lib.baseboard_fab2(sch_1):page37_i310:vccin(145)"
				( attribute "PN" "BM73"
					( Origin gPackager )
				)
				( objectStatus "U5D1.BM73" )
			)
			( pin "@baseboard_fab2_lib.baseboard_fab2(sch_1):page37_i310:vccin(146)"
				( attribute "PN" "BM71"
					( Origin gPackager )
				)
				( objectStatus "U5D1.BM71" )
			)
			( pin "@baseboard_fab2_lib.baseboard_fab2(sch_1):page37_i310:vccin(147)"
				( attribute "PN" "BM69"
					( Origin gPackager )
				)
				( objectStatus "U5D1.BM69" )
			)
			( pin "@baseboard_fab2_lib.baseboard_fab2(sch_1):page37_i310:vccin(148)"
				( attribute "PN" "BM67"
					( Origin gPackager )
				)
				( objectStatus "U5D1.BM67" )
			)
			( pin "@baseboard_fab2_lib.baseboard_fab2(sch_1):page37_i310:vccin(149)"
				( attribute "PN" "BM65"
					( Origin gPackager )
				)
				( objectStatus "U5D1.BM65" )
			)
			( pin "@baseboard_fab2_lib.baseboard_fab2(sch_1):page37_i310:vccin(150)"
				( attribute "PN" "BM63"
					( Origin gPackager )
				)
				( objectStatus "U5D1.BM63" )
			)
			( pin "@baseboard_fab2_lib.baseboard_fab2(sch_1):page37_i310:vccin(151)"
				( attribute "PN" "BM61"
					( Origin gPackager )
				)
				( objectStatus "U5D1.BM61" )
			)
			( pin "@baseboard_fab2_lib.baseboard_fab2(sch_1):page37_i310:vccin(152)"
				( attribute "PN" "BL84"
					( Origin gPackager )
				)
				( objectStatus "U5D1.BL84" )
			)
			( pin "@baseboard_fab2_lib.baseboard_fab2(sch_1):page37_i310:vccin(153)"
				( attribute "PN" "BL62"
					( Origin gPackager )
				)
				( objectStatus "U5D1.BL62" )
			)
			( pin "@baseboard_fab2_lib.baseboard_fab2(sch_1):page37_i310:vccin(154)"
				( attribute "PN" "BL60"
					( Origin gPackager )
				)
				( objectStatus "U5D1.BL60" )
			)
			( pin "@baseboard_fab2_lib.baseboard_fab2(sch_1):page37_i310:vccin(155)"
				( attribute "PN" "BK83"
					( Origin gPackager )
				)
				( objectStatus "U5D1.BK83" )
			)
			( pin "@baseboard_fab2_lib.baseboard_fab2(sch_1):page37_i310:vccin(156)"
				( attribute "PN" "BK81"
					( Origin gPackager )
				)
				( objectStatus "U5D1.BK81" )
			)
			( pin "@baseboard_fab2_lib.baseboard_fab2(sch_1):page37_i310:vccin(157)"
				( attribute "PN" "BK79"
					( Origin gPackager )
				)
				( objectStatus "U5D1.BK79" )
			)
			( pin "@baseboard_fab2_lib.baseboard_fab2(sch_1):page37_i310:vccin(158)"
				( attribute "PN" "BK77"
					( Origin gPackager )
				)
				( objectStatus "U5D1.BK77" )
			)
			( pin "@baseboard_fab2_lib.baseboard_fab2(sch_1):page37_i310:vccin(159)"
				( attribute "PN" "BK75"
					( Origin gPackager )
				)
				( objectStatus "U5D1.BK75" )
			)
			( pin "@baseboard_fab2_lib.baseboard_fab2(sch_1):page37_i310:vccin(160)"
				( attribute "PN" "BK73"
					( Origin gPackager )
				)
				( objectStatus "U5D1.BK73" )
			)
			( pin "@baseboard_fab2_lib.baseboard_fab2(sch_1):page37_i310:vccin(161)"
				( attribute "PN" "BK71"
					( Origin gPackager )
				)
				( objectStatus "U5D1.BK71" )
			)
			( pin "@baseboard_fab2_lib.baseboard_fab2(sch_1):page37_i310:vccin(162)"
				( attribute "PN" "BK69"
					( Origin gPackager )
				)
				( objectStatus "U5D1.BK69" )
			)
			( pin "@baseboard_fab2_lib.baseboard_fab2(sch_1):page37_i310:vccin(163)"
				( attribute "PN" "BK67"
					( Origin gPackager )
				)
				( objectStatus "U5D1.BK67" )
			)
			( pin "@baseboard_fab2_lib.baseboard_fab2(sch_1):page37_i310:vccin(164)"
				( attribute "PN" "BK65"
					( Origin gPackager )
				)
				( objectStatus "U5D1.BK65" )
			)
			( pin "@baseboard_fab2_lib.baseboard_fab2(sch_1):page37_i310:vccin(165)"
				( attribute "PN" "BK63"
					( Origin gPackager )
				)
				( objectStatus "U5D1.BK63" )
			)
			( pin "@baseboard_fab2_lib.baseboard_fab2(sch_1):page37_i310:vccin(166)"
				( attribute "PN" "BK61"
					( Origin gPackager )
				)
				( objectStatus "U5D1.BK61" )
			)
			( pin "@baseboard_fab2_lib.baseboard_fab2(sch_1):page37_i310:vccin(167)"
				( attribute "PN" "BJ84"
					( Origin gPackager )
				)
				( objectStatus "U5D1.BJ84" )
			)
			( pin "@baseboard_fab2_lib.baseboard_fab2(sch_1):page37_i310:vccin(168)"
				( attribute "PN" "BJ82"
					( Origin gPackager )
				)
				( objectStatus "U5D1.BJ82" )
			)
			( pin "@baseboard_fab2_lib.baseboard_fab2(sch_1):page37_i310:vccin(169)"
				( attribute "PN" "BJ80"
					( Origin gPackager )
				)
				( objectStatus "U5D1.BJ80" )
			)
			( pin "@baseboard_fab2_lib.baseboard_fab2(sch_1):page37_i310:vccin(170)"
				( attribute "PN" "BJ78"
					( Origin gPackager )
				)
				( objectStatus "U5D1.BJ78" )
			)
			( pin "@baseboard_fab2_lib.baseboard_fab2(sch_1):page37_i310:vccin(171)"
				( attribute "PN" "BJ76"
					( Origin gPackager )
				)
				( objectStatus "U5D1.BJ76" )
			)
			( pin "@baseboard_fab2_lib.baseboard_fab2(sch_1):page37_i310:vccin(172)"
				( attribute "PN" "BJ74"
					( Origin gPackager )
				)
				( objectStatus "U5D1.BJ74" )
			)
			( pin "@baseboard_fab2_lib.baseboard_fab2(sch_1):page37_i310:vccin(173)"
				( attribute "PN" "BJ72"
					( Origin gPackager )
				)
				( objectStatus "U5D1.BJ72" )
			)
			( pin "@baseboard_fab2_lib.baseboard_fab2(sch_1):page37_i310:vccin(174)"
				( attribute "PN" "BJ70"
					( Origin gPackager )
				)
				( objectStatus "U5D1.BJ70" )
			)
			( pin "@baseboard_fab2_lib.baseboard_fab2(sch_1):page37_i310:vccin(175)"
				( attribute "PN" "BJ68"
					( Origin gPackager )
				)
				( objectStatus "U5D1.BJ68" )
			)
			( pin "@baseboard_fab2_lib.baseboard_fab2(sch_1):page37_i310:vccin(176)"
				( attribute "PN" "BJ66"
					( Origin gPackager )
				)
				( objectStatus "U5D1.BJ66" )
			)
			( pin "@baseboard_fab2_lib.baseboard_fab2(sch_1):page37_i310:vccin(177)"
				( attribute "PN" "BJ64"
					( Origin gPackager )
				)
				( objectStatus "U5D1.BJ64" )
			)
			( pin "@baseboard_fab2_lib.baseboard_fab2(sch_1):page37_i310:vccin(178)"
				( attribute "PN" "BJ62"
					( Origin gPackager )
				)
				( objectStatus "U5D1.BJ62" )
			)
			( pin "@baseboard_fab2_lib.baseboard_fab2(sch_1):page37_i310:vccin(179)"
				( attribute "PN" "BJ60"
					( Origin gPackager )
				)
				( objectStatus "U5D1.BJ60" )
			)
			( pin "@baseboard_fab2_lib.baseboard_fab2(sch_1):page37_i310:vccin(180)"
				( attribute "PN" "BH83"
					( Origin gPackager )
				)
				( objectStatus "U5D1.BH83" )
			)
			( pin "@baseboard_fab2_lib.baseboard_fab2(sch_1):page37_i310:vccin(181)"
				( attribute "PN" "BH81"
					( Origin gPackager )
				)
				( objectStatus "U5D1.BH81" )
			)
			( pin "@baseboard_fab2_lib.baseboard_fab2(sch_1):page37_i310:vccin(182)"
				( attribute "PN" "BH79"
					( Origin gPackager )
				)
				( objectStatus "U5D1.BH79" )
			)
			( pin "@baseboard_fab2_lib.baseboard_fab2(sch_1):page37_i310:vccin(183)"
				( attribute "PN" "BH77"
					( Origin gPackager )
				)
				( objectStatus "U5D1.BH77" )
			)
			( pin "@baseboard_fab2_lib.baseboard_fab2(sch_1):page37_i310:vccin(184)"
				( attribute "PN" "BH75"
					( Origin gPackager )
				)
				( objectStatus "U5D1.BH75" )
			)
			( pin "@baseboard_fab2_lib.baseboard_fab2(sch_1):page37_i310:vccin(185)"
				( attribute "PN" "BH73"
					( Origin gPackager )
				)
				( objectStatus "U5D1.BH73" )
			)
			( pin "@baseboard_fab2_lib.baseboard_fab2(sch_1):page37_i310:vccin(186)"
				( attribute "PN" "BH71"
					( Origin gPackager )
				)
				( objectStatus "U5D1.BH71" )
			)
			( pin "@baseboard_fab2_lib.baseboard_fab2(sch_1):page37_i310:vccin(187)"
				( attribute "PN" "BH69"
					( Origin gPackager )
				)
				( objectStatus "U5D1.BH69" )
			)
			( pin "@baseboard_fab2_lib.baseboard_fab2(sch_1):page37_i310:vccin(188)"
				( attribute "PN" "BH67"
					( Origin gPackager )
				)
				( objectStatus "U5D1.BH67" )
			)
			( pin "@baseboard_fab2_lib.baseboard_fab2(sch_1):page37_i310:vccin(189)"
				( attribute "PN" "BH65"
					( Origin gPackager )
				)
				( objectStatus "U5D1.BH65" )
			)
			( pin "@baseboard_fab2_lib.baseboard_fab2(sch_1):page37_i310:vccin(190)"
				( attribute "PN" "BH63"
					( Origin gPackager )
				)
				( objectStatus "U5D1.BH63" )
			)
			( pin "@baseboard_fab2_lib.baseboard_fab2(sch_1):page37_i310:vccin(191)"
				( attribute "PN" "BH61"
					( Origin gPackager )
				)
				( objectStatus "U5D1.BH61" )
			)
			( pin "@baseboard_fab2_lib.baseboard_fab2(sch_1):page37_i310:vccin(192)"
				( attribute "PN" "BG84"
					( Origin gPackager )
				)
				( objectStatus "U5D1.BG84" )
			)
			( pin "@baseboard_fab2_lib.baseboard_fab2(sch_1):page37_i310:vccin(193)"
				( attribute "PN" "BG70"
					( Origin gPackager )
				)
				( objectStatus "U5D1.BG70" )
			)
			( pin "@baseboard_fab2_lib.baseboard_fab2(sch_1):page37_i310:vccin(194)"
				( attribute "PN" "BG68"
					( Origin gPackager )
				)
				( objectStatus "U5D1.BG68" )
			)
			( pin "@baseboard_fab2_lib.baseboard_fab2(sch_1):page37_i310:vccin(195)"
				( attribute "PN" "BG66"
					( Origin gPackager )
				)
				( objectStatus "U5D1.BG66" )
			)
			( pin "@baseboard_fab2_lib.baseboard_fab2(sch_1):page37_i310:vccin(196)"
				( attribute "PN" "BG64"
					( Origin gPackager )
				)
				( objectStatus "U5D1.BG64" )
			)
			( pin "@baseboard_fab2_lib.baseboard_fab2(sch_1):page37_i310:vccin(197)"
				( attribute "PN" "BG62"
					( Origin gPackager )
				)
				( objectStatus "U5D1.BG62" )
			)
			( pin "@baseboard_fab2_lib.baseboard_fab2(sch_1):page37_i310:vccin(198)"
				( attribute "PN" "BG60"
					( Origin gPackager )
				)
				( objectStatus "U5D1.BG60" )
			)
			( pin "@baseboard_fab2_lib.baseboard_fab2(sch_1):page37_i310:vccin(199)"
				( attribute "PN" "BF85"
					( Origin gPackager )
				)
				( objectStatus "U5D1.BF85" )
			)
			( pin "@baseboard_fab2_lib.baseboard_fab2(sch_1):page37_i310:vccin(200)"
				( attribute "PN" "BF83"
					( Origin gPackager )
				)
				( objectStatus "U5D1.BF83" )
			)
			( pin "@baseboard_fab2_lib.baseboard_fab2(sch_1):page37_i310:vccin(201)"
				( attribute "PN" "BF81"
					( Origin gPackager )
				)
				( objectStatus "U5D1.BF81" )
			)
			( pin "@baseboard_fab2_lib.baseboard_fab2(sch_1):page37_i310:vccin(202)"
				( attribute "PN" "BF79"
					( Origin gPackager )
				)
				( objectStatus "U5D1.BF79" )
			)
			( pin "@baseboard_fab2_lib.baseboard_fab2(sch_1):page37_i310:vccin(203)"
				( attribute "PN" "BF77"
					( Origin gPackager )
				)
				( objectStatus "U5D1.BF77" )
			)
			( pin "@baseboard_fab2_lib.baseboard_fab2(sch_1):page37_i310:vccin(204)"
				( attribute "PN" "BF75"
					( Origin gPackager )
				)
				( objectStatus "U5D1.BF75" )
			)
			( pin "@baseboard_fab2_lib.baseboard_fab2(sch_1):page37_i310:vccin(205)"
				( attribute "PN" "BF73"
					( Origin gPackager )
				)
				( objectStatus "U5D1.BF73" )
			)
			( pin "@baseboard_fab2_lib.baseboard_fab2(sch_1):page37_i310:vccin(206)"
				( attribute "PN" "BF61"
					( Origin gPackager )
				)
				( objectStatus "U5D1.BF61" )
			)
			( pin "@baseboard_fab2_lib.baseboard_fab2(sch_1):page37_i310:vccin(207)"
				( attribute "PN" "BE84"
					( Origin gPackager )
				)
				( objectStatus "U5D1.BE84" )
			)
			( pin "@baseboard_fab2_lib.baseboard_fab2(sch_1):page37_i310:vccin(208)"
				( attribute "PN" "BE82"
					( Origin gPackager )
				)
				( objectStatus "U5D1.BE82" )
			)
			( pin "@baseboard_fab2_lib.baseboard_fab2(sch_1):page37_i310:vccin(209)"
				( attribute "PN" "BE80"
					( Origin gPackager )
				)
				( objectStatus "U5D1.BE80" )
			)
			( pin "@baseboard_fab2_lib.baseboard_fab2(sch_1):page37_i310:vccin(210)"
				( attribute "PN" "BE78"
					( Origin gPackager )
				)
				( objectStatus "U5D1.BE78" )
			)
			( pin "@baseboard_fab2_lib.baseboard_fab2(sch_1):page37_i310:vccin(211)"
				( attribute "PN" "BE76"
					( Origin gPackager )
				)
				( objectStatus "U5D1.BE76" )
			)
			( pin "@baseboard_fab2_lib.baseboard_fab2(sch_1):page37_i310:vccin(212)"
				( attribute "PN" "BE74"
					( Origin gPackager )
				)
				( objectStatus "U5D1.BE74" )
			)
			( pin "@baseboard_fab2_lib.baseboard_fab2(sch_1):page37_i310:vccin(213)"
				( attribute "PN" "BE72"
					( Origin gPackager )
				)
				( objectStatus "U5D1.BE72" )
			)
			( pin "@baseboard_fab2_lib.baseboard_fab2(sch_1):page37_i310:vccin(214)"
				( attribute "PN" "BE62"
					( Origin gPackager )
				)
				( objectStatus "U5D1.BE62" )
			)
			( pin "@baseboard_fab2_lib.baseboard_fab2(sch_1):page37_i310:vccin(215)"
				( attribute "PN" "BE60"
					( Origin gPackager )
				)
				( objectStatus "U5D1.BE60" )
			)
			( pin "@baseboard_fab2_lib.baseboard_fab2(sch_1):page37_i310:vccin(216)"
				( attribute "PN" "BD85"
					( Origin gPackager )
				)
				( objectStatus "U5D1.BD85" )
			)
			( pin "@baseboard_fab2_lib.baseboard_fab2(sch_1):page37_i310:vccin(217)"
				( attribute "PN" "BD83"
					( Origin gPackager )
				)
				( objectStatus "U5D1.BD83" )
			)
			( pin "@baseboard_fab2_lib.baseboard_fab2(sch_1):page37_i310:vccin(218)"
				( attribute "PN" "BD81"
					( Origin gPackager )
				)
				( objectStatus "U5D1.BD81" )
			)
			( pin "@baseboard_fab2_lib.baseboard_fab2(sch_1):page37_i310:vccin(219)"
				( attribute "PN" "BD79"
					( Origin gPackager )
				)
				( objectStatus "U5D1.BD79" )
			)
			( pin "@baseboard_fab2_lib.baseboard_fab2(sch_1):page37_i310:vccin(220)"
				( attribute "PN" "BD77"
					( Origin gPackager )
				)
				( objectStatus "U5D1.BD77" )
			)
			( pin "@baseboard_fab2_lib.baseboard_fab2(sch_1):page37_i310:vccin(221)"
				( attribute "PN" "BD75"
					( Origin gPackager )
				)
				( objectStatus "U5D1.BD75" )
			)
			( pin "@baseboard_fab2_lib.baseboard_fab2(sch_1):page37_i310:vccin(222)"
				( attribute "PN" "BD73"
					( Origin gPackager )
				)
				( objectStatus "U5D1.BD73" )
			)
			( pin "@baseboard_fab2_lib.baseboard_fab2(sch_1):page37_i310:vccin(223)"
				( attribute "PN" "BD61"
					( Origin gPackager )
				)
				( objectStatus "U5D1.BD61" )
			)
			( pin "@baseboard_fab2_lib.baseboard_fab2(sch_1):page37_i310:vccin(224)"
				( attribute "PN" "BC84"
					( Origin gPackager )
				)
				( objectStatus "U5D1.BC84" )
			)
			( pin "@baseboard_fab2_lib.baseboard_fab2(sch_1):page37_i310:vccin(225)"
				( attribute "PN" "BC62"
					( Origin gPackager )
				)
				( objectStatus "U5D1.BC62" )
			)
			( pin "@baseboard_fab2_lib.baseboard_fab2(sch_1):page37_i310:vccin(226)"
				( attribute "PN" "BC60"
					( Origin gPackager )
				)
				( objectStatus "U5D1.BC60" )
			)
			( pin "@baseboard_fab2_lib.baseboard_fab2(sch_1):page37_i310:vccin(227)"
				( attribute "PN" "BB85"
					( Origin gPackager )
				)
				( objectStatus "U5D1.BB85" )
			)
			( pin "@baseboard_fab2_lib.baseboard_fab2(sch_1):page37_i310:vccin(228)"
				( attribute "PN" "BB61"
					( Origin gPackager )
				)
				( objectStatus "U5D1.BB61" )
			)
			( pin "@baseboard_fab2_lib.baseboard_fab2(sch_1):page37_i310:vccin(229)"
				( attribute "PN" "BA60"
					( Origin gPackager )
				)
				( objectStatus "U5D1.BA60" )
			)
			( pin "@baseboard_fab2_lib.baseboard_fab2(sch_1):page37_i310:vccin(230)"
				( attribute "PN" "AY61"
					( Origin gPackager )
				)
				( objectStatus "U5D1.AY61" )
			)
			( pin "@baseboard_fab2_lib.baseboard_fab2(sch_1):page37_i310:vccin(231)"
				( attribute "PN" "AW60"
					( Origin gPackager )
				)
				( objectStatus "U5D1.AW60" )
			)
			( pin "@baseboard_fab2_lib.baseboard_fab2(sch_1):page37_i310:vccin(232)"
				( attribute "PN" "AV61"
					( Origin gPackager )
				)
				( objectStatus "U5D1.AV61" )
			)
			( pin "@baseboard_fab2_lib.baseboard_fab2(sch_1):page37_i310:vccin(233)"
				( attribute "PN" "AV59"
					( Origin gPackager )
				)
				( objectStatus "U5D1.AV59" )
			)
			( pin "@baseboard_fab2_lib.baseboard_fab2(sch_1):page37_i310:vccin(234)"
				( attribute "PN" "AU60"
					( Origin gPackager )
				)
				( objectStatus "U5D1.AU60" )
			)
			( pin "@baseboard_fab2_lib.baseboard_fab2(sch_1):page37_i310:vccin(235)"
				( attribute "PN" "AU58"
					( Origin gPackager )
				)
				( objectStatus "U5D1.AU58" )
			)
			( pin "@baseboard_fab2_lib.baseboard_fab2(sch_1):page37_i310:vccin(236)"
				( attribute "PN" "AT59"
					( Origin gPackager )
				)
				( objectStatus "U5D1.AT59" )
			)
			( pin "@baseboard_fab2_lib.baseboard_fab2(sch_1):page37_i310:vccin(237)"
				( attribute "PN" "AT57"
					( Origin gPackager )
				)
				( objectStatus "U5D1.AT57" )
			)
			( pin "@baseboard_fab2_lib.baseboard_fab2(sch_1):page37_i310:vccin(238)"
				( attribute "PN" "AR58"
					( Origin gPackager )
				)
				( objectStatus "U5D1.AR58" )
			)
			( pin "@baseboard_fab2_lib.baseboard_fab2(sch_1):page37_i310:vccin(239)"
				( attribute "PN" "AR56"
					( Origin gPackager )
				)
				( objectStatus "U5D1.AR56" )
			)
			( pin "@baseboard_fab2_lib.baseboard_fab2(sch_1):page37_i310:vccin(240)"
				( attribute "PN" "AP57"
					( Origin gPackager )
				)
				( objectStatus "U5D1.AP57" )
			)
			( pin "@baseboard_fab2_lib.baseboard_fab2(sch_1):page37_i310:vccin(241)"
				( attribute "PN" "AP55"
					( Origin gPackager )
				)
				( objectStatus "U5D1.AP55" )
			)
			( pin "@baseboard_fab2_lib.baseboard_fab2(sch_1):page37_i310:vccin(242)"
				( attribute "PN" "AN56"
					( Origin gPackager )
				)
				( objectStatus "U5D1.AN56" )
			)
			( pin "@baseboard_fab2_lib.baseboard_fab2(sch_1):page37_i310:vccin(243)"
				( attribute "PN" "AN54"
					( Origin gPackager )
				)
				( objectStatus "U5D1.AN54" )
			)
			( pin "@baseboard_fab2_lib.baseboard_fab2(sch_1):page37_i310:vccin(244)"
				( attribute "PN" "AN32"
					( Origin gPackager )
				)
				( objectStatus "U5D1.AN32" )
			)
			( pin "@baseboard_fab2_lib.baseboard_fab2(sch_1):page37_i310:vccin(245)"
				( attribute "PN" "AM55"
					( Origin gPackager )
				)
				( objectStatus "U5D1.AM55" )
			)
			( pin "@baseboard_fab2_lib.baseboard_fab2(sch_1):page37_i310:vccin(246)"
				( attribute "PN" "AM53"
					( Origin gPackager )
				)
				( objectStatus "U5D1.AM53" )
			)
			( pin "@baseboard_fab2_lib.baseboard_fab2(sch_1):page37_i310:vccin(247)"
				( attribute "PN" "AM33"
					( Origin gPackager )
				)
				( objectStatus "U5D1.AM33" )
			)
			( pin "@baseboard_fab2_lib.baseboard_fab2(sch_1):page37_i310:vccin(248)"
				( attribute "PN" "AL54"
					( Origin gPackager )
				)
				( objectStatus "U5D1.AL54" )
			)
			( pin "@baseboard_fab2_lib.baseboard_fab2(sch_1):page37_i310:vccin(249)"
				( attribute "PN" "AL52"
					( Origin gPackager )
				)
				( objectStatus "U5D1.AL52" )
			)
			( pin "@baseboard_fab2_lib.baseboard_fab2(sch_1):page37_i310:vccin(250)"
				( attribute "PN" "AL50"
					( Origin gPackager )
				)
				( objectStatus "U5D1.AL50" )
			)
			( pin "@baseboard_fab2_lib.baseboard_fab2(sch_1):page37_i310:vccin(251)"
				( attribute "PN" "AL48"
					( Origin gPackager )
				)
				( objectStatus "U5D1.AL48" )
			)
			( pin "@baseboard_fab2_lib.baseboard_fab2(sch_1):page37_i310:vccin(252)"
				( attribute "PN" "AL46"
					( Origin gPackager )
				)
				( objectStatus "U5D1.AL46" )
			)
			( pin "@baseboard_fab2_lib.baseboard_fab2(sch_1):page37_i310:vccin(253)"
				( attribute "PN" "AL34"
					( Origin gPackager )
				)
				( objectStatus "U5D1.AL34" )
			)
			( pin "@baseboard_fab2_lib.baseboard_fab2(sch_1):page37_i310:vccin(254)"
				( attribute "PN" "AK53"
					( Origin gPackager )
				)
				( objectStatus "U5D1.AK53" )
			)
			( pin "@baseboard_fab2_lib.baseboard_fab2(sch_1):page37_i310:vccin(255)"
				( attribute "PN" "AK51"
					( Origin gPackager )
				)
				( objectStatus "U5D1.AK51" )
			)
			( pin "@baseboard_fab2_lib.baseboard_fab2(sch_1):page37_i310:vccin(256)"
				( attribute "PN" "AK49"
					( Origin gPackager )
				)
				( objectStatus "U5D1.AK49" )
			)
			( pin "@baseboard_fab2_lib.baseboard_fab2(sch_1):page37_i310:vccin(257)"
				( attribute "PN" "AK47"
					( Origin gPackager )
				)
				( objectStatus "U5D1.AK47" )
			)
			( pin "@baseboard_fab2_lib.baseboard_fab2(sch_1):page37_i310:vccin(258)"
				( attribute "PN" "AK45"
					( Origin gPackager )
				)
				( objectStatus "U5D1.AK45" )
			)
			( pin "@baseboard_fab2_lib.baseboard_fab2(sch_1):page37_i310:vccin(259)"
				( attribute "PN" "AK35"
					( Origin gPackager )
				)
				( objectStatus "U5D1.AK35" )
			)
			( pin "@baseboard_fab2_lib.baseboard_fab2(sch_1):page37_i310:vccin(260)"
				( attribute "PN" "AJ36"
					( Origin gPackager )
				)
				( objectStatus "U5D1.AJ36" )
			)
			( pin "@baseboard_fab2_lib.baseboard_fab2(sch_1):page37_i310:vccin(261)"
				( attribute "PN" "AH41"
					( Origin gPackager )
				)
				( objectStatus "U5D1.AH41" )
			)
			( pin "@baseboard_fab2_lib.baseboard_fab2(sch_1):page37_i310:vccin(262)"
				( attribute "PN" "AH39"
					( Origin gPackager )
				)
				( objectStatus "U5D1.AH39" )
			)
			( pin "@baseboard_fab2_lib.baseboard_fab2(sch_1):page37_i310:vccin(263)"
				( attribute "PN" "AH37"
					( Origin gPackager )
				)
				( objectStatus "U5D1.AH37" )
			)
			( pin "@baseboard_fab2_lib.baseboard_fab2(sch_1):page37_i310:vccin(264)"
				( attribute "PN" "AG42"
					( Origin gPackager )
				)
				( objectStatus "U5D1.AG42" )
			)
			( pin "@baseboard_fab2_lib.baseboard_fab2(sch_1):page37_i310:vccin(265)"
				( attribute "PN" "AG40"
					( Origin gPackager )
				)
				( objectStatus "U5D1.AG40" )
			)
			( pin "@baseboard_fab2_lib.baseboard_fab2(sch_1):page37_i310:vccin(266)"
				( attribute "PN" "AG38"
					( Origin gPackager )
				)
				( objectStatus "U5D1.AG38" )
			)
			( pin "@baseboard_fab2_lib.baseboard_fab2(sch_1):page37_i310:vccin(267)"
				( attribute "PN" "AF43"
					( Origin gPackager )
				)
				( objectStatus "U5D1.AF43" )
			)
			( pin "@baseboard_fab2_lib.baseboard_fab2(sch_1):page37_i311:vccin(0)"
				( attribute "PN" "CY49"
					( Origin gPackager )
				)
				( objectStatus "U5D1.CY49" )
			)
			( pin "@baseboard_fab2_lib.baseboard_fab2(sch_1):page37_i311:vccin(1)"
				( attribute "PN" "CY47"
					( Origin gPackager )
				)
				( objectStatus "U5D1.CY47" )
			)
			( pin "@baseboard_fab2_lib.baseboard_fab2(sch_1):page37_i311:vccin(2)"
				( attribute "PN" "CW50"
					( Origin gPackager )
				)
				( objectStatus "U5D1.CW50" )
			)
			( pin "@baseboard_fab2_lib.baseboard_fab2(sch_1):page37_i311:vccin(3)"
				( attribute "PN" "CW48"
					( Origin gPackager )
				)
				( objectStatus "U5D1.CW48" )
			)
			( pin "@baseboard_fab2_lib.baseboard_fab2(sch_1):page37_i311:vccin(4)"
				( attribute "PN" "CW46"
					( Origin gPackager )
				)
				( objectStatus "U5D1.CW46" )
			)
			( pin "@baseboard_fab2_lib.baseboard_fab2(sch_1):page37_i311:vccin(5)"
				( attribute "PN" "CV51"
					( Origin gPackager )
				)
				( objectStatus "U5D1.CV51" )
			)
			( pin "@baseboard_fab2_lib.baseboard_fab2(sch_1):page37_i311:vccin(6)"
				( attribute "PN" "CU54"
					( Origin gPackager )
				)
				( objectStatus "U5D1.CU54" )
			)
			( pin "@baseboard_fab2_lib.baseboard_fab2(sch_1):page37_i311:vccin(7)"
				( attribute "PN" "CU52"
					( Origin gPackager )
				)
				( objectStatus "U5D1.CU52" )
			)
			( pin "@baseboard_fab2_lib.baseboard_fab2(sch_1):page37_i311:vccin(8)"
				( attribute "PN" "CU42"
					( Origin gPackager )
				)
				( objectStatus "U5D1.CU42" )
			)
			( pin "@baseboard_fab2_lib.baseboard_fab2(sch_1):page37_i311:vccin(9)"
				( attribute "PN" "CU40"
					( Origin gPackager )
				)
				( objectStatus "U5D1.CU40" )
			)
			( pin "@baseboard_fab2_lib.baseboard_fab2(sch_1):page37_i311:vccin(10)"
				( attribute "PN" "CU38"
					( Origin gPackager )
				)
				( objectStatus "U5D1.CU38" )
			)
			( pin "@baseboard_fab2_lib.baseboard_fab2(sch_1):page37_i311:vccin(11)"
				( attribute "PN" "CT55"
					( Origin gPackager )
				)
				( objectStatus "U5D1.CT55" )
			)
			( pin "@baseboard_fab2_lib.baseboard_fab2(sch_1):page37_i311:vccin(12)"
				( attribute "PN" "CT53"
					( Origin gPackager )
				)
				( objectStatus "U5D1.CT53" )
			)
			( pin "@baseboard_fab2_lib.baseboard_fab2(sch_1):page37_i311:vccin(13)"
				( attribute "PN" "CT41"
					( Origin gPackager )
				)
				( objectStatus "U5D1.CT41" )
			)
			( pin "@baseboard_fab2_lib.baseboard_fab2(sch_1):page37_i311:vccin(14)"
				( attribute "PN" "CT39"
					( Origin gPackager )
				)
				( objectStatus "U5D1.CT39" )
			)
			( pin "@baseboard_fab2_lib.baseboard_fab2(sch_1):page37_i311:vccin(15)"
				( attribute "PN" "CT37"
					( Origin gPackager )
				)
				( objectStatus "U5D1.CT37" )
			)
			( pin "@baseboard_fab2_lib.baseboard_fab2(sch_1):page37_i311:vccin(16)"
				( attribute "PN" "CR56"
					( Origin gPackager )
				)
				( objectStatus "U5D1.CR56" )
			)
			( pin "@baseboard_fab2_lib.baseboard_fab2(sch_1):page37_i311:vccin(17)"
				( attribute "PN" "CR54"
					( Origin gPackager )
				)
				( objectStatus "U5D1.CR54" )
			)
			( pin "@baseboard_fab2_lib.baseboard_fab2(sch_1):page37_i311:vccin(18)"
				( attribute "PN" "CR34"
					( Origin gPackager )
				)
				( objectStatus "U5D1.CR34" )
			)
			( pin "@baseboard_fab2_lib.baseboard_fab2(sch_1):page37_i311:vccin(19)"
				( attribute "PN" "CP57"
					( Origin gPackager )
				)
				( objectStatus "U5D1.CP57" )
			)
			( pin "@baseboard_fab2_lib.baseboard_fab2(sch_1):page37_i311:vccin(20)"
				( attribute "PN" "CP55"
					( Origin gPackager )
				)
				( objectStatus "U5D1.CP55" )
			)
			( pin "@baseboard_fab2_lib.baseboard_fab2(sch_1):page37_i311:vccin(21)"
				( attribute "PN" "CP33"
					( Origin gPackager )
				)
				( objectStatus "U5D1.CP33" )
			)
			( pin "@baseboard_fab2_lib.baseboard_fab2(sch_1):page37_i311:vccin(22)"
				( attribute "PN" "CN58"
					( Origin gPackager )
				)
				( objectStatus "U5D1.CN58" )
			)
			( pin "@baseboard_fab2_lib.baseboard_fab2(sch_1):page37_i311:vccin(23)"
				( attribute "PN" "CN56"
					( Origin gPackager )
				)
				( objectStatus "U5D1.CN56" )
			)
			( pin "@baseboard_fab2_lib.baseboard_fab2(sch_1):page37_i311:vccin(24)"
				( attribute "PN" "CM59"
					( Origin gPackager )
				)
				( objectStatus "U5D1.CM59" )
			)
			( pin "@baseboard_fab2_lib.baseboard_fab2(sch_1):page37_i311:vccin(25)"
				( attribute "PN" "CM57"
					( Origin gPackager )
				)
				( objectStatus "U5D1.CM57" )
			)
			( pin "@baseboard_fab2_lib.baseboard_fab2(sch_1):page37_i311:vccin(26)"
				( attribute "PN" "CL60"
					( Origin gPackager )
				)
				( objectStatus "U5D1.CL60" )
			)
			( pin "@baseboard_fab2_lib.baseboard_fab2(sch_1):page37_i311:vccin(27)"
				( attribute "PN" "CL58"
					( Origin gPackager )
				)
				( objectStatus "U5D1.CL58" )
			)
			( pin "@baseboard_fab2_lib.baseboard_fab2(sch_1):page37_i311:vccin(28)"
				( attribute "PN" "CK61"
					( Origin gPackager )
				)
				( objectStatus "U5D1.CK61" )
			)
			( pin "@baseboard_fab2_lib.baseboard_fab2(sch_1):page37_i311:vccin(29)"
				( attribute "PN" "CK59"
					( Origin gPackager )
				)
				( objectStatus "U5D1.CK59" )
			)
			( pin "@baseboard_fab2_lib.baseboard_fab2(sch_1):page37_i311:vccin(30)"
				( attribute "PN" "CJ60"
					( Origin gPackager )
				)
				( objectStatus "U5D1.CJ60" )
			)
			( pin "@baseboard_fab2_lib.baseboard_fab2(sch_1):page37_i311:vccin(31)"
				( attribute "PN" "CH85"
					( Origin gPackager )
				)
				( objectStatus "U5D1.CH85" )
			)
			( pin "@baseboard_fab2_lib.baseboard_fab2(sch_1):page37_i311:vccin(32)"
				( attribute "PN" "CH61"
					( Origin gPackager )
				)
				( objectStatus "U5D1.CH61" )
			)
			( pin "@baseboard_fab2_lib.baseboard_fab2(sch_1):page37_i311:vccin(33)"
				( attribute "PN" "CG84"
					( Origin gPackager )
				)
				( objectStatus "U5D1.CG84" )
			)
			( pin "@baseboard_fab2_lib.baseboard_fab2(sch_1):page37_i311:vccin(34)"
				( attribute "PN" "CG60"
					( Origin gPackager )
				)
				( objectStatus "U5D1.CG60" )
			)
			( pin "@baseboard_fab2_lib.baseboard_fab2(sch_1):page37_i311:vccin(35)"
				( attribute "PN" "CF85"
					( Origin gPackager )
				)
				( objectStatus "U5D1.CF85" )
			)
			( pin "@baseboard_fab2_lib.baseboard_fab2(sch_1):page37_i311:vccin(36)"
				( attribute "PN" "CF61"
					( Origin gPackager )
				)
				( objectStatus "U5D1.CF61" )
			)
			( pin "@baseboard_fab2_lib.baseboard_fab2(sch_1):page37_i311:vccin(37)"
				( attribute "PN" "CE84"
					( Origin gPackager )
				)
				( objectStatus "U5D1.CE84" )
			)
			( pin "@baseboard_fab2_lib.baseboard_fab2(sch_1):page37_i311:vccin(38)"
				( attribute "PN" "CE60"
					( Origin gPackager )
				)
				( objectStatus "U5D1.CE60" )
			)
			( pin "@baseboard_fab2_lib.baseboard_fab2(sch_1):page37_i311:vccin(39)"
				( attribute "PN" "CD85"
					( Origin gPackager )
				)
				( objectStatus "U5D1.CD85" )
			)
			( pin "@baseboard_fab2_lib.baseboard_fab2(sch_1):page37_i311:vccin(40)"
				( attribute "PN" "CD83"
					( Origin gPackager )
				)
				( objectStatus "U5D1.CD83" )
			)
			( pin "@baseboard_fab2_lib.baseboard_fab2(sch_1):page37_i311:vccin(41)"
				( attribute "PN" "CD61"
					( Origin gPackager )
				)
				( objectStatus "U5D1.CD61" )
			)
			( pin "@baseboard_fab2_lib.baseboard_fab2(sch_1):page37_i311:vccin(42)"
				( attribute "PN" "CC84"
					( Origin gPackager )
				)
				( objectStatus "U5D1.CC84" )
			)
			( pin "@baseboard_fab2_lib.baseboard_fab2(sch_1):page37_i311:vccin(43)"
				( attribute "PN" "CC62"
					( Origin gPackager )
				)
				( objectStatus "U5D1.CC62" )
			)
			( pin "@baseboard_fab2_lib.baseboard_fab2(sch_1):page37_i311:vccin(44)"
				( attribute "PN" "CC60"
					( Origin gPackager )
				)
				( objectStatus "U5D1.CC60" )
			)
			( pin "@baseboard_fab2_lib.baseboard_fab2(sch_1):page37_i311:vccin(45)"
				( attribute "PN" "CB83"
					( Origin gPackager )
				)
				( objectStatus "U5D1.CB83" )
			)
			( pin "@baseboard_fab2_lib.baseboard_fab2(sch_1):page37_i311:vccin(46)"
				( attribute "PN" "CB81"
					( Origin gPackager )
				)
				( objectStatus "U5D1.CB81" )
			)
			( pin "@baseboard_fab2_lib.baseboard_fab2(sch_1):page37_i311:vccin(47)"
				( attribute "PN" "CB79"
					( Origin gPackager )
				)
				( objectStatus "U5D1.CB79" )
			)
			( pin "@baseboard_fab2_lib.baseboard_fab2(sch_1):page37_i311:vccin(48)"
				( attribute "PN" "CB77"
					( Origin gPackager )
				)
				( objectStatus "U5D1.CB77" )
			)
			( pin "@baseboard_fab2_lib.baseboard_fab2(sch_1):page37_i311:vccin(49)"
				( attribute "PN" "CB75"
					( Origin gPackager )
				)
				( objectStatus "U5D1.CB75" )
			)
			( pin "@baseboard_fab2_lib.baseboard_fab2(sch_1):page37_i311:vccin(50)"
				( attribute "PN" "CB73"
					( Origin gPackager )
				)
				( objectStatus "U5D1.CB73" )
			)
			( pin "@baseboard_fab2_lib.baseboard_fab2(sch_1):page37_i311:vccin(51)"
				( attribute "PN" "CB61"
					( Origin gPackager )
				)
				( objectStatus "U5D1.CB61" )
			)
			( pin "@baseboard_fab2_lib.baseboard_fab2(sch_1):page37_i311:vccin(52)"
				( attribute "PN" "CA84"
					( Origin gPackager )
				)
				( objectStatus "U5D1.CA84" )
			)
			( pin "@baseboard_fab2_lib.baseboard_fab2(sch_1):page37_i311:vccin(53)"
				( attribute "PN" "CA82"
					( Origin gPackager )
				)
				( objectStatus "U5D1.CA82" )
			)
			( pin "@baseboard_fab2_lib.baseboard_fab2(sch_1):page37_i311:vccin(54)"
				( attribute "PN" "CA80"
					( Origin gPackager )
				)
				( objectStatus "U5D1.CA80" )
			)
			( pin "@baseboard_fab2_lib.baseboard_fab2(sch_1):page37_i311:vccin(55)"
				( attribute "PN" "CA78"
					( Origin gPackager )
				)
				( objectStatus "U5D1.CA78" )
			)
			( pin "@baseboard_fab2_lib.baseboard_fab2(sch_1):page37_i311:vccin(56)"
				( attribute "PN" "CA76"
					( Origin gPackager )
				)
				( objectStatus "U5D1.CA76" )
			)
			( pin "@baseboard_fab2_lib.baseboard_fab2(sch_1):page37_i311:vccin(57)"
				( attribute "PN" "CA74"
					( Origin gPackager )
				)
				( objectStatus "U5D1.CA74" )
			)
			( pin "@baseboard_fab2_lib.baseboard_fab2(sch_1):page37_i311:vccin(58)"
				( attribute "PN" "CA72"
					( Origin gPackager )
				)
				( objectStatus "U5D1.CA72" )
			)
			( pin "@baseboard_fab2_lib.baseboard_fab2(sch_1):page37_i311:vccin(59)"
				( attribute "PN" "CA62"
					( Origin gPackager )
				)
				( objectStatus "U5D1.CA62" )
			)
			( pin "@baseboard_fab2_lib.baseboard_fab2(sch_1):page37_i311:vccin(60)"
				( attribute "PN" "CA60"
					( Origin gPackager )
				)
				( objectStatus "U5D1.CA60" )
			)
			( pin "@baseboard_fab2_lib.baseboard_fab2(sch_1):page37_i311:vccin(61)"
				( attribute "PN" "BY83"
					( Origin gPackager )
				)
				( objectStatus "U5D1.BY83" )
			)
			( pin "@baseboard_fab2_lib.baseboard_fab2(sch_1):page37_i311:vccin(62)"
				( attribute "PN" "BY81"
					( Origin gPackager )
				)
				( objectStatus "U5D1.BY81" )
			)
			( pin "@baseboard_fab2_lib.baseboard_fab2(sch_1):page37_i311:vccin(63)"
				( attribute "PN" "BY79"
					( Origin gPackager )
				)
				( objectStatus "U5D1.BY79" )
			)
			( pin "@baseboard_fab2_lib.baseboard_fab2(sch_1):page37_i311:vccin(64)"
				( attribute "PN" "BY77"
					( Origin gPackager )
				)
				( objectStatus "U5D1.BY77" )
			)
			( pin "@baseboard_fab2_lib.baseboard_fab2(sch_1):page37_i311:vccin(65)"
				( attribute "PN" "BY75"
					( Origin gPackager )
				)
				( objectStatus "U5D1.BY75" )
			)
			( pin "@baseboard_fab2_lib.baseboard_fab2(sch_1):page37_i311:vccin(66)"
				( attribute "PN" "BY73"
					( Origin gPackager )
				)
				( objectStatus "U5D1.BY73" )
			)
			( pin "@baseboard_fab2_lib.baseboard_fab2(sch_1):page37_i311:vccin(67)"
				( attribute "PN" "BY61"
					( Origin gPackager )
				)
				( objectStatus "U5D1.BY61" )
			)
			( pin "@baseboard_fab2_lib.baseboard_fab2(sch_1):page37_i311:vccin(68)"
				( attribute "PN" "BW84"
					( Origin gPackager )
				)
				( objectStatus "U5D1.BW84" )
			)
			( pin "@baseboard_fab2_lib.baseboard_fab2(sch_1):page37_i311:vccin(69)"
				( attribute "PN" "BW70"
					( Origin gPackager )
				)
				( objectStatus "U5D1.BW70" )
			)
			( pin "@baseboard_fab2_lib.baseboard_fab2(sch_1):page37_i311:vccin(70)"
				( attribute "PN" "BW68"
					( Origin gPackager )
				)
				( objectStatus "U5D1.BW68" )
			)
			( pin "@baseboard_fab2_lib.baseboard_fab2(sch_1):page37_i311:vccin(71)"
				( attribute "PN" "BW66"
					( Origin gPackager )
				)
				( objectStatus "U5D1.BW66" )
			)
			( pin "@baseboard_fab2_lib.baseboard_fab2(sch_1):page37_i311:vccin(72)"
				( attribute "PN" "BW64"
					( Origin gPackager )
				)
				( objectStatus "U5D1.BW64" )
			)
			( pin "@baseboard_fab2_lib.baseboard_fab2(sch_1):page37_i311:vccin(73)"
				( attribute "PN" "BW62"
					( Origin gPackager )
				)
				( objectStatus "U5D1.BW62" )
			)
			( pin "@baseboard_fab2_lib.baseboard_fab2(sch_1):page37_i311:vccin(74)"
				( attribute "PN" "BW60"
					( Origin gPackager )
				)
				( objectStatus "U5D1.BW60" )
			)
			( pin "@baseboard_fab2_lib.baseboard_fab2(sch_1):page37_i311:vccin(75)"
				( attribute "PN" "BV83"
					( Origin gPackager )
				)
				( objectStatus "U5D1.BV83" )
			)
			( pin "@baseboard_fab2_lib.baseboard_fab2(sch_1):page37_i311:vccin(76)"
				( attribute "PN" "BV81"
					( Origin gPackager )
				)
				( objectStatus "U5D1.BV81" )
			)
			( pin "@baseboard_fab2_lib.baseboard_fab2(sch_1):page37_i311:vccin(77)"
				( attribute "PN" "BV79"
					( Origin gPackager )
				)
				( objectStatus "U5D1.BV79" )
			)
			( pin "@baseboard_fab2_lib.baseboard_fab2(sch_1):page37_i311:vccin(78)"
				( attribute "PN" "BV77"
					( Origin gPackager )
				)
				( objectStatus "U5D1.BV77" )
			)
			( pin "@baseboard_fab2_lib.baseboard_fab2(sch_1):page37_i311:vccin(79)"
				( attribute "PN" "BV75"
					( Origin gPackager )
				)
				( objectStatus "U5D1.BV75" )
			)
			( pin "@baseboard_fab2_lib.baseboard_fab2(sch_1):page37_i311:vccin(80)"
				( attribute "PN" "BV73"
					( Origin gPackager )
				)
				( objectStatus "U5D1.BV73" )
			)
			( pin "@baseboard_fab2_lib.baseboard_fab2(sch_1):page37_i311:vccin(81)"
				( attribute "PN" "BV71"
					( Origin gPackager )
				)
				( objectStatus "U5D1.BV71" )
			)
			( pin "@baseboard_fab2_lib.baseboard_fab2(sch_1):page37_i311:vccin(82)"
				( attribute "PN" "BV69"
					( Origin gPackager )
				)
				( objectStatus "U5D1.BV69" )
			)
			( pin "@baseboard_fab2_lib.baseboard_fab2(sch_1):page37_i311:vccin(83)"
				( attribute "PN" "BV67"
					( Origin gPackager )
				)
				( objectStatus "U5D1.BV67" )
			)
			( pin "@baseboard_fab2_lib.baseboard_fab2(sch_1):page37_i311:vccin(84)"
				( attribute "PN" "BV65"
					( Origin gPackager )
				)
				( objectStatus "U5D1.BV65" )
			)
			( pin "@baseboard_fab2_lib.baseboard_fab2(sch_1):page37_i311:vccin(85)"
				( attribute "PN" "BV63"
					( Origin gPackager )
				)
				( objectStatus "U5D1.BV63" )
			)
			( pin "@baseboard_fab2_lib.baseboard_fab2(sch_1):page37_i311:vccin(86)"
				( attribute "PN" "BV61"
					( Origin gPackager )
				)
				( objectStatus "U5D1.BV61" )
			)
			( pin "@baseboard_fab2_lib.baseboard_fab2(sch_1):page37_i311:vccin(87)"
				( attribute "PN" "BU84"
					( Origin gPackager )
				)
				( objectStatus "U5D1.BU84" )
			)
			( pin "@baseboard_fab2_lib.baseboard_fab2(sch_1):page37_i311:vccin(88)"
				( attribute "PN" "BU82"
					( Origin gPackager )
				)
				( objectStatus "U5D1.BU82" )
			)
			( pin "@baseboard_fab2_lib.baseboard_fab2(sch_1):page37_i311:vccin(89)"
				( attribute "PN" "BU80"
					( Origin gPackager )
				)
				( objectStatus "U5D1.BU80" )
			)
			( pin "@baseboard_fab2_lib.baseboard_fab2(sch_1):page37_i311:vccin(90)"
				( attribute "PN" "BU78"
					( Origin gPackager )
				)
				( objectStatus "U5D1.BU78" )
			)
			( pin "@baseboard_fab2_lib.baseboard_fab2(sch_1):page37_i311:vccin(91)"
				( attribute "PN" "BU76"
					( Origin gPackager )
				)
				( objectStatus "U5D1.BU76" )
			)
			( pin "@baseboard_fab2_lib.baseboard_fab2(sch_1):page37_i311:vccin(92)"
				( attribute "PN" "BU74"
					( Origin gPackager )
				)
				( objectStatus "U5D1.BU74" )
			)
			( pin "@baseboard_fab2_lib.baseboard_fab2(sch_1):page37_i311:vccin(93)"
				( attribute "PN" "BU72"
					( Origin gPackager )
				)
				( objectStatus "U5D1.BU72" )
			)
			( pin "@baseboard_fab2_lib.baseboard_fab2(sch_1):page37_i311:vccin(94)"
				( attribute "PN" "BU70"
					( Origin gPackager )
				)
				( objectStatus "U5D1.BU70" )
			)
			( pin "@baseboard_fab2_lib.baseboard_fab2(sch_1):page37_i311:vccin(95)"
				( attribute "PN" "BU68"
					( Origin gPackager )
				)
				( objectStatus "U5D1.BU68" )
			)
			( pin "@baseboard_fab2_lib.baseboard_fab2(sch_1):page37_i311:vccin(96)"
				( attribute "PN" "BU66"
					( Origin gPackager )
				)
				( objectStatus "U5D1.BU66" )
			)
			( pin "@baseboard_fab2_lib.baseboard_fab2(sch_1):page37_i311:vccin(97)"
				( attribute "PN" "BU64"
					( Origin gPackager )
				)
				( objectStatus "U5D1.BU64" )
			)
			( pin "@baseboard_fab2_lib.baseboard_fab2(sch_1):page37_i311:vccin(98)"
				( attribute "PN" "BU62"
					( Origin gPackager )
				)
				( objectStatus "U5D1.BU62" )
			)
			( pin "@baseboard_fab2_lib.baseboard_fab2(sch_1):page37_i311:vccin(99)"
				( attribute "PN" "BU60"
					( Origin gPackager )
				)
				( objectStatus "U5D1.BU60" )
			)
			( pin "@baseboard_fab2_lib.baseboard_fab2(sch_1):page37_i311:vccin(100)"
				( attribute "PN" "BT83"
					( Origin gPackager )
				)
				( objectStatus "U5D1.BT83" )
			)
			( pin "@baseboard_fab2_lib.baseboard_fab2(sch_1):page37_i311:vccin(101)"
				( attribute "PN" "BT81"
					( Origin gPackager )
				)
				( objectStatus "U5D1.BT81" )
			)
			( pin "@baseboard_fab2_lib.baseboard_fab2(sch_1):page37_i311:vccin(102)"
				( attribute "PN" "BT79"
					( Origin gPackager )
				)
				( objectStatus "U5D1.BT79" )
			)
			( pin "@baseboard_fab2_lib.baseboard_fab2(sch_1):page37_i311:vccin(103)"
				( attribute "PN" "BT77"
					( Origin gPackager )
				)
				( objectStatus "U5D1.BT77" )
			)
			( pin "@baseboard_fab2_lib.baseboard_fab2(sch_1):page37_i311:vccin(104)"
				( attribute "PN" "BT75"
					( Origin gPackager )
				)
				( objectStatus "U5D1.BT75" )
			)
			( pin "@baseboard_fab2_lib.baseboard_fab2(sch_1):page37_i311:vccin(105)"
				( attribute "PN" "BT73"
					( Origin gPackager )
				)
				( objectStatus "U5D1.BT73" )
			)
			( pin "@baseboard_fab2_lib.baseboard_fab2(sch_1):page37_i311:vccin(106)"
				( attribute "PN" "BT71"
					( Origin gPackager )
				)
				( objectStatus "U5D1.BT71" )
			)
			( pin "@baseboard_fab2_lib.baseboard_fab2(sch_1):page37_i311:vccin(107)"
				( attribute "PN" "BT69"
					( Origin gPackager )
				)
				( objectStatus "U5D1.BT69" )
			)
			( pin "@baseboard_fab2_lib.baseboard_fab2(sch_1):page37_i311:vccin(108)"
				( attribute "PN" "BT67"
					( Origin gPackager )
				)
				( objectStatus "U5D1.BT67" )
			)
			( pin "@baseboard_fab2_lib.baseboard_fab2(sch_1):page37_i311:vccin(109)"
				( attribute "PN" "BT65"
					( Origin gPackager )
				)
				( objectStatus "U5D1.BT65" )
			)
			( pin "@baseboard_fab2_lib.baseboard_fab2(sch_1):page37_i311:vccin(110)"
				( attribute "PN" "BT63"
					( Origin gPackager )
				)
				( objectStatus "U5D1.BT63" )
			)
			( pin "@baseboard_fab2_lib.baseboard_fab2(sch_1):page37_i311:vccin(111)"
				( attribute "PN" "BT61"
					( Origin gPackager )
				)
				( objectStatus "U5D1.BT61" )
			)
			( pin "@baseboard_fab2_lib.baseboard_fab2(sch_1):page37_i311:vccin(112)"
				( attribute "PN" "BR84"
					( Origin gPackager )
				)
				( objectStatus "U5D1.BR84" )
			)
			( pin "@baseboard_fab2_lib.baseboard_fab2(sch_1):page37_i311:vccin(113)"
				( attribute "PN" "BR62"
					( Origin gPackager )
				)
				( objectStatus "U5D1.BR62" )
			)
			( pin "@baseboard_fab2_lib.baseboard_fab2(sch_1):page37_i311:vccin(114)"
				( attribute "PN" "BR60"
					( Origin gPackager )
				)
				( objectStatus "U5D1.BR60" )
			)
			( pin "@baseboard_fab2_lib.baseboard_fab2(sch_1):page37_i311:vccin(115)"
				( attribute "PN" "BP83"
					( Origin gPackager )
				)
				( objectStatus "U5D1.BP83" )
			)
			( pin "@baseboard_fab2_lib.baseboard_fab2(sch_1):page37_i311:vccin(116)"
				( attribute "PN" "BP81"
					( Origin gPackager )
				)
				( objectStatus "U5D1.BP81" )
			)
			( pin "@baseboard_fab2_lib.baseboard_fab2(sch_1):page37_i311:vccin(117)"
				( attribute "PN" "BP79"
					( Origin gPackager )
				)
				( objectStatus "U5D1.BP79" )
			)
			( pin "@baseboard_fab2_lib.baseboard_fab2(sch_1):page37_i311:vccin(118)"
				( attribute "PN" "BP77"
					( Origin gPackager )
				)
				( objectStatus "U5D1.BP77" )
			)
			( pin "@baseboard_fab2_lib.baseboard_fab2(sch_1):page37_i311:vccin(119)"
				( attribute "PN" "BP75"
					( Origin gPackager )
				)
				( objectStatus "U5D1.BP75" )
			)
			( pin "@baseboard_fab2_lib.baseboard_fab2(sch_1):page37_i311:vccin(120)"
				( attribute "PN" "BP73"
					( Origin gPackager )
				)
				( objectStatus "U5D1.BP73" )
			)
			( pin "@baseboard_fab2_lib.baseboard_fab2(sch_1):page37_i311:vccin(121)"
				( attribute "PN" "BP71"
					( Origin gPackager )
				)
				( objectStatus "U5D1.BP71" )
			)
			( pin "@baseboard_fab2_lib.baseboard_fab2(sch_1):page37_i311:vccin(122)"
				( attribute "PN" "BP69"
					( Origin gPackager )
				)
				( objectStatus "U5D1.BP69" )
			)
			( pin "@baseboard_fab2_lib.baseboard_fab2(sch_1):page37_i311:vccin(123)"
				( attribute "PN" "BP67"
					( Origin gPackager )
				)
				( objectStatus "U5D1.BP67" )
			)
			( pin "@baseboard_fab2_lib.baseboard_fab2(sch_1):page37_i311:vccin(124)"
				( attribute "PN" "BP65"
					( Origin gPackager )
				)
				( objectStatus "U5D1.BP65" )
			)
			( pin "@baseboard_fab2_lib.baseboard_fab2(sch_1):page37_i311:vccin(125)"
				( attribute "PN" "BP63"
					( Origin gPackager )
				)
				( objectStatus "U5D1.BP63" )
			)
			( pin "@baseboard_fab2_lib.baseboard_fab2(sch_1):page37_i311:vccin(126)"
				( attribute "PN" "BP61"
					( Origin gPackager )
				)
				( objectStatus "U5D1.BP61" )
			)
			( pin "@baseboard_fab2_lib.baseboard_fab2(sch_1):page37_i311:vccin(127)"
				( attribute "PN" "BN84"
					( Origin gPackager )
				)
				( objectStatus "U5D1.BN84" )
			)
			( pin "@baseboard_fab2_lib.baseboard_fab2(sch_1):page37_i311:vccin(128)"
				( attribute "PN" "BN82"
					( Origin gPackager )
				)
				( objectStatus "U5D1.BN82" )
			)
			( pin "@baseboard_fab2_lib.baseboard_fab2(sch_1):page37_i311:vccin(129)"
				( attribute "PN" "BN80"
					( Origin gPackager )
				)
				( objectStatus "U5D1.BN80" )
			)
			( pin "@baseboard_fab2_lib.baseboard_fab2(sch_1):page37_i311:vccin_sense"
				( attribute "PN" "BA86"
					( Origin gPackager )
				)
				( objectStatus "U5D1.BA86" )
			)
			( pin "@baseboard_fab2_lib.baseboard_fab2(sch_1):page37_i311:vccinpmax(0)"
				( attribute "PN" "AW86"
					( Origin gPackager )
				)
				( objectStatus "U5D1.AW86" )
			)
			( pin "@baseboard_fab2_lib.baseboard_fab2(sch_1):page37_i311:vccinpmax(1)"
				( attribute "PN" "AV85"
					( Origin gPackager )
				)
				( objectStatus "U5D1.AV85" )
			)
			( pin "@baseboard_fab2_lib.baseboard_fab2(sch_1):page37_i311:vsensepmax"
				( attribute "PN" "AD41"
					( Origin gPackager )
				)
				( objectStatus "U5D1.AD41" )
			)
			( pin "@baseboard_fab2_lib.baseboard_fab2(sch_1):page37_i311:vss_vccin_sense"
				( attribute "PN" "AY85"
					( Origin gPackager )
				)
				( objectStatus "U5D1.AY85" )
			)
			( pin "@baseboard_fab2_lib.baseboard_fab2(sch_1):page37_i312:a"
				( attribute "PN" "1"
					( Origin gPackager )
				)
				( objectStatus "R5D6.1" )
			)
			( pin "@baseboard_fab2_lib.baseboard_fab2(sch_1):page37_i312:b"
				( attribute "PN" "2"
					( Origin gPackager )
				)
				( objectStatus "R5D6.2" )
			)
			( pin "@baseboard_fab2_lib.baseboard_fab2(sch_1):page38_i19:a"
				( attribute "PN" "1"
					( Origin gPackager )
				)
				( objectStatus "C6D1.1" )
			)
			( pin "@baseboard_fab2_lib.baseboard_fab2(sch_1):page38_i19:b"
				( attribute "PN" "2"
					( Origin gPackager )
				)
				( objectStatus "C6D1.2" )
			)
			( pin "@baseboard_fab2_lib.baseboard_fab2(sch_1):page38_i33:vccd012(0)"
				( attribute "PN" "B49"
					( Origin gPackager )
				)
				( objectStatus "U5D1.B49" )
			)
			( pin "@baseboard_fab2_lib.baseboard_fab2(sch_1):page38_i33:vccd012(1)"
				( attribute "PN" "B53"
					( Origin gPackager )
				)
				( objectStatus "U5D1.B53" )
			)
			( pin "@baseboard_fab2_lib.baseboard_fab2(sch_1):page38_i33:vccd012(2)"
				( attribute "PN" "B59"
					( Origin gPackager )
				)
				( objectStatus "U5D1.B59" )
			)
			( pin "@baseboard_fab2_lib.baseboard_fab2(sch_1):page38_i33:vccd012(3)"
				( attribute "PN" "E46"
					( Origin gPackager )
				)
				( objectStatus "U5D1.E46" )
			)
			( pin "@baseboard_fab2_lib.baseboard_fab2(sch_1):page38_i33:vccd012(4)"
				( attribute "PN" "E48"
					( Origin gPackager )
				)
				( objectStatus "U5D1.E48" )
			)
			( pin "@baseboard_fab2_lib.baseboard_fab2(sch_1):page38_i33:vccd012(5)"
				( attribute "PN" "E50"
					( Origin gPackager )
				)
				( objectStatus "U5D1.E50" )
			)
			( pin "@baseboard_fab2_lib.baseboard_fab2(sch_1):page38_i33:vccd012(6)"
				( attribute "PN" "E52"
					( Origin gPackager )
				)
				( objectStatus "U5D1.E52" )
			)
			( pin "@baseboard_fab2_lib.baseboard_fab2(sch_1):page38_i33:vccd012(7)"
				( attribute "PN" "E54"
					( Origin gPackager )
				)
				( objectStatus "U5D1.E54" )
			)
			( pin "@baseboard_fab2_lib.baseboard_fab2(sch_1):page38_i33:vccd012(8)"
				( attribute "PN" "E56"
					( Origin gPackager )
				)
				( objectStatus "U5D1.E56" )
			)
			( pin "@baseboard_fab2_lib.baseboard_fab2(sch_1):page38_i33:vccd012(9)"
				( attribute "PN" "E58"
					( Origin gPackager )
				)
				( objectStatus "U5D1.E58" )
			)
			( pin "@baseboard_fab2_lib.baseboard_fab2(sch_1):page38_i33:vccd012(10)"
				( attribute "PN" "E60"
					( Origin gPackager )
				)
				( objectStatus "U5D1.E60" )
			)
			( pin "@baseboard_fab2_lib.baseboard_fab2(sch_1):page38_i33:vccd012(11)"
				( attribute "PN" "E62"
					( Origin gPackager )
				)
				( objectStatus "U5D1.E62" )
			)
			( pin "@baseboard_fab2_lib.baseboard_fab2(sch_1):page38_i33:vccd012(12)"
				( attribute "PN" "E64"
					( Origin gPackager )
				)
				( objectStatus "U5D1.E64" )
			)
			( pin "@baseboard_fab2_lib.baseboard_fab2(sch_1):page38_i33:vccd012(13)"
				( attribute "PN" "L46"
					( Origin gPackager )
				)
				( objectStatus "U5D1.L46" )
			)
			( pin "@baseboard_fab2_lib.baseboard_fab2(sch_1):page38_i33:vccd012(14)"
				( attribute "PN" "L48"
					( Origin gPackager )
				)
				( objectStatus "U5D1.L48" )
			)
			( pin "@baseboard_fab2_lib.baseboard_fab2(sch_1):page38_i33:vccd012(15)"
				( attribute "PN" "L50"
					( Origin gPackager )
				)
				( objectStatus "U5D1.L50" )
			)
			( pin "@baseboard_fab2_lib.baseboard_fab2(sch_1):page38_i33:vccd012(16)"
				( attribute "PN" "L52"
					( Origin gPackager )
				)
				( objectStatus "U5D1.L52" )
			)
			( pin "@baseboard_fab2_lib.baseboard_fab2(sch_1):page38_i33:vccd012(17)"
				( attribute "PN" "L54"
					( Origin gPackager )
				)
				( objectStatus "U5D1.L54" )
			)
			( pin "@baseboard_fab2_lib.baseboard_fab2(sch_1):page38_i33:vccd012(18)"
				( attribute "PN" "L56"
					( Origin gPackager )
				)
				( objectStatus "U5D1.L56" )
			)
			( pin "@baseboard_fab2_lib.baseboard_fab2(sch_1):page38_i33:vccd012(19)"
				( attribute "PN" "L58"
					( Origin gPackager )
				)
				( objectStatus "U5D1.L58" )
			)
			( pin "@baseboard_fab2_lib.baseboard_fab2(sch_1):page38_i33:vccd012(20)"
				( attribute "PN" "L60"
					( Origin gPackager )
				)
				( objectStatus "U5D1.L60" )
			)
			( pin "@baseboard_fab2_lib.baseboard_fab2(sch_1):page38_i33:vccd012(21)"
				( attribute "PN" "L62"
					( Origin gPackager )
				)
				( objectStatus "U5D1.L62" )
			)
			( pin "@baseboard_fab2_lib.baseboard_fab2(sch_1):page38_i33:vccd012(22)"
				( attribute "PN" "N64"
					( Origin gPackager )
				)
				( objectStatus "U5D1.N64" )
			)
			( pin "@baseboard_fab2_lib.baseboard_fab2(sch_1):page38_i33:vccd012(23)"
				( attribute "PN" "U46"
					( Origin gPackager )
				)
				( objectStatus "U5D1.U46" )
			)
			( pin "@baseboard_fab2_lib.baseboard_fab2(sch_1):page38_i33:vccd012(24)"
				( attribute "PN" "U48"
					( Origin gPackager )
				)
				( objectStatus "U5D1.U48" )
			)
			( pin "@baseboard_fab2_lib.baseboard_fab2(sch_1):page38_i33:vccd012(25)"
				( attribute "PN" "U50"
					( Origin gPackager )
				)
				( objectStatus "U5D1.U50" )
			)
			( pin "@baseboard_fab2_lib.baseboard_fab2(sch_1):page38_i33:vccd012(26)"
				( attribute "PN" "U52"
					( Origin gPackager )
				)
				( objectStatus "U5D1.U52" )
			)
			( pin "@baseboard_fab2_lib.baseboard_fab2(sch_1):page38_i33:vccd012(27)"
				( attribute "PN" "U54"
					( Origin gPackager )
				)
				( objectStatus "U5D1.U54" )
			)
			( pin "@baseboard_fab2_lib.baseboard_fab2(sch_1):page38_i33:vccd012(28)"
				( attribute "PN" "U56"
					( Origin gPackager )
				)
				( objectStatus "U5D1.U56" )
			)
			( pin "@baseboard_fab2_lib.baseboard_fab2(sch_1):page38_i33:vccd012(29)"
				( attribute "PN" "U58"
					( Origin gPackager )
				)
				( objectStatus "U5D1.U58" )
			)
			( pin "@baseboard_fab2_lib.baseboard_fab2(sch_1):page38_i33:vccd012(30)"
				( attribute "PN" "U60"
					( Origin gPackager )
				)
				( objectStatus "U5D1.U60" )
			)
			( pin "@baseboard_fab2_lib.baseboard_fab2(sch_1):page38_i33:vccd012(31)"
				( attribute "PN" "U62"
					( Origin gPackager )
				)
				( objectStatus "U5D1.U62" )
			)
			( pin "@baseboard_fab2_lib.baseboard_fab2(sch_1):page38_i33:vccd012(32)"
				( attribute "PN" "W64"
					( Origin gPackager )
				)
				( objectStatus "U5D1.W64" )
			)
			( pin "@baseboard_fab2_lib.baseboard_fab2(sch_1):page38_i33:vccd012(33)"
				( attribute "PN" "Y45"
					( Origin gPackager )
				)
				( objectStatus "U5D1.Y45" )
			)
			( pin "@baseboard_fab2_lib.baseboard_fab2(sch_1):page38_i33:vccd012(34)"
				( attribute "PN" "Y47"
					( Origin gPackager )
				)
				( objectStatus "U5D1.Y47" )
			)
			( pin "@baseboard_fab2_lib.baseboard_fab2(sch_1):page38_i33:vccd012(35)"
				( attribute "PN" "Y49"
					( Origin gPackager )
				)
				( objectStatus "U5D1.Y49" )
			)
			( pin "@baseboard_fab2_lib.baseboard_fab2(sch_1):page38_i33:vccd012(36)"
				( attribute "PN" "Y51"
					( Origin gPackager )
				)
				( objectStatus "U5D1.Y51" )
			)
			( pin "@baseboard_fab2_lib.baseboard_fab2(sch_1):page38_i33:vccd012(37)"
				( attribute "PN" "Y53"
					( Origin gPackager )
				)
				( objectStatus "U5D1.Y53" )
			)
			( pin "@baseboard_fab2_lib.baseboard_fab2(sch_1):page38_i33:vccd012(38)"
				( attribute "PN" "Y55"
					( Origin gPackager )
				)
				( objectStatus "U5D1.Y55" )
			)
			( pin "@baseboard_fab2_lib.baseboard_fab2(sch_1):page38_i33:vccd012(39)"
				( attribute "PN" "Y57"
					( Origin gPackager )
				)
				( objectStatus "U5D1.Y57" )
			)
			( pin "@baseboard_fab2_lib.baseboard_fab2(sch_1):page38_i33:vccd012(40)"
				( attribute "PN" "Y59"
					( Origin gPackager )
				)
				( objectStatus "U5D1.Y59" )
			)
			( pin "@baseboard_fab2_lib.baseboard_fab2(sch_1):page38_i33:vccd012(41)"
				( attribute "PN" "Y61"
					( Origin gPackager )
				)
				( objectStatus "U5D1.Y61" )
			)
			( pin "@baseboard_fab2_lib.baseboard_fab2(sch_1):page38_i33:vccd012(42)"
				( attribute "PN" "Y63"
					( Origin gPackager )
				)
				( objectStatus "U5D1.Y63" )
			)
			( pin "@baseboard_fab2_lib.baseboard_fab2(sch_1):page38_i33:vccd012(43)"
				( attribute "PN" "AD45"
					( Origin gPackager )
				)
				( objectStatus "U5D1.AD45" )
			)
			( pin "@baseboard_fab2_lib.baseboard_fab2(sch_1):page38_i33:vccd012(44)"
				( attribute "PN" "AF55"
					( Origin gPackager )
				)
				( objectStatus "U5D1.AF55" )
			)
			( pin "@baseboard_fab2_lib.baseboard_fab2(sch_1):page38_i33:vccd012(45)"
				( attribute "PN" "AF57"
					( Origin gPackager )
				)
				( objectStatus "U5D1.AF57" )
			)
			( pin "@baseboard_fab2_lib.baseboard_fab2(sch_1):page38_i33:vccd012(46)"
				( attribute "PN" "AF59"
					( Origin gPackager )
				)
				( objectStatus "U5D1.AF59" )
			)
			( pin "@baseboard_fab2_lib.baseboard_fab2(sch_1):page38_i33:vccd012(47)"
				( attribute "PN" "AF61"
					( Origin gPackager )
				)
				( objectStatus "U5D1.AF61" )
			)
			( pin "@baseboard_fab2_lib.baseboard_fab2(sch_1):page38_i33:vccd012(48)"
				( attribute "PN" "AF63"
					( Origin gPackager )
				)
				( objectStatus "U5D1.AF63" )
			)
			( pin "@baseboard_fab2_lib.baseboard_fab2(sch_1):page38_i33:vccd012(49)"
				( attribute "PN" "D45"
					( Origin gPackager )
				)
				( objectStatus "U5D1.D45" )
			)
			( pin "@baseboard_fab2_lib.baseboard_fab2(sch_1):page38_i33:vccd012(50)"
				( attribute "PN" "C46"
					( Origin gPackager )
				)
				( objectStatus "U5D1.C46" )
			)
			( pin "@baseboard_fab2_lib.baseboard_fab2(sch_1):page38_i33:vccd012(51)"
				( attribute "PN" "B47"
					( Origin gPackager )
				)
				( objectStatus "U5D1.B47" )
			)
			( pin "@baseboard_fab2_lib.baseboard_fab2(sch_1):page38_i33:vccd345(0)"
				( attribute "PN" "EF59"
					( Origin gPackager )
				)
				( objectStatus "U5D1.EF59" )
			)
			( pin "@baseboard_fab2_lib.baseboard_fab2(sch_1):page38_i33:vccd345(1)"
				( attribute "PN" "EF53"
					( Origin gPackager )
				)
				( objectStatus "U5D1.EF53" )
			)
			( pin "@baseboard_fab2_lib.baseboard_fab2(sch_1):page38_i33:vccd345(2)"
				( attribute "PN" "EF49"
					( Origin gPackager )
				)
				( objectStatus "U5D1.EF49" )
			)
			( pin "@baseboard_fab2_lib.baseboard_fab2(sch_1):page38_i33:vccd345(3)"
				( attribute "PN" "EC62"
					( Origin gPackager )
				)
				( objectStatus "U5D1.EC62" )
			)
			( pin "@baseboard_fab2_lib.baseboard_fab2(sch_1):page38_i33:vccd345(4)"
				( attribute "PN" "EC60"
					( Origin gPackager )
				)
				( objectStatus "U5D1.EC60" )
			)
			( pin "@baseboard_fab2_lib.baseboard_fab2(sch_1):page38_i33:vccd345(5)"
				( attribute "PN" "EC58"
					( Origin gPackager )
				)
				( objectStatus "U5D1.EC58" )
			)
			( pin "@baseboard_fab2_lib.baseboard_fab2(sch_1):page38_i33:vccd345(6)"
				( attribute "PN" "EC56"
					( Origin gPackager )
				)
				( objectStatus "U5D1.EC56" )
			)
			( pin "@baseboard_fab2_lib.baseboard_fab2(sch_1):page38_i33:vccd345(7)"
				( attribute "PN" "EC54"
					( Origin gPackager )
				)
				( objectStatus "U5D1.EC54" )
			)
			( pin "@baseboard_fab2_lib.baseboard_fab2(sch_1):page38_i33:vccd345(8)"
				( attribute "PN" "EC52"
					( Origin gPackager )
				)
				( objectStatus "U5D1.EC52" )
			)
			( pin "@baseboard_fab2_lib.baseboard_fab2(sch_1):page38_i33:vccd345(9)"
				( attribute "PN" "EC50"
					( Origin gPackager )
				)
				( objectStatus "U5D1.EC50" )
			)
			( pin "@baseboard_fab2_lib.baseboard_fab2(sch_1):page38_i33:vccd345(10)"
				( attribute "PN" "EC48"
					( Origin gPackager )
				)
				( objectStatus "U5D1.EC48" )
			)
			( pin "@baseboard_fab2_lib.baseboard_fab2(sch_1):page38_i33:vccd345(11)"
				( attribute "PN" "EC46"
					( Origin gPackager )
				)
				( objectStatus "U5D1.EC46" )
			)
			( pin "@baseboard_fab2_lib.baseboard_fab2(sch_1):page38_i33:vccd345(12)"
				( attribute "PN" "DU64"
					( Origin gPackager )
				)
				( objectStatus "U5D1.DU64" )
			)
			( pin "@baseboard_fab2_lib.baseboard_fab2(sch_1):page38_i33:vccd345(13)"
				( attribute "PN" "DU62"
					( Origin gPackager )
				)
				( objectStatus "U5D1.DU62" )
			)
			( pin "@baseboard_fab2_lib.baseboard_fab2(sch_1):page38_i33:vccd345(14)"
				( attribute "PN" "DU60"
					( Origin gPackager )
				)
				( objectStatus "U5D1.DU60" )
			)
			( pin "@baseboard_fab2_lib.baseboard_fab2(sch_1):page38_i33:vccd345(15)"
				( attribute "PN" "DU58"
					( Origin gPackager )
				)
				( objectStatus "U5D1.DU58" )
			)
			( pin "@baseboard_fab2_lib.baseboard_fab2(sch_1):page38_i33:vccd345(16)"
				( attribute "PN" "DU56"
					( Origin gPackager )
				)
				( objectStatus "U5D1.DU56" )
			)
			( pin "@baseboard_fab2_lib.baseboard_fab2(sch_1):page38_i33:vccd345(17)"
				( attribute "PN" "DU54"
					( Origin gPackager )
				)
				( objectStatus "U5D1.DU54" )
			)
			( pin "@baseboard_fab2_lib.baseboard_fab2(sch_1):page38_i33:vccd345(18)"
				( attribute "PN" "DU52"
					( Origin gPackager )
				)
				( objectStatus "U5D1.DU52" )
			)
			( pin "@baseboard_fab2_lib.baseboard_fab2(sch_1):page38_i33:vccd345(19)"
				( attribute "PN" "DU50"
					( Origin gPackager )
				)
				( objectStatus "U5D1.DU50" )
			)
			( pin "@baseboard_fab2_lib.baseboard_fab2(sch_1):page38_i33:vccd345(20)"
				( attribute "PN" "DU48"
					( Origin gPackager )
				)
				( objectStatus "U5D1.DU48" )
			)
			( pin "@baseboard_fab2_lib.baseboard_fab2(sch_1):page38_i33:vccd345(21)"
				( attribute "PN" "DU46"
					( Origin gPackager )
				)
				( objectStatus "U5D1.DU46" )
			)
			( pin "@baseboard_fab2_lib.baseboard_fab2(sch_1):page38_i33:vccd345(22)"
				( attribute "PN" "DL62"
					( Origin gPackager )
				)
				( objectStatus "U5D1.DL62" )
			)
			( pin "@baseboard_fab2_lib.baseboard_fab2(sch_1):page38_i33:vccd345(23)"
				( attribute "PN" "DL60"
					( Origin gPackager )
				)
				( objectStatus "U5D1.DL60" )
			)
			( pin "@baseboard_fab2_lib.baseboard_fab2(sch_1):page38_i33:vccd345(24)"
				( attribute "PN" "DL58"
					( Origin gPackager )
				)
				( objectStatus "U5D1.DL58" )
			)
			( pin "@baseboard_fab2_lib.baseboard_fab2(sch_1):page38_i33:vccd345(25)"
				( attribute "PN" "DL56"
					( Origin gPackager )
				)
				( objectStatus "U5D1.DL56" )
			)
			( pin "@baseboard_fab2_lib.baseboard_fab2(sch_1):page38_i33:vccd345(26)"
				( attribute "PN" "DL54"
					( Origin gPackager )
				)
				( objectStatus "U5D1.DL54" )
			)
			( pin "@baseboard_fab2_lib.baseboard_fab2(sch_1):page38_i33:vccd345(27)"
				( attribute "PN" "DL52"
					( Origin gPackager )
				)
				( objectStatus "U5D1.DL52" )
			)
			( pin "@baseboard_fab2_lib.baseboard_fab2(sch_1):page38_i33:vccd345(28)"
				( attribute "PN" "DL50"
					( Origin gPackager )
				)
				( objectStatus "U5D1.DL50" )
			)
			( pin "@baseboard_fab2_lib.baseboard_fab2(sch_1):page38_i33:vccd345(29)"
				( attribute "PN" "DL48"
					( Origin gPackager )
				)
				( objectStatus "U5D1.DL48" )
			)
			( pin "@baseboard_fab2_lib.baseboard_fab2(sch_1):page38_i33:vccd345(30)"
				( attribute "PN" "DL46"
					( Origin gPackager )
				)
				( objectStatus "U5D1.DL46" )
			)
			( pin "@baseboard_fab2_lib.baseboard_fab2(sch_1):page38_i33:vccd345(31)"
				( attribute "PN" "DJ64"
					( Origin gPackager )
				)
				( objectStatus "U5D1.DJ64" )
			)
			( pin "@baseboard_fab2_lib.baseboard_fab2(sch_1):page38_i33:vccd345(32)"
				( attribute "PN" "DH63"
					( Origin gPackager )
				)
				( objectStatus "U5D1.DH63" )
			)
			( pin "@baseboard_fab2_lib.baseboard_fab2(sch_1):page38_i33:vccd345(33)"
				( attribute "PN" "DH61"
					( Origin gPackager )
				)
				( objectStatus "U5D1.DH61" )
			)
			( pin "@baseboard_fab2_lib.baseboard_fab2(sch_1):page38_i33:vccd345(34)"
				( attribute "PN" "DH59"
					( Origin gPackager )
				)
				( objectStatus "U5D1.DH59" )
			)
			( pin "@baseboard_fab2_lib.baseboard_fab2(sch_1):page38_i33:vccd345(35)"
				( attribute "PN" "DH57"
					( Origin gPackager )
				)
				( objectStatus "U5D1.DH57" )
			)
			( pin "@baseboard_fab2_lib.baseboard_fab2(sch_1):page38_i33:vccd345(36)"
				( attribute "PN" "DH55"
					( Origin gPackager )
				)
				( objectStatus "U5D1.DH55" )
			)
			( pin "@baseboard_fab2_lib.baseboard_fab2(sch_1):page38_i33:vccd345(37)"
				( attribute "PN" "DH53"
					( Origin gPackager )
				)
				( objectStatus "U5D1.DH53" )
			)
			( pin "@baseboard_fab2_lib.baseboard_fab2(sch_1):page38_i33:vccd345(38)"
				( attribute "PN" "DH51"
					( Origin gPackager )
				)
				( objectStatus "U5D1.DH51" )
			)
			( pin "@baseboard_fab2_lib.baseboard_fab2(sch_1):page38_i33:vccd345(39)"
				( attribute "PN" "DH49"
					( Origin gPackager )
				)
				( objectStatus "U5D1.DH49" )
			)
			( pin "@baseboard_fab2_lib.baseboard_fab2(sch_1):page38_i33:vccd345(40)"
				( attribute "PN" "DH47"
					( Origin gPackager )
				)
				( objectStatus "U5D1.DH47" )
			)
			( pin "@baseboard_fab2_lib.baseboard_fab2(sch_1):page38_i33:vccd345(41)"
				( attribute "PN" "DH45"
					( Origin gPackager )
				)
				( objectStatus "U5D1.DH45" )
			)
			( pin "@baseboard_fab2_lib.baseboard_fab2(sch_1):page38_i33:vccd345(42)"
				( attribute "PN" "DD45"
					( Origin gPackager )
				)
				( objectStatus "U5D1.DD45" )
			)
			( pin "@baseboard_fab2_lib.baseboard_fab2(sch_1):page38_i33:vccd345(43)"
				( attribute "PN" "DB63"
					( Origin gPackager )
				)
				( objectStatus "U5D1.DB63" )
			)
			( pin "@baseboard_fab2_lib.baseboard_fab2(sch_1):page38_i33:vccd345(44)"
				( attribute "PN" "DB61"
					( Origin gPackager )
				)
				( objectStatus "U5D1.DB61" )
			)
			( pin "@baseboard_fab2_lib.baseboard_fab2(sch_1):page38_i33:vccd345(45)"
				( attribute "PN" "DB59"
					( Origin gPackager )
				)
				( objectStatus "U5D1.DB59" )
			)
			( pin "@baseboard_fab2_lib.baseboard_fab2(sch_1):page38_i33:vccd345(46)"
				( attribute "PN" "DB57"
					( Origin gPackager )
				)
				( objectStatus "U5D1.DB57" )
			)
			( pin "@baseboard_fab2_lib.baseboard_fab2(sch_1):page38_i33:vccd345(47)"
				( attribute "PN" "DB55"
					( Origin gPackager )
				)
				( objectStatus "U5D1.DB55" )
			)
			( pin "@baseboard_fab2_lib.baseboard_fab2(sch_1):page38_i33:vccd345(48)"
				( attribute "PN" "DB53"
					( Origin gPackager )
				)
				( objectStatus "U5D1.DB53" )
			)
			( pin "@baseboard_fab2_lib.baseboard_fab2(sch_1):page38_i33:vccd345(49)"
				( attribute "PN" "EF45"
					( Origin gPackager )
				)
				( objectStatus "U5D1.EF45" )
			)
			( pin "@baseboard_fab2_lib.baseboard_fab2(sch_1):page38_i33:vccd345(50)"
				( attribute "PN" "EE44"
					( Origin gPackager )
				)
				( objectStatus "U5D1.EE44" )
			)
			( pin "@baseboard_fab2_lib.baseboard_fab2(sch_1):page38_i34:cd_vcc_core(0)"
				( attribute "PN" "BL14"
					( Origin gPackager )
				)
				( objectStatus "U5D1.BL14" )
			)
			( pin "@baseboard_fab2_lib.baseboard_fab2(sch_1):page38_i34:cd_vcc_core(1)"
				( attribute "PN" "BK15"
					( Origin gPackager )
				)
				( objectStatus "U5D1.BK15" )
			)
			( pin "@baseboard_fab2_lib.baseboard_fab2(sch_1):page38_i34:cd_vcc_core(2)"
				( attribute "PN" "BK13"
					( Origin gPackager )
				)
				( objectStatus "U5D1.BK13" )
			)
			( pin "@baseboard_fab2_lib.baseboard_fab2(sch_1):page38_i34:cd_vcc_core(3)"
				( attribute "PN" "BJ14"
					( Origin gPackager )
				)
				( objectStatus "U5D1.BJ14" )
			)
			( pin "@baseboard_fab2_lib.baseboard_fab2(sch_1):page38_i34:cd_vcc_core(4)"
				( attribute "PN" "BJ12"
					( Origin gPackager )
				)
				( objectStatus "U5D1.BJ12" )
			)
			( pin "@baseboard_fab2_lib.baseboard_fab2(sch_1):page38_i34:cd_vcc_core(5)"
				( attribute "PN" "BH13"
					( Origin gPackager )
				)
				( objectStatus "U5D1.BH13" )
			)
			( pin "@baseboard_fab2_lib.baseboard_fab2(sch_1):page38_i34:cd_vcc_core(6)"
				( attribute "PN" "BG14"
					( Origin gPackager )
				)
				( objectStatus "U5D1.BG14" )
			)
			( pin "@baseboard_fab2_lib.baseboard_fab2(sch_1):page38_i34:cd_vcc_core(7)"
				( attribute "PN" "BG12"
					( Origin gPackager )
				)
				( objectStatus "U5D1.BG12" )
			)
			( pin "@baseboard_fab2_lib.baseboard_fab2(sch_1):page38_i34:cd_vcc_core(8)"
				( attribute "PN" "BF13"
					( Origin gPackager )
				)
				( objectStatus "U5D1.BF13" )
			)
			( pin "@baseboard_fab2_lib.baseboard_fab2(sch_1):page38_i34:cd_vcc_core(9)"
				( attribute "PN" "BF11"
					( Origin gPackager )
				)
				( objectStatus "U5D1.BF11" )
			)
			( pin "@baseboard_fab2_lib.baseboard_fab2(sch_1):page38_i34:cd_vcc_core(10)"
				( attribute "PN" "BE14"
					( Origin gPackager )
				)
				( objectStatus "U5D1.BE14" )
			)
			( pin "@baseboard_fab2_lib.baseboard_fab2(sch_1):page38_i34:cd_vcc_core(11)"
				( attribute "PN" "BE12"
					( Origin gPackager )
				)
				( objectStatus "U5D1.BE12" )
			)
			( pin "@baseboard_fab2_lib.baseboard_fab2(sch_1):page38_i34:cd_vcc_core(12)"
				( attribute "PN" "BD13"
					( Origin gPackager )
				)
				( objectStatus "U5D1.BD13" )
			)
			( pin "@baseboard_fab2_lib.baseboard_fab2(sch_1):page38_i34:cd_vccin(0)"
				( attribute "PN" "BT27"
					( Origin gPackager )
				)
				( objectStatus "U5D1.BT27" )
			)
			( pin "@baseboard_fab2_lib.baseboard_fab2(sch_1):page38_i34:cd_vccin(1)"
				( attribute "PN" "BU26"
					( Origin gPackager )
				)
				( objectStatus "U5D1.BU26" )
			)
			( pin "@baseboard_fab2_lib.baseboard_fab2(sch_1):page38_i34:cd_vccin(2)"
				( attribute "PN" "BV27"
					( Origin gPackager )
				)
				( objectStatus "U5D1.BV27" )
			)
			( pin "@baseboard_fab2_lib.baseboard_fab2(sch_1):page38_i34:cd_vccin(3)"
				( attribute "PN" "BY27"
					( Origin gPackager )
				)
				( objectStatus "U5D1.BY27" )
			)
			( pin "@baseboard_fab2_lib.baseboard_fab2(sch_1):page38_i34:cd_vccp(0)"
				( attribute "PN" "BV15"
					( Origin gPackager )
				)
				( objectStatus "U5D1.BV15" )
			)
			( pin "@baseboard_fab2_lib.baseboard_fab2(sch_1):page38_i34:cd_vccp(1)"
				( attribute "PN" "BV13"
					( Origin gPackager )
				)
				( objectStatus "U5D1.BV13" )
			)
			( pin "@baseboard_fab2_lib.baseboard_fab2(sch_1):page38_i34:cd_vccp(2)"
				( attribute "PN" "BV11"
					( Origin gPackager )
				)
				( objectStatus "U5D1.BV11" )
			)
			( pin "@baseboard_fab2_lib.baseboard_fab2(sch_1):page38_i34:cd_vccp(3)"
				( attribute "PN" "BU14"
					( Origin gPackager )
				)
				( objectStatus "U5D1.BU14" )
			)
			( pin "@baseboard_fab2_lib.baseboard_fab2(sch_1):page38_i34:cd_vccp(4)"
				( attribute "PN" "BU12"
					( Origin gPackager )
				)
				( objectStatus "U5D1.BU12" )
			)
			( pin "@baseboard_fab2_lib.baseboard_fab2(sch_1):page38_i34:cd_vccp(5)"
				( attribute "PN" "BT15"
					( Origin gPackager )
				)
				( objectStatus "U5D1.BT15" )
			)
			( pin "@baseboard_fab2_lib.baseboard_fab2(sch_1):page38_i34:cd_vccp(6)"
				( attribute "PN" "BT13"
					( Origin gPackager )
				)
				( objectStatus "U5D1.BT13" )
			)
			( pin "@baseboard_fab2_lib.baseboard_fab2(sch_1):page38_i34:cd_vccp(7)"
				( attribute "PN" "BT11"
					( Origin gPackager )
				)
				( objectStatus "U5D1.BT11" )
			)
			( pin "@baseboard_fab2_lib.baseboard_fab2(sch_1):page38_i34:cd_vccp(8)"
				( attribute "PN" "BR14"
					( Origin gPackager )
				)
				( objectStatus "U5D1.BR14" )
			)
			( pin "@baseboard_fab2_lib.baseboard_fab2(sch_1):page38_i34:cd_vccp(9)"
				( attribute "PN" "BR12"
					( Origin gPackager )
				)
				( objectStatus "U5D1.BR12" )
			)
			( pin "@baseboard_fab2_lib.baseboard_fab2(sch_1):page38_i34:cd_vccp(10)"
				( attribute "PN" "BP15"
					( Origin gPackager )
				)
				( objectStatus "U5D1.BP15" )
			)
			( pin "@baseboard_fab2_lib.baseboard_fab2(sch_1):page38_i34:cd_vccp(11)"
				( attribute "PN" "BP13"
					( Origin gPackager )
				)
				( objectStatus "U5D1.BP13" )
			)
			( pin "@baseboard_fab2_lib.baseboard_fab2(sch_1):page38_i34:cd_vccp(12)"
				( attribute "PN" "BP11"
					( Origin gPackager )
				)
				( objectStatus "U5D1.BP11" )
			)
			( pin "@baseboard_fab2_lib.baseboard_fab2(sch_1):page38_i34:cd_vccp(13)"
				( attribute "PN" "BN14"
					( Origin gPackager )
				)
				( objectStatus "U5D1.BN14" )
			)
			( pin "@baseboard_fab2_lib.baseboard_fab2(sch_1):page38_i34:cd_vccp(14)"
				( attribute "PN" "BN12"
					( Origin gPackager )
				)
				( objectStatus "U5D1.BN12" )
			)
			( pin "@baseboard_fab2_lib.baseboard_fab2(sch_1):page38_i34:cd_vccp(15)"
				( attribute "PN" "BM11"
					( Origin gPackager )
				)
				( objectStatus "U5D1.BM11" )
			)
			( pin "@baseboard_fab2_lib.baseboard_fab2(sch_1):page38_i34:cd_vpp(0)"
				( attribute "PN" "B11"
					( Origin gPackager )
				)
				( objectStatus "U5D1.B11" )
			)
			( pin "@baseboard_fab2_lib.baseboard_fab2(sch_1):page38_i34:cd_vpp(1)"
				( attribute "PN" "A12"
					( Origin gPackager )
				)
				( objectStatus "U5D1.A12" )
			)
			( pin "@baseboard_fab2_lib.baseboard_fab2(sch_1):page38_i34:cd_vpp(2)"
				( attribute "PN" "A10"
					( Origin gPackager )
				)
				( objectStatus "U5D1.A10" )
			)
			( pin "@baseboard_fab2_lib.baseboard_fab2(sch_1):page38_i34:cd_vpp(3)"
				( attribute "PN" "A8"
					( Origin gPackager )
				)
				( objectStatus "U5D1.A8" )
			)
			( pin "@baseboard_fab2_lib.baseboard_fab2(sch_1):page38_i34:vcc33"
				( attribute "PN" "CY55"
					( Origin gPackager )
				)
				( objectStatus "U5D1.CY55" )
			)
			( pin "@baseboard_fab2_lib.baseboard_fab2(sch_1):page38_i34:vccio(20)"
				( attribute "PN" "CM15"
					( Origin gPackager )
				)
				( objectStatus "U5D1.CM15" )
			)
			( pin "@baseboard_fab2_lib.baseboard_fab2(sch_1):page38_i34:vccio(21)"
				( attribute "PN" "CL12"
					( Origin gPackager )
				)
				( objectStatus "U5D1.CL12" )
			)
			( pin "@baseboard_fab2_lib.baseboard_fab2(sch_1):page38_i34:vccio(22)"
				( attribute "PN" "CK5"
					( Origin gPackager )
				)
				( objectStatus "U5D1.CK5" )
			)
			( pin "@baseboard_fab2_lib.baseboard_fab2(sch_1):page38_i34:vccio(23)"
				( attribute "PN" "CV7"
					( Origin gPackager )
				)
				( objectStatus "U5D1.CV7" )
			)
			( pin "@baseboard_fab2_lib.baseboard_fab2(sch_1):page38_i34:vccio(24)"
				( attribute "PN" "CH9"
					( Origin gPackager )
				)
				( objectStatus "U5D1.CH9" )
			)
			( pin "@baseboard_fab2_lib.baseboard_fab2(sch_1):page38_i34:vccio(25)"
				( attribute "PN" "D7"
					( Origin gPackager )
				)
				( objectStatus "U5D1.D7" )
			)
			( pin "@baseboard_fab2_lib.baseboard_fab2(sch_1):page38_i34:vccio(26)"
				( attribute "PN" "CE18"
					( Origin gPackager )
				)
				( objectStatus "U5D1.CE18" )
			)
			( pin "@baseboard_fab2_lib.baseboard_fab2(sch_1):page38_i34:vccio(27)"
				( attribute "PN" "CD9"
					( Origin gPackager )
				)
				( objectStatus "U5D1.CD9" )
			)
			( pin "@baseboard_fab2_lib.baseboard_fab2(sch_1):page38_i34:vccio(28)"
				( attribute "PN" "CB17"
					( Origin gPackager )
				)
				( objectStatus "U5D1.CB17" )
			)
			( pin "@baseboard_fab2_lib.baseboard_fab2(sch_1):page38_i34:vccio(29)"
				( attribute "PN" "CB13"
					( Origin gPackager )
				)
				( objectStatus "U5D1.CB13" )
			)
			( pin "@baseboard_fab2_lib.baseboard_fab2(sch_1):page38_i34:vccio(30)"
				( attribute "PN" "BP25"
					( Origin gPackager )
				)
				( objectStatus "U5D1.BP25" )
			)
			( pin "@baseboard_fab2_lib.baseboard_fab2(sch_1):page38_i34:vccio(31)"
				( attribute "PN" "BJ24"
					( Origin gPackager )
				)
				( objectStatus "U5D1.BJ24" )
			)
			( pin "@baseboard_fab2_lib.baseboard_fab2(sch_1):page38_i34:vccio(32)"
				( attribute "PN" "BF23"
					( Origin gPackager )
				)
				( objectStatus "U5D1.BF23" )
			)
			( pin "@baseboard_fab2_lib.baseboard_fab2(sch_1):page38_i34:vccio(33)"
				( attribute "PN" "DA14"
					( Origin gPackager )
				)
				( objectStatus "U5D1.DA14" )
			)
			( pin "@baseboard_fab2_lib.baseboard_fab2(sch_1):page38_i34:vccio(34)"
				( attribute "PN" "BB5"
					( Origin gPackager )
				)
				( objectStatus "U5D1.BB5" )
			)
			( pin "@baseboard_fab2_lib.baseboard_fab2(sch_1):page38_i34:vccio(35)"
				( attribute "PN" "BA24"
					( Origin gPackager )
				)
				( objectStatus "U5D1.BA24" )
			)
			( pin "@baseboard_fab2_lib.baseboard_fab2(sch_1):page38_i34:vccio(36)"
				( attribute "PN" "AY11"
					( Origin gPackager )
				)
				( objectStatus "U5D1.AY11" )
			)
			( pin "@baseboard_fab2_lib.baseboard_fab2(sch_1):page38_i34:vccio(37)"
				( attribute "PN" "AW6"
					( Origin gPackager )
				)
				( objectStatus "U5D1.AW6" )
			)
			( pin "@baseboard_fab2_lib.baseboard_fab2(sch_1):page38_i34:vccio(38)"
				( attribute "PN" "AT11"
					( Origin gPackager )
				)
				( objectStatus "U5D1.AT11" )
			)
			( pin "@baseboard_fab2_lib.baseboard_fab2(sch_1):page38_i34:vccio(39)"
				( attribute "PN" "DD7"
					( Origin gPackager )
				)
				( objectStatus "U5D1.DD7" )
			)
			( pin "@baseboard_fab2_lib.baseboard_fab2(sch_1):page38_i34:vccio(40)"
				( attribute "PN" "AN10"
					( Origin gPackager )
				)
				( objectStatus "U5D1.AN10" )
			)
			( pin "@baseboard_fab2_lib.baseboard_fab2(sch_1):page38_i34:vccio(41)"
				( attribute "PN" "DF13"
					( Origin gPackager )
				)
				( objectStatus "U5D1.DF13" )
			)
			( pin "@baseboard_fab2_lib.baseboard_fab2(sch_1):page38_i34:vccio(42)"
				( attribute "PN" "AH9"
					( Origin gPackager )
				)
				( objectStatus "U5D1.AH9" )
			)
			( pin "@baseboard_fab2_lib.baseboard_fab2(sch_1):page38_i34:vccio(43)"
				( attribute "PN" "AC4"
					( Origin gPackager )
				)
				( objectStatus "U5D1.AC4" )
			)
			( pin "@baseboard_fab2_lib.baseboard_fab2(sch_1):page38_i34:vccio(44)"
				( attribute "PN" "AC20"
					( Origin gPackager )
				)
				( objectStatus "U5D1.AC20" )
			)
			( pin "@baseboard_fab2_lib.baseboard_fab2(sch_1):page38_i34:vccio(45)"
				( attribute "PN" "AA10"
					( Origin gPackager )
				)
				( objectStatus "U5D1.AA10" )
			)
			( pin "@baseboard_fab2_lib.baseboard_fab2(sch_1):page38_i34:vccio(46)"
				( attribute "PN" "W6"
					( Origin gPackager )
				)
				( objectStatus "U5D1.W6" )
			)
			( pin "@baseboard_fab2_lib.baseboard_fab2(sch_1):page38_i34:vccio(47)"
				( attribute "PN" "W4"
					( Origin gPackager )
				)
				( objectStatus "U5D1.W4" )
			)
			( pin "@baseboard_fab2_lib.baseboard_fab2(sch_1):page38_i34:vccio(48)"
				( attribute "PN" "DF21"
					( Origin gPackager )
				)
				( objectStatus "U5D1.DF21" )
			)
			( pin "@baseboard_fab2_lib.baseboard_fab2(sch_1):page38_i34:vccio(49)"
				( attribute "PN" "U14"
					( Origin gPackager )
				)
				( objectStatus "U5D1.U14" )
			)
			( pin "@baseboard_fab2_lib.baseboard_fab2(sch_1):page38_i34:vccio(50)"
				( attribute "PN" "T3"
					( Origin gPackager )
				)
				( objectStatus "U5D1.T3" )
			)
			( pin "@baseboard_fab2_lib.baseboard_fab2(sch_1):page38_i34:vccio(51)"
				( attribute "PN" "P5"
					( Origin gPackager )
				)
				( objectStatus "U5D1.P5" )
			)
			( pin "@baseboard_fab2_lib.baseboard_fab2(sch_1):page38_i34:vccio(52)"
				( attribute "PN" "M21"
					( Origin gPackager )
				)
				( objectStatus "U5D1.M21" )
			)
			( pin "@baseboard_fab2_lib.baseboard_fab2(sch_1):page38_i34:vccio(53)"
				( attribute "PN" "M11"
					( Origin gPackager )
				)
				( objectStatus "U5D1.M11" )
			)
			( pin "@baseboard_fab2_lib.baseboard_fab2(sch_1):page38_i34:vccio(54)"
				( attribute "PN" "DG8"
					( Origin gPackager )
				)
				( objectStatus "U5D1.DG8" )
			)
			( pin "@baseboard_fab2_lib.baseboard_fab2(sch_1):page38_i34:vccio(55)"
				( attribute "PN" "DH7"
					( Origin gPackager )
				)
				( objectStatus "U5D1.DH7" )
			)
			( pin "@baseboard_fab2_lib.baseboard_fab2(sch_1):page38_i34:vccio(56)"
				( attribute "PN" "L16"
					( Origin gPackager )
				)
				( objectStatus "U5D1.L16" )
			)
			( pin "@baseboard_fab2_lib.baseboard_fab2(sch_1):page38_i34:vccio(57)"
				( attribute "PN" "L14"
					( Origin gPackager )
				)
				( objectStatus "U5D1.L14" )
			)
			( pin "@baseboard_fab2_lib.baseboard_fab2(sch_1):page38_i34:vccio(58)"
				( attribute "PN" "J10"
					( Origin gPackager )
				)
				( objectStatus "U5D1.J10" )
			)
			( pin "@baseboard_fab2_lib.baseboard_fab2(sch_1):page38_i34:vccio(59)"
				( attribute "PN" "H13"
					( Origin gPackager )
				)
				( objectStatus "U5D1.H13" )
			)
			( pin "@baseboard_fab2_lib.baseboard_fab2(sch_1):page38_i34:vccio(60)"
				( attribute "PN" "DJ16"
					( Origin gPackager )
				)
				( objectStatus "U5D1.DJ16" )
			)
			( pin "@baseboard_fab2_lib.baseboard_fab2(sch_1):page38_i34:vccio(61)"
				( attribute "PN" "DM17"
					( Origin gPackager )
				)
				( objectStatus "U5D1.DM17" )
			)
			( pin "@baseboard_fab2_lib.baseboard_fab2(sch_1):page38_i34:vccio(62)"
				( attribute "PN" "DN8"
					( Origin gPackager )
				)
				( objectStatus "U5D1.DN8" )
			)
			( pin "@baseboard_fab2_lib.baseboard_fab2(sch_1):page38_i34:vccio(63)"
				( attribute "PN" "DP19"
					( Origin gPackager )
				)
				( objectStatus "U5D1.DP19" )
			)
			( pin "@baseboard_fab2_lib.baseboard_fab2(sch_1):page38_i34:vccio(64)"
				( attribute "PN" "DR10"
					( Origin gPackager )
				)
				( objectStatus "U5D1.DR10" )
			)
			( pin "@baseboard_fab2_lib.baseboard_fab2(sch_1):page38_i34:vccio(65)"
				( attribute "PN" "DR2"
					( Origin gPackager )
				)
				( objectStatus "U5D1.DR2" )
			)
			( pin "@baseboard_fab2_lib.baseboard_fab2(sch_1):page38_i34:vccio(66)"
				( attribute "PN" "DU20"
					( Origin gPackager )
				)
				( objectStatus "U5D1.DU20" )
			)
			( pin "@baseboard_fab2_lib.baseboard_fab2(sch_1):page38_i34:vccio(67)"
				( attribute "PN" "EA12"
					( Origin gPackager )
				)
				( objectStatus "U5D1.EA12" )
			)
			( pin "@baseboard_fab2_lib.baseboard_fab2(sch_1):page38_i34:vccio(68)"
				( attribute "PN" "EB15"
					( Origin gPackager )
				)
				( objectStatus "U5D1.EB15" )
			)
			( pin "@baseboard_fab2_lib.baseboard_fab2(sch_1):page38_i34:vccio(69)"
				( attribute "PN" "J2"
					( Origin gPackager )
				)
				( objectStatus "U5D1.J2" )
			)
			( pin "@baseboard_fab2_lib.baseboard_fab2(sch_1):page38_i34:vccio(70)"
				( attribute "PN" "K15"
					( Origin gPackager )
				)
				( objectStatus "U5D1.K15" )
			)
			( pin "@baseboard_fab2_lib.baseboard_fab2(sch_1):page38_i34:vccio(71)"
				( attribute "PN" "M7"
					( Origin gPackager )
				)
				( objectStatus "U5D1.M7" )
			)
			( pin "@baseboard_fab2_lib.baseboard_fab2(sch_1):page38_i34:vccio(72)"
				( attribute "PN" "M9"
					( Origin gPackager )
				)
				( objectStatus "U5D1.M9" )
			)
			( pin "@baseboard_fab2_lib.baseboard_fab2(sch_1):page38_i34:vccio(73)"
				( attribute "PN" "N18"
					( Origin gPackager )
				)
				( objectStatus "U5D1.N18" )
			)
			( pin "@baseboard_fab2_lib.baseboard_fab2(sch_1):page38_i34:vccio(74)"
				( attribute "PN" "W10"
					( Origin gPackager )
				)
				( objectStatus "U5D1.W10" )
			)
			( pin "@baseboard_fab2_lib.baseboard_fab2(sch_1):page38_i34:vccio(75)"
				( attribute "PN" "BC26"
					( Origin gPackager )
				)
				( objectStatus "U5D1.BC26" )
			)
			( pin "@baseboard_fab2_lib.baseboard_fab2(sch_1):page38_i34:vccio(76)"
				( attribute "PN" "BB27"
					( Origin gPackager )
				)
				( objectStatus "U5D1.BB27" )
			)
			( pin "@baseboard_fab2_lib.baseboard_fab2(sch_1):page38_i34:vccio(77)"
				( attribute "PN" "BA26"
					( Origin gPackager )
				)
				( objectStatus "U5D1.BA26" )
			)
			( pin "@baseboard_fab2_lib.baseboard_fab2(sch_1):page38_i34:vccio(78)"
				( attribute "PN" "AY27"
					( Origin gPackager )
				)
				( objectStatus "U5D1.AY27" )
			)
			( pin "@baseboard_fab2_lib.baseboard_fab2(sch_1):page38_i34:vccio(79)"
				( attribute "PN" "AW26"
					( Origin gPackager )
				)
				( objectStatus "U5D1.AW26" )
			)
			( pin "@baseboard_fab2_lib.baseboard_fab2(sch_1):page38_i34:vccio(80)"
				( attribute "PN" "AV27"
					( Origin gPackager )
				)
				( objectStatus "U5D1.AV27" )
			)
			( pin "@baseboard_fab2_lib.baseboard_fab2(sch_1):page38_i34:vccio(81)"
				( attribute "PN" "CF27"
					( Origin gPackager )
				)
				( objectStatus "U5D1.CF27" )
			)
			( pin "@baseboard_fab2_lib.baseboard_fab2(sch_1):page38_i34:vccio(82)"
				( attribute "PN" "CD27"
					( Origin gPackager )
				)
				( objectStatus "U5D1.CD27" )
			)
			( pin "@baseboard_fab2_lib.baseboard_fab2(sch_1):page38_i34:vccio(83)"
				( attribute "PN" "CC26"
					( Origin gPackager )
				)
				( objectStatus "U5D1.CC26" )
			)
			( pin "@baseboard_fab2_lib.baseboard_fab2(sch_1):page38_i34:vccio(84)"
				( attribute "PN" "CJ28"
					( Origin gPackager )
				)
				( objectStatus "U5D1.CJ28" )
			)
			( pin "@baseboard_fab2_lib.baseboard_fab2(sch_1):page38_i34:vccio(85)"
				( attribute "PN" "CH27"
					( Origin gPackager )
				)
				( objectStatus "U5D1.CH27" )
			)
			( pin "@baseboard_fab2_lib.baseboard_fab2(sch_1):page38_i34:vccio(86)"
				( attribute "PN" "BM27"
					( Origin gPackager )
				)
				( objectStatus "U5D1.BM27" )
			)
			( pin "@baseboard_fab2_lib.baseboard_fab2(sch_1):page38_i34:vccio(87)"
				( attribute "PN" "BL26"
					( Origin gPackager )
				)
				( objectStatus "U5D1.BL26" )
			)
			( pin "@baseboard_fab2_lib.baseboard_fab2(sch_1):page38_i34:vccio(88)"
				( attribute "PN" "BK27"
					( Origin gPackager )
				)
				( objectStatus "U5D1.BK27" )
			)
			( pin "@baseboard_fab2_lib.baseboard_fab2(sch_1):page38_i34:vccio(89)"
				( attribute "PN" "BK25"
					( Origin gPackager )
				)
				( objectStatus "U5D1.BK25" )
			)
			( pin "@baseboard_fab2_lib.baseboard_fab2(sch_1):page38_i34:vccio(90)"
				( attribute "PN" "BJ26"
					( Origin gPackager )
				)
				( objectStatus "U5D1.BJ26" )
			)
			( pin "@baseboard_fab2_lib.baseboard_fab2(sch_1):page38_i34:vccio(91)"
				( attribute "PN" "BH27"
					( Origin gPackager )
				)
				( objectStatus "U5D1.BH27" )
			)
			( pin "@baseboard_fab2_lib.baseboard_fab2(sch_1):page38_i34:vccio(92)"
				( attribute "PN" "BH25"
					( Origin gPackager )
				)
				( objectStatus "U5D1.BH25" )
			)
			( pin "@baseboard_fab2_lib.baseboard_fab2(sch_1):page38_i34:vccio(93)"
				( attribute "PN" "BG26"
					( Origin gPackager )
				)
				( objectStatus "U5D1.BG26" )
			)
			( pin "@baseboard_fab2_lib.baseboard_fab2(sch_1):page38_i34:vccio(94)"
				( attribute "PN" "BF27"
					( Origin gPackager )
				)
				( objectStatus "U5D1.BF27" )
			)
			( pin "@baseboard_fab2_lib.baseboard_fab2(sch_1):page38_i34:vccio(95)"
				( attribute "PN" "AE36"
					( Origin gPackager )
				)
				( objectStatus "U5D1.AE36" )
			)
			( pin "@baseboard_fab2_lib.baseboard_fab2(sch_1):page38_i34:vccio(96)"
				( attribute "PN" "AD37"
					( Origin gPackager )
				)
				( objectStatus "U5D1.AD37" )
			)
			( pin "@baseboard_fab2_lib.baseboard_fab2(sch_1):page38_i34:vccio(97)"
				( attribute "PN" "AC36"
					( Origin gPackager )
				)
				( objectStatus "U5D1.AC36" )
			)
			( pin "@baseboard_fab2_lib.baseboard_fab2(sch_1):page38_i34:vccio(98)"
				( attribute "PN" "AF35"
					( Origin gPackager )
				)
				( objectStatus "U5D1.AF35" )
			)
			( pin "@baseboard_fab2_lib.baseboard_fab2(sch_1):page38_i34:vccio(99)"
				( attribute "PN" "AD35"
					( Origin gPackager )
				)
				( objectStatus "U5D1.AD35" )
			)
			( pin "@baseboard_fab2_lib.baseboard_fab2(sch_1):page38_i34:vccio(100)"
				( attribute "PN" "AE34"
					( Origin gPackager )
				)
				( objectStatus "U5D1.AE34" )
			)
			( pin "@baseboard_fab2_lib.baseboard_fab2(sch_1):page38_i34:vccio(101)"
				( attribute "PN" "AG34"
					( Origin gPackager )
				)
				( objectStatus "U5D1.AG34" )
			)
			( pin "@baseboard_fab2_lib.baseboard_fab2(sch_1):page38_i34:vccio(102)"
				( attribute "PN" "AM29"
					( Origin gPackager )
				)
				( objectStatus "U5D1.AM29" )
			)
			( pin "@baseboard_fab2_lib.baseboard_fab2(sch_1):page38_i34:vccio(103)"
				( attribute "PN" "AL28"
					( Origin gPackager )
				)
				( objectStatus "U5D1.AL28" )
			)
			( pin "@baseboard_fab2_lib.baseboard_fab2(sch_1):page38_i34:vccio(104)"
				( attribute "PN" "AR28"
					( Origin gPackager )
				)
				( objectStatus "U5D1.AR28" )
			)
			( pin "@baseboard_fab2_lib.baseboard_fab2(sch_1):page38_i34:vccsa(0)"
				( attribute "PN" "CJ66"
					( Origin gPackager )
				)
				( objectStatus "U5D1.CJ66" )
			)
			( pin "@baseboard_fab2_lib.baseboard_fab2(sch_1):page38_i34:vccsa(1)"
				( attribute "PN" "CJ64"
					( Origin gPackager )
				)
				( objectStatus "U5D1.CJ64" )
			)
			( pin "@baseboard_fab2_lib.baseboard_fab2(sch_1):page38_i34:vccsa(2)"
				( attribute "PN" "CH75"
					( Origin gPackager )
				)
				( objectStatus "U5D1.CH75" )
			)
			( pin "@baseboard_fab2_lib.baseboard_fab2(sch_1):page38_i34:vccsa(3)"
				( attribute "PN" "CH65"
					( Origin gPackager )
				)
				( objectStatus "U5D1.CH65" )
			)
			( pin "@baseboard_fab2_lib.baseboard_fab2(sch_1):page38_i34:vccsa(4)"
				( attribute "PN" "CG74"
					( Origin gPackager )
				)
				( objectStatus "U5D1.CG74" )
			)
			( pin "@baseboard_fab2_lib.baseboard_fab2(sch_1):page38_i34:vccsa(5)"
				( attribute "PN" "CG66"
					( Origin gPackager )
				)
				( objectStatus "U5D1.CG66" )
			)
			( pin "@baseboard_fab2_lib.baseboard_fab2(sch_1):page38_i34:vccsa(6)"
				( attribute "PN" "CG64"
					( Origin gPackager )
				)
				( objectStatus "U5D1.CG64" )
			)
			( pin "@baseboard_fab2_lib.baseboard_fab2(sch_1):page38_i34:vccsa(7)"
				( attribute "PN" "CF75"
					( Origin gPackager )
				)
				( objectStatus "U5D1.CF75" )
			)
			( pin "@baseboard_fab2_lib.baseboard_fab2(sch_1):page38_i34:vccsa(8)"
				( attribute "PN" "CF73"
					( Origin gPackager )
				)
				( objectStatus "U5D1.CF73" )
			)
			( pin "@baseboard_fab2_lib.baseboard_fab2(sch_1):page38_i34:vccsa(9)"
				( attribute "PN" "CF67"
					( Origin gPackager )
				)
				( objectStatus "U5D1.CF67" )
			)
			( pin "@baseboard_fab2_lib.baseboard_fab2(sch_1):page38_i34:vccsa(10)"
				( attribute "PN" "CF65"
					( Origin gPackager )
				)
				( objectStatus "U5D1.CF65" )
			)
			( pin "@baseboard_fab2_lib.baseboard_fab2(sch_1):page38_i34:vccsa(11)"
				( attribute "PN" "CE74"
					( Origin gPackager )
				)
				( objectStatus "U5D1.CE74" )
			)
			( pin "@baseboard_fab2_lib.baseboard_fab2(sch_1):page38_i34:vccsa(12)"
				( attribute "PN" "CE72"
					( Origin gPackager )
				)
				( objectStatus "U5D1.CE72" )
			)
			( pin "@baseboard_fab2_lib.baseboard_fab2(sch_1):page38_i34:vccsa(13)"
				( attribute "PN" "CE68"
					( Origin gPackager )
				)
				( objectStatus "U5D1.CE68" )
			)
			( pin "@baseboard_fab2_lib.baseboard_fab2(sch_1):page38_i34:vccsa(14)"
				( attribute "PN" "CE66"
					( Origin gPackager )
				)
				( objectStatus "U5D1.CE66" )
			)
			( pin "@baseboard_fab2_lib.baseboard_fab2(sch_1):page38_i34:vccsa(15)"
				( attribute "PN" "CE64"
					( Origin gPackager )
				)
				( objectStatus "U5D1.CE64" )
			)
			( pin "@baseboard_fab2_lib.baseboard_fab2(sch_1):page38_i34:vccsa(16)"
				( attribute "PN" "CD71"
					( Origin gPackager )
				)
				( objectStatus "U5D1.CD71" )
			)
			( pin "@baseboard_fab2_lib.baseboard_fab2(sch_1):page38_i34:vccsa(17)"
				( attribute "PN" "CD69"
					( Origin gPackager )
				)
				( objectStatus "U5D1.CD69" )
			)
			( pin "@baseboard_fab2_lib.baseboard_fab2(sch_1):page38_i34:vccsa(18)"
				( attribute "PN" "CD67"
					( Origin gPackager )
				)
				( objectStatus "U5D1.CD67" )
			)
			( pin "@baseboard_fab2_lib.baseboard_fab2(sch_1):page38_i34:vccsa(19)"
				( attribute "PN" "CD65"
					( Origin gPackager )
				)
				( objectStatus "U5D1.CD65" )
			)
			( pin "@baseboard_fab2_lib.baseboard_fab2(sch_1):page38_i34:vccsa(20)"
				( attribute "PN" "CC70"
					( Origin gPackager )
				)
				( objectStatus "U5D1.CC70" )
			)
			( pin "@baseboard_fab2_lib.baseboard_fab2(sch_1):page38_i34:vccsa(21)"
				( attribute "PN" "CC68"
					( Origin gPackager )
				)
				( objectStatus "U5D1.CC68" )
			)
			( pin "@baseboard_fab2_lib.baseboard_fab2(sch_1):page38_i34:vccsa(22)"
				( attribute "PN" "CC66"
					( Origin gPackager )
				)
				( objectStatus "U5D1.CC66" )
			)
			( pin "@baseboard_fab2_lib.baseboard_fab2(sch_1):page38_i34:vccsa(23)"
				( attribute "PN" "CB69"
					( Origin gPackager )
				)
				( objectStatus "U5D1.CB69" )
			)
			( pin "@baseboard_fab2_lib.baseboard_fab2(sch_1):page38_i34:vccsa(24)"
				( attribute "PN" "CB67"
					( Origin gPackager )
				)
				( objectStatus "U5D1.CB67" )
			)
			( pin "@baseboard_fab2_lib.baseboard_fab2(sch_1):page38_i34:vccsa(25)"
				( attribute "PN" "CB65"
					( Origin gPackager )
				)
				( objectStatus "U5D1.CB65" )
			)
			( pin "@baseboard_fab2_lib.baseboard_fab2(sch_1):page39_i127:cd_vcc_core_sense"
				( attribute "PN" "BN16"
					( Origin gPackager )
				)
				( objectStatus "U5D1.BN16" )
			)
			( pin "@baseboard_fab2_lib.baseboard_fab2(sch_1):page39_i127:cd_vccp_sense(0)"
				( attribute "PN" "BU16"
					( Origin gPackager )
				)
				( objectStatus "U5D1.BU16" )
			)
			( pin "@baseboard_fab2_lib.baseboard_fab2(sch_1):page39_i127:cd_vccp_sense(1)"
				( attribute "PN" "BT17"
					( Origin gPackager )
				)
				( objectStatus "U5D1.BT17" )
			)
			( pin "@baseboard_fab2_lib.baseboard_fab2(sch_1):page39_i127:cd_vss_vcc_core_sense"
				( attribute "PN" "BL16"
					( Origin gPackager )
				)
				( objectStatus "U5D1.BL16" )
			)
			( pin "@baseboard_fab2_lib.baseboard_fab2(sch_1):page39_i127:rsvd(0)"
				( attribute "PN" "EF83"
					( Origin gPackager )
				)
				( objectStatus "U5D1.EF83" )
			)
			( pin "@baseboard_fab2_lib.baseboard_fab2(sch_1):page39_i127:rsvd(1)"
				( attribute "PN" "EF81"
					( Origin gPackager )
				)
				( objectStatus "U5D1.EF81" )
			)
			( pin "@baseboard_fab2_lib.baseboard_fab2(sch_1):page39_i127:rsvd(2)"
				( attribute "PN" "EF77"
					( Origin gPackager )
				)
				( objectStatus "U5D1.EF77" )
			)
			( pin "@baseboard_fab2_lib.baseboard_fab2(sch_1):page39_i127:rsvd(3)"
				( attribute "PN" "EF47"
					( Origin gPackager )
				)
				( objectStatus "U5D1.EF47" )
			)
			( pin "@baseboard_fab2_lib.baseboard_fab2(sch_1):page39_i127:rsvd(4)"
				( attribute "PN" "EE84"
					( Origin gPackager )
				)
				( objectStatus "U5D1.EE84" )
			)
			( pin "@baseboard_fab2_lib.baseboard_fab2(sch_1):page39_i127:rsvd(5)"
				( attribute "PN" "EE82"
					( Origin gPackager )
				)
				( objectStatus "U5D1.EE82" )
			)
			( pin "@baseboard_fab2_lib.baseboard_fab2(sch_1):page39_i127:rsvd(6)"
				( attribute "PN" "EE6"
					( Origin gPackager )
				)
				( objectStatus "U5D1.EE6" )
			)
			( pin "@baseboard_fab2_lib.baseboard_fab2(sch_1):page39_i127:rsvd(7)"
				( attribute "PN" "EE46"
					( Origin gPackager )
				)
				( objectStatus "U5D1.EE46" )
			)
			( pin "@baseboard_fab2_lib.baseboard_fab2(sch_1):page39_i127:rsvd(8)"
				( attribute "PN" "EE16"
					( Origin gPackager )
				)
				( objectStatus "U5D1.EE16" )
			)
			( pin "@baseboard_fab2_lib.baseboard_fab2(sch_1):page39_i127:rsvd(9)"
				( attribute "PN" "ED83"
					( Origin gPackager )
				)
				( objectStatus "U5D1.ED83" )
			)
			( pin "@baseboard_fab2_lib.baseboard_fab2(sch_1):page39_i127:rsvd(10)"
				( attribute "PN" "ED5"
					( Origin gPackager )
				)
				( objectStatus "U5D1.ED5" )
			)
			( pin "@baseboard_fab2_lib.baseboard_fab2(sch_1):page39_i127:rsvd(11)"
				( attribute "PN" "ED45"
					( Origin gPackager )
				)
				( objectStatus "U5D1.ED45" )
			)
			( pin "@baseboard_fab2_lib.baseboard_fab2(sch_1):page39_i127:rsvd(12)"
				( attribute "PN" "EC84"
					( Origin gPackager )
				)
				( objectStatus "U5D1.EC84" )
			)
			( pin "@baseboard_fab2_lib.baseboard_fab2(sch_1):page39_i127:rsvd(13)"
				( attribute "PN" "EC44"
					( Origin gPackager )
				)
				( objectStatus "U5D1.EC44" )
			)
			( pin "@baseboard_fab2_lib.baseboard_fab2(sch_1):page39_i127:rsvd(14)"
				( attribute "PN" "EC4"
					( Origin gPackager )
				)
				( objectStatus "U5D1.EC4" )
			)
			( pin "@baseboard_fab2_lib.baseboard_fab2(sch_1):page39_i127:rsvd(15)"
				( attribute "PN" "EC16"
					( Origin gPackager )
				)
				( objectStatus "U5D1.EC16" )
			)
			( pin "@baseboard_fab2_lib.baseboard_fab2(sch_1):page39_i127:rsvd(16)"
				( attribute "PN" "EB85"
					( Origin gPackager )
				)
				( objectStatus "U5D1.EB85" )
			)
			( pin "@baseboard_fab2_lib.baseboard_fab2(sch_1):page39_i127:rsvd(17)"
				( attribute "PN" "EB5"
					( Origin gPackager )
				)
				( objectStatus "U5D1.EB5" )
			)
			( pin "@baseboard_fab2_lib.baseboard_fab2(sch_1):page39_i127:rsvd(18)"
				( attribute "PN" "EB3"
					( Origin gPackager )
				)
				( objectStatus "U5D1.EB3" )
			)
			( pin "@baseboard_fab2_lib.baseboard_fab2(sch_1):page39_i127:rsvd(19)"
				( attribute "PN" "EA44"
					( Origin gPackager )
				)
				( objectStatus "U5D1.EA44" )
			)
			( pin "@baseboard_fab2_lib.baseboard_fab2(sch_1):page39_i127:rsvd(20)"
				( attribute "PN" "EA4"
					( Origin gPackager )
				)
				( objectStatus "U5D1.EA4" )
			)
			( pin "@baseboard_fab2_lib.baseboard_fab2(sch_1):page39_i127:rsvd(21)"
				( attribute "PN" "DY3"
					( Origin gPackager )
				)
				( objectStatus "U5D1.DY3" )
			)
			( pin "@baseboard_fab2_lib.baseboard_fab2(sch_1):page39_i127:rsvd(22)"
				( attribute "PN" "DW46"
					( Origin gPackager )
				)
				( objectStatus "U5D1.DW46" )
			)
			( pin "@baseboard_fab2_lib.baseboard_fab2(sch_1):page39_i127:rsvd(23)"
				( attribute "PN" "DW44"
					( Origin gPackager )
				)
				( objectStatus "U5D1.DW44" )
			)
			( pin "@baseboard_fab2_lib.baseboard_fab2(sch_1):page39_i127:rsvd(24)"
				( attribute "PN" "DV71"
					( Origin gPackager )
				)
				( objectStatus "U5D1.DV71" )
			)
			( pin "@baseboard_fab2_lib.baseboard_fab2(sch_1):page39_i127:rsvd(25)"
				( attribute "PN" "DV61"
					( Origin gPackager )
				)
				( objectStatus "U5D1.DV61" )
			)
			( pin "@baseboard_fab2_lib.baseboard_fab2(sch_1):page39_i127:rsvd(26)"
				( attribute "PN" "DU44"
					( Origin gPackager )
				)
				( objectStatus "U5D1.DU44" )
			)
			( pin "@baseboard_fab2_lib.baseboard_fab2(sch_1):page39_i127:rsvd(27)"
				( attribute "PN" "DT71"
					( Origin gPackager )
				)
				( objectStatus "U5D1.DT71" )
			)
			( pin "@baseboard_fab2_lib.baseboard_fab2(sch_1):page39_i127:rsvd(28)"
				( attribute "PN" "DR44"
					( Origin gPackager )
				)
				( objectStatus "U5D1.DR44" )
			)
			( pin "@baseboard_fab2_lib.baseboard_fab2(sch_1):page39_i127:rsvd(29)"
				( attribute "PN" "DP65"
					( Origin gPackager )
				)
				( objectStatus "U5D1.DP65" )
			)
			( pin "@baseboard_fab2_lib.baseboard_fab2(sch_1):page39_i127:rsvd(30)"
				( attribute "PN" "DP17"
					( Origin gPackager )
				)
				( objectStatus "U5D1.DP17" )
			)
			( pin "@baseboard_fab2_lib.baseboard_fab2(sch_1):page39_i127:rsvd(31)"
				( attribute "PN" "DN66"
					( Origin gPackager )
				)
				( objectStatus "U5D1.DN66" )
			)
			( pin "@baseboard_fab2_lib.baseboard_fab2(sch_1):page39_i127:rsvd(32)"
				( attribute "PN" "DN62"
					( Origin gPackager )
				)
				( objectStatus "U5D1.DN62" )
			)
			( pin "@baseboard_fab2_lib.baseboard_fab2(sch_1):page39_i127:rsvd(33)"
				( attribute "PN" "DM67"
					( Origin gPackager )
				)
				( objectStatus "U5D1.DM67" )
			)
			( pin "@baseboard_fab2_lib.baseboard_fab2(sch_1):page39_i127:rsvd(34)"
				( attribute "PN" "DL66"
					( Origin gPackager )
				)
				( objectStatus "U5D1.DL66" )
			)
			( pin "@baseboard_fab2_lib.baseboard_fab2(sch_1):page39_i127:rsvd(35)"
				( attribute "PN" "DL38"
					( Origin gPackager )
				)
				( objectStatus "U5D1.DL38" )
			)
			( pin "@baseboard_fab2_lib.baseboard_fab2(sch_1):page39_i127:rsvd(36)"
				( attribute "PN" "DK67"
					( Origin gPackager )
				)
				( objectStatus "U5D1.DK67" )
			)
			( pin "@baseboard_fab2_lib.baseboard_fab2(sch_1):page39_i127:rsvd(37)"
				( attribute "PN" "DK65"
					( Origin gPackager )
				)
				( objectStatus "U5D1.DK65" )
			)
			( pin "@baseboard_fab2_lib.baseboard_fab2(sch_1):page39_i127:rsvd(38)"
				( attribute "PN" "DK37"
					( Origin gPackager )
				)
				( objectStatus "U5D1.DK37" )
			)
			( pin "@baseboard_fab2_lib.baseboard_fab2(sch_1):page39_i127:rsvd(39)"
				( attribute "PN" "DK15"
					( Origin gPackager )
				)
				( objectStatus "U5D1.DK15" )
			)
			( pin "@baseboard_fab2_lib.baseboard_fab2(sch_1):page39_i127:rsvd(40)"
				( attribute "PN" "DJ66"
					( Origin gPackager )
				)
				( objectStatus "U5D1.DJ66" )
			)
			( pin "@baseboard_fab2_lib.baseboard_fab2(sch_1):page39_i127:rsvd(41)"
				( attribute "PN" "DJ36"
					( Origin gPackager )
				)
				( objectStatus "U5D1.DJ36" )
			)
			( pin "@baseboard_fab2_lib.baseboard_fab2(sch_1):page39_i127:rsvd(42)"
				( attribute "PN" "DH65"
					( Origin gPackager )
				)
				( objectStatus "U5D1.DH65" )
			)
			( pin "@baseboard_fab2_lib.baseboard_fab2(sch_1):page39_i127:rsvd(43)"
				( attribute "PN" "DG64"
					( Origin gPackager )
				)
				( objectStatus "U5D1.DG64" )
			)
			( pin "@baseboard_fab2_lib.baseboard_fab2(sch_1):page39_i127:rsvd(44)"
				( attribute "PN" "DG36"
					( Origin gPackager )
				)
				( objectStatus "U5D1.DG36" )
			)
			( pin "@baseboard_fab2_lib.baseboard_fab2(sch_1):page39_i127:rsvd(45)"
				( attribute "PN" "DD51"
					( Origin gPackager )
				)
				( objectStatus "U5D1.DD51" )
			)
			( pin "@baseboard_fab2_lib.baseboard_fab2(sch_1):page39_i127:rsvd(46)"
				( attribute "PN" "DC52"
					( Origin gPackager )
				)
				( objectStatus "U5D1.DC52" )
			)
			( pin "@baseboard_fab2_lib.baseboard_fab2(sch_1):page39_i127:rsvd(47)"
				( attribute "PN" "DC46"
					( Origin gPackager )
				)
				( objectStatus "U5D1.DC46" )
			)
			( pin "@baseboard_fab2_lib.baseboard_fab2(sch_1):page39_i127:rsvd(48)"
				( attribute "PN" "DA56"
					( Origin gPackager )
				)
				( objectStatus "U5D1.DA56" )
			)
			( pin "@baseboard_fab2_lib.baseboard_fab2(sch_1):page39_i127:rsvd(49)"
				( attribute "PN" "DA54"
					( Origin gPackager )
				)
				( objectStatus "U5D1.DA54" )
			)
			( pin "@baseboard_fab2_lib.baseboard_fab2(sch_1):page39_i127:rsvd(50)"
				( attribute "PN" "DA52"
					( Origin gPackager )
				)
				( objectStatus "U5D1.DA52" )
			)
			( pin "@baseboard_fab2_lib.baseboard_fab2(sch_1):page39_i127:rsvd(51)"
				( attribute "PN" "DA40"
					( Origin gPackager )
				)
				( objectStatus "U5D1.DA40" )
			)
			( pin "@baseboard_fab2_lib.baseboard_fab2(sch_1):page39_i127:rsvd(52)"
				( attribute "PN" "DA24"
					( Origin gPackager )
				)
				( objectStatus "U5D1.DA24" )
			)
			( pin "@baseboard_fab2_lib.baseboard_fab2(sch_1):page39_i127:rsvd(53)"
				( attribute "PN" "CY73"
					( Origin gPackager )
				)
				( objectStatus "U5D1.CY73" )
			)
			( pin "@baseboard_fab2_lib.baseboard_fab2(sch_1):page39_i127:rsvd(54)"
				( attribute "PN" "CY63"
					( Origin gPackager )
				)
				( objectStatus "U5D1.CY63" )
			)
			( pin "@baseboard_fab2_lib.baseboard_fab2(sch_1):page39_i127:rsvd(55)"
				( attribute "PN" "CY57"
					( Origin gPackager )
				)
				( objectStatus "U5D1.CY57" )
			)
			( pin "@baseboard_fab2_lib.baseboard_fab2(sch_1):page39_i127:rsvd(56)"
				( attribute "PN" "CY53"
					( Origin gPackager )
				)
				( objectStatus "U5D1.CY53" )
			)
			( pin "@baseboard_fab2_lib.baseboard_fab2(sch_1):page39_i127:rsvd(57)"
				( attribute "PN" "CY39"
					( Origin gPackager )
				)
				( objectStatus "U5D1.CY39" )
			)
			( pin "@baseboard_fab2_lib.baseboard_fab2(sch_1):page39_i127:rsvd(58)"
				( attribute "PN" "CY25"
					( Origin gPackager )
				)
				( objectStatus "U5D1.CY25" )
			)
			( pin "@baseboard_fab2_lib.baseboard_fab2(sch_1):page39_i127:rsvd(59)"
				( attribute "PN" "CY23"
					( Origin gPackager )
				)
				( objectStatus "U5D1.CY23" )
			)
			( pin "@baseboard_fab2_lib.baseboard_fab2(sch_1):page39_i127:rsvd(60)"
				( attribute "PN" "CW62"
					( Origin gPackager )
				)
				( objectStatus "U5D1.CW62" )
			)
			( pin "@baseboard_fab2_lib.baseboard_fab2(sch_1):page39_i127:rsvd(61)"
				( attribute "PN" "CW60"
					( Origin gPackager )
				)
				( objectStatus "U5D1.CW60" )
			)
			( pin "@baseboard_fab2_lib.baseboard_fab2(sch_1):page39_i127:rsvd(62)"
				( attribute "PN" "CW24"
					( Origin gPackager )
				)
				( objectStatus "U5D1.CW24" )
			)
			( pin "@baseboard_fab2_lib.baseboard_fab2(sch_1):page39_i127:rsvd(63)"
				( attribute "PN" "CW22"
					( Origin gPackager )
				)
				( objectStatus "U5D1.CW22" )
			)
			( pin "@baseboard_fab2_lib.baseboard_fab2(sch_1):page39_i127:rsvd(64)"
				( attribute "PN" "CV69"
					( Origin gPackager )
				)
				( objectStatus "U5D1.CV69" )
			)
			( pin "@baseboard_fab2_lib.baseboard_fab2(sch_1):page39_i127:rsvd(65)"
				( attribute "PN" "CV23"
					( Origin gPackager )
				)
				( objectStatus "U5D1.CV23" )
			)
			( pin "@baseboard_fab2_lib.baseboard_fab2(sch_1):page39_i127:rsvd(66)"
				( attribute "PN" "CU60"
					( Origin gPackager )
				)
				( objectStatus "U5D1.CU60" )
			)
			( pin "@baseboard_fab2_lib.baseboard_fab2(sch_1):page39_i127:rsvd(67)"
				( attribute "PN" "CU6"
					( Origin gPackager )
				)
				( objectStatus "U5D1.CU6" )
			)
			( pin "@baseboard_fab2_lib.baseboard_fab2(sch_1):page39_i127:rsvd(68)"
				( attribute "PN" "CU24"
					( Origin gPackager )
				)
				( objectStatus "U5D1.CU24" )
			)
			( pin "@baseboard_fab2_lib.baseboard_fab2(sch_1):page39_i127:rsvd(69)"
				( attribute "PN" "CT69"
					( Origin gPackager )
				)
				( objectStatus "U5D1.CT69" )
			)
			( pin "@baseboard_fab2_lib.baseboard_fab2(sch_1):page39_i127:rsvd(70)"
				( attribute "PN" "CT5"
					( Origin gPackager )
				)
				( objectStatus "U5D1.CT5" )
			)
			( pin "@baseboard_fab2_lib.baseboard_fab2(sch_1):page39_i127:rsvd(71)"
				( attribute "PN" "CT23"
					( Origin gPackager )
				)
				( objectStatus "U5D1.CT23" )
			)
			( pin "@baseboard_fab2_lib.baseboard_fab2(sch_1):page39_i127:rsvd(72)"
				( attribute "PN" "CR60"
					( Origin gPackager )
				)
				( objectStatus "U5D1.CR60" )
			)
			( pin "@baseboard_fab2_lib.baseboard_fab2(sch_1):page39_i127:rsvd(73)"
				( attribute "PN" "CP31"
					( Origin gPackager )
				)
				( objectStatus "U5D1.CP31" )
			)
			( pin "@baseboard_fab2_lib.baseboard_fab2(sch_1):page39_i127:rsvd(74)"
				( attribute "PN" "CP23"
					( Origin gPackager )
				)
				( objectStatus "U5D1.CP23" )
			)
			( pin "@baseboard_fab2_lib.baseboard_fab2(sch_1):page39_i127:rsvd(75)"
				( attribute "PN" "CN28"
					( Origin gPackager )
				)
				( objectStatus "U5D1.CN28" )
			)
			( pin "@baseboard_fab2_lib.baseboard_fab2(sch_1):page39_i127:rsvd(76)"
				( attribute "PN" "CN24"
					( Origin gPackager )
				)
				( objectStatus "U5D1.CN24" )
			)
			( pin "@baseboard_fab2_lib.baseboard_fab2(sch_1):page39_i127:rsvd(77)"
				( attribute "PN" "CN22"
					( Origin gPackager )
				)
				( objectStatus "U5D1.CN22" )
			)
			( pin "@baseboard_fab2_lib.baseboard_fab2(sch_1):page39_i127:rsvd(78)"
				( attribute "PN" "CM25"
					( Origin gPackager )
				)
				( objectStatus "U5D1.CM25" )
			)
			( pin "@baseboard_fab2_lib.baseboard_fab2(sch_1):page39_i127:rsvd(79)"
				( attribute "PN" "CM23"
					( Origin gPackager )
				)
				( objectStatus "U5D1.CM23" )
			)
			( pin "@baseboard_fab2_lib.baseboard_fab2(sch_1):page39_i127:rsvd(80)"
				( attribute "PN" "CL26"
					( Origin gPackager )
				)
				( objectStatus "U5D1.CL26" )
			)
			( pin "@baseboard_fab2_lib.baseboard_fab2(sch_1):page39_i127:vccio(0)"
				( attribute "PN" "EE10"
					( Origin gPackager )
				)
				( objectStatus "U5D1.EE10" )
			)
			( pin "@baseboard_fab2_lib.baseboard_fab2(sch_1):page39_i127:vccio(1)"
				( attribute "PN" "AE10"
					( Origin gPackager )
				)
				( objectStatus "U5D1.AE10" )
			)
			( pin "@baseboard_fab2_lib.baseboard_fab2(sch_1):page39_i127:vccio(2)"
				( attribute "PN" "AF5"
					( Origin gPackager )
				)
				( objectStatus "U5D1.AF5" )
			)
			( pin "@baseboard_fab2_lib.baseboard_fab2(sch_1):page39_i127:vccio(3)"
				( attribute "PN" "DV11"
					( Origin gPackager )
				)
				( objectStatus "U5D1.DV11" )
			)
			( pin "@baseboard_fab2_lib.baseboard_fab2(sch_1):page39_i127:vccio(4)"
				( attribute "PN" "AM5"
					( Origin gPackager )
				)
				( objectStatus "U5D1.AM5" )
			)
			( pin "@baseboard_fab2_lib.baseboard_fab2(sch_1):page39_i127:vccio(5)"
				( attribute "PN" "AT5"
					( Origin gPackager )
				)
				( objectStatus "U5D1.AT5" )
			)
			( pin "@baseboard_fab2_lib.baseboard_fab2(sch_1):page39_i127:vccio(6)"
				( attribute "PN" "AT7"
					( Origin gPackager )
				)
				( objectStatus "U5D1.AT7" )
			)
			( pin "@baseboard_fab2_lib.baseboard_fab2(sch_1):page39_i127:vccio(7)"
				( attribute "PN" "BE24"
					( Origin gPackager )
				)
				( objectStatus "U5D1.BE24" )
			)
			( pin "@baseboard_fab2_lib.baseboard_fab2(sch_1):page39_i127:vccio(8)"
				( attribute "PN" "DK21"
					( Origin gPackager )
				)
				( objectStatus "U5D1.DK21" )
			)
			( pin "@baseboard_fab2_lib.baseboard_fab2(sch_1):page39_i127:vccio(9)"
				( attribute "PN" "CF5"
					( Origin gPackager )
				)
				( objectStatus "U5D1.CF5" )
			)
			( pin "@baseboard_fab2_lib.baseboard_fab2(sch_1):page39_i127:vccio(10)"
				( attribute "PN" "CG14"
					( Origin gPackager )
				)
				( objectStatus "U5D1.CG14" )
			)
			( pin "@baseboard_fab2_lib.baseboard_fab2(sch_1):page39_i127:vccio(11)"
				( attribute "PN" "CL20"
					( Origin gPackager )
				)
				( objectStatus "U5D1.CL20" )
			)
			( pin "@baseboard_fab2_lib.baseboard_fab2(sch_1):page39_i127:vccio(12)"
				( attribute "PN" "CP13"
					( Origin gPackager )
				)
				( objectStatus "U5D1.CP13" )
			)
			( pin "@baseboard_fab2_lib.baseboard_fab2(sch_1):page39_i127:vccio(13)"
				( attribute "PN" "DE14"
					( Origin gPackager )
				)
				( objectStatus "U5D1.DE14" )
			)
			( pin "@baseboard_fab2_lib.baseboard_fab2(sch_1):page39_i127:vccio(14)"
				( attribute "PN" "DC18"
					( Origin gPackager )
				)
				( objectStatus "U5D1.DC18" )
			)
			( pin "@baseboard_fab2_lib.baseboard_fab2(sch_1):page39_i127:vccio(15)"
				( attribute "PN" "CY17"
					( Origin gPackager )
				)
				( objectStatus "U5D1.CY17" )
			)
			( pin "@baseboard_fab2_lib.baseboard_fab2(sch_1):page39_i127:vccio(16)"
				( attribute "PN" "CU18"
					( Origin gPackager )
				)
				( objectStatus "U5D1.CU18" )
			)
			( pin "@baseboard_fab2_lib.baseboard_fab2(sch_1):page39_i127:vccio(17)"
				( attribute "PN" "CV21"
					( Origin gPackager )
				)
				( objectStatus "U5D1.CV21" )
			)
			( pin "@baseboard_fab2_lib.baseboard_fab2(sch_1):page39_i127:vccio(18)"
				( attribute "PN" "CU12"
					( Origin gPackager )
				)
				( objectStatus "U5D1.CU12" )
			)
			( pin "@baseboard_fab2_lib.baseboard_fab2(sch_1):page39_i127:vccio(19)"
				( attribute "PN" "CN6"
					( Origin gPackager )
				)
				( objectStatus "U5D1.CN6" )
			)
			( pin "@baseboard_fab2_lib.baseboard_fab2(sch_1):page39_i127:vccio_sense"
				( attribute "PN" "BH5"
					( Origin gPackager )
				)
				( objectStatus "U5D1.BH5" )
			)
			( pin "@baseboard_fab2_lib.baseboard_fab2(sch_1):page39_i127:vccsa_sense"
				( attribute "PN" "CE76"
					( Origin gPackager )
				)
				( objectStatus "U5D1.CE76" )
			)
			( pin "@baseboard_fab2_lib.baseboard_fab2(sch_1):page39_i127:vss_vccio_sense"
				( attribute "PN" "BF5"
					( Origin gPackager )
				)
				( objectStatus "U5D1.BF5" )
			)
			( pin "@baseboard_fab2_lib.baseboard_fab2(sch_1):page39_i127:vss_vccsa_sense"
				( attribute "PN" "CG76"
					( Origin gPackager )
				)
				( objectStatus "U5D1.CG76" )
			)
			( pin "@baseboard_fab2_lib.baseboard_fab2(sch_1):page40_i20:vss(1094)"
				( attribute "PN" "J74"
					( Origin gPackager )
				)
				( objectStatus "U5D1.J74" )
			)
			( pin "@baseboard_fab2_lib.baseboard_fab2(sch_1):page40_i20:vss(1095)"
				( attribute "PN" "J72"
					( Origin gPackager )
				)
				( objectStatus "U5D1.J72" )
			)
			( pin "@baseboard_fab2_lib.baseboard_fab2(sch_1):page40_i20:vss(1096)"
				( attribute "PN" "J40"
					( Origin gPackager )
				)
				( objectStatus "U5D1.J40" )
			)
			( pin "@baseboard_fab2_lib.baseboard_fab2(sch_1):page40_i20:vss(1097)"
				( attribute "PN" "J38"
					( Origin gPackager )
				)
				( objectStatus "U5D1.J38" )
			)
			( pin "@baseboard_fab2_lib.baseboard_fab2(sch_1):page40_i20:vss(1098)"
				( attribute "PN" "J34"
					( Origin gPackager )
				)
				( objectStatus "U5D1.J34" )
			)
			( pin "@baseboard_fab2_lib.baseboard_fab2(sch_1):page40_i20:vss(1099)"
				( attribute "PN" "J32"
					( Origin gPackager )
				)
				( objectStatus "U5D1.J32" )
			)
			( pin "@baseboard_fab2_lib.baseboard_fab2(sch_1):page40_i20:vss(1100)"
				( attribute "PN" "J28"
					( Origin gPackager )
				)
				( objectStatus "U5D1.J28" )
			)
			( pin "@baseboard_fab2_lib.baseboard_fab2(sch_1):page40_i20:vss(1101)"
				( attribute "PN" "J26"
					( Origin gPackager )
				)
				( objectStatus "U5D1.J26" )
			)
			( pin "@baseboard_fab2_lib.baseboard_fab2(sch_1):page40_i20:vss(1102)"
				( attribute "PN" "J22"
					( Origin gPackager )
				)
				( objectStatus "U5D1.J22" )
			)
			( pin "@baseboard_fab2_lib.baseboard_fab2(sch_1):page40_i20:vss(1103)"
				( attribute "PN" "J14"
					( Origin gPackager )
				)
				( objectStatus "U5D1.J14" )
			)
			( pin "@baseboard_fab2_lib.baseboard_fab2(sch_1):page40_i20:vss(1104)"
				( attribute "PN" "J12"
					( Origin gPackager )
				)
				( objectStatus "U5D1.J12" )
			)
			( pin "@baseboard_fab2_lib.baseboard_fab2(sch_1):page40_i20:vss(1105)"
				( attribute "PN" "J4"
					( Origin gPackager )
				)
				( objectStatus "U5D1.J4" )
			)
			( pin "@baseboard_fab2_lib.baseboard_fab2(sch_1):page40_i20:vss(1106)"
				( attribute "PN" "DN44"
					( Origin gPackager )
				)
				( objectStatus "U5D1.DN44" )
			)
			( pin "@baseboard_fab2_lib.baseboard_fab2(sch_1):page40_i20:vss(1107)"
				( attribute "PN" "H75"
					( Origin gPackager )
				)
				( objectStatus "U5D1.H75" )
			)
			( pin "@baseboard_fab2_lib.baseboard_fab2(sch_1):page40_i20:vss(1108)"
				( attribute "PN" "H71"
					( Origin gPackager )
				)
				( objectStatus "U5D1.H71" )
			)
			( pin "@baseboard_fab2_lib.baseboard_fab2(sch_1):page40_i20:vss(1109)"
				( attribute "PN" "H65"
					( Origin gPackager )
				)
				( objectStatus "U5D1.H65" )
			)
			( pin "@baseboard_fab2_lib.baseboard_fab2(sch_1):page40_i20:vss(1110)"
				( attribute "PN" "H41"
					( Origin gPackager )
				)
				( objectStatus "U5D1.H41" )
			)
			( pin "@baseboard_fab2_lib.baseboard_fab2(sch_1):page40_i20:vss(1111)"
				( attribute "PN" "H39"
					( Origin gPackager )
				)
				( objectStatus "U5D1.H39" )
			)
			( pin "@baseboard_fab2_lib.baseboard_fab2(sch_1):page40_i20:vss(1112)"
				( attribute "PN" "H37"
					( Origin gPackager )
				)
				( objectStatus "U5D1.H37" )
			)
			( pin "@baseboard_fab2_lib.baseboard_fab2(sch_1):page40_i20:vss(1113)"
				( attribute "PN" "H35"
					( Origin gPackager )
				)
				( objectStatus "U5D1.H35" )
			)
			( pin "@baseboard_fab2_lib.baseboard_fab2(sch_1):page40_i20:vss(1114)"
				( attribute "PN" "H33"
					( Origin gPackager )
				)
				( objectStatus "U5D1.H33" )
			)
			( pin "@baseboard_fab2_lib.baseboard_fab2(sch_1):page40_i20:vss(1115)"
				( attribute "PN" "H31"
					( Origin gPackager )
				)
				( objectStatus "U5D1.H31" )
			)
			( pin "@baseboard_fab2_lib.baseboard_fab2(sch_1):page40_i20:vss(1116)"
				( attribute "PN" "H29"
					( Origin gPackager )
				)
				( objectStatus "U5D1.H29" )
			)
			( pin "@baseboard_fab2_lib.baseboard_fab2(sch_1):page40_i20:vss(1117)"
				( attribute "PN" "H27"
					( Origin gPackager )
				)
				( objectStatus "U5D1.H27" )
			)
			( pin "@baseboard_fab2_lib.baseboard_fab2(sch_1):page40_i20:vss(1118)"
				( attribute "PN" "H25"
					( Origin gPackager )
				)
				( objectStatus "U5D1.H25" )
			)
			( pin "@baseboard_fab2_lib.baseboard_fab2(sch_1):page40_i20:vss(1119)"
				( attribute "PN" "H11"
					( Origin gPackager )
				)
				( objectStatus "U5D1.H11" )
			)
			( pin "@baseboard_fab2_lib.baseboard_fab2(sch_1):page40_i20:vss(1120)"
				( attribute "PN" "H3"
					( Origin gPackager )
				)
				( objectStatus "U5D1.H3" )
			)
			( pin "@baseboard_fab2_lib.baseboard_fab2(sch_1):page40_i20:vss(1121)"
				( attribute "PN" "G82"
					( Origin gPackager )
				)
				( objectStatus "U5D1.G82" )
			)
			( pin "@baseboard_fab2_lib.baseboard_fab2(sch_1):page40_i20:vss(1122)"
				( attribute "PN" "G80"
					( Origin gPackager )
				)
				( objectStatus "U5D1.G80" )
			)
			( pin "@baseboard_fab2_lib.baseboard_fab2(sch_1):page40_i20:vss(1123)"
				( attribute "PN" "G78"
					( Origin gPackager )
				)
				( objectStatus "U5D1.G78" )
			)
			( pin "@baseboard_fab2_lib.baseboard_fab2(sch_1):page40_i20:vss(1124)"
				( attribute "PN" "G76"
					( Origin gPackager )
				)
				( objectStatus "U5D1.G76" )
			)
			( pin "@baseboard_fab2_lib.baseboard_fab2(sch_1):page40_i20:vss(1125)"
				( attribute "PN" "G70"
					( Origin gPackager )
				)
				( objectStatus "U5D1.G70" )
			)
			( pin "@baseboard_fab2_lib.baseboard_fab2(sch_1):page40_i20:vss(1126)"
				( attribute "PN" "G66"
					( Origin gPackager )
				)
				( objectStatus "U5D1.G66" )
			)
			( pin "@baseboard_fab2_lib.baseboard_fab2(sch_1):page40_i20:vss(1127)"
				( attribute "PN" "G42"
					( Origin gPackager )
				)
				( objectStatus "U5D1.G42" )
			)
			( pin "@baseboard_fab2_lib.baseboard_fab2(sch_1):page40_i20:vss(1128)"
				( attribute "PN" "G38"
					( Origin gPackager )
				)
				( objectStatus "U5D1.G38" )
			)
			( pin "@baseboard_fab2_lib.baseboard_fab2(sch_1):page40_i20:vss(1129)"
				( attribute "PN" "G36"
					( Origin gPackager )
				)
				( objectStatus "U5D1.G36" )
			)
			( pin "@baseboard_fab2_lib.baseboard_fab2(sch_1):page40_i20:vss(1130)"
				( attribute "PN" "G32"
					( Origin gPackager )
				)
				( objectStatus "U5D1.G32" )
			)
			( pin "@baseboard_fab2_lib.baseboard_fab2(sch_1):page40_i20:vss(1131)"
				( attribute "PN" "G30"
					( Origin gPackager )
				)
				( objectStatus "U5D1.G30" )
			)
			( pin "@baseboard_fab2_lib.baseboard_fab2(sch_1):page40_i20:vss(1132)"
				( attribute "PN" "G26"
					( Origin gPackager )
				)
				( objectStatus "U5D1.G26" )
			)
			( pin "@baseboard_fab2_lib.baseboard_fab2(sch_1):page40_i20:vss(1133)"
				( attribute "PN" "G24"
					( Origin gPackager )
				)
				( objectStatus "U5D1.G24" )
			)
			( pin "@baseboard_fab2_lib.baseboard_fab2(sch_1):page40_i20:vss(1134)"
				( attribute "PN" "G22"
					( Origin gPackager )
				)
				( objectStatus "U5D1.G22" )
			)
			( pin "@baseboard_fab2_lib.baseboard_fab2(sch_1):page40_i20:vss(1135)"
				( attribute "PN" "G8"
					( Origin gPackager )
				)
				( objectStatus "U5D1.G8" )
			)
			( pin "@baseboard_fab2_lib.baseboard_fab2(sch_1):page40_i20:vss(1136)"
				( attribute "PN" "G4"
					( Origin gPackager )
				)
				( objectStatus "U5D1.G4" )
			)
			( pin "@baseboard_fab2_lib.baseboard_fab2(sch_1):page40_i20:vss(1137)"
				( attribute "PN" "F69"
					( Origin gPackager )
				)
				( objectStatus "U5D1.F69" )
			)
			( pin "@baseboard_fab2_lib.baseboard_fab2(sch_1):page40_i20:vss(1138)"
				( attribute "PN" "F67"
					( Origin gPackager )
				)
				( objectStatus "U5D1.F67" )
			)
			( pin "@baseboard_fab2_lib.baseboard_fab2(sch_1):page40_i20:vss(1139)"
				( attribute "PN" "F43"
					( Origin gPackager )
				)
				( objectStatus "U5D1.F43" )
			)
			( pin "@baseboard_fab2_lib.baseboard_fab2(sch_1):page40_i20:vss(1140)"
				( attribute "PN" "F37"
					( Origin gPackager )
				)
				( objectStatus "U5D1.F37" )
			)
			( pin "@baseboard_fab2_lib.baseboard_fab2(sch_1):page40_i20:vss(1141)"
				( attribute "PN" "F31"
					( Origin gPackager )
				)
				( objectStatus "U5D1.F31" )
			)
			( pin "@baseboard_fab2_lib.baseboard_fab2(sch_1):page40_i20:vss(1142)"
				( attribute "PN" "F25"
					( Origin gPackager )
				)
				( objectStatus "U5D1.F25" )
			)
			( pin "@baseboard_fab2_lib.baseboard_fab2(sch_1):page40_i20:vss(1143)"
				( attribute "PN" "F19"
					( Origin gPackager )
				)
				( objectStatus "U5D1.F19" )
			)
			( pin "@baseboard_fab2_lib.baseboard_fab2(sch_1):page40_i20:vss(1144)"
				( attribute "PN" "F17"
					( Origin gPackager )
				)
				( objectStatus "U5D1.F17" )
			)
			( pin "@baseboard_fab2_lib.baseboard_fab2(sch_1):page40_i20:vss(1145)"
				( attribute "PN" "F5"
					( Origin gPackager )
				)
				( objectStatus "U5D1.F5" )
			)
			( pin "@baseboard_fab2_lib.baseboard_fab2(sch_1):page40_i20:vss(1146)"
				( attribute "PN" "E76"
					( Origin gPackager )
				)
				( objectStatus "U5D1.E76" )
			)
			( pin "@baseboard_fab2_lib.baseboard_fab2(sch_1):page40_i20:vss(1147)"
				( attribute "PN" "E74"
					( Origin gPackager )
				)
				( objectStatus "U5D1.E74" )
			)
			( pin "@baseboard_fab2_lib.baseboard_fab2(sch_1):page40_i20:vss(1148)"
				( attribute "PN" "E72"
					( Origin gPackager )
				)
				( objectStatus "U5D1.E72" )
			)
			( pin "@baseboard_fab2_lib.baseboard_fab2(sch_1):page40_i20:vss(1149)"
				( attribute "PN" "E22"
					( Origin gPackager )
				)
				( objectStatus "U5D1.E22" )
			)
			( pin "@baseboard_fab2_lib.baseboard_fab2(sch_1):page40_i20:vss(1150)"
				( attribute "PN" "E20"
					( Origin gPackager )
				)
				( objectStatus "U5D1.E20" )
			)
			( pin "@baseboard_fab2_lib.baseboard_fab2(sch_1):page40_i20:vss(1151)"
				( attribute "PN" "E18"
					( Origin gPackager )
				)
				( objectStatus "U5D1.E18" )
			)
			( pin "@baseboard_fab2_lib.baseboard_fab2(sch_1):page40_i20:vss(1152)"
				( attribute "PN" "E16"
					( Origin gPackager )
				)
				( objectStatus "U5D1.E16" )
			)
			( pin "@baseboard_fab2_lib.baseboard_fab2(sch_1):page40_i20:vss(1153)"
				( attribute "PN" "E8"
					( Origin gPackager )
				)
				( objectStatus "U5D1.E8" )
			)
			( pin "@baseboard_fab2_lib.baseboard_fab2(sch_1):page40_i20:vss(1154)"
				( attribute "PN" "E6"
					( Origin gPackager )
				)
				( objectStatus "U5D1.E6" )
			)
			( pin "@baseboard_fab2_lib.baseboard_fab2(sch_1):page40_i20:vss(1155)"
				( attribute "PN" "D77"
					( Origin gPackager )
				)
				( objectStatus "U5D1.D77" )
			)
			( pin "@baseboard_fab2_lib.baseboard_fab2(sch_1):page40_i20:vss(1156)"
				( attribute "PN" "D43"
					( Origin gPackager )
				)
				( objectStatus "U5D1.D43" )
			)
			( pin "@baseboard_fab2_lib.baseboard_fab2(sch_1):page40_i20:vss(1157)"
				( attribute "PN" "D41"
					( Origin gPackager )
				)
				( objectStatus "U5D1.D41" )
			)
			( pin "@baseboard_fab2_lib.baseboard_fab2(sch_1):page40_i20:vss(1158)"
				( attribute "PN" "D39"
					( Origin gPackager )
				)
				( objectStatus "U5D1.D39" )
			)
			( pin "@baseboard_fab2_lib.baseboard_fab2(sch_1):page40_i20:vss(1159)"
				( attribute "PN" "D37"
					( Origin gPackager )
				)
				( objectStatus "U5D1.D37" )
			)
			( pin "@baseboard_fab2_lib.baseboard_fab2(sch_1):page40_i20:vss(1160)"
				( attribute "PN" "D35"
					( Origin gPackager )
				)
				( objectStatus "U5D1.D35" )
			)
			( pin "@baseboard_fab2_lib.baseboard_fab2(sch_1):page40_i20:vss(1161)"
				( attribute "PN" "D33"
					( Origin gPackager )
				)
				( objectStatus "U5D1.D33" )
			)
			( pin "@baseboard_fab2_lib.baseboard_fab2(sch_1):page40_i20:vss(1162)"
				( attribute "PN" "D31"
					( Origin gPackager )
				)
				( objectStatus "U5D1.D31" )
			)
			( pin "@baseboard_fab2_lib.baseboard_fab2(sch_1):page40_i20:vss(1163)"
				( attribute "PN" "D29"
					( Origin gPackager )
				)
				( objectStatus "U5D1.D29" )
			)
			( pin "@baseboard_fab2_lib.baseboard_fab2(sch_1):page40_i20:vss(1164)"
				( attribute "PN" "D27"
					( Origin gPackager )
				)
				( objectStatus "U5D1.D27" )
			)
			( pin "@baseboard_fab2_lib.baseboard_fab2(sch_1):page40_i20:vss(1165)"
				( attribute "PN" "D25"
					( Origin gPackager )
				)
				( objectStatus "U5D1.D25" )
			)
			( pin "@baseboard_fab2_lib.baseboard_fab2(sch_1):page40_i20:vss(1166)"
				( attribute "PN" "D13"
					( Origin gPackager )
				)
				( objectStatus "U5D1.D13" )
			)
			( pin "@baseboard_fab2_lib.baseboard_fab2(sch_1):page40_i20:vss(1167)"
				( attribute "PN" "D11"
					( Origin gPackager )
				)
				( objectStatus "U5D1.D11" )
			)
			( pin "@baseboard_fab2_lib.baseboard_fab2(sch_1):page40_i20:vss(1168)"
				( attribute "PN" "CM27"
					( Origin gPackager )
				)
				( objectStatus "U5D1.CM27" )
			)
			( pin "@baseboard_fab2_lib.baseboard_fab2(sch_1):page40_i20:vss(1169)"
				( attribute "PN" "C78"
					( Origin gPackager )
				)
				( objectStatus "U5D1.C78" )
			)
			( pin "@baseboard_fab2_lib.baseboard_fab2(sch_1):page40_i20:vss(1170)"
				( attribute "PN" "C76"
					( Origin gPackager )
				)
				( objectStatus "U5D1.C76" )
			)
			( pin "@baseboard_fab2_lib.baseboard_fab2(sch_1):page40_i20:vss(1171)"
				( attribute "PN" "C16"
					( Origin gPackager )
				)
				( objectStatus "U5D1.C16" )
			)
			( pin "@baseboard_fab2_lib.baseboard_fab2(sch_1):page40_i20:vss(1172)"
				( attribute "PN" "C14"
					( Origin gPackager )
				)
				( objectStatus "U5D1.C14" )
			)
			( pin "@baseboard_fab2_lib.baseboard_fab2(sch_1):page40_i20:vss(1173)"
				( attribute "PN" "C12"
					( Origin gPackager )
				)
				( objectStatus "U5D1.C12" )
			)
			( pin "@baseboard_fab2_lib.baseboard_fab2(sch_1):page40_i20:vss(1174)"
				( attribute "PN" "C10"
					( Origin gPackager )
				)
				( objectStatus "U5D1.C10" )
			)
			( pin "@baseboard_fab2_lib.baseboard_fab2(sch_1):page40_i20:vss(1175)"
				( attribute "PN" "C8"
					( Origin gPackager )
				)
				( objectStatus "U5D1.C8" )
			)
			( pin "@baseboard_fab2_lib.baseboard_fab2(sch_1):page40_i20:vss(1176)"
				( attribute "PN" "B75"
					( Origin gPackager )
				)
				( objectStatus "U5D1.B75" )
			)
			( pin "@baseboard_fab2_lib.baseboard_fab2(sch_1):page40_i20:vss(1177)"
				( attribute "PN" "B71"
					( Origin gPackager )
				)
				( objectStatus "U5D1.B71" )
			)
			( pin "@baseboard_fab2_lib.baseboard_fab2(sch_1):page40_i20:vss(1178)"
				( attribute "PN" "B37"
					( Origin gPackager )
				)
				( objectStatus "U5D1.B37" )
			)
			( pin "@baseboard_fab2_lib.baseboard_fab2(sch_1):page40_i20:vss(1179)"
				( attribute "PN" "B31"
					( Origin gPackager )
				)
				( objectStatus "U5D1.B31" )
			)
			( pin "@baseboard_fab2_lib.baseboard_fab2(sch_1):page40_i20:vss(1180)"
				( attribute "PN" "B25"
					( Origin gPackager )
				)
				( objectStatus "U5D1.B25" )
			)
			( pin "@baseboard_fab2_lib.baseboard_fab2(sch_1):page40_i20:vss(1181)"
				( attribute "PN" "A38"
					( Origin gPackager )
				)
				( objectStatus "U5D1.A38" )
			)
			( pin "@baseboard_fab2_lib.baseboard_fab2(sch_1):page40_i20:vss(1182)"
				( attribute "PN" "A36"
					( Origin gPackager )
				)
				( objectStatus "U5D1.A36" )
			)
			( pin "@baseboard_fab2_lib.baseboard_fab2(sch_1):page40_i20:vss(1183)"
				( attribute "PN" "A32"
					( Origin gPackager )
				)
				( objectStatus "U5D1.A32" )
			)
			( pin "@baseboard_fab2_lib.baseboard_fab2(sch_1):page40_i20:vss(1184)"
				( attribute "PN" "A30"
					( Origin gPackager )
				)
				( objectStatus "U5D1.A30" )
			)
			( pin "@baseboard_fab2_lib.baseboard_fab2(sch_1):page40_i20:vss(1185)"
				( attribute "PN" "A26"
					( Origin gPackager )
				)
				( objectStatus "U5D1.A26" )
			)
			( pin "@baseboard_fab2_lib.baseboard_fab2(sch_1):page40_i20:vss(1186)"
				( attribute "PN" "AC58"
					( Origin gPackager )
				)
				( objectStatus "U5D1.AC58" )
			)
			( pin "@baseboard_fab2_lib.baseboard_fab2(sch_1):page40_i20:vss(1187)"
				( attribute "PN" "AC60"
					( Origin gPackager )
				)
				( objectStatus "U5D1.AC60" )
			)
			( pin "@baseboard_fab2_lib.baseboard_fab2(sch_1):page40_i20:vss(1188)"
				( attribute "PN" "AC62"
					( Origin gPackager )
				)
				( objectStatus "U5D1.AC62" )
			)
			( pin "@baseboard_fab2_lib.baseboard_fab2(sch_1):page40_i20:vss(1189)"
				( attribute "PN" "AJ4"
					( Origin gPackager )
				)
				( objectStatus "U5D1.AJ4" )
			)
			( pin "@baseboard_fab2_lib.baseboard_fab2(sch_1):page40_i20:vss(1190)"
				( attribute "PN" "AR6"
					( Origin gPackager )
				)
				( objectStatus "U5D1.AR6" )
			)
			( pin "@baseboard_fab2_lib.baseboard_fab2(sch_1):page40_i20:vss(1191)"
				( attribute "PN" "CG6"
					( Origin gPackager )
				)
				( objectStatus "U5D1.CG6" )
			)
			( pin "@baseboard_fab2_lib.baseboard_fab2(sch_1):page40_i20:vss(1192)"
				( attribute "PN" "CW6"
					( Origin gPackager )
				)
				( objectStatus "U5D1.CW6" )
			)
			( pin "@baseboard_fab2_lib.baseboard_fab2(sch_1):page40_i20:vss(1193)"
				( attribute "PN" "DE48"
					( Origin gPackager )
				)
				( objectStatus "U5D1.DE48" )
			)
			( pin "@baseboard_fab2_lib.baseboard_fab2(sch_1):page40_i20:vss(1194)"
				( attribute "PN" "DE50"
					( Origin gPackager )
				)
				( objectStatus "U5D1.DE50" )
			)
			( pin "@baseboard_fab2_lib.baseboard_fab2(sch_1):page40_i20:vss(1195)"
				( attribute "PN" "DE52"
					( Origin gPackager )
				)
				( objectStatus "U5D1.DE52" )
			)
			( pin "@baseboard_fab2_lib.baseboard_fab2(sch_1):page40_i20:vss(1196)"
				( attribute "PN" "DE54"
					( Origin gPackager )
				)
				( objectStatus "U5D1.DE54" )
			)
			( pin "@baseboard_fab2_lib.baseboard_fab2(sch_1):page40_i20:vss(1197)"
				( attribute "PN" "DE56"
					( Origin gPackager )
				)
				( objectStatus "U5D1.DE56" )
			)
			( pin "@baseboard_fab2_lib.baseboard_fab2(sch_1):page40_i20:vss(1198)"
				( attribute "PN" "DE58"
					( Origin gPackager )
				)
				( objectStatus "U5D1.DE58" )
			)
			( pin "@baseboard_fab2_lib.baseboard_fab2(sch_1):page40_i20:vss(1199)"
				( attribute "PN" "DE60"
					( Origin gPackager )
				)
				( objectStatus "U5D1.DE60" )
			)
			( pin "@baseboard_fab2_lib.baseboard_fab2(sch_1):page40_i20:vss(1200)"
				( attribute "PN" "DE62"
					( Origin gPackager )
				)
				( objectStatus "U5D1.DE62" )
			)
			( pin "@baseboard_fab2_lib.baseboard_fab2(sch_1):page40_i20:vss(1201)"
				( attribute "PN" "DL8"
					( Origin gPackager )
				)
				( objectStatus "U5D1.DL8" )
			)
			( pin "@baseboard_fab2_lib.baseboard_fab2(sch_1):page40_i20:vss(1202)"
				( attribute "PN" "DN18"
					( Origin gPackager )
				)
				( objectStatus "U5D1.DN18" )
			)
			( pin "@baseboard_fab2_lib.baseboard_fab2(sch_1):page40_i20:vss(1203)"
				( attribute "PN" "DP45"
					( Origin gPackager )
				)
				( objectStatus "U5D1.DP45" )
			)
			( pin "@baseboard_fab2_lib.baseboard_fab2(sch_1):page40_i20:vss(1204)"
				( attribute "PN" "DP47"
					( Origin gPackager )
				)
				( objectStatus "U5D1.DP47" )
			)
			( pin "@baseboard_fab2_lib.baseboard_fab2(sch_1):page40_i20:vss(1205)"
				( attribute "PN" "DP49"
					( Origin gPackager )
				)
				( objectStatus "U5D1.DP49" )
			)
			( pin "@baseboard_fab2_lib.baseboard_fab2(sch_1):page40_i20:vss(1206)"
				( attribute "PN" "DP51"
					( Origin gPackager )
				)
				( objectStatus "U5D1.DP51" )
			)
			( pin "@baseboard_fab2_lib.baseboard_fab2(sch_1):page40_i20:vss(1207)"
				( attribute "PN" "DP53"
					( Origin gPackager )
				)
				( objectStatus "U5D1.DP53" )
			)
			( pin "@baseboard_fab2_lib.baseboard_fab2(sch_1):page40_i20:vss(1208)"
				( attribute "PN" "DP55"
					( Origin gPackager )
				)
				( objectStatus "U5D1.DP55" )
			)
			( pin "@baseboard_fab2_lib.baseboard_fab2(sch_1):page40_i20:vss(1209)"
				( attribute "PN" "DP57"
					( Origin gPackager )
				)
				( objectStatus "U5D1.DP57" )
			)
			( pin "@baseboard_fab2_lib.baseboard_fab2(sch_1):page40_i20:vss(1210)"
				( attribute "PN" "DP59"
					( Origin gPackager )
				)
				( objectStatus "U5D1.DP59" )
			)
			( pin "@baseboard_fab2_lib.baseboard_fab2(sch_1):page40_i20:vss(1211)"
				( attribute "PN" "DP61"
					( Origin gPackager )
				)
				( objectStatus "U5D1.DP61" )
			)
			( pin "@baseboard_fab2_lib.baseboard_fab2(sch_1):page40_i20:vss(1212)"
				( attribute "PN" "DP63"
					( Origin gPackager )
				)
				( objectStatus "U5D1.DP63" )
			)
			( pin "@baseboard_fab2_lib.baseboard_fab2(sch_1):page40_i20:vss(1213)"
				( attribute "PN" "DP9"
					( Origin gPackager )
				)
				( objectStatus "U5D1.DP9" )
			)
			( pin "@baseboard_fab2_lib.baseboard_fab2(sch_1):page40_i20:vss(1214)"
				( attribute "PN" "DV19"
					( Origin gPackager )
				)
				( objectStatus "U5D1.DV19" )
			)
			( pin "@baseboard_fab2_lib.baseboard_fab2(sch_1):page40_i20:vss(1215)"
				( attribute "PN" "DY45"
					( Origin gPackager )
				)
				( objectStatus "U5D1.DY45" )
			)
			( pin "@baseboard_fab2_lib.baseboard_fab2(sch_1):page40_i20:vss(1216)"
				( attribute "PN" "DY47"
					( Origin gPackager )
				)
				( objectStatus "U5D1.DY47" )
			)
			( pin "@baseboard_fab2_lib.baseboard_fab2(sch_1):page40_i20:vss(1217)"
				( attribute "PN" "DY49"
					( Origin gPackager )
				)
				( objectStatus "U5D1.DY49" )
			)
			( pin "@baseboard_fab2_lib.baseboard_fab2(sch_1):page40_i20:vss(1218)"
				( attribute "PN" "DY51"
					( Origin gPackager )
				)
				( objectStatus "U5D1.DY51" )
			)
			( pin "@baseboard_fab2_lib.baseboard_fab2(sch_1):page40_i20:vss(1219)"
				( attribute "PN" "DY53"
					( Origin gPackager )
				)
				( objectStatus "U5D1.DY53" )
			)
			( pin "@baseboard_fab2_lib.baseboard_fab2(sch_1):page40_i20:vss(1220)"
				( attribute "PN" "DY55"
					( Origin gPackager )
				)
				( objectStatus "U5D1.DY55" )
			)
			( pin "@baseboard_fab2_lib.baseboard_fab2(sch_1):page40_i20:vss(1221)"
				( attribute "PN" "DY57"
					( Origin gPackager )
				)
				( objectStatus "U5D1.DY57" )
			)
			( pin "@baseboard_fab2_lib.baseboard_fab2(sch_1):page40_i20:vss(1222)"
				( attribute "PN" "DY59"
					( Origin gPackager )
				)
				( objectStatus "U5D1.DY59" )
			)
			( pin "@baseboard_fab2_lib.baseboard_fab2(sch_1):page40_i20:vss(1223)"
				( attribute "PN" "DY61"
					( Origin gPackager )
				)
				( objectStatus "U5D1.DY61" )
			)
			( pin "@baseboard_fab2_lib.baseboard_fab2(sch_1):page40_i20:vss(1224)"
				( attribute "PN" "DY63"
					( Origin gPackager )
				)
				( objectStatus "U5D1.DY63" )
			)
			( pin "@baseboard_fab2_lib.baseboard_fab2(sch_1):page40_i20:vss(1225)"
				( attribute "PN" "EA14"
					( Origin gPackager )
				)
				( objectStatus "U5D1.EA14" )
			)
			( pin "@baseboard_fab2_lib.baseboard_fab2(sch_1):page40_i20:vss(1226)"
				( attribute "PN" "L8"
					( Origin gPackager )
				)
				( objectStatus "U5D1.L8" )
			)
			( pin "@baseboard_fab2_lib.baseboard_fab2(sch_1):page40_i20:vss(1227)"
				( attribute "PN" "V11"
					( Origin gPackager )
				)
				( objectStatus "U5D1.V11" )
			)
			( pin "@baseboard_fab2_lib.baseboard_fab2(sch_1):page40_i20:vss(1228)"
				( attribute "PN" "E66"
					( Origin gPackager )
				)
				( objectStatus "U5D1.E66" )
			)
			( pin "@baseboard_fab2_lib.baseboard_fab2(sch_1):page40_i20:vss(1229)"
				( attribute "PN" "ED69"
					( Origin gPackager )
				)
				( objectStatus "U5D1.ED69" )
			)
			( pin "@baseboard_fab2_lib.baseboard_fab2(sch_1):page40_i20:vss(1230)"
				( attribute "PN" "EE80"
					( Origin gPackager )
				)
				( objectStatus "U5D1.EE80" )
			)
			( pin "@baseboard_fab2_lib.baseboard_fab2(sch_1):page40_i20:vss(1231)"
				( attribute "PN" "EE8"
					( Origin gPackager )
				)
				( objectStatus "U5D1.EE8" )
			)
			( pin "@baseboard_fab2_lib.baseboard_fab2(sch_1):page40_i20:vss(1232)"
				( attribute "PN" "EE40"
					( Origin gPackager )
				)
				( objectStatus "U5D1.EE40" )
			)
			( pin "@baseboard_fab2_lib.baseboard_fab2(sch_1):page40_i20:vss(1233)"
				( attribute "PN" "ED81"
					( Origin gPackager )
				)
				( objectStatus "U5D1.ED81" )
			)
			( pin "@baseboard_fab2_lib.baseboard_fab2(sch_1):page40_i20:vss(1234)"
				( attribute "PN" "ED7"
					( Origin gPackager )
				)
				( objectStatus "U5D1.ED7" )
			)
			( pin "@baseboard_fab2_lib.baseboard_fab2(sch_1):page40_i20:vss(1235)"
				( attribute "PN" "ED41"
					( Origin gPackager )
				)
				( objectStatus "U5D1.ED41" )
			)
			( pin "@baseboard_fab2_lib.baseboard_fab2(sch_1):page40_i20:vss(1236)"
				( attribute "PN" "EC82"
					( Origin gPackager )
				)
				( objectStatus "U5D1.EC82" )
			)
			( pin "@baseboard_fab2_lib.baseboard_fab2(sch_1):page40_i20:vss(1237)"
				( attribute "PN" "EC6"
					( Origin gPackager )
				)
				( objectStatus "U5D1.EC6" )
			)
			( pin "@baseboard_fab2_lib.baseboard_fab2(sch_1):page40_i20:vss(1238)"
				( attribute "PN" "EC42"
					( Origin gPackager )
				)
				( objectStatus "U5D1.EC42" )
			)
			( pin "@baseboard_fab2_lib.baseboard_fab2(sch_1):page40_i20:vss(1239)"
				( attribute "PN" "DW2"
					( Origin gPackager )
				)
				( objectStatus "U5D1.DW2" )
			)
			( pin "@baseboard_fab2_lib.baseboard_fab2(sch_1):page40_i20:vss(1240)"
				( attribute "PN" "EB83"
					( Origin gPackager )
				)
				( objectStatus "U5D1.EB83" )
			)
			( pin "@baseboard_fab2_lib.baseboard_fab2(sch_1):page40_i20:vss(1241)"
				( attribute "PN" "EA84"
					( Origin gPackager )
				)
				( objectStatus "U5D1.EA84" )
			)
			( pin "@baseboard_fab2_lib.baseboard_fab2(sch_1):page40_i20:vss(1242)"
				( attribute "PN" "DY85"
					( Origin gPackager )
				)
				( objectStatus "U5D1.DY85" )
			)
			( pin "@baseboard_fab2_lib.baseboard_fab2(sch_1):page40_i20:vss(1243)"
				( attribute "PN" "J86"
					( Origin gPackager )
				)
				( objectStatus "U5D1.J86" )
			)
			( pin "@baseboard_fab2_lib.baseboard_fab2(sch_1):page40_i20:vss(1244)"
				( attribute "PN" "E82"
					( Origin gPackager )
				)
				( objectStatus "U5D1.E82" )
			)
			( pin "@baseboard_fab2_lib.baseboard_fab2(sch_1):page40_i20:vss(1245)"
				( attribute "PN" "D81"
					( Origin gPackager )
				)
				( objectStatus "U5D1.D81" )
			)
			( pin "@baseboard_fab2_lib.baseboard_fab2(sch_1):page40_i20:vss(1246)"
				( attribute "PN" "D3"
					( Origin gPackager )
				)
				( objectStatus "U5D1.D3" )
			)
			( pin "@baseboard_fab2_lib.baseboard_fab2(sch_1):page40_i20:vss(1247)"
				( attribute "PN" "C80"
					( Origin gPackager )
				)
				( objectStatus "U5D1.C80" )
			)
			( pin "@baseboard_fab2_lib.baseboard_fab2(sch_1):page40_i20:vss(1248)"
				( attribute "PN" "C4"
					( Origin gPackager )
				)
				( objectStatus "U5D1.C4" )
			)
			( pin "@baseboard_fab2_lib.baseboard_fab2(sch_1):page40_i20:vss(1249)"
				( attribute "PN" "B79"
					( Origin gPackager )
				)
				( objectStatus "U5D1.B79" )
			)
			( pin "@baseboard_fab2_lib.baseboard_fab2(sch_1):page40_i20:vss(1250)"
				( attribute "PN" "B5"
					( Origin gPackager )
				)
				( objectStatus "U5D1.B5" )
			)
			( pin "@baseboard_fab2_lib.baseboard_fab2(sch_1):page40_i20:vss(1251)"
				( attribute "PN" "B43"
					( Origin gPackager )
				)
				( objectStatus "U5D1.B43" )
			)
			( pin "@baseboard_fab2_lib.baseboard_fab2(sch_1):page40_i20:vss(1252)"
				( attribute "PN" "A42"
					( Origin gPackager )
				)
				( objectStatus "U5D1.A42" )
			)
			( pin "@baseboard_fab2_lib.baseboard_fab2(sch_1):page40_i20:vss(1253)"
				( attribute "PN" "B9"
					( Origin gPackager )
				)
				( objectStatus "U5D1.B9" )
			)
			( pin "@baseboard_fab2_lib.baseboard_fab2(sch_1):page40_i21:vss(934)"
				( attribute "PN" "AA16"
					( Origin gPackager )
				)
				( objectStatus "U5D1.AA16" )
			)
			( pin "@baseboard_fab2_lib.baseboard_fab2(sch_1):page40_i21:vss(935)"
				( attribute "PN" "AA4"
					( Origin gPackager )
				)
				( objectStatus "U5D1.AA4" )
			)
			( pin "@baseboard_fab2_lib.baseboard_fab2(sch_1):page40_i21:vss(936)"
				( attribute "PN" "Y85"
					( Origin gPackager )
				)
				( objectStatus "U5D1.Y85" )
			)
			( pin "@baseboard_fab2_lib.baseboard_fab2(sch_1):page40_i21:vss(937)"
				( attribute "PN" "Y83"
					( Origin gPackager )
				)
				( objectStatus "U5D1.Y83" )
			)
			( pin "@baseboard_fab2_lib.baseboard_fab2(sch_1):page40_i21:vss(938)"
				( attribute "PN" "Y81"
					( Origin gPackager )
				)
				( objectStatus "U5D1.Y81" )
			)
			( pin "@baseboard_fab2_lib.baseboard_fab2(sch_1):page40_i21:vss(939)"
				( attribute "PN" "Y79"
					( Origin gPackager )
				)
				( objectStatus "U5D1.Y79" )
			)
			( pin "@baseboard_fab2_lib.baseboard_fab2(sch_1):page40_i21:vss(940)"
				( attribute "PN" "Y73"
					( Origin gPackager )
				)
				( objectStatus "U5D1.Y73" )
			)
			( pin "@baseboard_fab2_lib.baseboard_fab2(sch_1):page40_i21:vss(941)"
				( attribute "PN" "Y71"
					( Origin gPackager )
				)
				( objectStatus "U5D1.Y71" )
			)
			( pin "@baseboard_fab2_lib.baseboard_fab2(sch_1):page40_i21:vss(942)"
				( attribute "PN" "Y9"
					( Origin gPackager )
				)
				( objectStatus "U5D1.Y9" )
			)
			( pin "@baseboard_fab2_lib.baseboard_fab2(sch_1):page40_i21:vss(943)"
				( attribute "PN" "Y7"
					( Origin gPackager )
				)
				( objectStatus "U5D1.Y7" )
			)
			( pin "@baseboard_fab2_lib.baseboard_fab2(sch_1):page40_i21:vss(944)"
				( attribute "PN" "Y67"
					( Origin gPackager )
				)
				( objectStatus "U5D1.Y67" )
			)
			( pin "@baseboard_fab2_lib.baseboard_fab2(sch_1):page40_i21:vss(945)"
				( attribute "PN" "Y5"
					( Origin gPackager )
				)
				( objectStatus "U5D1.Y5" )
			)
			( pin "@baseboard_fab2_lib.baseboard_fab2(sch_1):page40_i21:vss(946)"
				( attribute "PN" "Y17"
					( Origin gPackager )
				)
				( objectStatus "U5D1.Y17" )
			)
			( pin "@baseboard_fab2_lib.baseboard_fab2(sch_1):page40_i21:vss(947)"
				( attribute "PN" "Y15"
					( Origin gPackager )
				)
				( objectStatus "U5D1.Y15" )
			)
			( pin "@baseboard_fab2_lib.baseboard_fab2(sch_1):page40_i21:vss(948)"
				( attribute "PN" "W82"
					( Origin gPackager )
				)
				( objectStatus "U5D1.W82" )
			)
			( pin "@baseboard_fab2_lib.baseboard_fab2(sch_1):page40_i21:vss(949)"
				( attribute "PN" "W78"
					( Origin gPackager )
				)
				( objectStatus "U5D1.W78" )
			)
			( pin "@baseboard_fab2_lib.baseboard_fab2(sch_1):page40_i21:vss(950)"
				( attribute "PN" "W74"
					( Origin gPackager )
				)
				( objectStatus "U5D1.W74" )
			)
			( pin "@baseboard_fab2_lib.baseboard_fab2(sch_1):page40_i21:vss(951)"
				( attribute "PN" "W68"
					( Origin gPackager )
				)
				( objectStatus "U5D1.W68" )
			)
			( pin "@baseboard_fab2_lib.baseboard_fab2(sch_1):page40_i21:vss(952)"
				( attribute "PN" "W42"
					( Origin gPackager )
				)
				( objectStatus "U5D1.W42" )
			)
			( pin "@baseboard_fab2_lib.baseboard_fab2(sch_1):page40_i21:vss(953)"
				( attribute "PN" "W40"
					( Origin gPackager )
				)
				( objectStatus "U5D1.W40" )
			)
			( pin "@baseboard_fab2_lib.baseboard_fab2(sch_1):page40_i21:vss(954)"
				( attribute "PN" "W38"
					( Origin gPackager )
				)
				( objectStatus "U5D1.W38" )
			)
			( pin "@baseboard_fab2_lib.baseboard_fab2(sch_1):page40_i21:vss(955)"
				( attribute "PN" "W36"
					( Origin gPackager )
				)
				( objectStatus "U5D1.W36" )
			)
			( pin "@baseboard_fab2_lib.baseboard_fab2(sch_1):page40_i21:vss(956)"
				( attribute "PN" "W34"
					( Origin gPackager )
				)
				( objectStatus "U5D1.W34" )
			)
			( pin "@baseboard_fab2_lib.baseboard_fab2(sch_1):page40_i21:vss(957)"
				( attribute "PN" "W32"
					( Origin gPackager )
				)
				( objectStatus "U5D1.W32" )
			)
			( pin "@baseboard_fab2_lib.baseboard_fab2(sch_1):page40_i21:vss(958)"
				( attribute "PN" "W30"
					( Origin gPackager )
				)
				( objectStatus "U5D1.W30" )
			)
			( pin "@baseboard_fab2_lib.baseboard_fab2(sch_1):page40_i21:vss(959)"
				( attribute "PN" "W28"
					( Origin gPackager )
				)
				( objectStatus "U5D1.W28" )
			)
			( pin "@baseboard_fab2_lib.baseboard_fab2(sch_1):page40_i21:vss(960)"
				( attribute "PN" "W26"
					( Origin gPackager )
				)
				( objectStatus "U5D1.W26" )
			)
			( pin "@baseboard_fab2_lib.baseboard_fab2(sch_1):page40_i21:vss(961)"
				( attribute "PN" "W24"
					( Origin gPackager )
				)
				( objectStatus "U5D1.W24" )
			)
			( pin "@baseboard_fab2_lib.baseboard_fab2(sch_1):page40_i21:vss(962)"
				( attribute "PN" "W22"
					( Origin gPackager )
				)
				( objectStatus "U5D1.W22" )
			)
			( pin "@baseboard_fab2_lib.baseboard_fab2(sch_1):page40_i21:vss(963)"
				( attribute "PN" "W12"
					( Origin gPackager )
				)
				( objectStatus "U5D1.W12" )
			)
			( pin "@baseboard_fab2_lib.baseboard_fab2(sch_1):page40_i21:vss(964)"
				( attribute "PN" "AC56"
					( Origin gPackager )
				)
				( objectStatus "U5D1.AC56" )
			)
			( pin "@baseboard_fab2_lib.baseboard_fab2(sch_1):page40_i21:vss(965)"
				( attribute "PN" "W8"
					( Origin gPackager )
				)
				( objectStatus "U5D1.W8" )
			)
			( pin "@baseboard_fab2_lib.baseboard_fab2(sch_1):page40_i21:vss(966)"
				( attribute "PN" "V83"
					( Origin gPackager )
				)
				( objectStatus "U5D1.V83" )
			)
			( pin "@baseboard_fab2_lib.baseboard_fab2(sch_1):page40_i21:vss(967)"
				( attribute "PN" "V77"
					( Origin gPackager )
				)
				( objectStatus "U5D1.V77" )
			)
			( pin "@baseboard_fab2_lib.baseboard_fab2(sch_1):page40_i21:vss(968)"
				( attribute "PN" "V75"
					( Origin gPackager )
				)
				( objectStatus "U5D1.V75" )
			)
			( pin "@baseboard_fab2_lib.baseboard_fab2(sch_1):page40_i21:vss(969)"
				( attribute "PN" "V73"
					( Origin gPackager )
				)
				( objectStatus "U5D1.V73" )
			)
			( pin "@baseboard_fab2_lib.baseboard_fab2(sch_1):page40_i21:vss(970)"
				( attribute "PN" "V43"
					( Origin gPackager )
				)
				( objectStatus "U5D1.V43" )
			)
			( pin "@baseboard_fab2_lib.baseboard_fab2(sch_1):page40_i21:vss(971)"
				( attribute "PN" "V23"
					( Origin gPackager )
				)
				( objectStatus "U5D1.V23" )
			)
			( pin "@baseboard_fab2_lib.baseboard_fab2(sch_1):page40_i21:vss(972)"
				( attribute "PN" "V21"
					( Origin gPackager )
				)
				( objectStatus "U5D1.V21" )
			)
			( pin "@baseboard_fab2_lib.baseboard_fab2(sch_1):page40_i21:vss(973)"
				( attribute "PN" "V15"
					( Origin gPackager )
				)
				( objectStatus "U5D1.V15" )
			)
			( pin "@baseboard_fab2_lib.baseboard_fab2(sch_1):page40_i21:vss(974)"
				( attribute "PN" "V13"
					( Origin gPackager )
				)
				( objectStatus "U5D1.V13" )
			)
			( pin "@baseboard_fab2_lib.baseboard_fab2(sch_1):page40_i21:vss(975)"
				( attribute "PN" "V9"
					( Origin gPackager )
				)
				( objectStatus "U5D1.V9" )
			)
			( pin "@baseboard_fab2_lib.baseboard_fab2(sch_1):page40_i21:vss(976)"
				( attribute "PN" "V5"
					( Origin gPackager )
				)
				( objectStatus "U5D1.V5" )
			)
			( pin "@baseboard_fab2_lib.baseboard_fab2(sch_1):page40_i21:vss(977)"
				( attribute "PN" "V1"
					( Origin gPackager )
				)
				( objectStatus "U5D1.V1" )
			)
			( pin "@baseboard_fab2_lib.baseboard_fab2(sch_1):page40_i21:vss(978)"
				( attribute "PN" "U86"
					( Origin gPackager )
				)
				( objectStatus "U5D1.U86" )
			)
			( pin "@baseboard_fab2_lib.baseboard_fab2(sch_1):page40_i21:vss(979)"
				( attribute "PN" "U80"
					( Origin gPackager )
				)
				( objectStatus "U5D1.U80" )
			)
			( pin "@baseboard_fab2_lib.baseboard_fab2(sch_1):page40_i21:vss(980)"
				( attribute "PN" "U78"
					( Origin gPackager )
				)
				( objectStatus "U5D1.U78" )
			)
			( pin "@baseboard_fab2_lib.baseboard_fab2(sch_1):page40_i21:vss(981)"
				( attribute "PN" "U76"
					( Origin gPackager )
				)
				( objectStatus "U5D1.U76" )
			)
			( pin "@baseboard_fab2_lib.baseboard_fab2(sch_1):page40_i21:vss(982)"
				( attribute "PN" "U74"
					( Origin gPackager )
				)
				( objectStatus "U5D1.U74" )
			)
			( pin "@baseboard_fab2_lib.baseboard_fab2(sch_1):page40_i21:vss(983)"
				( attribute "PN" "U70"
					( Origin gPackager )
				)
				( objectStatus "U5D1.U70" )
			)
			( pin "@baseboard_fab2_lib.baseboard_fab2(sch_1):page40_i21:vss(984)"
				( attribute "PN" "U68"
					( Origin gPackager )
				)
				( objectStatus "U5D1.U68" )
			)
			( pin "@baseboard_fab2_lib.baseboard_fab2(sch_1):page40_i21:vss(985)"
				( attribute "PN" "U42"
					( Origin gPackager )
				)
				( objectStatus "U5D1.U42" )
			)
			( pin "@baseboard_fab2_lib.baseboard_fab2(sch_1):page40_i21:vss(986)"
				( attribute "PN" "U36"
					( Origin gPackager )
				)
				( objectStatus "U5D1.U36" )
			)
			( pin "@baseboard_fab2_lib.baseboard_fab2(sch_1):page40_i21:vss(987)"
				( attribute "PN" "U30"
					( Origin gPackager )
				)
				( objectStatus "U5D1.U30" )
			)
			( pin "@baseboard_fab2_lib.baseboard_fab2(sch_1):page40_i21:vss(988)"
				( attribute "PN" "U24"
					( Origin gPackager )
				)
				( objectStatus "U5D1.U24" )
			)
			( pin "@baseboard_fab2_lib.baseboard_fab2(sch_1):page40_i21:vss(989)"
				( attribute "PN" "U22"
					( Origin gPackager )
				)
				( objectStatus "U5D1.U22" )
			)
			( pin "@baseboard_fab2_lib.baseboard_fab2(sch_1):page40_i21:vss(990)"
				( attribute "PN" "U20"
					( Origin gPackager )
				)
				( objectStatus "U5D1.U20" )
			)
			( pin "@baseboard_fab2_lib.baseboard_fab2(sch_1):page40_i21:vss(991)"
				( attribute "PN" "U6"
					( Origin gPackager )
				)
				( objectStatus "U5D1.U6" )
			)
			( pin "@baseboard_fab2_lib.baseboard_fab2(sch_1):page40_i21:vss(992)"
				( attribute "PN" "U4"
					( Origin gPackager )
				)
				( objectStatus "U5D1.U4" )
			)
			( pin "@baseboard_fab2_lib.baseboard_fab2(sch_1):page40_i21:vss(993)"
				( attribute "PN" "U2"
					( Origin gPackager )
				)
				( objectStatus "U5D1.U2" )
			)
			( pin "@baseboard_fab2_lib.baseboard_fab2(sch_1):page40_i21:vss(994)"
				( attribute "PN" "T85"
					( Origin gPackager )
				)
				( objectStatus "U5D1.T85" )
			)
			( pin "@baseboard_fab2_lib.baseboard_fab2(sch_1):page40_i21:vss(995)"
				( attribute "PN" "T83"
					( Origin gPackager )
				)
				( objectStatus "U5D1.T83" )
			)
			( pin "@baseboard_fab2_lib.baseboard_fab2(sch_1):page40_i21:vss(996)"
				( attribute "PN" "T77"
					( Origin gPackager )
				)
				( objectStatus "U5D1.T77" )
			)
			( pin "@baseboard_fab2_lib.baseboard_fab2(sch_1):page40_i21:vss(997)"
				( attribute "PN" "T73"
					( Origin gPackager )
				)
				( objectStatus "U5D1.T73" )
			)
			( pin "@baseboard_fab2_lib.baseboard_fab2(sch_1):page40_i21:vss(998)"
				( attribute "PN" "T65"
					( Origin gPackager )
				)
				( objectStatus "U5D1.T65" )
			)
			( pin "@baseboard_fab2_lib.baseboard_fab2(sch_1):page40_i21:vss(999)"
				( attribute "PN" "T41"
					( Origin gPackager )
				)
				( objectStatus "U5D1.T41" )
			)
			( pin "@baseboard_fab2_lib.baseboard_fab2(sch_1):page40_i21:vss(1000)"
				( attribute "PN" "T37"
					( Origin gPackager )
				)
				( objectStatus "U5D1.T37" )
			)
			( pin "@baseboard_fab2_lib.baseboard_fab2(sch_1):page40_i21:vss(1001)"
				( attribute "PN" "T35"
					( Origin gPackager )
				)
				( objectStatus "U5D1.T35" )
			)
			( pin "@baseboard_fab2_lib.baseboard_fab2(sch_1):page40_i21:vss(1002)"
				( attribute "PN" "T31"
					( Origin gPackager )
				)
				( objectStatus "U5D1.T31" )
			)
			( pin "@baseboard_fab2_lib.baseboard_fab2(sch_1):page40_i21:vss(1003)"
				( attribute "PN" "T29"
					( Origin gPackager )
				)
				( objectStatus "U5D1.T29" )
			)
			( pin "@baseboard_fab2_lib.baseboard_fab2(sch_1):page40_i21:vss(1004)"
				( attribute "PN" "T25"
					( Origin gPackager )
				)
				( objectStatus "U5D1.T25" )
			)
			( pin "@baseboard_fab2_lib.baseboard_fab2(sch_1):page40_i21:vss(1005)"
				( attribute "PN" "T17"
					( Origin gPackager )
				)
				( objectStatus "U5D1.T17" )
			)
			( pin "@baseboard_fab2_lib.baseboard_fab2(sch_1):page40_i21:vss(1006)"
				( attribute "PN" "T13"
					( Origin gPackager )
				)
				( objectStatus "U5D1.T13" )
			)
			( pin "@baseboard_fab2_lib.baseboard_fab2(sch_1):page40_i21:vss(1007)"
				( attribute "PN" "R86"
					( Origin gPackager )
				)
				( objectStatus "U5D1.R86" )
			)
			( pin "@baseboard_fab2_lib.baseboard_fab2(sch_1):page40_i21:vss(1008)"
				( attribute "PN" "R78"
					( Origin gPackager )
				)
				( objectStatus "U5D1.R78" )
			)
			( pin "@baseboard_fab2_lib.baseboard_fab2(sch_1):page40_i21:vss(1009)"
				( attribute "PN" "R72"
					( Origin gPackager )
				)
				( objectStatus "U5D1.R72" )
			)
			( pin "@baseboard_fab2_lib.baseboard_fab2(sch_1):page40_i21:vss(1010)"
				( attribute "PN" "R68"
					( Origin gPackager )
				)
				( objectStatus "U5D1.R68" )
			)
			( pin "@baseboard_fab2_lib.baseboard_fab2(sch_1):page40_i21:vss(1011)"
				( attribute "PN" "R40"
					( Origin gPackager )
				)
				( objectStatus "U5D1.R40" )
			)
			( pin "@baseboard_fab2_lib.baseboard_fab2(sch_1):page40_i21:vss(1012)"
				( attribute "PN" "R38"
					( Origin gPackager )
				)
				( objectStatus "U5D1.R38" )
			)
			( pin "@baseboard_fab2_lib.baseboard_fab2(sch_1):page40_i21:vss(1013)"
				( attribute "PN" "R34"
					( Origin gPackager )
				)
				( objectStatus "U5D1.R34" )
			)
			( pin "@baseboard_fab2_lib.baseboard_fab2(sch_1):page40_i21:vss(1014)"
				( attribute "PN" "R32"
					( Origin gPackager )
				)
				( objectStatus "U5D1.R32" )
			)
			( pin "@baseboard_fab2_lib.baseboard_fab2(sch_1):page40_i21:vss(1015)"
				( attribute "PN" "R28"
					( Origin gPackager )
				)
				( objectStatus "U5D1.R28" )
			)
			( pin "@baseboard_fab2_lib.baseboard_fab2(sch_1):page40_i21:vss(1016)"
				( attribute "PN" "R26"
					( Origin gPackager )
				)
				( objectStatus "U5D1.R26" )
			)
			( pin "@baseboard_fab2_lib.baseboard_fab2(sch_1):page40_i21:vss(1017)"
				( attribute "PN" "R22"
					( Origin gPackager )
				)
				( objectStatus "U5D1.R22" )
			)
			( pin "@baseboard_fab2_lib.baseboard_fab2(sch_1):page40_i21:vss(1018)"
				( attribute "PN" "R4"
					( Origin gPackager )
				)
				( objectStatus "U5D1.R4" )
			)
			( pin "@baseboard_fab2_lib.baseboard_fab2(sch_1):page40_i21:vss(1019)"
				( attribute "PN" "R2"
					( Origin gPackager )
				)
				( objectStatus "U5D1.R2" )
			)
			( pin "@baseboard_fab2_lib.baseboard_fab2(sch_1):page40_i21:vss(1020)"
				( attribute "PN" "R18"
					( Origin gPackager )
				)
				( objectStatus "U5D1.R18" )
			)
			( pin "@baseboard_fab2_lib.baseboard_fab2(sch_1):page40_i21:vss(1021)"
				( attribute "PN" "R14"
					( Origin gPackager )
				)
				( objectStatus "U5D1.R14" )
			)
			( pin "@baseboard_fab2_lib.baseboard_fab2(sch_1):page40_i21:vss(1022)"
				( attribute "PN" "P83"
					( Origin gPackager )
				)
				( objectStatus "U5D1.P83" )
			)
			( pin "@baseboard_fab2_lib.baseboard_fab2(sch_1):page40_i21:vss(1023)"
				( attribute "PN" "P81"
					( Origin gPackager )
				)
				( objectStatus "U5D1.P81" )
			)
			( pin "@baseboard_fab2_lib.baseboard_fab2(sch_1):page40_i21:vss(1024)"
				( attribute "PN" "P71"
					( Origin gPackager )
				)
				( objectStatus "U5D1.P71" )
			)
			( pin "@baseboard_fab2_lib.baseboard_fab2(sch_1):page40_i21:vss(1025)"
				( attribute "PN" "P69"
					( Origin gPackager )
				)
				( objectStatus "U5D1.P69" )
			)
			( pin "@baseboard_fab2_lib.baseboard_fab2(sch_1):page40_i21:vss(1026)"
				( attribute "PN" "P67"
					( Origin gPackager )
				)
				( objectStatus "U5D1.P67" )
			)
			( pin "@baseboard_fab2_lib.baseboard_fab2(sch_1):page40_i21:vss(1027)"
				( attribute "PN" "P39"
					( Origin gPackager )
				)
				( objectStatus "U5D1.P39" )
			)
			( pin "@baseboard_fab2_lib.baseboard_fab2(sch_1):page40_i21:vss(1028)"
				( attribute "PN" "P33"
					( Origin gPackager )
				)
				( objectStatus "U5D1.P33" )
			)
			( pin "@baseboard_fab2_lib.baseboard_fab2(sch_1):page40_i21:vss(1029)"
				( attribute "PN" "P27"
					( Origin gPackager )
				)
				( objectStatus "U5D1.P27" )
			)
			( pin "@baseboard_fab2_lib.baseboard_fab2(sch_1):page40_i21:vss(1030)"
				( attribute "PN" "P15"
					( Origin gPackager )
				)
				( objectStatus "U5D1.P15" )
			)
			( pin "@baseboard_fab2_lib.baseboard_fab2(sch_1):page40_i21:vss(1031)"
				( attribute "PN" "P11"
					( Origin gPackager )
				)
				( objectStatus "U5D1.P11" )
			)
			( pin "@baseboard_fab2_lib.baseboard_fab2(sch_1):page40_i21:vss(1032)"
				( attribute "PN" "N8"
					( Origin gPackager )
				)
				( objectStatus "U5D1.N8" )
			)
			( pin "@baseboard_fab2_lib.baseboard_fab2(sch_1):page40_i21:vss(1033)"
				( attribute "PN" "N4"
					( Origin gPackager )
				)
				( objectStatus "U5D1.N4" )
			)
			( pin "@baseboard_fab2_lib.baseboard_fab2(sch_1):page40_i21:vss(1034)"
				( attribute "PN" "N78"
					( Origin gPackager )
				)
				( objectStatus "U5D1.N78" )
			)
			( pin "@baseboard_fab2_lib.baseboard_fab2(sch_1):page40_i21:vss(1035)"
				( attribute "PN" "N76"
					( Origin gPackager )
				)
				( objectStatus "U5D1.N76" )
			)
			( pin "@baseboard_fab2_lib.baseboard_fab2(sch_1):page40_i21:vss(1036)"
				( attribute "PN" "N74"
					( Origin gPackager )
				)
				( objectStatus "U5D1.N74" )
			)
			( pin "@baseboard_fab2_lib.baseboard_fab2(sch_1):page40_i21:vss(1037)"
				( attribute "PN" "N72"
					( Origin gPackager )
				)
				( objectStatus "U5D1.N72" )
			)
			( pin "@baseboard_fab2_lib.baseboard_fab2(sch_1):page40_i21:vss(1038)"
				( attribute "PN" "N70"
					( Origin gPackager )
				)
				( objectStatus "U5D1.N70" )
			)
			( pin "@baseboard_fab2_lib.baseboard_fab2(sch_1):page40_i21:vss(1039)"
				( attribute "PN" "N66"
					( Origin gPackager )
				)
				( objectStatus "U5D1.N66" )
			)
			( pin "@baseboard_fab2_lib.baseboard_fab2(sch_1):page40_i21:vss(1040)"
				( attribute "PN" "N6"
					( Origin gPackager )
				)
				( objectStatus "U5D1.N6" )
			)
			( pin "@baseboard_fab2_lib.baseboard_fab2(sch_1):page40_i21:vss(1041)"
				( attribute "PN" "N22"
					( Origin gPackager )
				)
				( objectStatus "U5D1.N22" )
			)
			( pin "@baseboard_fab2_lib.baseboard_fab2(sch_1):page40_i21:vss(1042)"
				( attribute "PN" "N20"
					( Origin gPackager )
				)
				( objectStatus "U5D1.N20" )
			)
			( pin "@baseboard_fab2_lib.baseboard_fab2(sch_1):page40_i21:vss(1043)"
				( attribute "PN" "DM19"
					( Origin gPackager )
				)
				( objectStatus "U5D1.DM19" )
			)
			( pin "@baseboard_fab2_lib.baseboard_fab2(sch_1):page40_i21:vss(1044)"
				( attribute "PN" "M85"
					( Origin gPackager )
				)
				( objectStatus "U5D1.M85" )
			)
			( pin "@baseboard_fab2_lib.baseboard_fab2(sch_1):page40_i21:vss(1045)"
				( attribute "PN" "M83"
					( Origin gPackager )
				)
				( objectStatus "U5D1.M83" )
			)
			( pin "@baseboard_fab2_lib.baseboard_fab2(sch_1):page40_i21:vss(1046)"
				( attribute "PN" "M79"
					( Origin gPackager )
				)
				( objectStatus "U5D1.M79" )
			)
			( pin "@baseboard_fab2_lib.baseboard_fab2(sch_1):page40_i21:vss(1047)"
				( attribute "PN" "M71"
					( Origin gPackager )
				)
				( objectStatus "U5D1.M71" )
			)
			( pin "@baseboard_fab2_lib.baseboard_fab2(sch_1):page40_i21:vss(1048)"
				( attribute "PN" "M65"
					( Origin gPackager )
				)
				( objectStatus "U5D1.M65" )
			)
			( pin "@baseboard_fab2_lib.baseboard_fab2(sch_1):page40_i21:vss(1049)"
				( attribute "PN" "M43"
					( Origin gPackager )
				)
				( objectStatus "U5D1.M43" )
			)
			( pin "@baseboard_fab2_lib.baseboard_fab2(sch_1):page40_i21:vss(1050)"
				( attribute "PN" "M41"
					( Origin gPackager )
				)
				( objectStatus "U5D1.M41" )
			)
			( pin "@baseboard_fab2_lib.baseboard_fab2(sch_1):page40_i21:vss(1051)"
				( attribute "PN" "M39"
					( Origin gPackager )
				)
				( objectStatus "U5D1.M39" )
			)
			( pin "@baseboard_fab2_lib.baseboard_fab2(sch_1):page40_i21:vss(1052)"
				( attribute "PN" "M37"
					( Origin gPackager )
				)
				( objectStatus "U5D1.M37" )
			)
			( pin "@baseboard_fab2_lib.baseboard_fab2(sch_1):page40_i21:vss(1053)"
				( attribute "PN" "M35"
					( Origin gPackager )
				)
				( objectStatus "U5D1.M35" )
			)
			( pin "@baseboard_fab2_lib.baseboard_fab2(sch_1):page40_i21:vss(1054)"
				( attribute "PN" "M33"
					( Origin gPackager )
				)
				( objectStatus "U5D1.M33" )
			)
			( pin "@baseboard_fab2_lib.baseboard_fab2(sch_1):page40_i21:vss(1055)"
				( attribute "PN" "M31"
					( Origin gPackager )
				)
				( objectStatus "U5D1.M31" )
			)
			( pin "@baseboard_fab2_lib.baseboard_fab2(sch_1):page40_i21:vss(1056)"
				( attribute "PN" "M29"
					( Origin gPackager )
				)
				( objectStatus "U5D1.M29" )
			)
			( pin "@baseboard_fab2_lib.baseboard_fab2(sch_1):page40_i21:vss(1057)"
				( attribute "PN" "M27"
					( Origin gPackager )
				)
				( objectStatus "U5D1.M27" )
			)
			( pin "@baseboard_fab2_lib.baseboard_fab2(sch_1):page40_i21:vss(1058)"
				( attribute "PN" "M25"
					( Origin gPackager )
				)
				( objectStatus "U5D1.M25" )
			)
			( pin "@baseboard_fab2_lib.baseboard_fab2(sch_1):page40_i21:vss(1059)"
				( attribute "PN" "M23"
					( Origin gPackager )
				)
				( objectStatus "U5D1.M23" )
			)
			( pin "@baseboard_fab2_lib.baseboard_fab2(sch_1):page40_i21:vss(1060)"
				( attribute "PN" "M19"
					( Origin gPackager )
				)
				( objectStatus "U5D1.M19" )
			)
			( pin "@baseboard_fab2_lib.baseboard_fab2(sch_1):page40_i21:vss(1061)"
				( attribute "PN" "M17"
					( Origin gPackager )
				)
				( objectStatus "U5D1.M17" )
			)
			( pin "@baseboard_fab2_lib.baseboard_fab2(sch_1):page40_i21:vss(1062)"
				( attribute "PN" "M15"
					( Origin gPackager )
				)
				( objectStatus "U5D1.M15" )
			)
			( pin "@baseboard_fab2_lib.baseboard_fab2(sch_1):page40_i21:vss(1063)"
				( attribute "PN" "CT7"
					( Origin gPackager )
				)
				( objectStatus "U5D1.CT7" )
			)
			( pin "@baseboard_fab2_lib.baseboard_fab2(sch_1):page40_i21:vss(1064)"
				( attribute "PN" "BT9"
					( Origin gPackager )
				)
				( objectStatus "U5D1.BT9" )
			)
			( pin "@baseboard_fab2_lib.baseboard_fab2(sch_1):page40_i21:vss(1065)"
				( attribute "PN" "L82"
					( Origin gPackager )
				)
				( objectStatus "U5D1.L82" )
			)
			( pin "@baseboard_fab2_lib.baseboard_fab2(sch_1):page40_i21:vss(1066)"
				( attribute "PN" "L80"
					( Origin gPackager )
				)
				( objectStatus "U5D1.L80" )
			)
			( pin "@baseboard_fab2_lib.baseboard_fab2(sch_1):page40_i21:vss(1067)"
				( attribute "PN" "L78"
					( Origin gPackager )
				)
				( objectStatus "U5D1.L78" )
			)
			( pin "@baseboard_fab2_lib.baseboard_fab2(sch_1):page40_i21:vss(1068)"
				( attribute "PN" "L72"
					( Origin gPackager )
				)
				( objectStatus "U5D1.L72" )
			)
			( pin "@baseboard_fab2_lib.baseboard_fab2(sch_1):page40_i21:vss(1069)"
				( attribute "PN" "L22"
					( Origin gPackager )
				)
				( objectStatus "U5D1.L22" )
			)
			( pin "@baseboard_fab2_lib.baseboard_fab2(sch_1):page40_i21:vss(1070)"
				( attribute "PN" "L20"
					( Origin gPackager )
				)
				( objectStatus "U5D1.L20" )
			)
			( pin "@baseboard_fab2_lib.baseboard_fab2(sch_1):page40_i21:vss(1071)"
				( attribute "PN" "L6"
					( Origin gPackager )
				)
				( objectStatus "U5D1.L6" )
			)
			( pin "@baseboard_fab2_lib.baseboard_fab2(sch_1):page40_i21:vss(1072)"
				( attribute "PN" "L2"
					( Origin gPackager )
				)
				( objectStatus "U5D1.L2" )
			)
			( pin "@baseboard_fab2_lib.baseboard_fab2(sch_1):page40_i21:vss(1073)"
				( attribute "PN" "L10"
					( Origin gPackager )
				)
				( objectStatus "U5D1.L10" )
			)
			( pin "@baseboard_fab2_lib.baseboard_fab2(sch_1):page40_i21:vss(1074)"
				( attribute "PN" "K85"
					( Origin gPackager )
				)
				( objectStatus "U5D1.K85" )
			)
			( pin "@baseboard_fab2_lib.baseboard_fab2(sch_1):page40_i21:vss(1075)"
				( attribute "PN" "K83"
					( Origin gPackager )
				)
				( objectStatus "U5D1.K83" )
			)
			( pin "@baseboard_fab2_lib.baseboard_fab2(sch_1):page40_i21:vss(1076)"
				( attribute "PN" "K81"
					( Origin gPackager )
				)
				( objectStatus "U5D1.K81" )
			)
			( pin "@baseboard_fab2_lib.baseboard_fab2(sch_1):page40_i21:vss(1077)"
				( attribute "PN" "K77"
					( Origin gPackager )
				)
				( objectStatus "U5D1.K77" )
			)
			( pin "@baseboard_fab2_lib.baseboard_fab2(sch_1):page40_i21:vss(1078)"
				( attribute "PN" "K73"
					( Origin gPackager )
				)
				( objectStatus "U5D1.K73" )
			)
			( pin "@baseboard_fab2_lib.baseboard_fab2(sch_1):page40_i21:vss(1079)"
				( attribute "PN" "K71"
					( Origin gPackager )
				)
				( objectStatus "U5D1.K71" )
			)
			( pin "@baseboard_fab2_lib.baseboard_fab2(sch_1):page40_i21:vss(1080)"
				( attribute "PN" "K69"
					( Origin gPackager )
				)
				( objectStatus "U5D1.K69" )
			)
			( pin "@baseboard_fab2_lib.baseboard_fab2(sch_1):page40_i21:vss(1081)"
				( attribute "PN" "K67"
					( Origin gPackager )
				)
				( objectStatus "U5D1.K67" )
			)
			( pin "@baseboard_fab2_lib.baseboard_fab2(sch_1):page40_i21:vss(1082)"
				( attribute "PN" "K65"
					( Origin gPackager )
				)
				( objectStatus "U5D1.K65" )
			)
			( pin "@baseboard_fab2_lib.baseboard_fab2(sch_1):page40_i21:vss(1083)"
				( attribute "PN" "K39"
					( Origin gPackager )
				)
				( objectStatus "U5D1.K39" )
			)
			( pin "@baseboard_fab2_lib.baseboard_fab2(sch_1):page40_i21:vss(1084)"
				( attribute "PN" "K33"
					( Origin gPackager )
				)
				( objectStatus "U5D1.K33" )
			)
			( pin "@baseboard_fab2_lib.baseboard_fab2(sch_1):page40_i21:vss(1085)"
				( attribute "PN" "K27"
					( Origin gPackager )
				)
				( objectStatus "U5D1.K27" )
			)
			( pin "@baseboard_fab2_lib.baseboard_fab2(sch_1):page40_i21:vss(1086)"
				( attribute "PN" "DB7"
					( Origin gPackager )
				)
				( objectStatus "U5D1.DB7" )
			)
			( pin "@baseboard_fab2_lib.baseboard_fab2(sch_1):page40_i21:vss(1087)"
				( attribute "PN" "K17"
					( Origin gPackager )
				)
				( objectStatus "U5D1.K17" )
			)
			( pin "@baseboard_fab2_lib.baseboard_fab2(sch_1):page40_i21:vss(1088)"
				( attribute "PN" "K13"
					( Origin gPackager )
				)
				( objectStatus "U5D1.K13" )
			)
			( pin "@baseboard_fab2_lib.baseboard_fab2(sch_1):page40_i21:vss(1089)"
				( attribute "PN" "K11"
					( Origin gPackager )
				)
				( objectStatus "U5D1.K11" )
			)
			( pin "@baseboard_fab2_lib.baseboard_fab2(sch_1):page40_i21:vss(1090)"
				( attribute "PN" "K1"
					( Origin gPackager )
				)
				( objectStatus "U5D1.K1" )
			)
			( pin "@baseboard_fab2_lib.baseboard_fab2(sch_1):page40_i21:vss(1091)"
				( attribute "PN" "J84"
					( Origin gPackager )
				)
				( objectStatus "U5D1.J84" )
			)
			( pin "@baseboard_fab2_lib.baseboard_fab2(sch_1):page40_i21:vss(1092)"
				( attribute "PN" "J82"
					( Origin gPackager )
				)
				( objectStatus "U5D1.J82" )
			)
			( pin "@baseboard_fab2_lib.baseboard_fab2(sch_1):page40_i21:vss(1093)"
				( attribute "PN" "J76"
					( Origin gPackager )
				)
				( objectStatus "U5D1.J76" )
			)
			( pin "@baseboard_fab2_lib.baseboard_fab2(sch_1):page40_i22:vss(774)"
				( attribute "PN" "AL68"
					( Origin gPackager )
				)
				( objectStatus "U5D1.AL68" )
			)
			( pin "@baseboard_fab2_lib.baseboard_fab2(sch_1):page40_i22:vss(775)"
				( attribute "PN" "AL64"
					( Origin gPackager )
				)
				( objectStatus "U5D1.AL64" )
			)
			( pin "@baseboard_fab2_lib.baseboard_fab2(sch_1):page40_i22:vss(776)"
				( attribute "PN" "AL56"
					( Origin gPackager )
				)
				( objectStatus "U5D1.AL56" )
			)
			( pin "@baseboard_fab2_lib.baseboard_fab2(sch_1):page40_i22:vss(777)"
				( attribute "PN" "AL32"
					( Origin gPackager )
				)
				( objectStatus "U5D1.AL32" )
			)
			( pin "@baseboard_fab2_lib.baseboard_fab2(sch_1):page40_i22:vss(778)"
				( attribute "PN" "AL30"
					( Origin gPackager )
				)
				( objectStatus "U5D1.AL30" )
			)
			( pin "@baseboard_fab2_lib.baseboard_fab2(sch_1):page40_i22:vss(779)"
				( attribute "PN" "AL24"
					( Origin gPackager )
				)
				( objectStatus "U5D1.AL24" )
			)
			( pin "@baseboard_fab2_lib.baseboard_fab2(sch_1):page40_i22:vss(780)"
				( attribute "PN" "AL10"
					( Origin gPackager )
				)
				( objectStatus "U5D1.AL10" )
			)
			( pin "@baseboard_fab2_lib.baseboard_fab2(sch_1):page40_i22:vss(781)"
				( attribute "PN" "AL4"
					( Origin gPackager )
				)
				( objectStatus "U5D1.AL4" )
			)
			( pin "@baseboard_fab2_lib.baseboard_fab2(sch_1):page40_i22:vss(782)"
				( attribute "PN" "AK85"
					( Origin gPackager )
				)
				( objectStatus "U5D1.AK85" )
			)
			( pin "@baseboard_fab2_lib.baseboard_fab2(sch_1):page40_i22:vss(783)"
				( attribute "PN" "AK83"
					( Origin gPackager )
				)
				( objectStatus "U5D1.AK83" )
			)
			( pin "@baseboard_fab2_lib.baseboard_fab2(sch_1):page40_i22:vss(784)"
				( attribute "PN" "AK81"
					( Origin gPackager )
				)
				( objectStatus "U5D1.AK81" )
			)
			( pin "@baseboard_fab2_lib.baseboard_fab2(sch_1):page40_i22:vss(785)"
				( attribute "PN" "AK79"
					( Origin gPackager )
				)
				( objectStatus "U5D1.AK79" )
			)
			( pin "@baseboard_fab2_lib.baseboard_fab2(sch_1):page40_i22:vss(786)"
				( attribute "PN" "AK73"
					( Origin gPackager )
				)
				( objectStatus "U5D1.AK73" )
			)
			( pin "@baseboard_fab2_lib.baseboard_fab2(sch_1):page40_i22:vss(787)"
				( attribute "PN" "AK67"
					( Origin gPackager )
				)
				( objectStatus "U5D1.AK67" )
			)
			( pin "@baseboard_fab2_lib.baseboard_fab2(sch_1):page40_i22:vss(788)"
				( attribute "PN" "AK65"
					( Origin gPackager )
				)
				( objectStatus "U5D1.AK65" )
			)
			( pin "@baseboard_fab2_lib.baseboard_fab2(sch_1):page40_i22:vss(789)"
				( attribute "PN" "AK55"
					( Origin gPackager )
				)
				( objectStatus "U5D1.AK55" )
			)
			( pin "@baseboard_fab2_lib.baseboard_fab2(sch_1):page40_i22:vss(790)"
				( attribute "PN" "AK33"
					( Origin gPackager )
				)
				( objectStatus "U5D1.AK33" )
			)
			( pin "@baseboard_fab2_lib.baseboard_fab2(sch_1):page40_i22:vss(791)"
				( attribute "PN" "AK31"
					( Origin gPackager )
				)
				( objectStatus "U5D1.AK31" )
			)
			( pin "@baseboard_fab2_lib.baseboard_fab2(sch_1):page40_i22:vss(792)"
				( attribute "PN" "AK29"
					( Origin gPackager )
				)
				( objectStatus "U5D1.AK29" )
			)
			( pin "@baseboard_fab2_lib.baseboard_fab2(sch_1):page40_i22:vss(793)"
				( attribute "PN" "AK25"
					( Origin gPackager )
				)
				( objectStatus "U5D1.AK25" )
			)
			( pin "@baseboard_fab2_lib.baseboard_fab2(sch_1):page40_i22:vss(794)"
				( attribute "PN" "AK23"
					( Origin gPackager )
				)
				( objectStatus "U5D1.AK23" )
			)
			( pin "@baseboard_fab2_lib.baseboard_fab2(sch_1):page40_i22:vss(795)"
				( attribute "PN" "AK19"
					( Origin gPackager )
				)
				( objectStatus "U5D1.AK19" )
			)
			( pin "@baseboard_fab2_lib.baseboard_fab2(sch_1):page40_i22:vss(796)"
				( attribute "PN" "AK13"
					( Origin gPackager )
				)
				( objectStatus "U5D1.AK13" )
			)
			( pin "@baseboard_fab2_lib.baseboard_fab2(sch_1):page40_i22:vss(797)"
				( attribute "PN" "AK9"
					( Origin gPackager )
				)
				( objectStatus "U5D1.AK9" )
			)
			( pin "@baseboard_fab2_lib.baseboard_fab2(sch_1):page40_i22:vss(798)"
				( attribute "PN" "AJ86"
					( Origin gPackager )
				)
				( objectStatus "U5D1.AJ86" )
			)
			( pin "@baseboard_fab2_lib.baseboard_fab2(sch_1):page40_i22:vss(799)"
				( attribute "PN" "AJ82"
					( Origin gPackager )
				)
				( objectStatus "U5D1.AJ82" )
			)
			( pin "@baseboard_fab2_lib.baseboard_fab2(sch_1):page40_i22:vss(800)"
				( attribute "PN" "AJ78"
					( Origin gPackager )
				)
				( objectStatus "U5D1.AJ78" )
			)
			( pin "@baseboard_fab2_lib.baseboard_fab2(sch_1):page40_i22:vss(801)"
				( attribute "PN" "AJ74"
					( Origin gPackager )
				)
				( objectStatus "U5D1.AJ74" )
			)
			( pin "@baseboard_fab2_lib.baseboard_fab2(sch_1):page40_i22:vss(802)"
				( attribute "PN" "AJ68"
					( Origin gPackager )
				)
				( objectStatus "U5D1.AJ68" )
			)
			( pin "@baseboard_fab2_lib.baseboard_fab2(sch_1):page40_i22:vss(803)"
				( attribute "PN" "AJ66"
					( Origin gPackager )
				)
				( objectStatus "U5D1.AJ66" )
			)
			( pin "@baseboard_fab2_lib.baseboard_fab2(sch_1):page40_i22:vss(804)"
				( attribute "PN" "AJ54"
					( Origin gPackager )
				)
				( objectStatus "U5D1.AJ54" )
			)
			( pin "@baseboard_fab2_lib.baseboard_fab2(sch_1):page40_i22:vss(805)"
				( attribute "PN" "AJ52"
					( Origin gPackager )
				)
				( objectStatus "U5D1.AJ52" )
			)
			( pin "@baseboard_fab2_lib.baseboard_fab2(sch_1):page40_i22:vss(806)"
				( attribute "PN" "AJ50"
					( Origin gPackager )
				)
				( objectStatus "U5D1.AJ50" )
			)
			( pin "@baseboard_fab2_lib.baseboard_fab2(sch_1):page40_i22:vss(807)"
				( attribute "PN" "AJ48"
					( Origin gPackager )
				)
				( objectStatus "U5D1.AJ48" )
			)
			( pin "@baseboard_fab2_lib.baseboard_fab2(sch_1):page40_i22:vss(808)"
				( attribute "PN" "AJ46"
					( Origin gPackager )
				)
				( objectStatus "U5D1.AJ46" )
			)
			( pin "@baseboard_fab2_lib.baseboard_fab2(sch_1):page40_i22:vss(809)"
				( attribute "PN" "AJ34"
					( Origin gPackager )
				)
				( objectStatus "U5D1.AJ34" )
			)
			( pin "@baseboard_fab2_lib.baseboard_fab2(sch_1):page40_i22:vss(810)"
				( attribute "PN" "AJ32"
					( Origin gPackager )
				)
				( objectStatus "U5D1.AJ32" )
			)
			( pin "@baseboard_fab2_lib.baseboard_fab2(sch_1):page40_i22:vss(811)"
				( attribute "PN" "AJ28"
					( Origin gPackager )
				)
				( objectStatus "U5D1.AJ28" )
			)
			( pin "@baseboard_fab2_lib.baseboard_fab2(sch_1):page40_i22:vss(812)"
				( attribute "PN" "AJ26"
					( Origin gPackager )
				)
				( objectStatus "U5D1.AJ26" )
			)
			( pin "@baseboard_fab2_lib.baseboard_fab2(sch_1):page40_i22:vss(813)"
				( attribute "PN" "AJ22"
					( Origin gPackager )
				)
				( objectStatus "U5D1.AJ22" )
			)
			( pin "@baseboard_fab2_lib.baseboard_fab2(sch_1):page40_i22:vss(814)"
				( attribute "PN" "AJ8"
					( Origin gPackager )
				)
				( objectStatus "U5D1.AJ8" )
			)
			( pin "@baseboard_fab2_lib.baseboard_fab2(sch_1):page40_i22:vss(815)"
				( attribute "PN" "AH83"
					( Origin gPackager )
				)
				( objectStatus "U5D1.AH83" )
			)
			( pin "@baseboard_fab2_lib.baseboard_fab2(sch_1):page40_i22:vss(816)"
				( attribute "PN" "AH77"
					( Origin gPackager )
				)
				( objectStatus "U5D1.AH77" )
			)
			( pin "@baseboard_fab2_lib.baseboard_fab2(sch_1):page40_i22:vss(817)"
				( attribute "PN" "AH75"
					( Origin gPackager )
				)
				( objectStatus "U5D1.AH75" )
			)
			( pin "@baseboard_fab2_lib.baseboard_fab2(sch_1):page40_i22:vss(818)"
				( attribute "PN" "AH69"
					( Origin gPackager )
				)
				( objectStatus "U5D1.AH69" )
			)
			( pin "@baseboard_fab2_lib.baseboard_fab2(sch_1):page40_i22:vss(819)"
				( attribute "PN" "AH65"
					( Origin gPackager )
				)
				( objectStatus "U5D1.AH65" )
			)
			( pin "@baseboard_fab2_lib.baseboard_fab2(sch_1):page40_i22:vss(820)"
				( attribute "PN" "AH61"
					( Origin gPackager )
				)
				( objectStatus "U5D1.AH61" )
			)
			( pin "@baseboard_fab2_lib.baseboard_fab2(sch_1):page40_i22:vss(821)"
				( attribute "PN" "AH59"
					( Origin gPackager )
				)
				( objectStatus "U5D1.AH59" )
			)
			( pin "@baseboard_fab2_lib.baseboard_fab2(sch_1):page40_i22:vss(822)"
				( attribute "PN" "AH53"
					( Origin gPackager )
				)
				( objectStatus "U5D1.AH53" )
			)
			( pin "@baseboard_fab2_lib.baseboard_fab2(sch_1):page40_i22:vss(823)"
				( attribute "PN" "AH51"
					( Origin gPackager )
				)
				( objectStatus "U5D1.AH51" )
			)
			( pin "@baseboard_fab2_lib.baseboard_fab2(sch_1):page40_i22:vss(824)"
				( attribute "PN" "AH49"
					( Origin gPackager )
				)
				( objectStatus "U5D1.AH49" )
			)
			( pin "@baseboard_fab2_lib.baseboard_fab2(sch_1):page40_i22:vss(825)"
				( attribute "PN" "AH47"
					( Origin gPackager )
				)
				( objectStatus "U5D1.AH47" )
			)
			( pin "@baseboard_fab2_lib.baseboard_fab2(sch_1):page40_i22:vss(826)"
				( attribute "PN" "AH45"
					( Origin gPackager )
				)
				( objectStatus "U5D1.AH45" )
			)
			( pin "@baseboard_fab2_lib.baseboard_fab2(sch_1):page40_i22:vss(827)"
				( attribute "PN" "AH35"
					( Origin gPackager )
				)
				( objectStatus "U5D1.AH35" )
			)
			( pin "@baseboard_fab2_lib.baseboard_fab2(sch_1):page40_i22:vss(828)"
				( attribute "PN" "AH33"
					( Origin gPackager )
				)
				( objectStatus "U5D1.AH33" )
			)
			( pin "@baseboard_fab2_lib.baseboard_fab2(sch_1):page40_i22:vss(829)"
				( attribute "PN" "AH27"
					( Origin gPackager )
				)
				( objectStatus "U5D1.AH27" )
			)
			( pin "@baseboard_fab2_lib.baseboard_fab2(sch_1):page40_i22:vss(830)"
				( attribute "PN" "AH21"
					( Origin gPackager )
				)
				( objectStatus "U5D1.AH21" )
			)
			( pin "@baseboard_fab2_lib.baseboard_fab2(sch_1):page40_i22:vss(831)"
				( attribute "PN" "AH5"
					( Origin gPackager )
				)
				( objectStatus "U5D1.AH5" )
			)
			( pin "@baseboard_fab2_lib.baseboard_fab2(sch_1):page40_i22:vss(832)"
				( attribute "PN" "AH1"
					( Origin gPackager )
				)
				( objectStatus "U5D1.AH1" )
			)
			( pin "@baseboard_fab2_lib.baseboard_fab2(sch_1):page40_i22:vss(833)"
				( attribute "PN" "AG80"
					( Origin gPackager )
				)
				( objectStatus "U5D1.AG80" )
			)
			( pin "@baseboard_fab2_lib.baseboard_fab2(sch_1):page40_i22:vss(834)"
				( attribute "PN" "AG78"
					( Origin gPackager )
				)
				( objectStatus "U5D1.AG78" )
			)
			( pin "@baseboard_fab2_lib.baseboard_fab2(sch_1):page40_i22:vss(835)"
				( attribute "PN" "AG76"
					( Origin gPackager )
				)
				( objectStatus "U5D1.AG76" )
			)
			( pin "@baseboard_fab2_lib.baseboard_fab2(sch_1):page40_i22:vss(836)"
				( attribute "PN" "AG74"
					( Origin gPackager )
				)
				( objectStatus "U5D1.AG74" )
			)
			( pin "@baseboard_fab2_lib.baseboard_fab2(sch_1):page40_i22:vss(837)"
				( attribute "PN" "AG70"
					( Origin gPackager )
				)
				( objectStatus "U5D1.AG70" )
			)
			( pin "@baseboard_fab2_lib.baseboard_fab2(sch_1):page40_i22:vss(838)"
				( attribute "PN" "AG64"
					( Origin gPackager )
				)
				( objectStatus "U5D1.AG64" )
			)
			( pin "@baseboard_fab2_lib.baseboard_fab2(sch_1):page40_i22:vss(839)"
				( attribute "PN" "AG36"
					( Origin gPackager )
				)
				( objectStatus "U5D1.AG36" )
			)
			( pin "@baseboard_fab2_lib.baseboard_fab2(sch_1):page40_i22:vss(840)"
				( attribute "PN" "AG18"
					( Origin gPackager )
				)
				( objectStatus "U5D1.AG18" )
			)
			( pin "@baseboard_fab2_lib.baseboard_fab2(sch_1):page40_i22:vss(841)"
				( attribute "PN" "AG14"
					( Origin gPackager )
				)
				( objectStatus "U5D1.AG14" )
			)
			( pin "@baseboard_fab2_lib.baseboard_fab2(sch_1):page40_i22:vss(842)"
				( attribute "PN" "AG12"
					( Origin gPackager )
				)
				( objectStatus "U5D1.AG12" )
			)
			( pin "@baseboard_fab2_lib.baseboard_fab2(sch_1):page40_i22:vss(843)"
				( attribute "PN" "AF85"
					( Origin gPackager )
				)
				( objectStatus "U5D1.AF85" )
			)
			( pin "@baseboard_fab2_lib.baseboard_fab2(sch_1):page40_i22:vss(844)"
				( attribute "PN" "AF83"
					( Origin gPackager )
				)
				( objectStatus "U5D1.AF83" )
			)
			( pin "@baseboard_fab2_lib.baseboard_fab2(sch_1):page40_i22:vss(845)"
				( attribute "PN" "AF77"
					( Origin gPackager )
				)
				( objectStatus "U5D1.AF77" )
			)
			( pin "@baseboard_fab2_lib.baseboard_fab2(sch_1):page40_i22:vss(846)"
				( attribute "PN" "AF73"
					( Origin gPackager )
				)
				( objectStatus "U5D1.AF73" )
			)
			( pin "@baseboard_fab2_lib.baseboard_fab2(sch_1):page40_i22:vss(847)"
				( attribute "PN" "AF41"
					( Origin gPackager )
				)
				( objectStatus "U5D1.AF41" )
			)
			( pin "@baseboard_fab2_lib.baseboard_fab2(sch_1):page40_i22:vss(848)"
				( attribute "PN" "AF39"
					( Origin gPackager )
				)
				( objectStatus "U5D1.AF39" )
			)
			( pin "@baseboard_fab2_lib.baseboard_fab2(sch_1):page40_i22:vss(849)"
				( attribute "PN" "AF37"
					( Origin gPackager )
				)
				( objectStatus "U5D1.AF37" )
			)
			( pin "@baseboard_fab2_lib.baseboard_fab2(sch_1):page40_i22:vss(850)"
				( attribute "PN" "AF33"
					( Origin gPackager )
				)
				( objectStatus "U5D1.AF33" )
			)
			( pin "@baseboard_fab2_lib.baseboard_fab2(sch_1):page40_i22:vss(851)"
				( attribute "PN" "AF31"
					( Origin gPackager )
				)
				( objectStatus "U5D1.AF31" )
			)
			( pin "@baseboard_fab2_lib.baseboard_fab2(sch_1):page40_i22:vss(852)"
				( attribute "PN" "AF29"
					( Origin gPackager )
				)
				( objectStatus "U5D1.AF29" )
			)
			( pin "@baseboard_fab2_lib.baseboard_fab2(sch_1):page40_i22:vss(853)"
				( attribute "PN" "AF27"
					( Origin gPackager )
				)
				( objectStatus "U5D1.AF27" )
			)
			( pin "@baseboard_fab2_lib.baseboard_fab2(sch_1):page40_i22:vss(854)"
				( attribute "PN" "AF25"
					( Origin gPackager )
				)
				( objectStatus "U5D1.AF25" )
			)
			( pin "@baseboard_fab2_lib.baseboard_fab2(sch_1):page40_i22:vss(855)"
				( attribute "PN" "AF23"
					( Origin gPackager )
				)
				( objectStatus "U5D1.AF23" )
			)
			( pin "@baseboard_fab2_lib.baseboard_fab2(sch_1):page40_i22:vss(856)"
				( attribute "PN" "AF21"
					( Origin gPackager )
				)
				( objectStatus "U5D1.AF21" )
			)
			( pin "@baseboard_fab2_lib.baseboard_fab2(sch_1):page40_i22:vss(857)"
				( attribute "PN" "AF9"
					( Origin gPackager )
				)
				( objectStatus "U5D1.AF9" )
			)
			( pin "@baseboard_fab2_lib.baseboard_fab2(sch_1):page40_i22:vss(858)"
				( attribute "PN" "AC52"
					( Origin gPackager )
				)
				( objectStatus "U5D1.AC52" )
			)
			( pin "@baseboard_fab2_lib.baseboard_fab2(sch_1):page40_i22:vss(859)"
				( attribute "PN" "AF1"
					( Origin gPackager )
				)
				( objectStatus "U5D1.AF1" )
			)
			( pin "@baseboard_fab2_lib.baseboard_fab2(sch_1):page40_i22:vss(860)"
				( attribute "PN" "AE78"
					( Origin gPackager )
				)
				( objectStatus "U5D1.AE78" )
			)
			( pin "@baseboard_fab2_lib.baseboard_fab2(sch_1):page40_i22:vss(861)"
				( attribute "PN" "AE70"
					( Origin gPackager )
				)
				( objectStatus "U5D1.AE70" )
			)
			( pin "@baseboard_fab2_lib.baseboard_fab2(sch_1):page40_i22:vss(862)"
				( attribute "PN" "AE68"
					( Origin gPackager )
				)
				( objectStatus "U5D1.AE68" )
			)
			( pin "@baseboard_fab2_lib.baseboard_fab2(sch_1):page40_i22:vss(863)"
				( attribute "PN" "AE66"
					( Origin gPackager )
				)
				( objectStatus "U5D1.AE66" )
			)
			( pin "@baseboard_fab2_lib.baseboard_fab2(sch_1):page40_i22:vss(864)"
				( attribute "PN" "AE64"
					( Origin gPackager )
				)
				( objectStatus "U5D1.AE64" )
			)
			( pin "@baseboard_fab2_lib.baseboard_fab2(sch_1):page40_i22:vss(865)"
				( attribute "PN" "AE42"
					( Origin gPackager )
				)
				( objectStatus "U5D1.AE42" )
			)
			( pin "@baseboard_fab2_lib.baseboard_fab2(sch_1):page40_i22:vss(866)"
				( attribute "PN" "AE40"
					( Origin gPackager )
				)
				( objectStatus "U5D1.AE40" )
			)
			( pin "@baseboard_fab2_lib.baseboard_fab2(sch_1):page40_i22:vss(867)"
				( attribute "PN" "AE38"
					( Origin gPackager )
				)
				( objectStatus "U5D1.AE38" )
			)
			( pin "@baseboard_fab2_lib.baseboard_fab2(sch_1):page40_i22:vss(868)"
				( attribute "PN" "AE16"
					( Origin gPackager )
				)
				( objectStatus "U5D1.AE16" )
			)
			( pin "@baseboard_fab2_lib.baseboard_fab2(sch_1):page40_i22:vss(869)"
				( attribute "PN" "AC54"
					( Origin gPackager )
				)
				( objectStatus "U5D1.AC54" )
			)
			( pin "@baseboard_fab2_lib.baseboard_fab2(sch_1):page40_i22:vss(870)"
				( attribute "PN" "AE8"
					( Origin gPackager )
				)
				( objectStatus "U5D1.AE8" )
			)
			( pin "@baseboard_fab2_lib.baseboard_fab2(sch_1):page40_i22:vss(871)"
				( attribute "PN" "AE4"
					( Origin gPackager )
				)
				( objectStatus "U5D1.AE4" )
			)
			( pin "@baseboard_fab2_lib.baseboard_fab2(sch_1):page40_i22:vss(872)"
				( attribute "PN" "AD85"
					( Origin gPackager )
				)
				( objectStatus "U5D1.AD85" )
			)
			( pin "@baseboard_fab2_lib.baseboard_fab2(sch_1):page40_i22:vss(873)"
				( attribute "PN" "AD83"
					( Origin gPackager )
				)
				( objectStatus "U5D1.AD83" )
			)
			( pin "@baseboard_fab2_lib.baseboard_fab2(sch_1):page40_i22:vss(874)"
				( attribute "PN" "AD81"
					( Origin gPackager )
				)
				( objectStatus "U5D1.AD81" )
			)
			( pin "@baseboard_fab2_lib.baseboard_fab2(sch_1):page40_i22:vss(875)"
				( attribute "PN" "AD75"
					( Origin gPackager )
				)
				( objectStatus "U5D1.AD75" )
			)
			( pin "@baseboard_fab2_lib.baseboard_fab2(sch_1):page40_i22:vss(876)"
				( attribute "PN" "AD73"
					( Origin gPackager )
				)
				( objectStatus "U5D1.AD73" )
			)
			( pin "@baseboard_fab2_lib.baseboard_fab2(sch_1):page40_i22:vss(877)"
				( attribute "PN" "AD71"
					( Origin gPackager )
				)
				( objectStatus "U5D1.AD71" )
			)
			( pin "@baseboard_fab2_lib.baseboard_fab2(sch_1):page40_i22:vss(878)"
				( attribute "PN" "AD43"
					( Origin gPackager )
				)
				( objectStatus "U5D1.AD43" )
			)
			( pin "@baseboard_fab2_lib.baseboard_fab2(sch_1):page40_i22:vss(879)"
				( attribute "PN" "AD39"
					( Origin gPackager )
				)
				( objectStatus "U5D1.AD39" )
			)
			( pin "@baseboard_fab2_lib.baseboard_fab2(sch_1):page40_i22:vss(880)"
				( attribute "PN" "AD33"
					( Origin gPackager )
				)
				( objectStatus "U5D1.AD33" )
			)
			( pin "@baseboard_fab2_lib.baseboard_fab2(sch_1):page40_i22:vss(881)"
				( attribute "PN" "AD27"
					( Origin gPackager )
				)
				( objectStatus "U5D1.AD27" )
			)
			( pin "@baseboard_fab2_lib.baseboard_fab2(sch_1):page40_i22:vss(882)"
				( attribute "PN" "AD21"
					( Origin gPackager )
				)
				( objectStatus "U5D1.AD21" )
			)
			( pin "@baseboard_fab2_lib.baseboard_fab2(sch_1):page40_i22:vss(883)"
				( attribute "PN" "AD19"
					( Origin gPackager )
				)
				( objectStatus "U5D1.AD19" )
			)
			( pin "@baseboard_fab2_lib.baseboard_fab2(sch_1):page40_i22:vss(884)"
				( attribute "PN" "AD15"
					( Origin gPackager )
				)
				( objectStatus "U5D1.AD15" )
			)
			( pin "@baseboard_fab2_lib.baseboard_fab2(sch_1):page40_i22:vss(885)"
				( attribute "PN" "AD13"
					( Origin gPackager )
				)
				( objectStatus "U5D1.AD13" )
			)
			( pin "@baseboard_fab2_lib.baseboard_fab2(sch_1):page40_i22:vss(886)"
				( attribute "PN" "AD11"
					( Origin gPackager )
				)
				( objectStatus "U5D1.AD11" )
			)
			( pin "@baseboard_fab2_lib.baseboard_fab2(sch_1):page40_i22:vss(887)"
				( attribute "PN" "AD9"
					( Origin gPackager )
				)
				( objectStatus "U5D1.AD9" )
			)
			( pin "@baseboard_fab2_lib.baseboard_fab2(sch_1):page40_i22:vss(888)"
				( attribute "PN" "AD7"
					( Origin gPackager )
				)
				( objectStatus "U5D1.AD7" )
			)
			( pin "@baseboard_fab2_lib.baseboard_fab2(sch_1):page40_i22:vss(889)"
				( attribute "PN" "AD3"
					( Origin gPackager )
				)
				( objectStatus "U5D1.AD3" )
			)
			( pin "@baseboard_fab2_lib.baseboard_fab2(sch_1):page40_i22:vss(890)"
				( attribute "PN" "AC86"
					( Origin gPackager )
				)
				( objectStatus "U5D1.AC86" )
			)
			( pin "@baseboard_fab2_lib.baseboard_fab2(sch_1):page40_i22:vss(891)"
				( attribute "PN" "AC84"
					( Origin gPackager )
				)
				( objectStatus "U5D1.AC84" )
			)
			( pin "@baseboard_fab2_lib.baseboard_fab2(sch_1):page40_i22:vss(892)"
				( attribute "PN" "AC78"
					( Origin gPackager )
				)
				( objectStatus "U5D1.AC78" )
			)
			( pin "@baseboard_fab2_lib.baseboard_fab2(sch_1):page40_i22:vss(893)"
				( attribute "PN" "AC72"
					( Origin gPackager )
				)
				( objectStatus "U5D1.AC72" )
			)
			( pin "@baseboard_fab2_lib.baseboard_fab2(sch_1):page40_i22:vss(894)"
				( attribute "PN" "AC70"
					( Origin gPackager )
				)
				( objectStatus "U5D1.AC70" )
			)
			( pin "@baseboard_fab2_lib.baseboard_fab2(sch_1):page40_i22:vss(895)"
				( attribute "PN" "AC64"
					( Origin gPackager )
				)
				( objectStatus "U5D1.AC64" )
			)
			( pin "@baseboard_fab2_lib.baseboard_fab2(sch_1):page40_i22:vss(896)"
				( attribute "PN" "AC40"
					( Origin gPackager )
				)
				( objectStatus "U5D1.AC40" )
			)
			( pin "@baseboard_fab2_lib.baseboard_fab2(sch_1):page40_i22:vss(897)"
				( attribute "PN" "AC38"
					( Origin gPackager )
				)
				( objectStatus "U5D1.AC38" )
			)
			( pin "@baseboard_fab2_lib.baseboard_fab2(sch_1):page40_i22:vss(898)"
				( attribute "PN" "AC34"
					( Origin gPackager )
				)
				( objectStatus "U5D1.AC34" )
			)
			( pin "@baseboard_fab2_lib.baseboard_fab2(sch_1):page40_i22:vss(899)"
				( attribute "PN" "AC32"
					( Origin gPackager )
				)
				( objectStatus "U5D1.AC32" )
			)
			( pin "@baseboard_fab2_lib.baseboard_fab2(sch_1):page40_i22:vss(900)"
				( attribute "PN" "AC28"
					( Origin gPackager )
				)
				( objectStatus "U5D1.AC28" )
			)
			( pin "@baseboard_fab2_lib.baseboard_fab2(sch_1):page40_i22:vss(901)"
				( attribute "PN" "AC26"
					( Origin gPackager )
				)
				( objectStatus "U5D1.AC26" )
			)
			( pin "@baseboard_fab2_lib.baseboard_fab2(sch_1):page40_i22:vss(902)"
				( attribute "PN" "AC22"
					( Origin gPackager )
				)
				( objectStatus "U5D1.AC22" )
			)
			( pin "@baseboard_fab2_lib.baseboard_fab2(sch_1):page40_i22:vss(903)"
				( attribute "PN" "AC18"
					( Origin gPackager )
				)
				( objectStatus "U5D1.AC18" )
			)
			( pin "@baseboard_fab2_lib.baseboard_fab2(sch_1):page40_i22:vss(904)"
				( attribute "PN" "AB85"
					( Origin gPackager )
				)
				( objectStatus "U5D1.AB85" )
			)
			( pin "@baseboard_fab2_lib.baseboard_fab2(sch_1):page40_i22:vss(905)"
				( attribute "PN" "AB83"
					( Origin gPackager )
				)
				( objectStatus "U5D1.AB83" )
			)
			( pin "@baseboard_fab2_lib.baseboard_fab2(sch_1):page40_i22:vss(906)"
				( attribute "PN" "AB79"
					( Origin gPackager )
				)
				( objectStatus "U5D1.AB79" )
			)
			( pin "@baseboard_fab2_lib.baseboard_fab2(sch_1):page40_i22:vss(907)"
				( attribute "PN" "AB73"
					( Origin gPackager )
				)
				( objectStatus "U5D1.AB73" )
			)
			( pin "@baseboard_fab2_lib.baseboard_fab2(sch_1):page40_i22:vss(908)"
				( attribute "PN" "AB69"
					( Origin gPackager )
				)
				( objectStatus "U5D1.AB69" )
			)
			( pin "@baseboard_fab2_lib.baseboard_fab2(sch_1):page40_i22:vss(909)"
				( attribute "PN" "AB65"
					( Origin gPackager )
				)
				( objectStatus "U5D1.AB65" )
			)
			( pin "@baseboard_fab2_lib.baseboard_fab2(sch_1):page40_i22:vss(910)"
				( attribute "PN" "AB41"
					( Origin gPackager )
				)
				( objectStatus "U5D1.AB41" )
			)
			( pin "@baseboard_fab2_lib.baseboard_fab2(sch_1):page40_i22:vss(911)"
				( attribute "PN" "AB37"
					( Origin gPackager )
				)
				( objectStatus "U5D1.AB37" )
			)
			( pin "@baseboard_fab2_lib.baseboard_fab2(sch_1):page40_i22:vss(912)"
				( attribute "PN" "AB35"
					( Origin gPackager )
				)
				( objectStatus "U5D1.AB35" )
			)
			( pin "@baseboard_fab2_lib.baseboard_fab2(sch_1):page40_i22:vss(913)"
				( attribute "PN" "AB31"
					( Origin gPackager )
				)
				( objectStatus "U5D1.AB31" )
			)
			( pin "@baseboard_fab2_lib.baseboard_fab2(sch_1):page40_i22:vss(914)"
				( attribute "PN" "AB29"
					( Origin gPackager )
				)
				( objectStatus "U5D1.AB29" )
			)
			( pin "@baseboard_fab2_lib.baseboard_fab2(sch_1):page40_i22:vss(915)"
				( attribute "PN" "AB25"
					( Origin gPackager )
				)
				( objectStatus "U5D1.AB25" )
			)
			( pin "@baseboard_fab2_lib.baseboard_fab2(sch_1):page40_i22:vss(916)"
				( attribute "PN" "AB23"
					( Origin gPackager )
				)
				( objectStatus "U5D1.AB23" )
			)
			( pin "@baseboard_fab2_lib.baseboard_fab2(sch_1):page40_i22:vss(917)"
				( attribute "PN" "AB21"
					( Origin gPackager )
				)
				( objectStatus "U5D1.AB21" )
			)
			( pin "@baseboard_fab2_lib.baseboard_fab2(sch_1):page40_i22:vss(918)"
				( attribute "PN" "AB11"
					( Origin gPackager )
				)
				( objectStatus "U5D1.AB11" )
			)
			( pin "@baseboard_fab2_lib.baseboard_fab2(sch_1):page40_i22:vss(919)"
				( attribute "PN" "AB5"
					( Origin gPackager )
				)
				( objectStatus "U5D1.AB5" )
			)
			( pin "@baseboard_fab2_lib.baseboard_fab2(sch_1):page40_i22:vss(920)"
				( attribute "PN" "AB1"
					( Origin gPackager )
				)
				( objectStatus "U5D1.AB1" )
			)
			( pin "@baseboard_fab2_lib.baseboard_fab2(sch_1):page40_i22:vss(921)"
				( attribute "PN" "AA82"
					( Origin gPackager )
				)
				( objectStatus "U5D1.AA82" )
			)
			( pin "@baseboard_fab2_lib.baseboard_fab2(sch_1):page40_i22:vss(922)"
				( attribute "PN" "AA80"
					( Origin gPackager )
				)
				( objectStatus "U5D1.AA80" )
			)
			( pin "@baseboard_fab2_lib.baseboard_fab2(sch_1):page40_i22:vss(923)"
				( attribute "PN" "AA78"
					( Origin gPackager )
				)
				( objectStatus "U5D1.AA78" )
			)
			( pin "@baseboard_fab2_lib.baseboard_fab2(sch_1):page40_i22:vss(924)"
				( attribute "PN" "AA76"
					( Origin gPackager )
				)
				( objectStatus "U5D1.AA76" )
			)
			( pin "@baseboard_fab2_lib.baseboard_fab2(sch_1):page40_i22:vss(925)"
				( attribute "PN" "AA68"
					( Origin gPackager )
				)
				( objectStatus "U5D1.AA68" )
			)
			( pin "@baseboard_fab2_lib.baseboard_fab2(sch_1):page40_i22:vss(926)"
				( attribute "PN" "AA66"
					( Origin gPackager )
				)
				( objectStatus "U5D1.AA66" )
			)
			( pin "@baseboard_fab2_lib.baseboard_fab2(sch_1):page40_i22:vss(927)"
				( attribute "PN" "AA64"
					( Origin gPackager )
				)
				( objectStatus "U5D1.AA64" )
			)
			( pin "@baseboard_fab2_lib.baseboard_fab2(sch_1):page40_i22:vss(928)"
				( attribute "PN" "AA42"
					( Origin gPackager )
				)
				( objectStatus "U5D1.AA42" )
			)
			( pin "@baseboard_fab2_lib.baseboard_fab2(sch_1):page40_i22:vss(929)"
				( attribute "PN" "AA36"
					( Origin gPackager )
				)
				( objectStatus "U5D1.AA36" )
			)
			( pin "@baseboard_fab2_lib.baseboard_fab2(sch_1):page40_i22:vss(930)"
				( attribute "PN" "AA30"
					( Origin gPackager )
				)
				( objectStatus "U5D1.AA30" )
			)
			( pin "@baseboard_fab2_lib.baseboard_fab2(sch_1):page40_i22:vss(931)"
				( attribute "PN" "AA24"
					( Origin gPackager )
				)
				( objectStatus "U5D1.AA24" )
			)
			( pin "@baseboard_fab2_lib.baseboard_fab2(sch_1):page40_i22:vss(932)"
				( attribute "PN" "AA22"
					( Origin gPackager )
				)
				( objectStatus "U5D1.AA22" )
			)
			( pin "@baseboard_fab2_lib.baseboard_fab2(sch_1):page40_i22:vss(933)"
				( attribute "PN" "AA18"
					( Origin gPackager )
				)
				( objectStatus "U5D1.AA18" )
			)
			( pin "@baseboard_fab2_lib.baseboard_fab2(sch_1):page40_i23:vss(614)"
				( attribute "PN" "BG72"
					( Origin gPackager )
				)
				( objectStatus "U5D1.BG72" )
			)
			( pin "@baseboard_fab2_lib.baseboard_fab2(sch_1):page40_i23:vss(615)"
				( attribute "PN" "BG24"
					( Origin gPackager )
				)
				( objectStatus "U5D1.BG24" )
			)
			( pin "@baseboard_fab2_lib.baseboard_fab2(sch_1):page40_i23:vss(616)"
				( attribute "PN" "BG22"
					( Origin gPackager )
				)
				( objectStatus "U5D1.BG22" )
			)
			( pin "@baseboard_fab2_lib.baseboard_fab2(sch_1):page40_i23:vss(617)"
				( attribute "PN" "BG10"
					( Origin gPackager )
				)
				( objectStatus "U5D1.BG10" )
			)
			( pin "@baseboard_fab2_lib.baseboard_fab2(sch_1):page40_i23:vss(618)"
				( attribute "PN" "BG8"
					( Origin gPackager )
				)
				( objectStatus "U5D1.BG8" )
			)
			( pin "@baseboard_fab2_lib.baseboard_fab2(sch_1):page40_i23:vss(619)"
				( attribute "PN" "BG6"
					( Origin gPackager )
				)
				( objectStatus "U5D1.BG6" )
			)
			( pin "@baseboard_fab2_lib.baseboard_fab2(sch_1):page40_i23:vss(620)"
				( attribute "PN" "BF71"
					( Origin gPackager )
				)
				( objectStatus "U5D1.BF71" )
			)
			( pin "@baseboard_fab2_lib.baseboard_fab2(sch_1):page40_i23:vss(621)"
				( attribute "PN" "BF69"
					( Origin gPackager )
				)
				( objectStatus "U5D1.BF69" )
			)
			( pin "@baseboard_fab2_lib.baseboard_fab2(sch_1):page40_i23:vss(622)"
				( attribute "PN" "BF67"
					( Origin gPackager )
				)
				( objectStatus "U5D1.BF67" )
			)
			( pin "@baseboard_fab2_lib.baseboard_fab2(sch_1):page40_i23:vss(623)"
				( attribute "PN" "BF65"
					( Origin gPackager )
				)
				( objectStatus "U5D1.BF65" )
			)
			( pin "@baseboard_fab2_lib.baseboard_fab2(sch_1):page40_i23:vss(624)"
				( attribute "PN" "BF63"
					( Origin gPackager )
				)
				( objectStatus "U5D1.BF63" )
			)
			( pin "@baseboard_fab2_lib.baseboard_fab2(sch_1):page40_i23:vss(625)"
				( attribute "PN" "BF25"
					( Origin gPackager )
				)
				( objectStatus "U5D1.BF25" )
			)
			( pin "@baseboard_fab2_lib.baseboard_fab2(sch_1):page40_i23:vss(626)"
				( attribute "PN" "BF19"
					( Origin gPackager )
				)
				( objectStatus "U5D1.BF19" )
			)
			( pin "@baseboard_fab2_lib.baseboard_fab2(sch_1):page40_i23:vss(627)"
				( attribute "PN" "BF17"
					( Origin gPackager )
				)
				( objectStatus "U5D1.BF17" )
			)
			( pin "@baseboard_fab2_lib.baseboard_fab2(sch_1):page40_i23:vss(628)"
				( attribute "PN" "BF15"
					( Origin gPackager )
				)
				( objectStatus "U5D1.BF15" )
			)
			( pin "@baseboard_fab2_lib.baseboard_fab2(sch_1):page40_i23:vss(629)"
				( attribute "PN" "BF9"
					( Origin gPackager )
				)
				( objectStatus "U5D1.BF9" )
			)
			( pin "@baseboard_fab2_lib.baseboard_fab2(sch_1):page40_i23:vss(630)"
				( attribute "PN" "BE70"
					( Origin gPackager )
				)
				( objectStatus "U5D1.BE70" )
			)
			( pin "@baseboard_fab2_lib.baseboard_fab2(sch_1):page40_i23:vss(631)"
				( attribute "PN" "BE68"
					( Origin gPackager )
				)
				( objectStatus "U5D1.BE68" )
			)
			( pin "@baseboard_fab2_lib.baseboard_fab2(sch_1):page40_i23:vss(632)"
				( attribute "PN" "BE66"
					( Origin gPackager )
				)
				( objectStatus "U5D1.BE66" )
			)
			( pin "@baseboard_fab2_lib.baseboard_fab2(sch_1):page40_i23:vss(633)"
				( attribute "PN" "BE64"
					( Origin gPackager )
				)
				( objectStatus "U5D1.BE64" )
			)
			( pin "@baseboard_fab2_lib.baseboard_fab2(sch_1):page40_i23:vss(634)"
				( attribute "PN" "BE26"
					( Origin gPackager )
				)
				( objectStatus "U5D1.BE26" )
			)
			( pin "@baseboard_fab2_lib.baseboard_fab2(sch_1):page40_i23:vss(635)"
				( attribute "PN" "BE10"
					( Origin gPackager )
				)
				( objectStatus "U5D1.BE10" )
			)
			( pin "@baseboard_fab2_lib.baseboard_fab2(sch_1):page40_i23:vss(636)"
				( attribute "PN" "BE8"
					( Origin gPackager )
				)
				( objectStatus "U5D1.BE8" )
			)
			( pin "@baseboard_fab2_lib.baseboard_fab2(sch_1):page40_i23:vss(637)"
				( attribute "PN" "BE6"
					( Origin gPackager )
				)
				( objectStatus "U5D1.BE6" )
			)
			( pin "@baseboard_fab2_lib.baseboard_fab2(sch_1):page40_i23:vss(638)"
				( attribute "PN" "BE4"
					( Origin gPackager )
				)
				( objectStatus "U5D1.BE4" )
			)
			( pin "@baseboard_fab2_lib.baseboard_fab2(sch_1):page40_i23:vss(639)"
				( attribute "PN" "BD71"
					( Origin gPackager )
				)
				( objectStatus "U5D1.BD71" )
			)
			( pin "@baseboard_fab2_lib.baseboard_fab2(sch_1):page40_i23:vss(640)"
				( attribute "PN" "BD63"
					( Origin gPackager )
				)
				( objectStatus "U5D1.BD63" )
			)
			( pin "@baseboard_fab2_lib.baseboard_fab2(sch_1):page40_i23:vss(641)"
				( attribute "PN" "BD27"
					( Origin gPackager )
				)
				( objectStatus "U5D1.BD27" )
			)
			( pin "@baseboard_fab2_lib.baseboard_fab2(sch_1):page40_i23:vss(642)"
				( attribute "PN" "BD21"
					( Origin gPackager )
				)
				( objectStatus "U5D1.BD21" )
			)
			( pin "@baseboard_fab2_lib.baseboard_fab2(sch_1):page40_i23:vss(643)"
				( attribute "PN" "BD15"
					( Origin gPackager )
				)
				( objectStatus "U5D1.BD15" )
			)
			( pin "@baseboard_fab2_lib.baseboard_fab2(sch_1):page40_i23:vss(644)"
				( attribute "PN" "BD11"
					( Origin gPackager )
				)
				( objectStatus "U5D1.BD11" )
			)
			( pin "@baseboard_fab2_lib.baseboard_fab2(sch_1):page40_i23:vss(645)"
				( attribute "PN" "BD5"
					( Origin gPackager )
				)
				( objectStatus "U5D1.BD5" )
			)
			( pin "@baseboard_fab2_lib.baseboard_fab2(sch_1):page40_i23:vss(646)"
				( attribute "PN" "BC82"
					( Origin gPackager )
				)
				( objectStatus "U5D1.BC82" )
			)
			( pin "@baseboard_fab2_lib.baseboard_fab2(sch_1):page40_i23:vss(647)"
				( attribute "PN" "BC80"
					( Origin gPackager )
				)
				( objectStatus "U5D1.BC80" )
			)
			( pin "@baseboard_fab2_lib.baseboard_fab2(sch_1):page40_i23:vss(648)"
				( attribute "PN" "BC78"
					( Origin gPackager )
				)
				( objectStatus "U5D1.BC78" )
			)
			( pin "@baseboard_fab2_lib.baseboard_fab2(sch_1):page40_i23:vss(649)"
				( attribute "PN" "BC76"
					( Origin gPackager )
				)
				( objectStatus "U5D1.BC76" )
			)
			( pin "@baseboard_fab2_lib.baseboard_fab2(sch_1):page40_i23:vss(650)"
				( attribute "PN" "BC74"
					( Origin gPackager )
				)
				( objectStatus "U5D1.BC74" )
			)
			( pin "@baseboard_fab2_lib.baseboard_fab2(sch_1):page40_i23:vss(651)"
				( attribute "PN" "BC72"
					( Origin gPackager )
				)
				( objectStatus "U5D1.BC72" )
			)
			( pin "@baseboard_fab2_lib.baseboard_fab2(sch_1):page40_i23:vss(652)"
				( attribute "PN" "BC70"
					( Origin gPackager )
				)
				( objectStatus "U5D1.BC70" )
			)
			( pin "@baseboard_fab2_lib.baseboard_fab2(sch_1):page40_i23:vss(653)"
				( attribute "PN" "BC16"
					( Origin gPackager )
				)
				( objectStatus "U5D1.BC16" )
			)
			( pin "@baseboard_fab2_lib.baseboard_fab2(sch_1):page40_i23:vss(654)"
				( attribute "PN" "BC12"
					( Origin gPackager )
				)
				( objectStatus "U5D1.BC12" )
			)
			( pin "@baseboard_fab2_lib.baseboard_fab2(sch_1):page40_i23:vss(655)"
				( attribute "PN" "BC8"
					( Origin gPackager )
				)
				( objectStatus "U5D1.BC8" )
			)
			( pin "@baseboard_fab2_lib.baseboard_fab2(sch_1):page40_i23:vss(656)"
				( attribute "PN" "BC4"
					( Origin gPackager )
				)
				( objectStatus "U5D1.BC4" )
			)
			( pin "@baseboard_fab2_lib.baseboard_fab2(sch_1):page40_i23:vss(657)"
				( attribute "PN" "BB83"
					( Origin gPackager )
				)
				( objectStatus "U5D1.BB83" )
			)
			( pin "@baseboard_fab2_lib.baseboard_fab2(sch_1):page40_i23:vss(658)"
				( attribute "PN" "BB81"
					( Origin gPackager )
				)
				( objectStatus "U5D1.BB81" )
			)
			( pin "@baseboard_fab2_lib.baseboard_fab2(sch_1):page40_i23:vss(659)"
				( attribute "PN" "BB79"
					( Origin gPackager )
				)
				( objectStatus "U5D1.BB79" )
			)
			( pin "@baseboard_fab2_lib.baseboard_fab2(sch_1):page40_i23:vss(660)"
				( attribute "PN" "BB77"
					( Origin gPackager )
				)
				( objectStatus "U5D1.BB77" )
			)
			( pin "@baseboard_fab2_lib.baseboard_fab2(sch_1):page40_i23:vss(661)"
				( attribute "PN" "BB75"
					( Origin gPackager )
				)
				( objectStatus "U5D1.BB75" )
			)
			( pin "@baseboard_fab2_lib.baseboard_fab2(sch_1):page40_i23:vss(662)"
				( attribute "PN" "BB73"
					( Origin gPackager )
				)
				( objectStatus "U5D1.BB73" )
			)
			( pin "@baseboard_fab2_lib.baseboard_fab2(sch_1):page40_i23:vss(663)"
				( attribute "PN" "BB69"
					( Origin gPackager )
				)
				( objectStatus "U5D1.BB69" )
			)
			( pin "@baseboard_fab2_lib.baseboard_fab2(sch_1):page40_i23:vss(664)"
				( attribute "PN" "BB63"
					( Origin gPackager )
				)
				( objectStatus "U5D1.BB63" )
			)
			( pin "@baseboard_fab2_lib.baseboard_fab2(sch_1):page40_i23:vss(665)"
				( attribute "PN" "BB23"
					( Origin gPackager )
				)
				( objectStatus "U5D1.BB23" )
			)
			( pin "@baseboard_fab2_lib.baseboard_fab2(sch_1):page40_i23:vss(666)"
				( attribute "PN" "BB19"
					( Origin gPackager )
				)
				( objectStatus "U5D1.BB19" )
			)
			( pin "@baseboard_fab2_lib.baseboard_fab2(sch_1):page40_i23:vss(667)"
				( attribute "PN" "BA84"
					( Origin gPackager )
				)
				( objectStatus "U5D1.BA84" )
			)
			( pin "@baseboard_fab2_lib.baseboard_fab2(sch_1):page40_i23:vss(668)"
				( attribute "PN" "BA80"
					( Origin gPackager )
				)
				( objectStatus "U5D1.BA80" )
			)
			( pin "@baseboard_fab2_lib.baseboard_fab2(sch_1):page40_i23:vss(669)"
				( attribute "PN" "BA74"
					( Origin gPackager )
				)
				( objectStatus "U5D1.BA74" )
			)
			( pin "@baseboard_fab2_lib.baseboard_fab2(sch_1):page40_i23:vss(670)"
				( attribute "PN" "BA68"
					( Origin gPackager )
				)
				( objectStatus "U5D1.BA68" )
			)
			( pin "@baseboard_fab2_lib.baseboard_fab2(sch_1):page40_i23:vss(671)"
				( attribute "PN" "BA62"
					( Origin gPackager )
				)
				( objectStatus "U5D1.BA62" )
			)
			( pin "@baseboard_fab2_lib.baseboard_fab2(sch_1):page40_i23:vss(672)"
				( attribute "PN" "BA12"
					( Origin gPackager )
				)
				( objectStatus "U5D1.BA12" )
			)
			( pin "@baseboard_fab2_lib.baseboard_fab2(sch_1):page40_i23:vss(673)"
				( attribute "PN" "BA6"
					( Origin gPackager )
				)
				( objectStatus "U5D1.BA6" )
			)
			( pin "@baseboard_fab2_lib.baseboard_fab2(sch_1):page40_i23:vss(674)"
				( attribute "PN" "BA2"
					( Origin gPackager )
				)
				( objectStatus "U5D1.BA2" )
			)
			( pin "@baseboard_fab2_lib.baseboard_fab2(sch_1):page40_i23:vss(675)"
				( attribute "PN" "AY81"
					( Origin gPackager )
				)
				( objectStatus "U5D1.AY81" )
			)
			( pin "@baseboard_fab2_lib.baseboard_fab2(sch_1):page40_i23:vss(676)"
				( attribute "PN" "AY79"
					( Origin gPackager )
				)
				( objectStatus "U5D1.AY79" )
			)
			( pin "@baseboard_fab2_lib.baseboard_fab2(sch_1):page40_i23:vss(677)"
				( attribute "PN" "AY63"
					( Origin gPackager )
				)
				( objectStatus "U5D1.AY63" )
			)
			( pin "@baseboard_fab2_lib.baseboard_fab2(sch_1):page40_i23:vss(678)"
				( attribute "PN" "AY25"
					( Origin gPackager )
				)
				( objectStatus "U5D1.AY25" )
			)
			( pin "@baseboard_fab2_lib.baseboard_fab2(sch_1):page40_i23:vss(679)"
				( attribute "PN" "AY23"
					( Origin gPackager )
				)
				( objectStatus "U5D1.AY23" )
			)
			( pin "@baseboard_fab2_lib.baseboard_fab2(sch_1):page40_i23:vss(680)"
				( attribute "PN" "AY21"
					( Origin gPackager )
				)
				( objectStatus "U5D1.AY21" )
			)
			( pin "@baseboard_fab2_lib.baseboard_fab2(sch_1):page40_i23:vss(681)"
				( attribute "PN" "AY17"
					( Origin gPackager )
				)
				( objectStatus "U5D1.AY17" )
			)
			( pin "@baseboard_fab2_lib.baseboard_fab2(sch_1):page40_i23:vss(682)"
				( attribute "PN" "AY15"
					( Origin gPackager )
				)
				( objectStatus "U5D1.AY15" )
			)
			( pin "@baseboard_fab2_lib.baseboard_fab2(sch_1):page40_i23:vss(683)"
				( attribute "PN" "AY5"
					( Origin gPackager )
				)
				( objectStatus "U5D1.AY5" )
			)
			( pin "@baseboard_fab2_lib.baseboard_fab2(sch_1):page40_i23:vss(684)"
				( attribute "PN" "AW84"
					( Origin gPackager )
				)
				( objectStatus "U5D1.AW84" )
			)
			( pin "@baseboard_fab2_lib.baseboard_fab2(sch_1):page40_i23:vss(685)"
				( attribute "PN" "AW82"
					( Origin gPackager )
				)
				( objectStatus "U5D1.AW82" )
			)
			( pin "@baseboard_fab2_lib.baseboard_fab2(sch_1):page40_i23:vss(686)"
				( attribute "PN" "AW78"
					( Origin gPackager )
				)
				( objectStatus "U5D1.AW78" )
			)
			( pin "@baseboard_fab2_lib.baseboard_fab2(sch_1):page40_i23:vss(687)"
				( attribute "PN" "AW74"
					( Origin gPackager )
				)
				( objectStatus "U5D1.AW74" )
			)
			( pin "@baseboard_fab2_lib.baseboard_fab2(sch_1):page40_i23:vss(688)"
				( attribute "PN" "AW72"
					( Origin gPackager )
				)
				( objectStatus "U5D1.AW72" )
			)
			( pin "@baseboard_fab2_lib.baseboard_fab2(sch_1):page40_i23:vss(689)"
				( attribute "PN" "AW70"
					( Origin gPackager )
				)
				( objectStatus "U5D1.AW70" )
			)
			( pin "@baseboard_fab2_lib.baseboard_fab2(sch_1):page40_i23:vss(690)"
				( attribute "PN" "AW68"
					( Origin gPackager )
				)
				( objectStatus "U5D1.AW68" )
			)
			( pin "@baseboard_fab2_lib.baseboard_fab2(sch_1):page40_i23:vss(691)"
				( attribute "PN" "AW66"
					( Origin gPackager )
				)
				( objectStatus "U5D1.AW66" )
			)
			( pin "@baseboard_fab2_lib.baseboard_fab2(sch_1):page40_i23:vss(692)"
				( attribute "PN" "AW62"
					( Origin gPackager )
				)
				( objectStatus "U5D1.AW62" )
			)
			( pin "@baseboard_fab2_lib.baseboard_fab2(sch_1):page40_i23:vss(693)"
				( attribute "PN" "AW10"
					( Origin gPackager )
				)
				( objectStatus "U5D1.AW10" )
			)
			( pin "@baseboard_fab2_lib.baseboard_fab2(sch_1):page40_i23:vss(694)"
				( attribute "PN" "AW2"
					( Origin gPackager )
				)
				( objectStatus "U5D1.AW2" )
			)
			( pin "@baseboard_fab2_lib.baseboard_fab2(sch_1):page40_i23:vss(695)"
				( attribute "PN" "AV83"
					( Origin gPackager )
				)
				( objectStatus "U5D1.AV83" )
			)
			( pin "@baseboard_fab2_lib.baseboard_fab2(sch_1):page40_i23:vss(696)"
				( attribute "PN" "AV75"
					( Origin gPackager )
				)
				( objectStatus "U5D1.AV75" )
			)
			( pin "@baseboard_fab2_lib.baseboard_fab2(sch_1):page40_i23:vss(697)"
				( attribute "PN" "AV67"
					( Origin gPackager )
				)
				( objectStatus "U5D1.AV67" )
			)
			( pin "@baseboard_fab2_lib.baseboard_fab2(sch_1):page40_i23:vss(698)"
				( attribute "PN" "AV65"
					( Origin gPackager )
				)
				( objectStatus "U5D1.AV65" )
			)
			( pin "@baseboard_fab2_lib.baseboard_fab2(sch_1):page40_i23:vss(699)"
				( attribute "PN" "AV63"
					( Origin gPackager )
				)
				( objectStatus "U5D1.AV63" )
			)
			( pin "@baseboard_fab2_lib.baseboard_fab2(sch_1):page40_i23:vss(700)"
				( attribute "PN" "AV25"
					( Origin gPackager )
				)
				( objectStatus "U5D1.AV25" )
			)
			( pin "@baseboard_fab2_lib.baseboard_fab2(sch_1):page40_i23:vss(701)"
				( attribute "PN" "AV23"
					( Origin gPackager )
				)
				( objectStatus "U5D1.AV23" )
			)
			( pin "@baseboard_fab2_lib.baseboard_fab2(sch_1):page40_i23:vss(702)"
				( attribute "PN" "AV19"
					( Origin gPackager )
				)
				( objectStatus "U5D1.AV19" )
			)
			( pin "@baseboard_fab2_lib.baseboard_fab2(sch_1):page40_i23:vss(703)"
				( attribute "PN" "AV13"
					( Origin gPackager )
				)
				( objectStatus "U5D1.AV13" )
			)
			( pin "@baseboard_fab2_lib.baseboard_fab2(sch_1):page40_i23:vss(704)"
				( attribute "PN" "AV11"
					( Origin gPackager )
				)
				( objectStatus "U5D1.AV11" )
			)
			( pin "@baseboard_fab2_lib.baseboard_fab2(sch_1):page40_i23:vss(705)"
				( attribute "PN" "AV7"
					( Origin gPackager )
				)
				( objectStatus "U5D1.AV7" )
			)
			( pin "@baseboard_fab2_lib.baseboard_fab2(sch_1):page40_i23:vss(706)"
				( attribute "PN" "AV3"
					( Origin gPackager )
				)
				( objectStatus "U5D1.AV3" )
			)
			( pin "@baseboard_fab2_lib.baseboard_fab2(sch_1):page40_i23:vss(707)"
				( attribute "PN" "AV1"
					( Origin gPackager )
				)
				( objectStatus "U5D1.AV1" )
			)
			( pin "@baseboard_fab2_lib.baseboard_fab2(sch_1):page40_i23:vss(708)"
				( attribute "PN" "AU86"
					( Origin gPackager )
				)
				( objectStatus "U5D1.AU86" )
			)
			( pin "@baseboard_fab2_lib.baseboard_fab2(sch_1):page40_i23:vss(709)"
				( attribute "PN" "AU84"
					( Origin gPackager )
				)
				( objectStatus "U5D1.AU84" )
			)
			( pin "@baseboard_fab2_lib.baseboard_fab2(sch_1):page40_i23:vss(710)"
				( attribute "PN" "AU80"
					( Origin gPackager )
				)
				( objectStatus "U5D1.AU80" )
			)
			( pin "@baseboard_fab2_lib.baseboard_fab2(sch_1):page40_i23:vss(711)"
				( attribute "PN" "AU78"
					( Origin gPackager )
				)
				( objectStatus "U5D1.AU78" )
			)
			( pin "@baseboard_fab2_lib.baseboard_fab2(sch_1):page40_i23:vss(712)"
				( attribute "PN" "AU76"
					( Origin gPackager )
				)
				( objectStatus "U5D1.AU76" )
			)
			( pin "@baseboard_fab2_lib.baseboard_fab2(sch_1):page40_i23:vss(713)"
				( attribute "PN" "AU74"
					( Origin gPackager )
				)
				( objectStatus "U5D1.AU74" )
			)
			( pin "@baseboard_fab2_lib.baseboard_fab2(sch_1):page40_i23:vss(714)"
				( attribute "PN" "AU68"
					( Origin gPackager )
				)
				( objectStatus "U5D1.AU68" )
			)
			( pin "@baseboard_fab2_lib.baseboard_fab2(sch_1):page40_i23:vss(715)"
				( attribute "PN" "AU64"
					( Origin gPackager )
				)
				( objectStatus "U5D1.AU64" )
			)
			( pin "@baseboard_fab2_lib.baseboard_fab2(sch_1):page40_i23:vss(716)"
				( attribute "PN" "AU62"
					( Origin gPackager )
				)
				( objectStatus "U5D1.AU62" )
			)
			( pin "@baseboard_fab2_lib.baseboard_fab2(sch_1):page40_i23:vss(717)"
				( attribute "PN" "AU28"
					( Origin gPackager )
				)
				( objectStatus "U5D1.AU28" )
			)
			( pin "@baseboard_fab2_lib.baseboard_fab2(sch_1):page40_i23:vss(718)"
				( attribute "PN" "AU26"
					( Origin gPackager )
				)
				( objectStatus "U5D1.AU26" )
			)
			( pin "@baseboard_fab2_lib.baseboard_fab2(sch_1):page40_i23:vss(719)"
				( attribute "PN" "AU6"
					( Origin gPackager )
				)
				( objectStatus "U5D1.AU6" )
			)
			( pin "@baseboard_fab2_lib.baseboard_fab2(sch_1):page40_i23:vss(720)"
				( attribute "PN" "AU2"
					( Origin gPackager )
				)
				( objectStatus "U5D1.AU2" )
			)
			( pin "@baseboard_fab2_lib.baseboard_fab2(sch_1):page40_i23:vss(721)"
				( attribute "PN" "AT85"
					( Origin gPackager )
				)
				( objectStatus "U5D1.AT85" )
			)
			( pin "@baseboard_fab2_lib.baseboard_fab2(sch_1):page40_i23:vss(722)"
				( attribute "PN" "AT83"
					( Origin gPackager )
				)
				( objectStatus "U5D1.AT83" )
			)
			( pin "@baseboard_fab2_lib.baseboard_fab2(sch_1):page40_i23:vss(723)"
				( attribute "PN" "AT77"
					( Origin gPackager )
				)
				( objectStatus "U5D1.AT77" )
			)
			( pin "@baseboard_fab2_lib.baseboard_fab2(sch_1):page40_i23:vss(724)"
				( attribute "PN" "AT73"
					( Origin gPackager )
				)
				( objectStatus "U5D1.AT73" )
			)
			( pin "@baseboard_fab2_lib.baseboard_fab2(sch_1):page40_i23:vss(725)"
				( attribute "PN" "AT69"
					( Origin gPackager )
				)
				( objectStatus "U5D1.AT69" )
			)
			( pin "@baseboard_fab2_lib.baseboard_fab2(sch_1):page40_i23:vss(726)"
				( attribute "PN" "AT63"
					( Origin gPackager )
				)
				( objectStatus "U5D1.AT63" )
			)
			( pin "@baseboard_fab2_lib.baseboard_fab2(sch_1):page40_i23:vss(727)"
				( attribute "PN" "AT61"
					( Origin gPackager )
				)
				( objectStatus "U5D1.AT61" )
			)
			( pin "@baseboard_fab2_lib.baseboard_fab2(sch_1):page40_i23:vss(728)"
				( attribute "PN" "AT27"
					( Origin gPackager )
				)
				( objectStatus "U5D1.AT27" )
			)
			( pin "@baseboard_fab2_lib.baseboard_fab2(sch_1):page40_i23:vss(729)"
				( attribute "PN" "AT21"
					( Origin gPackager )
				)
				( objectStatus "U5D1.AT21" )
			)
			( pin "@baseboard_fab2_lib.baseboard_fab2(sch_1):page40_i23:vss(730)"
				( attribute "PN" "AT17"
					( Origin gPackager )
				)
				( objectStatus "U5D1.AT17" )
			)
			( pin "@baseboard_fab2_lib.baseboard_fab2(sch_1):page40_i23:vss(731)"
				( attribute "PN" "AT15"
					( Origin gPackager )
				)
				( objectStatus "U5D1.AT15" )
			)
			( pin "@baseboard_fab2_lib.baseboard_fab2(sch_1):page40_i23:vss(732)"
				( attribute "PN" "P63"
					( Origin gPackager )
				)
				( objectStatus "U5D1.P63" )
			)
			( pin "@baseboard_fab2_lib.baseboard_fab2(sch_1):page40_i23:vss(733)"
				( attribute "PN" "AC48"
					( Origin gPackager )
				)
				( objectStatus "U5D1.AC48" )
			)
			( pin "@baseboard_fab2_lib.baseboard_fab2(sch_1):page40_i23:vss(734)"
				( attribute "PN" "AR78"
					( Origin gPackager )
				)
				( objectStatus "U5D1.AR78" )
			)
			( pin "@baseboard_fab2_lib.baseboard_fab2(sch_1):page40_i23:vss(735)"
				( attribute "PN" "AR72"
					( Origin gPackager )
				)
				( objectStatus "U5D1.AR72" )
			)
			( pin "@baseboard_fab2_lib.baseboard_fab2(sch_1):page40_i23:vss(736)"
				( attribute "PN" "AR60"
					( Origin gPackager )
				)
				( objectStatus "U5D1.AR60" )
			)
			( pin "@baseboard_fab2_lib.baseboard_fab2(sch_1):page40_i23:vss(737)"
				( attribute "PN" "AR30"
					( Origin gPackager )
				)
				( objectStatus "U5D1.AR30" )
			)
			( pin "@baseboard_fab2_lib.baseboard_fab2(sch_1):page40_i23:vss(738)"
				( attribute "PN" "AR24"
					( Origin gPackager )
				)
				( objectStatus "U5D1.AR24" )
			)
			( pin "@baseboard_fab2_lib.baseboard_fab2(sch_1):page40_i23:vss(739)"
				( attribute "PN" "AR10"
					( Origin gPackager )
				)
				( objectStatus "U5D1.AR10" )
			)
			( pin "@baseboard_fab2_lib.baseboard_fab2(sch_1):page40_i23:vss(740)"
				( attribute "PN" "AP85"
					( Origin gPackager )
				)
				( objectStatus "U5D1.AP85" )
			)
			( pin "@baseboard_fab2_lib.baseboard_fab2(sch_1):page40_i23:vss(741)"
				( attribute "PN" "AP83"
					( Origin gPackager )
				)
				( objectStatus "U5D1.AP83" )
			)
			( pin "@baseboard_fab2_lib.baseboard_fab2(sch_1):page40_i23:vss(742)"
				( attribute "PN" "AP81"
					( Origin gPackager )
				)
				( objectStatus "U5D1.AP81" )
			)
			( pin "@baseboard_fab2_lib.baseboard_fab2(sch_1):page40_i23:vss(743)"
				( attribute "PN" "AP75"
					( Origin gPackager )
				)
				( objectStatus "U5D1.AP75" )
			)
			( pin "@baseboard_fab2_lib.baseboard_fab2(sch_1):page40_i23:vss(744)"
				( attribute "PN" "AP73"
					( Origin gPackager )
				)
				( objectStatus "U5D1.AP73" )
			)
			( pin "@baseboard_fab2_lib.baseboard_fab2(sch_1):page40_i23:vss(745)"
				( attribute "PN" "AP69"
					( Origin gPackager )
				)
				( objectStatus "U5D1.AP69" )
			)
			( pin "@baseboard_fab2_lib.baseboard_fab2(sch_1):page40_i23:vss(746)"
				( attribute "PN" "AP67"
					( Origin gPackager )
				)
				( objectStatus "U5D1.AP67" )
			)
			( pin "@baseboard_fab2_lib.baseboard_fab2(sch_1):page40_i23:vss(747)"
				( attribute "PN" "AP65"
					( Origin gPackager )
				)
				( objectStatus "U5D1.AP65" )
			)
			( pin "@baseboard_fab2_lib.baseboard_fab2(sch_1):page40_i23:vss(748)"
				( attribute "PN" "AP63"
					( Origin gPackager )
				)
				( objectStatus "U5D1.AP63" )
			)
			( pin "@baseboard_fab2_lib.baseboard_fab2(sch_1):page40_i23:vss(749)"
				( attribute "PN" "AP59"
					( Origin gPackager )
				)
				( objectStatus "U5D1.AP59" )
			)
			( pin "@baseboard_fab2_lib.baseboard_fab2(sch_1):page40_i23:vss(750)"
				( attribute "PN" "AP31"
					( Origin gPackager )
				)
				( objectStatus "U5D1.AP31" )
			)
			( pin "@baseboard_fab2_lib.baseboard_fab2(sch_1):page40_i23:vss(751)"
				( attribute "PN" "AP19"
					( Origin gPackager )
				)
				( objectStatus "U5D1.AP19" )
			)
			( pin "@baseboard_fab2_lib.baseboard_fab2(sch_1):page40_i23:vss(752)"
				( attribute "PN" "AP13"
					( Origin gPackager )
				)
				( objectStatus "U5D1.AP13" )
			)
			( pin "@baseboard_fab2_lib.baseboard_fab2(sch_1):page40_i23:vss(753)"
				( attribute "PN" "AP9"
					( Origin gPackager )
				)
				( objectStatus "U5D1.AP9" )
			)
			( pin "@baseboard_fab2_lib.baseboard_fab2(sch_1):page40_i23:vss(754)"
				( attribute "PN" "AP5"
					( Origin gPackager )
				)
				( objectStatus "U5D1.AP5" )
			)
			( pin "@baseboard_fab2_lib.baseboard_fab2(sch_1):page40_i23:vss(755)"
				( attribute "PN" "AN78"
					( Origin gPackager )
				)
				( objectStatus "U5D1.AN78" )
			)
			( pin "@baseboard_fab2_lib.baseboard_fab2(sch_1):page40_i23:vss(756)"
				( attribute "PN" "AN58"
					( Origin gPackager )
				)
				( objectStatus "U5D1.AN58" )
			)
			( pin "@baseboard_fab2_lib.baseboard_fab2(sch_1):page40_i23:vss(757)"
				( attribute "PN" "AN28"
					( Origin gPackager )
				)
				( objectStatus "U5D1.AN28" )
			)
			( pin "@baseboard_fab2_lib.baseboard_fab2(sch_1):page40_i23:vss(758)"
				( attribute "PN" "AN6"
					( Origin gPackager )
				)
				( objectStatus "U5D1.AN6" )
			)
			( pin "@baseboard_fab2_lib.baseboard_fab2(sch_1):page40_i23:vss(759)"
				( attribute "PN" "AN2"
					( Origin gPackager )
				)
				( objectStatus "U5D1.AN2" )
			)
			( pin "@baseboard_fab2_lib.baseboard_fab2(sch_1):page40_i23:vss(760)"
				( attribute "PN" "AM83"
					( Origin gPackager )
				)
				( objectStatus "U5D1.AM83" )
			)
			( pin "@baseboard_fab2_lib.baseboard_fab2(sch_1):page40_i23:vss(761)"
				( attribute "PN" "AM79"
					( Origin gPackager )
				)
				( objectStatus "U5D1.AM79" )
			)
			( pin "@baseboard_fab2_lib.baseboard_fab2(sch_1):page40_i23:vss(762)"
				( attribute "PN" "AM73"
					( Origin gPackager )
				)
				( objectStatus "U5D1.AM73" )
			)
			( pin "@baseboard_fab2_lib.baseboard_fab2(sch_1):page40_i23:vss(763)"
				( attribute "PN" "AM69"
					( Origin gPackager )
				)
				( objectStatus "U5D1.AM69" )
			)
			( pin "@baseboard_fab2_lib.baseboard_fab2(sch_1):page40_i23:vss(764)"
				( attribute "PN" "AM63"
					( Origin gPackager )
				)
				( objectStatus "U5D1.AM63" )
			)
			( pin "@baseboard_fab2_lib.baseboard_fab2(sch_1):page40_i23:vss(765)"
				( attribute "PN" "AM57"
					( Origin gPackager )
				)
				( objectStatus "U5D1.AM57" )
			)
			( pin "@baseboard_fab2_lib.baseboard_fab2(sch_1):page40_i23:vss(766)"
				( attribute "PN" "AM31"
					( Origin gPackager )
				)
				( objectStatus "U5D1.AM31" )
			)
			( pin "@baseboard_fab2_lib.baseboard_fab2(sch_1):page40_i23:vss(767)"
				( attribute "PN" "AC50"
					( Origin gPackager )
				)
				( objectStatus "U5D1.AC50" )
			)
			( pin "@baseboard_fab2_lib.baseboard_fab2(sch_1):page40_i23:vss(768)"
				( attribute "PN" "AM1"
					( Origin gPackager )
				)
				( objectStatus "U5D1.AM1" )
			)
			( pin "@baseboard_fab2_lib.baseboard_fab2(sch_1):page40_i23:vss(769)"
				( attribute "PN" "AL86"
					( Origin gPackager )
				)
				( objectStatus "U5D1.AL86" )
			)
			( pin "@baseboard_fab2_lib.baseboard_fab2(sch_1):page40_i23:vss(770)"
				( attribute "PN" "AL82"
					( Origin gPackager )
				)
				( objectStatus "U5D1.AL82" )
			)
			( pin "@baseboard_fab2_lib.baseboard_fab2(sch_1):page40_i23:vss(771)"
				( attribute "PN" "AL80"
					( Origin gPackager )
				)
				( objectStatus "U5D1.AL80" )
			)
			( pin "@baseboard_fab2_lib.baseboard_fab2(sch_1):page40_i23:vss(772)"
				( attribute "PN" "AL78"
					( Origin gPackager )
				)
				( objectStatus "U5D1.AL78" )
			)
			( pin "@baseboard_fab2_lib.baseboard_fab2(sch_1):page40_i23:vss(773)"
				( attribute "PN" "AL76"
					( Origin gPackager )
				)
				( objectStatus "U5D1.AL76" )
			)
			( pin "@baseboard_fab2_lib.baseboard_fab2(sch_1):page41_i283:vss(454)"
				( attribute "PN" "P49"
					( Origin gPackager )
				)
				( objectStatus "U5D1.P49" )
			)
			( pin "@baseboard_fab2_lib.baseboard_fab2(sch_1):page41_i283:vss(455)"
				( attribute "PN" "CJ12"
					( Origin gPackager )
				)
				( objectStatus "U5D1.CJ12" )
			)
			( pin "@baseboard_fab2_lib.baseboard_fab2(sch_1):page41_i283:vss(456)"
				( attribute "PN" "CJ10"
					( Origin gPackager )
				)
				( objectStatus "U5D1.CJ10" )
			)
			( pin "@baseboard_fab2_lib.baseboard_fab2(sch_1):page41_i283:vss(457)"
				( attribute "PN" "CJ8"
					( Origin gPackager )
				)
				( objectStatus "U5D1.CJ8" )
			)
			( pin "@baseboard_fab2_lib.baseboard_fab2(sch_1):page41_i283:vss(458)"
				( attribute "PN" "CJ6"
					( Origin gPackager )
				)
				( objectStatus "U5D1.CJ6" )
			)
			( pin "@baseboard_fab2_lib.baseboard_fab2(sch_1):page41_i283:vss(459)"
				( attribute "PN" "CJ2"
					( Origin gPackager )
				)
				( objectStatus "U5D1.CJ2" )
			)
			( pin "@baseboard_fab2_lib.baseboard_fab2(sch_1):page41_i283:vss(460)"
				( attribute "PN" "CH83"
					( Origin gPackager )
				)
				( objectStatus "U5D1.CH83" )
			)
			( pin "@baseboard_fab2_lib.baseboard_fab2(sch_1):page41_i283:vss(461)"
				( attribute "PN" "CH81"
					( Origin gPackager )
				)
				( objectStatus "U5D1.CH81" )
			)
			( pin "@baseboard_fab2_lib.baseboard_fab2(sch_1):page41_i283:vss(462)"
				( attribute "PN" "CH79"
					( Origin gPackager )
				)
				( objectStatus "U5D1.CH79" )
			)
			( pin "@baseboard_fab2_lib.baseboard_fab2(sch_1):page41_i283:vss(463)"
				( attribute "PN" "CH73"
					( Origin gPackager )
				)
				( objectStatus "U5D1.CH73" )
			)
			( pin "@baseboard_fab2_lib.baseboard_fab2(sch_1):page41_i283:vss(464)"
				( attribute "PN" "CH67"
					( Origin gPackager )
				)
				( objectStatus "U5D1.CH67" )
			)
			( pin "@baseboard_fab2_lib.baseboard_fab2(sch_1):page41_i283:vss(465)"
				( attribute "PN" "CH63"
					( Origin gPackager )
				)
				( objectStatus "U5D1.CH63" )
			)
			( pin "@baseboard_fab2_lib.baseboard_fab2(sch_1):page41_i283:vss(466)"
				( attribute "PN" "CH19"
					( Origin gPackager )
				)
				( objectStatus "U5D1.CH19" )
			)
			( pin "@baseboard_fab2_lib.baseboard_fab2(sch_1):page41_i283:vss(467)"
				( attribute "PN" "CH15"
					( Origin gPackager )
				)
				( objectStatus "U5D1.CH15" )
			)
			( pin "@baseboard_fab2_lib.baseboard_fab2(sch_1):page41_i283:vss(468)"
				( attribute "PN" "CH3"
					( Origin gPackager )
				)
				( objectStatus "U5D1.CH3" )
			)
			( pin "@baseboard_fab2_lib.baseboard_fab2(sch_1):page41_i283:vss(469)"
				( attribute "PN" "CH1"
					( Origin gPackager )
				)
				( objectStatus "U5D1.CH1" )
			)
			( pin "@baseboard_fab2_lib.baseboard_fab2(sch_1):page41_i283:vss(470)"
				( attribute "PN" "CG80"
					( Origin gPackager )
				)
				( objectStatus "U5D1.CG80" )
			)
			( pin "@baseboard_fab2_lib.baseboard_fab2(sch_1):page41_i283:vss(471)"
				( attribute "PN" "CG72"
					( Origin gPackager )
				)
				( objectStatus "U5D1.CG72" )
			)
			( pin "@baseboard_fab2_lib.baseboard_fab2(sch_1):page41_i283:vss(472)"
				( attribute "PN" "CG68"
					( Origin gPackager )
				)
				( objectStatus "U5D1.CG68" )
			)
			( pin "@baseboard_fab2_lib.baseboard_fab2(sch_1):page41_i283:vss(473)"
				( attribute "PN" "CG62"
					( Origin gPackager )
				)
				( objectStatus "U5D1.CG62" )
			)
			( pin "@baseboard_fab2_lib.baseboard_fab2(sch_1):page41_i283:vss(474)"
				( attribute "PN" "CG22"
					( Origin gPackager )
				)
				( objectStatus "U5D1.CG22" )
			)
			( pin "@baseboard_fab2_lib.baseboard_fab2(sch_1):page41_i283:vss(475)"
				( attribute "PN" "CG18"
					( Origin gPackager )
				)
				( objectStatus "U5D1.CG18" )
			)
			( pin "@baseboard_fab2_lib.baseboard_fab2(sch_1):page41_i283:vss(476)"
				( attribute "PN" "P51"
					( Origin gPackager )
				)
				( objectStatus "U5D1.P51" )
			)
			( pin "@baseboard_fab2_lib.baseboard_fab2(sch_1):page41_i283:vss(477)"
				( attribute "PN" "CF83"
					( Origin gPackager )
				)
				( objectStatus "U5D1.CF83" )
			)
			( pin "@baseboard_fab2_lib.baseboard_fab2(sch_1):page41_i283:vss(478)"
				( attribute "PN" "CF77"
					( Origin gPackager )
				)
				( objectStatus "U5D1.CF77" )
			)
			( pin "@baseboard_fab2_lib.baseboard_fab2(sch_1):page41_i283:vss(479)"
				( attribute "PN" "CF71"
					( Origin gPackager )
				)
				( objectStatus "U5D1.CF71" )
			)
			( pin "@baseboard_fab2_lib.baseboard_fab2(sch_1):page41_i283:vss(480)"
				( attribute "PN" "CF69"
					( Origin gPackager )
				)
				( objectStatus "U5D1.CF69" )
			)
			( pin "@baseboard_fab2_lib.baseboard_fab2(sch_1):page41_i283:vss(481)"
				( attribute "PN" "CF63"
					( Origin gPackager )
				)
				( objectStatus "U5D1.CF63" )
			)
			( pin "@baseboard_fab2_lib.baseboard_fab2(sch_1):page41_i283:vss(482)"
				( attribute "PN" "CF9"
					( Origin gPackager )
				)
				( objectStatus "U5D1.CF9" )
			)
			( pin "@baseboard_fab2_lib.baseboard_fab2(sch_1):page41_i283:vss(483)"
				( attribute "PN" "P53"
					( Origin gPackager )
				)
				( objectStatus "U5D1.P53" )
			)
			( pin "@baseboard_fab2_lib.baseboard_fab2(sch_1):page41_i283:vss(484)"
				( attribute "PN" "CE82"
					( Origin gPackager )
				)
				( objectStatus "U5D1.CE82" )
			)
			( pin "@baseboard_fab2_lib.baseboard_fab2(sch_1):page41_i283:vss(485)"
				( attribute "PN" "CE70"
					( Origin gPackager )
				)
				( objectStatus "U5D1.CE70" )
			)
			( pin "@baseboard_fab2_lib.baseboard_fab2(sch_1):page41_i283:vss(486)"
				( attribute "PN" "CE62"
					( Origin gPackager )
				)
				( objectStatus "U5D1.CE62" )
			)
			( pin "@baseboard_fab2_lib.baseboard_fab2(sch_1):page41_i283:vss(487)"
				( attribute "PN" "CE26"
					( Origin gPackager )
				)
				( objectStatus "U5D1.CE26" )
			)
			( pin "@baseboard_fab2_lib.baseboard_fab2(sch_1):page41_i283:vss(488)"
				( attribute "PN" "CE20"
					( Origin gPackager )
				)
				( objectStatus "U5D1.CE20" )
			)
			( pin "@baseboard_fab2_lib.baseboard_fab2(sch_1):page41_i283:vss(489)"
				( attribute "PN" "CE14"
					( Origin gPackager )
				)
				( objectStatus "U5D1.CE14" )
			)
			( pin "@baseboard_fab2_lib.baseboard_fab2(sch_1):page41_i283:vss(490)"
				( attribute "PN" "CE10"
					( Origin gPackager )
				)
				( objectStatus "U5D1.CE10" )
			)
			( pin "@baseboard_fab2_lib.baseboard_fab2(sch_1):page41_i283:vss(491)"
				( attribute "PN" "CD81"
					( Origin gPackager )
				)
				( objectStatus "U5D1.CD81" )
			)
			( pin "@baseboard_fab2_lib.baseboard_fab2(sch_1):page41_i283:vss(492)"
				( attribute "PN" "CD79"
					( Origin gPackager )
				)
				( objectStatus "U5D1.CD79" )
			)
			( pin "@baseboard_fab2_lib.baseboard_fab2(sch_1):page41_i283:vss(493)"
				( attribute "PN" "CD77"
					( Origin gPackager )
				)
				( objectStatus "U5D1.CD77" )
			)
			( pin "@baseboard_fab2_lib.baseboard_fab2(sch_1):page41_i283:vss(494)"
				( attribute "PN" "CD75"
					( Origin gPackager )
				)
				( objectStatus "U5D1.CD75" )
			)
			( pin "@baseboard_fab2_lib.baseboard_fab2(sch_1):page41_i283:vss(495)"
				( attribute "PN" "CD73"
					( Origin gPackager )
				)
				( objectStatus "U5D1.CD73" )
			)
			( pin "@baseboard_fab2_lib.baseboard_fab2(sch_1):page41_i283:vss(496)"
				( attribute "PN" "CD63"
					( Origin gPackager )
				)
				( objectStatus "U5D1.CD63" )
			)
			( pin "@baseboard_fab2_lib.baseboard_fab2(sch_1):page41_i283:vss(497)"
				( attribute "PN" "CD13"
					( Origin gPackager )
				)
				( objectStatus "U5D1.CD13" )
			)
			( pin "@baseboard_fab2_lib.baseboard_fab2(sch_1):page41_i283:vss(498)"
				( attribute "PN" "CD5"
					( Origin gPackager )
				)
				( objectStatus "U5D1.CD5" )
			)
			( pin "@baseboard_fab2_lib.baseboard_fab2(sch_1):page41_i283:vss(499)"
				( attribute "PN" "CC82"
					( Origin gPackager )
				)
				( objectStatus "U5D1.CC82" )
			)
			( pin "@baseboard_fab2_lib.baseboard_fab2(sch_1):page41_i283:vss(500)"
				( attribute "PN" "CC80"
					( Origin gPackager )
				)
				( objectStatus "U5D1.CC80" )
			)
			( pin "@baseboard_fab2_lib.baseboard_fab2(sch_1):page41_i283:vss(501)"
				( attribute "PN" "CC78"
					( Origin gPackager )
				)
				( objectStatus "U5D1.CC78" )
			)
			( pin "@baseboard_fab2_lib.baseboard_fab2(sch_1):page41_i283:vss(502)"
				( attribute "PN" "CC76"
					( Origin gPackager )
				)
				( objectStatus "U5D1.CC76" )
			)
			( pin "@baseboard_fab2_lib.baseboard_fab2(sch_1):page41_i283:vss(503)"
				( attribute "PN" "CC74"
					( Origin gPackager )
				)
				( objectStatus "U5D1.CC74" )
			)
			( pin "@baseboard_fab2_lib.baseboard_fab2(sch_1):page41_i283:vss(504)"
				( attribute "PN" "CC72"
					( Origin gPackager )
				)
				( objectStatus "U5D1.CC72" )
			)
			( pin "@baseboard_fab2_lib.baseboard_fab2(sch_1):page41_i283:vss(505)"
				( attribute "PN" "CC64"
					( Origin gPackager )
				)
				( objectStatus "U5D1.CC64" )
			)
			( pin "@baseboard_fab2_lib.baseboard_fab2(sch_1):page41_i283:vss(506)"
				( attribute "PN" "CC24"
					( Origin gPackager )
				)
				( objectStatus "U5D1.CC24" )
			)
			( pin "@baseboard_fab2_lib.baseboard_fab2(sch_1):page41_i283:vss(507)"
				( attribute "PN" "CC18"
					( Origin gPackager )
				)
				( objectStatus "U5D1.CC18" )
			)
			( pin "@baseboard_fab2_lib.baseboard_fab2(sch_1):page41_i283:vss(508)"
				( attribute "PN" "CC16"
					( Origin gPackager )
				)
				( objectStatus "U5D1.CC16" )
			)
			( pin "@baseboard_fab2_lib.baseboard_fab2(sch_1):page41_i283:vss(509)"
				( attribute "PN" "CC4"
					( Origin gPackager )
				)
				( objectStatus "U5D1.CC4" )
			)
			( pin "@baseboard_fab2_lib.baseboard_fab2(sch_1):page41_i283:vss(510)"
				( attribute "PN" "CB71"
					( Origin gPackager )
				)
				( objectStatus "U5D1.CB71" )
			)
			( pin "@baseboard_fab2_lib.baseboard_fab2(sch_1):page41_i283:vss(511)"
				( attribute "PN" "CB63"
					( Origin gPackager )
				)
				( objectStatus "U5D1.CB63" )
			)
			( pin "@baseboard_fab2_lib.baseboard_fab2(sch_1):page41_i283:vss(512)"
				( attribute "PN" "CB27"
					( Origin gPackager )
				)
				( objectStatus "U5D1.CB27" )
			)
			( pin "@baseboard_fab2_lib.baseboard_fab2(sch_1):page41_i283:vss(513)"
				( attribute "PN" "CB9"
					( Origin gPackager )
				)
				( objectStatus "U5D1.CB9" )
			)
			( pin "@baseboard_fab2_lib.baseboard_fab2(sch_1):page41_i283:vss(514)"
				( attribute "PN" "CB7"
					( Origin gPackager )
				)
				( objectStatus "U5D1.CB7" )
			)
			( pin "@baseboard_fab2_lib.baseboard_fab2(sch_1):page41_i283:vss(515)"
				( attribute "PN" "CA70"
					( Origin gPackager )
				)
				( objectStatus "U5D1.CA70" )
			)
			( pin "@baseboard_fab2_lib.baseboard_fab2(sch_1):page41_i283:vss(516)"
				( attribute "PN" "CA68"
					( Origin gPackager )
				)
				( objectStatus "U5D1.CA68" )
			)
			( pin "@baseboard_fab2_lib.baseboard_fab2(sch_1):page41_i283:vss(517)"
				( attribute "PN" "CA66"
					( Origin gPackager )
				)
				( objectStatus "U5D1.CA66" )
			)
			( pin "@baseboard_fab2_lib.baseboard_fab2(sch_1):page41_i283:vss(518)"
				( attribute "PN" "CA64"
					( Origin gPackager )
				)
				( objectStatus "U5D1.CA64" )
			)
			( pin "@baseboard_fab2_lib.baseboard_fab2(sch_1):page41_i283:vss(519)"
				( attribute "PN" "CA26"
					( Origin gPackager )
				)
				( objectStatus "U5D1.CA26" )
			)
			( pin "@baseboard_fab2_lib.baseboard_fab2(sch_1):page41_i283:vss(520)"
				( attribute "PN" "CA18"
					( Origin gPackager )
				)
				( objectStatus "U5D1.CA18" )
			)
			( pin "@baseboard_fab2_lib.baseboard_fab2(sch_1):page41_i283:vss(521)"
				( attribute "PN" "CA14"
					( Origin gPackager )
				)
				( objectStatus "U5D1.CA14" )
			)
			( pin "@baseboard_fab2_lib.baseboard_fab2(sch_1):page41_i283:vss(522)"
				( attribute "PN" "CA10"
					( Origin gPackager )
				)
				( objectStatus "U5D1.CA10" )
			)
			( pin "@baseboard_fab2_lib.baseboard_fab2(sch_1):page41_i283:vss(523)"
				( attribute "PN" "CA8"
					( Origin gPackager )
				)
				( objectStatus "U5D1.CA8" )
			)
			( pin "@baseboard_fab2_lib.baseboard_fab2(sch_1):page41_i283:vss(524)"
				( attribute "PN" "CA6"
					( Origin gPackager )
				)
				( objectStatus "U5D1.CA6" )
			)
			( pin "@baseboard_fab2_lib.baseboard_fab2(sch_1):page41_i283:vss(525)"
				( attribute "PN" "CA2"
					( Origin gPackager )
				)
				( objectStatus "U5D1.CA2" )
			)
			( pin "@baseboard_fab2_lib.baseboard_fab2(sch_1):page41_i283:vss(526)"
				( attribute "PN" "BY71"
					( Origin gPackager )
				)
				( objectStatus "U5D1.BY71" )
			)
			( pin "@baseboard_fab2_lib.baseboard_fab2(sch_1):page41_i283:vss(527)"
				( attribute "PN" "BY69"
					( Origin gPackager )
				)
				( objectStatus "U5D1.BY69" )
			)
			( pin "@baseboard_fab2_lib.baseboard_fab2(sch_1):page41_i283:vss(528)"
				( attribute "PN" "BY67"
					( Origin gPackager )
				)
				( objectStatus "U5D1.BY67" )
			)
			( pin "@baseboard_fab2_lib.baseboard_fab2(sch_1):page41_i283:vss(529)"
				( attribute "PN" "BY65"
					( Origin gPackager )
				)
				( objectStatus "U5D1.BY65" )
			)
			( pin "@baseboard_fab2_lib.baseboard_fab2(sch_1):page41_i283:vss(530)"
				( attribute "PN" "BY63"
					( Origin gPackager )
				)
				( objectStatus "U5D1.BY63" )
			)
			( pin "@baseboard_fab2_lib.baseboard_fab2(sch_1):page41_i283:vss(531)"
				( attribute "PN" "BY23"
					( Origin gPackager )
				)
				( objectStatus "U5D1.BY23" )
			)
			( pin "@baseboard_fab2_lib.baseboard_fab2(sch_1):page41_i283:vss(532)"
				( attribute "PN" "BY13"
					( Origin gPackager )
				)
				( objectStatus "U5D1.BY13" )
			)
			( pin "@baseboard_fab2_lib.baseboard_fab2(sch_1):page41_i283:vss(533)"
				( attribute "PN" "BY11"
					( Origin gPackager )
				)
				( objectStatus "U5D1.BY11" )
			)
			( pin "@baseboard_fab2_lib.baseboard_fab2(sch_1):page41_i283:vss(534)"
				( attribute "PN" "BW82"
					( Origin gPackager )
				)
				( objectStatus "U5D1.BW82" )
			)
			( pin "@baseboard_fab2_lib.baseboard_fab2(sch_1):page41_i283:vss(535)"
				( attribute "PN" "BW80"
					( Origin gPackager )
				)
				( objectStatus "U5D1.BW80" )
			)
			( pin "@baseboard_fab2_lib.baseboard_fab2(sch_1):page41_i283:vss(536)"
				( attribute "PN" "BW78"
					( Origin gPackager )
				)
				( objectStatus "U5D1.BW78" )
			)
			( pin "@baseboard_fab2_lib.baseboard_fab2(sch_1):page41_i283:vss(537)"
				( attribute "PN" "BW76"
					( Origin gPackager )
				)
				( objectStatus "U5D1.BW76" )
			)
			( pin "@baseboard_fab2_lib.baseboard_fab2(sch_1):page41_i283:vss(538)"
				( attribute "PN" "BW74"
					( Origin gPackager )
				)
				( objectStatus "U5D1.BW74" )
			)
			( pin "@baseboard_fab2_lib.baseboard_fab2(sch_1):page41_i283:vss(539)"
				( attribute "PN" "BW72"
					( Origin gPackager )
				)
				( objectStatus "U5D1.BW72" )
			)
			( pin "@baseboard_fab2_lib.baseboard_fab2(sch_1):page41_i283:vss(540)"
				( attribute "PN" "BW26"
					( Origin gPackager )
				)
				( objectStatus "U5D1.BW26" )
			)
			( pin "@baseboard_fab2_lib.baseboard_fab2(sch_1):page41_i283:vss(541)"
				( attribute "PN" "BW18"
					( Origin gPackager )
				)
				( objectStatus "U5D1.BW18" )
			)
			( pin "@baseboard_fab2_lib.baseboard_fab2(sch_1):page41_i283:vss(542)"
				( attribute "PN" "BW16"
					( Origin gPackager )
				)
				( objectStatus "U5D1.BW16" )
			)
			( pin "@baseboard_fab2_lib.baseboard_fab2(sch_1):page41_i283:vss(543)"
				( attribute "PN" "BW14"
					( Origin gPackager )
				)
				( objectStatus "U5D1.BW14" )
			)
			( pin "@baseboard_fab2_lib.baseboard_fab2(sch_1):page41_i283:vss(544)"
				( attribute "PN" "BW12"
					( Origin gPackager )
				)
				( objectStatus "U5D1.BW12" )
			)
			( pin "@baseboard_fab2_lib.baseboard_fab2(sch_1):page41_i283:vss(545)"
				( attribute "PN" "P55"
					( Origin gPackager )
				)
				( objectStatus "U5D1.P55" )
			)
			( pin "@baseboard_fab2_lib.baseboard_fab2(sch_1):page41_i283:vss(546)"
				( attribute "PN" "BW6"
					( Origin gPackager )
				)
				( objectStatus "U5D1.BW6" )
			)
			( pin "@baseboard_fab2_lib.baseboard_fab2(sch_1):page41_i283:vss(547)"
				( attribute "PN" "BV25"
					( Origin gPackager )
				)
				( objectStatus "U5D1.BV25" )
			)
			( pin "@baseboard_fab2_lib.baseboard_fab2(sch_1):page41_i283:vss(548)"
				( attribute "PN" "BV17"
					( Origin gPackager )
				)
				( objectStatus "U5D1.BV17" )
			)
			( pin "@baseboard_fab2_lib.baseboard_fab2(sch_1):page41_i283:vss(549)"
				( attribute "PN" "BU10"
					( Origin gPackager )
				)
				( objectStatus "U5D1.BU10" )
			)
			( pin "@baseboard_fab2_lib.baseboard_fab2(sch_1):page41_i283:vss(550)"
				( attribute "PN" "BV5"
					( Origin gPackager )
				)
				( objectStatus "U5D1.BV5" )
			)
			( pin "@baseboard_fab2_lib.baseboard_fab2(sch_1):page41_i283:vss(551)"
				( attribute "PN" "BU8"
					( Origin gPackager )
				)
				( objectStatus "U5D1.BU8" )
			)
			( pin "@baseboard_fab2_lib.baseboard_fab2(sch_1):page41_i283:vss(552)"
				( attribute "PN" "BT25"
					( Origin gPackager )
				)
				( objectStatus "U5D1.BT25" )
			)
			( pin "@baseboard_fab2_lib.baseboard_fab2(sch_1):page41_i283:vss(553)"
				( attribute "PN" "BT23"
					( Origin gPackager )
				)
				( objectStatus "U5D1.BT23" )
			)
			( pin "@baseboard_fab2_lib.baseboard_fab2(sch_1):page41_i283:vss(554)"
				( attribute "PN" "BT21"
					( Origin gPackager )
				)
				( objectStatus "U5D1.BT21" )
			)
			( pin "@baseboard_fab2_lib.baseboard_fab2(sch_1):page41_i283:vss(555)"
				( attribute "PN" "BT5"
					( Origin gPackager )
				)
				( objectStatus "U5D1.BT5" )
			)
			( pin "@baseboard_fab2_lib.baseboard_fab2(sch_1):page41_i283:vss(556)"
				( attribute "PN" "BT3"
					( Origin gPackager )
				)
				( objectStatus "U5D1.BT3" )
			)
			( pin "@baseboard_fab2_lib.baseboard_fab2(sch_1):page41_i283:vss(557)"
				( attribute "PN" "BR82"
					( Origin gPackager )
				)
				( objectStatus "U5D1.BR82" )
			)
			( pin "@baseboard_fab2_lib.baseboard_fab2(sch_1):page41_i283:vss(558)"
				( attribute "PN" "BR80"
					( Origin gPackager )
				)
				( objectStatus "U5D1.BR80" )
			)
			( pin "@baseboard_fab2_lib.baseboard_fab2(sch_1):page41_i283:vss(559)"
				( attribute "PN" "BR78"
					( Origin gPackager )
				)
				( objectStatus "U5D1.BR78" )
			)
			( pin "@baseboard_fab2_lib.baseboard_fab2(sch_1):page41_i283:vss(560)"
				( attribute "PN" "BR76"
					( Origin gPackager )
				)
				( objectStatus "U5D1.BR76" )
			)
			( pin "@baseboard_fab2_lib.baseboard_fab2(sch_1):page41_i283:vss(561)"
				( attribute "PN" "BR74"
					( Origin gPackager )
				)
				( objectStatus "U5D1.BR74" )
			)
			( pin "@baseboard_fab2_lib.baseboard_fab2(sch_1):page41_i283:vss(562)"
				( attribute "PN" "BR72"
					( Origin gPackager )
				)
				( objectStatus "U5D1.BR72" )
			)
			( pin "@baseboard_fab2_lib.baseboard_fab2(sch_1):page41_i283:vss(563)"
				( attribute "PN" "BR70"
					( Origin gPackager )
				)
				( objectStatus "U5D1.BR70" )
			)
			( pin "@baseboard_fab2_lib.baseboard_fab2(sch_1):page41_i283:vss(564)"
				( attribute "PN" "BR68"
					( Origin gPackager )
				)
				( objectStatus "U5D1.BR68" )
			)
			( pin "@baseboard_fab2_lib.baseboard_fab2(sch_1):page41_i283:vss(565)"
				( attribute "PN" "BR66"
					( Origin gPackager )
				)
				( objectStatus "U5D1.BR66" )
			)
			( pin "@baseboard_fab2_lib.baseboard_fab2(sch_1):page41_i283:vss(566)"
				( attribute "PN" "BR64"
					( Origin gPackager )
				)
				( objectStatus "U5D1.BR64" )
			)
			( pin "@baseboard_fab2_lib.baseboard_fab2(sch_1):page41_i283:vss(567)"
				( attribute "PN" "P57"
					( Origin gPackager )
				)
				( objectStatus "U5D1.P57" )
			)
			( pin "@baseboard_fab2_lib.baseboard_fab2(sch_1):page41_i283:vss(568)"
				( attribute "PN" "BR16"
					( Origin gPackager )
				)
				( objectStatus "U5D1.BR16" )
			)
			( pin "@baseboard_fab2_lib.baseboard_fab2(sch_1):page41_i283:vss(569)"
				( attribute "PN" "BR10"
					( Origin gPackager )
				)
				( objectStatus "U5D1.BR10" )
			)
			( pin "@baseboard_fab2_lib.baseboard_fab2(sch_1):page41_i283:vss(570)"
				( attribute "PN" "BR6"
					( Origin gPackager )
				)
				( objectStatus "U5D1.BR6" )
			)
			( pin "@baseboard_fab2_lib.baseboard_fab2(sch_1):page41_i283:vss(571)"
				( attribute "PN" "BP27"
					( Origin gPackager )
				)
				( objectStatus "U5D1.BP27" )
			)
			( pin "@baseboard_fab2_lib.baseboard_fab2(sch_1):page41_i283:vss(572)"
				( attribute "PN" "BP3"
					( Origin gPackager )
				)
				( objectStatus "U5D1.BP3" )
			)
			( pin "@baseboard_fab2_lib.baseboard_fab2(sch_1):page41_i283:vss(573)"
				( attribute "PN" "BN26"
					( Origin gPackager )
				)
				( objectStatus "U5D1.BN26" )
			)
			( pin "@baseboard_fab2_lib.baseboard_fab2(sch_1):page41_i283:vss(574)"
				( attribute "PN" "BN20"
					( Origin gPackager )
				)
				( objectStatus "U5D1.BN20" )
			)
			( pin "@baseboard_fab2_lib.baseboard_fab2(sch_1):page41_i283:vss(575)"
				( attribute "PN" "BN10"
					( Origin gPackager )
				)
				( objectStatus "U5D1.BN10" )
			)
			( pin "@baseboard_fab2_lib.baseboard_fab2(sch_1):page41_i283:vss(576)"
				( attribute "PN" "BN6"
					( Origin gPackager )
				)
				( objectStatus "U5D1.BN6" )
			)
			( pin "@baseboard_fab2_lib.baseboard_fab2(sch_1):page41_i283:vss(577)"
				( attribute "PN" "BM25"
					( Origin gPackager )
				)
				( objectStatus "U5D1.BM25" )
			)
			( pin "@baseboard_fab2_lib.baseboard_fab2(sch_1):page41_i283:vss(578)"
				( attribute "PN" "P59"
					( Origin gPackager )
				)
				( objectStatus "U5D1.P59" )
			)
			( pin "@baseboard_fab2_lib.baseboard_fab2(sch_1):page41_i283:vss(579)"
				( attribute "PN" "BM15"
					( Origin gPackager )
				)
				( objectStatus "U5D1.BM15" )
			)
			( pin "@baseboard_fab2_lib.baseboard_fab2(sch_1):page41_i283:vss(580)"
				( attribute "PN" "BM13"
					( Origin gPackager )
				)
				( objectStatus "U5D1.BM13" )
			)
			( pin "@baseboard_fab2_lib.baseboard_fab2(sch_1):page41_i283:vss(581)"
				( attribute "PN" "BM9"
					( Origin gPackager )
				)
				( objectStatus "U5D1.BM9" )
			)
			( pin "@baseboard_fab2_lib.baseboard_fab2(sch_1):page41_i283:vss(582)"
				( attribute "PN" "BL82"
					( Origin gPackager )
				)
				( objectStatus "U5D1.BL82" )
			)
			( pin "@baseboard_fab2_lib.baseboard_fab2(sch_1):page41_i283:vss(583)"
				( attribute "PN" "BL80"
					( Origin gPackager )
				)
				( objectStatus "U5D1.BL80" )
			)
			( pin "@baseboard_fab2_lib.baseboard_fab2(sch_1):page41_i283:vss(584)"
				( attribute "PN" "BL78"
					( Origin gPackager )
				)
				( objectStatus "U5D1.BL78" )
			)
			( pin "@baseboard_fab2_lib.baseboard_fab2(sch_1):page41_i283:vss(585)"
				( attribute "PN" "BL76"
					( Origin gPackager )
				)
				( objectStatus "U5D1.BL76" )
			)
			( pin "@baseboard_fab2_lib.baseboard_fab2(sch_1):page41_i283:vss(586)"
				( attribute "PN" "BL74"
					( Origin gPackager )
				)
				( objectStatus "U5D1.BL74" )
			)
			( pin "@baseboard_fab2_lib.baseboard_fab2(sch_1):page41_i283:vss(587)"
				( attribute "PN" "BL72"
					( Origin gPackager )
				)
				( objectStatus "U5D1.BL72" )
			)
			( pin "@baseboard_fab2_lib.baseboard_fab2(sch_1):page41_i283:vss(588)"
				( attribute "PN" "BL70"
					( Origin gPackager )
				)
				( objectStatus "U5D1.BL70" )
			)
			( pin "@baseboard_fab2_lib.baseboard_fab2(sch_1):page41_i283:vss(589)"
				( attribute "PN" "BL68"
					( Origin gPackager )
				)
				( objectStatus "U5D1.BL68" )
			)
			( pin "@baseboard_fab2_lib.baseboard_fab2(sch_1):page41_i283:vss(590)"
				( attribute "PN" "BL66"
					( Origin gPackager )
				)
				( objectStatus "U5D1.BL66" )
			)
			( pin "@baseboard_fab2_lib.baseboard_fab2(sch_1):page41_i283:vss(591)"
				( attribute "PN" "BL64"
					( Origin gPackager )
				)
				( objectStatus "U5D1.BL64" )
			)
			( pin "@baseboard_fab2_lib.baseboard_fab2(sch_1):page41_i283:vss(592)"
				( attribute "PN" "BL24"
					( Origin gPackager )
				)
				( objectStatus "U5D1.BL24" )
			)
			( pin "@baseboard_fab2_lib.baseboard_fab2(sch_1):page41_i283:vss(593)"
				( attribute "PN" "BL22"
					( Origin gPackager )
				)
				( objectStatus "U5D1.BL22" )
			)
			( pin "@baseboard_fab2_lib.baseboard_fab2(sch_1):page41_i283:vss(594)"
				( attribute "PN" "P61"
					( Origin gPackager )
				)
				( objectStatus "U5D1.P61" )
			)
			( pin "@baseboard_fab2_lib.baseboard_fab2(sch_1):page41_i283:vss(595)"
				( attribute "PN" "BL12"
					( Origin gPackager )
				)
				( objectStatus "U5D1.BL12" )
			)
			( pin "@baseboard_fab2_lib.baseboard_fab2(sch_1):page41_i283:vss(596)"
				( attribute "PN" "BL10"
					( Origin gPackager )
				)
				( objectStatus "U5D1.BL10" )
			)
			( pin "@baseboard_fab2_lib.baseboard_fab2(sch_1):page41_i283:vss(597)"
				( attribute "PN" "BL6"
					( Origin gPackager )
				)
				( objectStatus "U5D1.BL6" )
			)
			( pin "@baseboard_fab2_lib.baseboard_fab2(sch_1):page41_i283:vss(598)"
				( attribute "PN" "BK19"
					( Origin gPackager )
				)
				( objectStatus "U5D1.BK19" )
			)
			( pin "@baseboard_fab2_lib.baseboard_fab2(sch_1):page41_i283:vss(599)"
				( attribute "PN" "BK11"
					( Origin gPackager )
				)
				( objectStatus "U5D1.BK11" )
			)
			( pin "@baseboard_fab2_lib.baseboard_fab2(sch_1):page41_i283:vss(600)"
				( attribute "PN" "BK7"
					( Origin gPackager )
				)
				( objectStatus "U5D1.BK7" )
			)
			( pin "@baseboard_fab2_lib.baseboard_fab2(sch_1):page41_i283:vss(601)"
				( attribute "PN" "BK3"
					( Origin gPackager )
				)
				( objectStatus "U5D1.BK3" )
			)
			( pin "@baseboard_fab2_lib.baseboard_fab2(sch_1):page41_i283:vss(602)"
				( attribute "PN" "BJ6"
					( Origin gPackager )
				)
				( objectStatus "U5D1.BJ6" )
			)
			( pin "@baseboard_fab2_lib.baseboard_fab2(sch_1):page41_i283:vss(603)"
				( attribute "PN" "BJ4"
					( Origin gPackager )
				)
				( objectStatus "U5D1.BJ4" )
			)
			( pin "@baseboard_fab2_lib.baseboard_fab2(sch_1):page41_i283:vss(604)"
				( attribute "PN" "BH21"
					( Origin gPackager )
				)
				( objectStatus "U5D1.BH21" )
			)
			( pin "@baseboard_fab2_lib.baseboard_fab2(sch_1):page41_i283:vss(605)"
				( attribute "PN" "BH15"
					( Origin gPackager )
				)
				( objectStatus "U5D1.BH15" )
			)
			( pin "@baseboard_fab2_lib.baseboard_fab2(sch_1):page41_i283:vss(606)"
				( attribute "PN" "BH11"
					( Origin gPackager )
				)
				( objectStatus "U5D1.BH11" )
			)
			( pin "@baseboard_fab2_lib.baseboard_fab2(sch_1):page41_i283:vss(607)"
				( attribute "PN" "BH9"
					( Origin gPackager )
				)
				( objectStatus "U5D1.BH9" )
			)
			( pin "@baseboard_fab2_lib.baseboard_fab2(sch_1):page41_i283:vss(608)"
				( attribute "PN" "BH7"
					( Origin gPackager )
				)
				( objectStatus "U5D1.BH7" )
			)
			( pin "@baseboard_fab2_lib.baseboard_fab2(sch_1):page41_i283:vss(609)"
				( attribute "PN" "BG82"
					( Origin gPackager )
				)
				( objectStatus "U5D1.BG82" )
			)
			( pin "@baseboard_fab2_lib.baseboard_fab2(sch_1):page41_i283:vss(610)"
				( attribute "PN" "BG80"
					( Origin gPackager )
				)
				( objectStatus "U5D1.BG80" )
			)
			( pin "@baseboard_fab2_lib.baseboard_fab2(sch_1):page41_i283:vss(611)"
				( attribute "PN" "BG78"
					( Origin gPackager )
				)
				( objectStatus "U5D1.BG78" )
			)
			( pin "@baseboard_fab2_lib.baseboard_fab2(sch_1):page41_i283:vss(612)"
				( attribute "PN" "BG76"
					( Origin gPackager )
				)
				( objectStatus "U5D1.BG76" )
			)
			( pin "@baseboard_fab2_lib.baseboard_fab2(sch_1):page41_i283:vss(613)"
				( attribute "PN" "BG74"
					( Origin gPackager )
				)
				( objectStatus "U5D1.BG74" )
			)
			( pin "@baseboard_fab2_lib.baseboard_fab2(sch_1):page41_i284:vss(294)"
				( attribute "PN" "DA46"
					( Origin gPackager )
				)
				( objectStatus "U5D1.DA46" )
			)
			( pin "@baseboard_fab2_lib.baseboard_fab2(sch_1):page41_i284:vss(295)"
				( attribute "PN" "DA44"
					( Origin gPackager )
				)
				( objectStatus "U5D1.DA44" )
			)
			( pin "@baseboard_fab2_lib.baseboard_fab2(sch_1):page41_i284:vss(296)"
				( attribute "PN" "DA38"
					( Origin gPackager )
				)
				( objectStatus "U5D1.DA38" )
			)
			( pin "@baseboard_fab2_lib.baseboard_fab2(sch_1):page41_i284:vss(297)"
				( attribute "PN" "DA36"
					( Origin gPackager )
				)
				( objectStatus "U5D1.DA36" )
			)
			( pin "@baseboard_fab2_lib.baseboard_fab2(sch_1):page41_i284:vss(298)"
				( attribute "PN" "DA34"
					( Origin gPackager )
				)
				( objectStatus "U5D1.DA34" )
			)
			( pin "@baseboard_fab2_lib.baseboard_fab2(sch_1):page41_i284:vss(299)"
				( attribute "PN" "DA32"
					( Origin gPackager )
				)
				( objectStatus "U5D1.DA32" )
			)
			( pin "@baseboard_fab2_lib.baseboard_fab2(sch_1):page41_i284:vss(300)"
				( attribute "PN" "DA30"
					( Origin gPackager )
				)
				( objectStatus "U5D1.DA30" )
			)
			( pin "@baseboard_fab2_lib.baseboard_fab2(sch_1):page41_i284:vss(301)"
				( attribute "PN" "DA28"
					( Origin gPackager )
				)
				( objectStatus "U5D1.DA28" )
			)
			( pin "@baseboard_fab2_lib.baseboard_fab2(sch_1):page41_i284:vss(302)"
				( attribute "PN" "DA26"
					( Origin gPackager )
				)
				( objectStatus "U5D1.DA26" )
			)
			( pin "@baseboard_fab2_lib.baseboard_fab2(sch_1):page41_i284:vss(303)"
				( attribute "PN" "DA18"
					( Origin gPackager )
				)
				( objectStatus "U5D1.DA18" )
			)
			( pin "@baseboard_fab2_lib.baseboard_fab2(sch_1):page41_i284:vss(304)"
				( attribute "PN" "H53"
					( Origin gPackager )
				)
				( objectStatus "U5D1.H53" )
			)
			( pin "@baseboard_fab2_lib.baseboard_fab2(sch_1):page41_i284:vss(305)"
				( attribute "PN" "DA6"
					( Origin gPackager )
				)
				( objectStatus "U5D1.DA6" )
			)
			( pin "@baseboard_fab2_lib.baseboard_fab2(sch_1):page41_i284:vss(306)"
				( attribute "PN" "CY85"
					( Origin gPackager )
				)
				( objectStatus "U5D1.CY85" )
			)
			( pin "@baseboard_fab2_lib.baseboard_fab2(sch_1):page41_i284:vss(307)"
				( attribute "PN" "CY83"
					( Origin gPackager )
				)
				( objectStatus "U5D1.CY83" )
			)
			( pin "@baseboard_fab2_lib.baseboard_fab2(sch_1):page41_i284:vss(308)"
				( attribute "PN" "CY77"
					( Origin gPackager )
				)
				( objectStatus "U5D1.CY77" )
			)
			( pin "@baseboard_fab2_lib.baseboard_fab2(sch_1):page41_i284:vss(309)"
				( attribute "PN" "CY75"
					( Origin gPackager )
				)
				( objectStatus "U5D1.CY75" )
			)
			( pin "@baseboard_fab2_lib.baseboard_fab2(sch_1):page41_i284:vss(310)"
				( attribute "PN" "CY69"
					( Origin gPackager )
				)
				( objectStatus "U5D1.CY69" )
			)
			( pin "@baseboard_fab2_lib.baseboard_fab2(sch_1):page41_i284:vss(311)"
				( attribute "PN" "CY65"
					( Origin gPackager )
				)
				( objectStatus "U5D1.CY65" )
			)
			( pin "@baseboard_fab2_lib.baseboard_fab2(sch_1):page41_i284:vss(312)"
				( attribute "PN" "CY61"
					( Origin gPackager )
				)
				( objectStatus "U5D1.CY61" )
			)
			( pin "@baseboard_fab2_lib.baseboard_fab2(sch_1):page41_i284:vss(313)"
				( attribute "PN" "CY59"
					( Origin gPackager )
				)
				( objectStatus "U5D1.CY59" )
			)
			( pin "@baseboard_fab2_lib.baseboard_fab2(sch_1):page41_i284:vss(314)"
				( attribute "PN" "CY51"
					( Origin gPackager )
				)
				( objectStatus "U5D1.CY51" )
			)
			( pin "@baseboard_fab2_lib.baseboard_fab2(sch_1):page41_i284:vss(315)"
				( attribute "PN" "CY45"
					( Origin gPackager )
				)
				( objectStatus "U5D1.CY45" )
			)
			( pin "@baseboard_fab2_lib.baseboard_fab2(sch_1):page41_i284:vss(316)"
				( attribute "PN" "CY41"
					( Origin gPackager )
				)
				( objectStatus "U5D1.CY41" )
			)
			( pin "@baseboard_fab2_lib.baseboard_fab2(sch_1):page41_i284:vss(317)"
				( attribute "PN" "CY21"
					( Origin gPackager )
				)
				( objectStatus "U5D1.CY21" )
			)
			( pin "@baseboard_fab2_lib.baseboard_fab2(sch_1):page41_i284:vss(318)"
				( attribute "PN" "CY15"
					( Origin gPackager )
				)
				( objectStatus "U5D1.CY15" )
			)
			( pin "@baseboard_fab2_lib.baseboard_fab2(sch_1):page41_i284:vss(319)"
				( attribute "PN" "CY13"
					( Origin gPackager )
				)
				( objectStatus "U5D1.CY13" )
			)
			( pin "@baseboard_fab2_lib.baseboard_fab2(sch_1):page41_i284:vss(320)"
				( attribute "PN" "CY9"
					( Origin gPackager )
				)
				( objectStatus "U5D1.CY9" )
			)
			( pin "@baseboard_fab2_lib.baseboard_fab2(sch_1):page41_i284:vss(321)"
				( attribute "PN" "CY1"
					( Origin gPackager )
				)
				( objectStatus "U5D1.CY1" )
			)
			( pin "@baseboard_fab2_lib.baseboard_fab2(sch_1):page41_i284:vss(322)"
				( attribute "PN" "CW82"
					( Origin gPackager )
				)
				( objectStatus "U5D1.CW82" )
			)
			( pin "@baseboard_fab2_lib.baseboard_fab2(sch_1):page41_i284:vss(323)"
				( attribute "PN" "CW78"
					( Origin gPackager )
				)
				( objectStatus "U5D1.CW78" )
			)
			( pin "@baseboard_fab2_lib.baseboard_fab2(sch_1):page41_i284:vss(324)"
				( attribute "PN" "CW74"
					( Origin gPackager )
				)
				( objectStatus "U5D1.CW74" )
			)
			( pin "@baseboard_fab2_lib.baseboard_fab2(sch_1):page41_i284:vss(325)"
				( attribute "PN" "CW68"
					( Origin gPackager )
				)
				( objectStatus "U5D1.CW68" )
			)
			( pin "@baseboard_fab2_lib.baseboard_fab2(sch_1):page41_i284:vss(326)"
				( attribute "PN" "CW66"
					( Origin gPackager )
				)
				( objectStatus "U5D1.CW66" )
			)
			( pin "@baseboard_fab2_lib.baseboard_fab2(sch_1):page41_i284:vss(327)"
				( attribute "PN" "CW64"
					( Origin gPackager )
				)
				( objectStatus "U5D1.CW64" )
			)
			( pin "@baseboard_fab2_lib.baseboard_fab2(sch_1):page41_i284:vss(328)"
				( attribute "PN" "CW54"
					( Origin gPackager )
				)
				( objectStatus "U5D1.CW54" )
			)
			( pin "@baseboard_fab2_lib.baseboard_fab2(sch_1):page41_i284:vss(329)"
				( attribute "PN" "CW52"
					( Origin gPackager )
				)
				( objectStatus "U5D1.CW52" )
			)
			( pin "@baseboard_fab2_lib.baseboard_fab2(sch_1):page41_i284:vss(330)"
				( attribute "PN" "CW42"
					( Origin gPackager )
				)
				( objectStatus "U5D1.CW42" )
			)
			( pin "@baseboard_fab2_lib.baseboard_fab2(sch_1):page41_i284:vss(331)"
				( attribute "PN" "CW40"
					( Origin gPackager )
				)
				( objectStatus "U5D1.CW40" )
			)
			( pin "@baseboard_fab2_lib.baseboard_fab2(sch_1):page41_i284:vss(332)"
				( attribute "PN" "CW38"
					( Origin gPackager )
				)
				( objectStatus "U5D1.CW38" )
			)
			( pin "@baseboard_fab2_lib.baseboard_fab2(sch_1):page41_i284:vss(333)"
				( attribute "PN" "CW32"
					( Origin gPackager )
				)
				( objectStatus "U5D1.CW32" )
			)
			( pin "@baseboard_fab2_lib.baseboard_fab2(sch_1):page41_i284:vss(334)"
				( attribute "PN" "CW26"
					( Origin gPackager )
				)
				( objectStatus "U5D1.CW26" )
			)
			( pin "@baseboard_fab2_lib.baseboard_fab2(sch_1):page41_i284:vss(335)"
				( attribute "PN" "CW12"
					( Origin gPackager )
				)
				( objectStatus "U5D1.CW12" )
			)
			( pin "@baseboard_fab2_lib.baseboard_fab2(sch_1):page41_i284:vss(336)"
				( attribute "PN" "CV83"
					( Origin gPackager )
				)
				( objectStatus "U5D1.CV83" )
			)
			( pin "@baseboard_fab2_lib.baseboard_fab2(sch_1):page41_i284:vss(337)"
				( attribute "PN" "CV81"
					( Origin gPackager )
				)
				( objectStatus "U5D1.CV81" )
			)
			( pin "@baseboard_fab2_lib.baseboard_fab2(sch_1):page41_i284:vss(338)"
				( attribute "PN" "CV79"
					( Origin gPackager )
				)
				( objectStatus "U5D1.CV79" )
			)
			( pin "@baseboard_fab2_lib.baseboard_fab2(sch_1):page41_i284:vss(339)"
				( attribute "PN" "CV73"
					( Origin gPackager )
				)
				( objectStatus "U5D1.CV73" )
			)
			( pin "@baseboard_fab2_lib.baseboard_fab2(sch_1):page41_i284:vss(340)"
				( attribute "PN" "CV67"
					( Origin gPackager )
				)
				( objectStatus "U5D1.CV67" )
			)
			( pin "@baseboard_fab2_lib.baseboard_fab2(sch_1):page41_i284:vss(341)"
				( attribute "PN" "CV63"
					( Origin gPackager )
				)
				( objectStatus "U5D1.CV63" )
			)
			( pin "@baseboard_fab2_lib.baseboard_fab2(sch_1):page41_i284:vss(342)"
				( attribute "PN" "CV55"
					( Origin gPackager )
				)
				( objectStatus "U5D1.CV55" )
			)
			( pin "@baseboard_fab2_lib.baseboard_fab2(sch_1):page41_i284:vss(343)"
				( attribute "PN" "CV53"
					( Origin gPackager )
				)
				( objectStatus "U5D1.CV53" )
			)
			( pin "@baseboard_fab2_lib.baseboard_fab2(sch_1):page41_i284:vss(344)"
				( attribute "PN" "CV41"
					( Origin gPackager )
				)
				( objectStatus "U5D1.CV41" )
			)
			( pin "@baseboard_fab2_lib.baseboard_fab2(sch_1):page41_i284:vss(345)"
				( attribute "PN" "CV39"
					( Origin gPackager )
				)
				( objectStatus "U5D1.CV39" )
			)
			( pin "@baseboard_fab2_lib.baseboard_fab2(sch_1):page41_i284:vss(346)"
				( attribute "PN" "CV37"
					( Origin gPackager )
				)
				( objectStatus "U5D1.CV37" )
			)
			( pin "@baseboard_fab2_lib.baseboard_fab2(sch_1):page41_i284:vss(347)"
				( attribute "PN" "CV33"
					( Origin gPackager )
				)
				( objectStatus "U5D1.CV33" )
			)
			( pin "@baseboard_fab2_lib.baseboard_fab2(sch_1):page41_i284:vss(348)"
				( attribute "PN" "CV31"
					( Origin gPackager )
				)
				( objectStatus "U5D1.CV31" )
			)
			( pin "@baseboard_fab2_lib.baseboard_fab2(sch_1):page41_i284:vss(349)"
				( attribute "PN" "CV27"
					( Origin gPackager )
				)
				( objectStatus "U5D1.CV27" )
			)
			( pin "@baseboard_fab2_lib.baseboard_fab2(sch_1):page41_i284:vss(350)"
				( attribute "PN" "CV25"
					( Origin gPackager )
				)
				( objectStatus "U5D1.CV25" )
			)
			( pin "@baseboard_fab2_lib.baseboard_fab2(sch_1):page41_i284:vss(351)"
				( attribute "PN" "CV17"
					( Origin gPackager )
				)
				( objectStatus "U5D1.CV17" )
			)
			( pin "@baseboard_fab2_lib.baseboard_fab2(sch_1):page41_i284:vss(352)"
				( attribute "PN" "H55"
					( Origin gPackager )
				)
				( objectStatus "U5D1.H55" )
			)
			( pin "@baseboard_fab2_lib.baseboard_fab2(sch_1):page41_i284:vss(353)"
				( attribute "PN" "CV1"
					( Origin gPackager )
				)
				( objectStatus "U5D1.CV1" )
			)
			( pin "@baseboard_fab2_lib.baseboard_fab2(sch_1):page41_i284:vss(354)"
				( attribute "PN" "CU86"
					( Origin gPackager )
				)
				( objectStatus "U5D1.CU86" )
			)
			( pin "@baseboard_fab2_lib.baseboard_fab2(sch_1):page41_i284:vss(355)"
				( attribute "PN" "CU82"
					( Origin gPackager )
				)
				( objectStatus "U5D1.CU82" )
			)
			( pin "@baseboard_fab2_lib.baseboard_fab2(sch_1):page41_i284:vss(356)"
				( attribute "PN" "CU80"
					( Origin gPackager )
				)
				( objectStatus "U5D1.CU80" )
			)
			( pin "@baseboard_fab2_lib.baseboard_fab2(sch_1):page41_i284:vss(357)"
				( attribute "PN" "CU78"
					( Origin gPackager )
				)
				( objectStatus "U5D1.CU78" )
			)
			( pin "@baseboard_fab2_lib.baseboard_fab2(sch_1):page41_i284:vss(358)"
				( attribute "PN" "CU76"
					( Origin gPackager )
				)
				( objectStatus "U5D1.CU76" )
			)
			( pin "@baseboard_fab2_lib.baseboard_fab2(sch_1):page41_i284:vss(359)"
				( attribute "PN" "CU68"
					( Origin gPackager )
				)
				( objectStatus "U5D1.CU68" )
			)
			( pin "@baseboard_fab2_lib.baseboard_fab2(sch_1):page41_i284:vss(360)"
				( attribute "PN" "CU62"
					( Origin gPackager )
				)
				( objectStatus "U5D1.CU62" )
			)
			( pin "@baseboard_fab2_lib.baseboard_fab2(sch_1):page41_i284:vss(361)"
				( attribute "PN" "CU56"
					( Origin gPackager )
				)
				( objectStatus "U5D1.CU56" )
			)
			( pin "@baseboard_fab2_lib.baseboard_fab2(sch_1):page41_i284:vss(362)"
				( attribute "PN" "CU36"
					( Origin gPackager )
				)
				( objectStatus "U5D1.CU36" )
			)
			( pin "@baseboard_fab2_lib.baseboard_fab2(sch_1):page41_i284:vss(363)"
				( attribute "PN" "CU34"
					( Origin gPackager )
				)
				( objectStatus "U5D1.CU34" )
			)
			( pin "@baseboard_fab2_lib.baseboard_fab2(sch_1):page41_i284:vss(364)"
				( attribute "PN" "CU30"
					( Origin gPackager )
				)
				( objectStatus "U5D1.CU30" )
			)
			( pin "@baseboard_fab2_lib.baseboard_fab2(sch_1):page41_i284:vss(365)"
				( attribute "PN" "CU28"
					( Origin gPackager )
				)
				( objectStatus "U5D1.CU28" )
			)
			( pin "@baseboard_fab2_lib.baseboard_fab2(sch_1):page41_i284:vss(366)"
				( attribute "PN" "CU22"
					( Origin gPackager )
				)
				( objectStatus "U5D1.CU22" )
			)
			( pin "@baseboard_fab2_lib.baseboard_fab2(sch_1):page41_i284:vss(367)"
				( attribute "PN" "CU4"
					( Origin gPackager )
				)
				( objectStatus "U5D1.CU4" )
			)
			( pin "@baseboard_fab2_lib.baseboard_fab2(sch_1):page41_i284:vss(368)"
				( attribute "PN" "CT85"
					( Origin gPackager )
				)
				( objectStatus "U5D1.CT85" )
			)
			( pin "@baseboard_fab2_lib.baseboard_fab2(sch_1):page41_i284:vss(369)"
				( attribute "PN" "CT83"
					( Origin gPackager )
				)
				( objectStatus "U5D1.CT83" )
			)
			( pin "@baseboard_fab2_lib.baseboard_fab2(sch_1):page41_i284:vss(370)"
				( attribute "PN" "CT79"
					( Origin gPackager )
				)
				( objectStatus "U5D1.CT79" )
			)
			( pin "@baseboard_fab2_lib.baseboard_fab2(sch_1):page41_i284:vss(371)"
				( attribute "PN" "CT73"
					( Origin gPackager )
				)
				( objectStatus "U5D1.CT73" )
			)
			( pin "@baseboard_fab2_lib.baseboard_fab2(sch_1):page41_i284:vss(372)"
				( attribute "PN" "CT57"
					( Origin gPackager )
				)
				( objectStatus "U5D1.CT57" )
			)
			( pin "@baseboard_fab2_lib.baseboard_fab2(sch_1):page41_i284:vss(373)"
				( attribute "PN" "CT35"
					( Origin gPackager )
				)
				( objectStatus "U5D1.CT35" )
			)
			( pin "@baseboard_fab2_lib.baseboard_fab2(sch_1):page41_i284:vss(374)"
				( attribute "PN" "CT33"
					( Origin gPackager )
				)
				( objectStatus "U5D1.CT33" )
			)
			( pin "@baseboard_fab2_lib.baseboard_fab2(sch_1):page41_i284:vss(375)"
				( attribute "PN" "CT29"
					( Origin gPackager )
				)
				( objectStatus "U5D1.CT29" )
			)
			( pin "@baseboard_fab2_lib.baseboard_fab2(sch_1):page41_i284:vss(376)"
				( attribute "PN" "CT27"
					( Origin gPackager )
				)
				( objectStatus "U5D1.CT27" )
			)
			( pin "@baseboard_fab2_lib.baseboard_fab2(sch_1):page41_i284:vss(377)"
				( attribute "PN" "CT19"
					( Origin gPackager )
				)
				( objectStatus "U5D1.CT19" )
			)
			( pin "@baseboard_fab2_lib.baseboard_fab2(sch_1):page41_i284:vss(378)"
				( attribute "PN" "CT13"
					( Origin gPackager )
				)
				( objectStatus "U5D1.CT13" )
			)
			( pin "@baseboard_fab2_lib.baseboard_fab2(sch_1):page41_i284:vss(379)"
				( attribute "PN" "H57"
					( Origin gPackager )
				)
				( objectStatus "U5D1.H57" )
			)
			( pin "@baseboard_fab2_lib.baseboard_fab2(sch_1):page41_i284:vss(380)"
				( attribute "PN" "CR86"
					( Origin gPackager )
				)
				( objectStatus "U5D1.CR86" )
			)
			( pin "@baseboard_fab2_lib.baseboard_fab2(sch_1):page41_i284:vss(381)"
				( attribute "PN" "CR78"
					( Origin gPackager )
				)
				( objectStatus "U5D1.CR78" )
			)
			( pin "@baseboard_fab2_lib.baseboard_fab2(sch_1):page41_i284:vss(382)"
				( attribute "PN" "CR68"
					( Origin gPackager )
				)
				( objectStatus "U5D1.CR68" )
			)
			( pin "@baseboard_fab2_lib.baseboard_fab2(sch_1):page41_i284:vss(383)"
				( attribute "PN" "CR66"
					( Origin gPackager )
				)
				( objectStatus "U5D1.CR66" )
			)
			( pin "@baseboard_fab2_lib.baseboard_fab2(sch_1):page41_i284:vss(384)"
				( attribute "PN" "CR64"
					( Origin gPackager )
				)
				( objectStatus "U5D1.CR64" )
			)
			( pin "@baseboard_fab2_lib.baseboard_fab2(sch_1):page41_i284:vss(385)"
				( attribute "PN" "CR62"
					( Origin gPackager )
				)
				( objectStatus "U5D1.CR62" )
			)
			( pin "@baseboard_fab2_lib.baseboard_fab2(sch_1):page41_i284:vss(386)"
				( attribute "PN" "CR58"
					( Origin gPackager )
				)
				( objectStatus "U5D1.CR58" )
			)
			( pin "@baseboard_fab2_lib.baseboard_fab2(sch_1):page41_i284:vss(387)"
				( attribute "PN" "CR32"
					( Origin gPackager )
				)
				( objectStatus "U5D1.CR32" )
			)
			( pin "@baseboard_fab2_lib.baseboard_fab2(sch_1):page41_i284:vss(388)"
				( attribute "PN" "CR24"
					( Origin gPackager )
				)
				( objectStatus "U5D1.CR24" )
			)
			( pin "@baseboard_fab2_lib.baseboard_fab2(sch_1):page41_i284:vss(389)"
				( attribute "PN" "CR22"
					( Origin gPackager )
				)
				( objectStatus "U5D1.CR22" )
			)
			( pin "@baseboard_fab2_lib.baseboard_fab2(sch_1):page41_i284:vss(390)"
				( attribute "PN" "CR10"
					( Origin gPackager )
				)
				( objectStatus "U5D1.CR10" )
			)
			( pin "@baseboard_fab2_lib.baseboard_fab2(sch_1):page41_i284:vss(391)"
				( attribute "PN" "CR6"
					( Origin gPackager )
				)
				( objectStatus "U5D1.CR6" )
			)
			( pin "@baseboard_fab2_lib.baseboard_fab2(sch_1):page41_i284:vss(392)"
				( attribute "PN" "CP83"
					( Origin gPackager )
				)
				( objectStatus "U5D1.CP83" )
			)
			( pin "@baseboard_fab2_lib.baseboard_fab2(sch_1):page41_i284:vss(393)"
				( attribute "PN" "CP81"
					( Origin gPackager )
				)
				( objectStatus "U5D1.CP81" )
			)
			( pin "@baseboard_fab2_lib.baseboard_fab2(sch_1):page41_i284:vss(394)"
				( attribute "PN" "CP75"
					( Origin gPackager )
				)
				( objectStatus "U5D1.CP75" )
			)
			( pin "@baseboard_fab2_lib.baseboard_fab2(sch_1):page41_i284:vss(395)"
				( attribute "PN" "CP73"
					( Origin gPackager )
				)
				( objectStatus "U5D1.CP73" )
			)
			( pin "@baseboard_fab2_lib.baseboard_fab2(sch_1):page41_i284:vss(396)"
				( attribute "PN" "CP69"
					( Origin gPackager )
				)
				( objectStatus "U5D1.CP69" )
			)
			( pin "@baseboard_fab2_lib.baseboard_fab2(sch_1):page41_i284:vss(397)"
				( attribute "PN" "CP59"
					( Origin gPackager )
				)
				( objectStatus "U5D1.CP59" )
			)
			( pin "@baseboard_fab2_lib.baseboard_fab2(sch_1):page41_i284:vss(398)"
				( attribute "PN" "CP25"
					( Origin gPackager )
				)
				( objectStatus "U5D1.CP25" )
			)
			( pin "@baseboard_fab2_lib.baseboard_fab2(sch_1):page41_i284:vss(399)"
				( attribute "PN" "H59"
					( Origin gPackager )
				)
				( objectStatus "U5D1.H59" )
			)
			( pin "@baseboard_fab2_lib.baseboard_fab2(sch_1):page41_i284:vss(400)"
				( attribute "PN" "CP1"
					( Origin gPackager )
				)
				( objectStatus "U5D1.CP1" )
			)
			( pin "@baseboard_fab2_lib.baseboard_fab2(sch_1):page41_i284:vss(401)"
				( attribute "PN" "CN78"
					( Origin gPackager )
				)
				( objectStatus "U5D1.CN78" )
			)
			( pin "@baseboard_fab2_lib.baseboard_fab2(sch_1):page41_i284:vss(402)"
				( attribute "PN" "CN68"
					( Origin gPackager )
				)
				( objectStatus "U5D1.CN68" )
			)
			( pin "@baseboard_fab2_lib.baseboard_fab2(sch_1):page41_i284:vss(403)"
				( attribute "PN" "CN62"
					( Origin gPackager )
				)
				( objectStatus "U5D1.CN62" )
			)
			( pin "@baseboard_fab2_lib.baseboard_fab2(sch_1):page41_i284:vss(404)"
				( attribute "PN" "CN60"
					( Origin gPackager )
				)
				( objectStatus "U5D1.CN60" )
			)
			( pin "@baseboard_fab2_lib.baseboard_fab2(sch_1):page41_i284:vss(405)"
				( attribute "PN" "CN32"
					( Origin gPackager )
				)
				( objectStatus "U5D1.CN32" )
			)
			( pin "@baseboard_fab2_lib.baseboard_fab2(sch_1):page41_i284:vss(406)"
				( attribute "PN" "CN26"
					( Origin gPackager )
				)
				( objectStatus "U5D1.CN26" )
			)
			( pin "@baseboard_fab2_lib.baseboard_fab2(sch_1):page41_i284:vss(407)"
				( attribute "PN" "H61"
					( Origin gPackager )
				)
				( objectStatus "U5D1.H61" )
			)
			( pin "@baseboard_fab2_lib.baseboard_fab2(sch_1):page41_i284:vss(408)"
				( attribute "PN" "CN12"
					( Origin gPackager )
				)
				( objectStatus "U5D1.CN12" )
			)
			( pin "@baseboard_fab2_lib.baseboard_fab2(sch_1):page41_i284:vss(409)"
				( attribute "PN" "CN2"
					( Origin gPackager )
				)
				( objectStatus "U5D1.CN2" )
			)
			( pin "@baseboard_fab2_lib.baseboard_fab2(sch_1):page41_i284:vss(410)"
				( attribute "PN" "CM85"
					( Origin gPackager )
				)
				( objectStatus "U5D1.CM85" )
			)
			( pin "@baseboard_fab2_lib.baseboard_fab2(sch_1):page41_i284:vss(411)"
				( attribute "PN" "CM83"
					( Origin gPackager )
				)
				( objectStatus "U5D1.CM83" )
			)
			( pin "@baseboard_fab2_lib.baseboard_fab2(sch_1):page41_i284:vss(412)"
				( attribute "PN" "CM77"
					( Origin gPackager )
				)
				( objectStatus "U5D1.CM77" )
			)
			( pin "@baseboard_fab2_lib.baseboard_fab2(sch_1):page41_i284:vss(413)"
				( attribute "PN" "CM73"
					( Origin gPackager )
				)
				( objectStatus "U5D1.CM73" )
			)
			( pin "@baseboard_fab2_lib.baseboard_fab2(sch_1):page41_i284:vss(414)"
				( attribute "PN" "CM67"
					( Origin gPackager )
				)
				( objectStatus "U5D1.CM67" )
			)
			( pin "@baseboard_fab2_lib.baseboard_fab2(sch_1):page41_i284:vss(415)"
				( attribute "PN" "CM63"
					( Origin gPackager )
				)
				( objectStatus "U5D1.CM63" )
			)
			( pin "@baseboard_fab2_lib.baseboard_fab2(sch_1):page41_i284:vss(416)"
				( attribute "PN" "CM61"
					( Origin gPackager )
				)
				( objectStatus "U5D1.CM61" )
			)
			( pin "@baseboard_fab2_lib.baseboard_fab2(sch_1):page41_i284:vss(417)"
				( attribute "PN" "CM31"
					( Origin gPackager )
				)
				( objectStatus "U5D1.CM31" )
			)
			( pin "@baseboard_fab2_lib.baseboard_fab2(sch_1):page41_i284:vss(418)"
				( attribute "PN" "CM5"
					( Origin gPackager )
				)
				( objectStatus "U5D1.CM5" )
			)
			( pin "@baseboard_fab2_lib.baseboard_fab2(sch_1):page41_i284:vss(419)"
				( attribute "PN" "CM29"
					( Origin gPackager )
				)
				( objectStatus "U5D1.CM29" )
			)
			( pin "@baseboard_fab2_lib.baseboard_fab2(sch_1):page41_i284:vss(420)"
				( attribute "PN" "CM19"
					( Origin gPackager )
				)
				( objectStatus "U5D1.CM19" )
			)
			( pin "@baseboard_fab2_lib.baseboard_fab2(sch_1):page41_i284:vss(421)"
				( attribute "PN" "CL80"
					( Origin gPackager )
				)
				( objectStatus "U5D1.CL80" )
			)
			( pin "@baseboard_fab2_lib.baseboard_fab2(sch_1):page41_i284:vss(422)"
				( attribute "PN" "CL78"
					( Origin gPackager )
				)
				( objectStatus "U5D1.CL78" )
			)
			( pin "@baseboard_fab2_lib.baseboard_fab2(sch_1):page41_i284:vss(423)"
				( attribute "PN" "CL76"
					( Origin gPackager )
				)
				( objectStatus "U5D1.CL76" )
			)
			( pin "@baseboard_fab2_lib.baseboard_fab2(sch_1):page41_i284:vss(424)"
				( attribute "PN" "CL74"
					( Origin gPackager )
				)
				( objectStatus "U5D1.CL74" )
			)
			( pin "@baseboard_fab2_lib.baseboard_fab2(sch_1):page41_i284:vss(425)"
				( attribute "PN" "CL66"
					( Origin gPackager )
				)
				( objectStatus "U5D1.CL66" )
			)
			( pin "@baseboard_fab2_lib.baseboard_fab2(sch_1):page41_i284:vss(426)"
				( attribute "PN" "CL64"
					( Origin gPackager )
				)
				( objectStatus "U5D1.CL64" )
			)
			( pin "@baseboard_fab2_lib.baseboard_fab2(sch_1):page41_i284:vss(427)"
				( attribute "PN" "CL62"
					( Origin gPackager )
				)
				( objectStatus "U5D1.CL62" )
			)
			( pin "@baseboard_fab2_lib.baseboard_fab2(sch_1):page41_i284:vss(428)"
				( attribute "PN" "H63"
					( Origin gPackager )
				)
				( objectStatus "U5D1.H63" )
			)
			( pin "@baseboard_fab2_lib.baseboard_fab2(sch_1):page41_i284:vss(429)"
				( attribute "PN" "P45"
					( Origin gPackager )
				)
				( objectStatus "U5D1.P45" )
			)
			( pin "@baseboard_fab2_lib.baseboard_fab2(sch_1):page41_i284:vss(430)"
				( attribute "PN" "CL18"
					( Origin gPackager )
				)
				( objectStatus "U5D1.CL18" )
			)
			( pin "@baseboard_fab2_lib.baseboard_fab2(sch_1):page41_i284:vss(431)"
				( attribute "PN" "CL14"
					( Origin gPackager )
				)
				( objectStatus "U5D1.CL14" )
			)
			( pin "@baseboard_fab2_lib.baseboard_fab2(sch_1):page41_i284:vss(432)"
				( attribute "PN" "CL8"
					( Origin gPackager )
				)
				( objectStatus "U5D1.CL8" )
			)
			( pin "@baseboard_fab2_lib.baseboard_fab2(sch_1):page41_i284:vss(433)"
				( attribute "PN" "CK85"
					( Origin gPackager )
				)
				( objectStatus "U5D1.CK85" )
			)
			( pin "@baseboard_fab2_lib.baseboard_fab2(sch_1):page41_i284:vss(434)"
				( attribute "PN" "CK83"
					( Origin gPackager )
				)
				( objectStatus "U5D1.CK83" )
			)
			( pin "@baseboard_fab2_lib.baseboard_fab2(sch_1):page41_i284:vss(435)"
				( attribute "PN" "CK75"
					( Origin gPackager )
				)
				( objectStatus "U5D1.CK75" )
			)
			( pin "@baseboard_fab2_lib.baseboard_fab2(sch_1):page41_i284:vss(436)"
				( attribute "PN" "CK73"
					( Origin gPackager )
				)
				( objectStatus "U5D1.CK73" )
			)
			( pin "@baseboard_fab2_lib.baseboard_fab2(sch_1):page41_i284:vss(437)"
				( attribute "PN" "CK71"
					( Origin gPackager )
				)
				( objectStatus "U5D1.CK71" )
			)
			( pin "@baseboard_fab2_lib.baseboard_fab2(sch_1):page41_i284:vss(438)"
				( attribute "PN" "CK69"
					( Origin gPackager )
				)
				( objectStatus "U5D1.CK69" )
			)
			( pin "@baseboard_fab2_lib.baseboard_fab2(sch_1):page41_i284:vss(439)"
				( attribute "PN" "CK67"
					( Origin gPackager )
				)
				( objectStatus "U5D1.CK67" )
			)
			( pin "@baseboard_fab2_lib.baseboard_fab2(sch_1):page41_i284:vss(440)"
				( attribute "PN" "CK65"
					( Origin gPackager )
				)
				( objectStatus "U5D1.CK65" )
			)
			( pin "@baseboard_fab2_lib.baseboard_fab2(sch_1):page41_i284:vss(441)"
				( attribute "PN" "CK63"
					( Origin gPackager )
				)
				( objectStatus "U5D1.CK63" )
			)
			( pin "@baseboard_fab2_lib.baseboard_fab2(sch_1):page41_i284:vss(442)"
				( attribute "PN" "CK27"
					( Origin gPackager )
				)
				( objectStatus "U5D1.CK27" )
			)
			( pin "@baseboard_fab2_lib.baseboard_fab2(sch_1):page41_i284:vss(443)"
				( attribute "PN" "CK21"
					( Origin gPackager )
				)
				( objectStatus "U5D1.CK21" )
			)
			( pin "@baseboard_fab2_lib.baseboard_fab2(sch_1):page41_i284:vss(444)"
				( attribute "PN" "CK15"
					( Origin gPackager )
				)
				( objectStatus "U5D1.CK15" )
			)
			( pin "@baseboard_fab2_lib.baseboard_fab2(sch_1):page41_i284:vss(445)"
				( attribute "PN" "CK11"
					( Origin gPackager )
				)
				( objectStatus "U5D1.CK11" )
			)
			( pin "@baseboard_fab2_lib.baseboard_fab2(sch_1):page41_i284:vss(446)"
				( attribute "PN" "CJ86"
					( Origin gPackager )
				)
				( objectStatus "U5D1.CJ86" )
			)
			( pin "@baseboard_fab2_lib.baseboard_fab2(sch_1):page41_i284:vss(447)"
				( attribute "PN" "CJ84"
					( Origin gPackager )
				)
				( objectStatus "U5D1.CJ84" )
			)
			( pin "@baseboard_fab2_lib.baseboard_fab2(sch_1):page41_i284:vss(448)"
				( attribute "PN" "CJ82"
					( Origin gPackager )
				)
				( objectStatus "U5D1.CJ82" )
			)
			( pin "@baseboard_fab2_lib.baseboard_fab2(sch_1):page41_i284:vss(449)"
				( attribute "PN" "CJ78"
					( Origin gPackager )
				)
				( objectStatus "U5D1.CJ78" )
			)
			( pin "@baseboard_fab2_lib.baseboard_fab2(sch_1):page41_i284:vss(450)"
				( attribute "PN" "CJ76"
					( Origin gPackager )
				)
				( objectStatus "U5D1.CJ76" )
			)
			( pin "@baseboard_fab2_lib.baseboard_fab2(sch_1):page41_i284:vss(451)"
				( attribute "PN" "CJ74"
					( Origin gPackager )
				)
				( objectStatus "U5D1.CJ74" )
			)
			( pin "@baseboard_fab2_lib.baseboard_fab2(sch_1):page41_i284:vss(452)"
				( attribute "PN" "CJ62"
					( Origin gPackager )
				)
				( objectStatus "U5D1.CJ62" )
			)
			( pin "@baseboard_fab2_lib.baseboard_fab2(sch_1):page41_i284:vss(453)"
				( attribute "PN" "P47"
					( Origin gPackager )
				)
				( objectStatus "U5D1.P47" )
			)
			( pin "@baseboard_fab2_lib.baseboard_fab2(sch_1):page41_i285:vss(134)"
				( attribute "PN" "DN72"
					( Origin gPackager )
				)
				( objectStatus "U5D1.DN72" )
			)
			( pin "@baseboard_fab2_lib.baseboard_fab2(sch_1):page41_i285:vss(135)"
				( attribute "PN" "DN68"
					( Origin gPackager )
				)
				( objectStatus "U5D1.DN68" )
			)
			( pin "@baseboard_fab2_lib.baseboard_fab2(sch_1):page41_i285:vss(136)"
				( attribute "PN" "DN38"
					( Origin gPackager )
				)
				( objectStatus "U5D1.DN38" )
			)
			( pin "@baseboard_fab2_lib.baseboard_fab2(sch_1):page41_i285:vss(137)"
				( attribute "PN" "DN32"
					( Origin gPackager )
				)
				( objectStatus "U5D1.DN32" )
			)
			( pin "@baseboard_fab2_lib.baseboard_fab2(sch_1):page41_i285:vss(138)"
				( attribute "PN" "DN26"
					( Origin gPackager )
				)
				( objectStatus "U5D1.DN26" )
			)
			( pin "@baseboard_fab2_lib.baseboard_fab2(sch_1):page41_i285:vss(139)"
				( attribute "PN" "DN22"
					( Origin gPackager )
				)
				( objectStatus "U5D1.DN22" )
			)
			( pin "@baseboard_fab2_lib.baseboard_fab2(sch_1):page41_i285:vss(140)"
				( attribute "PN" "DN12"
					( Origin gPackager )
				)
				( objectStatus "U5D1.DN12" )
			)
			( pin "@baseboard_fab2_lib.baseboard_fab2(sch_1):page41_i285:vss(141)"
				( attribute "PN" "BH17"
					( Origin gPackager )
				)
				( objectStatus "U5D1.BH17" )
			)
			( pin "@baseboard_fab2_lib.baseboard_fab2(sch_1):page41_i285:vss(142)"
				( attribute "PN" "DN2"
					( Origin gPackager )
				)
				( objectStatus "U5D1.DN2" )
			)
			( pin "@baseboard_fab2_lib.baseboard_fab2(sch_1):page41_i285:vss(143)"
				( attribute "PN" "DM83"
					( Origin gPackager )
				)
				( objectStatus "U5D1.DM83" )
			)
			( pin "@baseboard_fab2_lib.baseboard_fab2(sch_1):page41_i285:vss(144)"
				( attribute "PN" "DM77"
					( Origin gPackager )
				)
				( objectStatus "U5D1.DM77" )
			)
			( pin "@baseboard_fab2_lib.baseboard_fab2(sch_1):page41_i285:vss(145)"
				( attribute "PN" "DM73"
					( Origin gPackager )
				)
				( objectStatus "U5D1.DM73" )
			)
			( pin "@baseboard_fab2_lib.baseboard_fab2(sch_1):page41_i285:vss(146)"
				( attribute "PN" "DM65"
					( Origin gPackager )
				)
				( objectStatus "U5D1.DM65" )
			)
			( pin "@baseboard_fab2_lib.baseboard_fab2(sch_1):page41_i285:vss(147)"
				( attribute "PN" "DM39"
					( Origin gPackager )
				)
				( objectStatus "U5D1.DM39" )
			)
			( pin "@baseboard_fab2_lib.baseboard_fab2(sch_1):page41_i285:vss(148)"
				( attribute "PN" "DM37"
					( Origin gPackager )
				)
				( objectStatus "U5D1.DM37" )
			)
			( pin "@baseboard_fab2_lib.baseboard_fab2(sch_1):page41_i285:vss(149)"
				( attribute "PN" "DM33"
					( Origin gPackager )
				)
				( objectStatus "U5D1.DM33" )
			)
			( pin "@baseboard_fab2_lib.baseboard_fab2(sch_1):page41_i285:vss(150)"
				( attribute "PN" "DM31"
					( Origin gPackager )
				)
				( objectStatus "U5D1.DM31" )
			)
			( pin "@baseboard_fab2_lib.baseboard_fab2(sch_1):page41_i285:vss(151)"
				( attribute "PN" "DM27"
					( Origin gPackager )
				)
				( objectStatus "U5D1.DM27" )
			)
			( pin "@baseboard_fab2_lib.baseboard_fab2(sch_1):page41_i285:vss(152)"
				( attribute "PN" "DM25"
					( Origin gPackager )
				)
				( objectStatus "U5D1.DM25" )
			)
			( pin "@baseboard_fab2_lib.baseboard_fab2(sch_1):page41_i285:vss(153)"
				( attribute "PN" "H45"
					( Origin gPackager )
				)
				( objectStatus "U5D1.H45" )
			)
			( pin "@baseboard_fab2_lib.baseboard_fab2(sch_1):page41_i285:vss(154)"
				( attribute "PN" "DM15"
					( Origin gPackager )
				)
				( objectStatus "U5D1.DM15" )
			)
			( pin "@baseboard_fab2_lib.baseboard_fab2(sch_1):page41_i285:vss(155)"
				( attribute "PN" "DL80"
					( Origin gPackager )
				)
				( objectStatus "U5D1.DL80" )
			)
			( pin "@baseboard_fab2_lib.baseboard_fab2(sch_1):page41_i285:vss(156)"
				( attribute "PN" "DL78"
					( Origin gPackager )
				)
				( objectStatus "U5D1.DL78" )
			)
			( pin "@baseboard_fab2_lib.baseboard_fab2(sch_1):page41_i285:vss(157)"
				( attribute "PN" "DL76"
					( Origin gPackager )
				)
				( objectStatus "U5D1.DL76" )
			)
			( pin "@baseboard_fab2_lib.baseboard_fab2(sch_1):page41_i285:vss(158)"
				( attribute "PN" "DL74"
					( Origin gPackager )
				)
				( objectStatus "U5D1.DL74" )
			)
			( pin "@baseboard_fab2_lib.baseboard_fab2(sch_1):page41_i285:vss(159)"
				( attribute "PN" "DL70"
					( Origin gPackager )
				)
				( objectStatus "U5D1.DL70" )
			)
			( pin "@baseboard_fab2_lib.baseboard_fab2(sch_1):page41_i285:vss(160)"
				( attribute "PN" "DL68"
					( Origin gPackager )
				)
				( objectStatus "U5D1.DL68" )
			)
			( pin "@baseboard_fab2_lib.baseboard_fab2(sch_1):page41_i285:vss(161)"
				( attribute "PN" "DL40"
					( Origin gPackager )
				)
				( objectStatus "U5D1.DL40" )
			)
			( pin "@baseboard_fab2_lib.baseboard_fab2(sch_1):page41_i285:vss(162)"
				( attribute "PN" "DL36"
					( Origin gPackager )
				)
				( objectStatus "U5D1.DL36" )
			)
			( pin "@baseboard_fab2_lib.baseboard_fab2(sch_1):page41_i285:vss(163)"
				( attribute "PN" "DL34"
					( Origin gPackager )
				)
				( objectStatus "U5D1.DL34" )
			)
			( pin "@baseboard_fab2_lib.baseboard_fab2(sch_1):page41_i285:vss(164)"
				( attribute "PN" "DL30"
					( Origin gPackager )
				)
				( objectStatus "U5D1.DL30" )
			)
			( pin "@baseboard_fab2_lib.baseboard_fab2(sch_1):page41_i285:vss(165)"
				( attribute "PN" "DL28"
					( Origin gPackager )
				)
				( objectStatus "U5D1.DL28" )
			)
			( pin "@baseboard_fab2_lib.baseboard_fab2(sch_1):page41_i285:vss(166)"
				( attribute "PN" "DL24"
					( Origin gPackager )
				)
				( objectStatus "U5D1.DL24" )
			)
			( pin "@baseboard_fab2_lib.baseboard_fab2(sch_1):page41_i285:vss(167)"
				( attribute "PN" "DL22"
					( Origin gPackager )
				)
				( objectStatus "U5D1.DL22" )
			)
			( pin "@baseboard_fab2_lib.baseboard_fab2(sch_1):page41_i285:vss(168)"
				( attribute "PN" "DL4"
					( Origin gPackager )
				)
				( objectStatus "U5D1.DL4" )
			)
			( pin "@baseboard_fab2_lib.baseboard_fab2(sch_1):page41_i285:vss(169)"
				( attribute "PN" "DL18"
					( Origin gPackager )
				)
				( objectStatus "U5D1.DL18" )
			)
			( pin "@baseboard_fab2_lib.baseboard_fab2(sch_1):page41_i285:vss(170)"
				( attribute "PN" "DL16"
					( Origin gPackager )
				)
				( objectStatus "U5D1.DL16" )
			)
			( pin "@baseboard_fab2_lib.baseboard_fab2(sch_1):page41_i285:vss(171)"
				( attribute "PN" "DK85"
					( Origin gPackager )
				)
				( objectStatus "U5D1.DK85" )
			)
			( pin "@baseboard_fab2_lib.baseboard_fab2(sch_1):page41_i285:vss(172)"
				( attribute "PN" "DK83"
					( Origin gPackager )
				)
				( objectStatus "U5D1.DK83" )
			)
			( pin "@baseboard_fab2_lib.baseboard_fab2(sch_1):page41_i285:vss(173)"
				( attribute "PN" "DK77"
					( Origin gPackager )
				)
				( objectStatus "U5D1.DK77" )
			)
			( pin "@baseboard_fab2_lib.baseboard_fab2(sch_1):page41_i285:vss(174)"
				( attribute "PN" "DK75"
					( Origin gPackager )
				)
				( objectStatus "U5D1.DK75" )
			)
			( pin "@baseboard_fab2_lib.baseboard_fab2(sch_1):page41_i285:vss(175)"
				( attribute "PN" "DK73"
					( Origin gPackager )
				)
				( objectStatus "U5D1.DK73" )
			)
			( pin "@baseboard_fab2_lib.baseboard_fab2(sch_1):page41_i285:vss(176)"
				( attribute "PN" "DK41"
					( Origin gPackager )
				)
				( objectStatus "U5D1.DK41" )
			)
			( pin "@baseboard_fab2_lib.baseboard_fab2(sch_1):page41_i285:vss(177)"
				( attribute "PN" "DK39"
					( Origin gPackager )
				)
				( objectStatus "U5D1.DK39" )
			)
			( pin "@baseboard_fab2_lib.baseboard_fab2(sch_1):page41_i285:vss(178)"
				( attribute "PN" "DK35"
					( Origin gPackager )
				)
				( objectStatus "U5D1.DK35" )
			)
			( pin "@baseboard_fab2_lib.baseboard_fab2(sch_1):page41_i285:vss(179)"
				( attribute "PN" "DK29"
					( Origin gPackager )
				)
				( objectStatus "U5D1.DK29" )
			)
			( pin "@baseboard_fab2_lib.baseboard_fab2(sch_1):page41_i285:vss(180)"
				( attribute "PN" "DK23"
					( Origin gPackager )
				)
				( objectStatus "U5D1.DK23" )
			)
			( pin "@baseboard_fab2_lib.baseboard_fab2(sch_1):page41_i285:vss(181)"
				( attribute "PN" "DK7"
					( Origin gPackager )
				)
				( objectStatus "U5D1.DK7" )
			)
			( pin "@baseboard_fab2_lib.baseboard_fab2(sch_1):page41_i285:vss(182)"
				( attribute "PN" "DJ84"
					( Origin gPackager )
				)
				( objectStatus "U5D1.DJ84" )
			)
			( pin "@baseboard_fab2_lib.baseboard_fab2(sch_1):page41_i285:vss(183)"
				( attribute "PN" "DJ82"
					( Origin gPackager )
				)
				( objectStatus "U5D1.DJ82" )
			)
			( pin "@baseboard_fab2_lib.baseboard_fab2(sch_1):page41_i285:vss(184)"
				( attribute "PN" "DJ78"
					( Origin gPackager )
				)
				( objectStatus "U5D1.DJ78" )
			)
			( pin "@baseboard_fab2_lib.baseboard_fab2(sch_1):page41_i285:vss(185)"
				( attribute "PN" "DJ74"
					( Origin gPackager )
				)
				( objectStatus "U5D1.DJ74" )
			)
			( pin "@baseboard_fab2_lib.baseboard_fab2(sch_1):page41_i285:vss(186)"
				( attribute "PN" "DJ68"
					( Origin gPackager )
				)
				( objectStatus "U5D1.DJ68" )
			)
			( pin "@baseboard_fab2_lib.baseboard_fab2(sch_1):page41_i285:vss(187)"
				( attribute "PN" "DJ42"
					( Origin gPackager )
				)
				( objectStatus "U5D1.DJ42" )
			)
			( pin "@baseboard_fab2_lib.baseboard_fab2(sch_1):page41_i285:vss(188)"
				( attribute "PN" "DJ38"
					( Origin gPackager )
				)
				( objectStatus "U5D1.DJ38" )
			)
			( pin "@baseboard_fab2_lib.baseboard_fab2(sch_1):page41_i285:vss(189)"
				( attribute "PN" "DJ22"
					( Origin gPackager )
				)
				( objectStatus "U5D1.DJ22" )
			)
			( pin "@baseboard_fab2_lib.baseboard_fab2(sch_1):page41_i285:vss(190)"
				( attribute "PN" "H47"
					( Origin gPackager )
				)
				( objectStatus "U5D1.H47" )
			)
			( pin "@baseboard_fab2_lib.baseboard_fab2(sch_1):page41_i285:vss(191)"
				( attribute "PN" "DJ10"
					( Origin gPackager )
				)
				( objectStatus "U5D1.DJ10" )
			)
			( pin "@baseboard_fab2_lib.baseboard_fab2(sch_1):page41_i285:vss(192)"
				( attribute "PN" "DJ2"
					( Origin gPackager )
				)
				( objectStatus "U5D1.DJ2" )
			)
			( pin "@baseboard_fab2_lib.baseboard_fab2(sch_1):page41_i285:vss(193)"
				( attribute "PN" "DH83"
					( Origin gPackager )
				)
				( objectStatus "U5D1.DH83" )
			)
			( pin "@baseboard_fab2_lib.baseboard_fab2(sch_1):page41_i285:vss(194)"
				( attribute "PN" "DH81"
					( Origin gPackager )
				)
				( objectStatus "U5D1.DH81" )
			)
			( pin "@baseboard_fab2_lib.baseboard_fab2(sch_1):page41_i285:vss(195)"
				( attribute "PN" "DH79"
					( Origin gPackager )
				)
				( objectStatus "U5D1.DH79" )
			)
			( pin "@baseboard_fab2_lib.baseboard_fab2(sch_1):page41_i285:vss(196)"
				( attribute "PN" "DH73"
					( Origin gPackager )
				)
				( objectStatus "U5D1.DH73" )
			)
			( pin "@baseboard_fab2_lib.baseboard_fab2(sch_1):page41_i285:vss(197)"
				( attribute "PN" "DH71"
					( Origin gPackager )
				)
				( objectStatus "U5D1.DH71" )
			)
			( pin "@baseboard_fab2_lib.baseboard_fab2(sch_1):page41_i285:vss(198)"
				( attribute "PN" "DH67"
					( Origin gPackager )
				)
				( objectStatus "U5D1.DH67" )
			)
			( pin "@baseboard_fab2_lib.baseboard_fab2(sch_1):page41_i285:vss(199)"
				( attribute "PN" "DH41"
					( Origin gPackager )
				)
				( objectStatus "U5D1.DH41" )
			)
			( pin "@baseboard_fab2_lib.baseboard_fab2(sch_1):page41_i285:vss(200)"
				( attribute "PN" "DH37"
					( Origin gPackager )
				)
				( objectStatus "U5D1.DH37" )
			)
			( pin "@baseboard_fab2_lib.baseboard_fab2(sch_1):page41_i285:vss(201)"
				( attribute "PN" "DH35"
					( Origin gPackager )
				)
				( objectStatus "U5D1.DH35" )
			)
			( pin "@baseboard_fab2_lib.baseboard_fab2(sch_1):page41_i285:vss(202)"
				( attribute "PN" "DH33"
					( Origin gPackager )
				)
				( objectStatus "U5D1.DH33" )
			)
			( pin "@baseboard_fab2_lib.baseboard_fab2(sch_1):page41_i285:vss(203)"
				( attribute "PN" "DH31"
					( Origin gPackager )
				)
				( objectStatus "U5D1.DH31" )
			)
			( pin "@baseboard_fab2_lib.baseboard_fab2(sch_1):page41_i285:vss(204)"
				( attribute "PN" "DH29"
					( Origin gPackager )
				)
				( objectStatus "U5D1.DH29" )
			)
			( pin "@baseboard_fab2_lib.baseboard_fab2(sch_1):page41_i285:vss(205)"
				( attribute "PN" "DH27"
					( Origin gPackager )
				)
				( objectStatus "U5D1.DH27" )
			)
			( pin "@baseboard_fab2_lib.baseboard_fab2(sch_1):page41_i285:vss(206)"
				( attribute "PN" "DH25"
					( Origin gPackager )
				)
				( objectStatus "U5D1.DH25" )
			)
			( pin "@baseboard_fab2_lib.baseboard_fab2(sch_1):page41_i285:vss(207)"
				( attribute "PN" "DH23"
					( Origin gPackager )
				)
				( objectStatus "U5D1.DH23" )
			)
			( pin "@baseboard_fab2_lib.baseboard_fab2(sch_1):page41_i285:vss(208)"
				( attribute "PN" "DH15"
					( Origin gPackager )
				)
				( objectStatus "U5D1.DH15" )
			)
			( pin "@baseboard_fab2_lib.baseboard_fab2(sch_1):page41_i285:vss(209)"
				( attribute "PN" "DH13"
					( Origin gPackager )
				)
				( objectStatus "U5D1.DH13" )
			)
			( pin "@baseboard_fab2_lib.baseboard_fab2(sch_1):page41_i285:vss(210)"
				( attribute "PN" "DG82"
					( Origin gPackager )
				)
				( objectStatus "U5D1.DG82" )
			)
			( pin "@baseboard_fab2_lib.baseboard_fab2(sch_1):page41_i285:vss(211)"
				( attribute "PN" "DG80"
					( Origin gPackager )
				)
				( objectStatus "U5D1.DG80" )
			)
			( pin "@baseboard_fab2_lib.baseboard_fab2(sch_1):page41_i285:vss(212)"
				( attribute "PN" "DG78"
					( Origin gPackager )
				)
				( objectStatus "U5D1.DG78" )
			)
			( pin "@baseboard_fab2_lib.baseboard_fab2(sch_1):page41_i285:vss(213)"
				( attribute "PN" "DG76"
					( Origin gPackager )
				)
				( objectStatus "U5D1.DG76" )
			)
			( pin "@baseboard_fab2_lib.baseboard_fab2(sch_1):page41_i285:vss(214)"
				( attribute "PN" "DG68"
					( Origin gPackager )
				)
				( objectStatus "U5D1.DG68" )
			)
			( pin "@baseboard_fab2_lib.baseboard_fab2(sch_1):page41_i285:vss(215)"
				( attribute "PN" "DG66"
					( Origin gPackager )
				)
				( objectStatus "U5D1.DG66" )
			)
			( pin "@baseboard_fab2_lib.baseboard_fab2(sch_1):page41_i285:vss(216)"
				( attribute "PN" "DG24"
					( Origin gPackager )
				)
				( objectStatus "U5D1.DG24" )
			)
			( pin "@baseboard_fab2_lib.baseboard_fab2(sch_1):page41_i285:vss(217)"
				( attribute "PN" "DG16"
					( Origin gPackager )
				)
				( objectStatus "U5D1.DG16" )
			)
			( pin "@baseboard_fab2_lib.baseboard_fab2(sch_1):page41_i285:vss(218)"
				( attribute "PN" "DG14"
					( Origin gPackager )
				)
				( objectStatus "U5D1.DG14" )
			)
			( pin "@baseboard_fab2_lib.baseboard_fab2(sch_1):page41_i285:vss(219)"
				( attribute "PN" "H49"
					( Origin gPackager )
				)
				( objectStatus "U5D1.H49" )
			)
			( pin "@baseboard_fab2_lib.baseboard_fab2(sch_1):page41_i285:vss(220)"
				( attribute "PN" "DG2"
					( Origin gPackager )
				)
				( objectStatus "U5D1.DG2" )
			)
			( pin "@baseboard_fab2_lib.baseboard_fab2(sch_1):page41_i285:vss(221)"
				( attribute "PN" "DF85"
					( Origin gPackager )
				)
				( objectStatus "U5D1.DF85" )
			)
			( pin "@baseboard_fab2_lib.baseboard_fab2(sch_1):page41_i285:vss(222)"
				( attribute "PN" "DF83"
					( Origin gPackager )
				)
				( objectStatus "U5D1.DF83" )
			)
			( pin "@baseboard_fab2_lib.baseboard_fab2(sch_1):page41_i285:vss(223)"
				( attribute "PN" "DF79"
					( Origin gPackager )
				)
				( objectStatus "U5D1.DF79" )
			)
			( pin "@baseboard_fab2_lib.baseboard_fab2(sch_1):page41_i285:vss(224)"
				( attribute "PN" "DF73"
					( Origin gPackager )
				)
				( objectStatus "U5D1.DF73" )
			)
			( pin "@baseboard_fab2_lib.baseboard_fab2(sch_1):page41_i285:vss(225)"
				( attribute "PN" "DF69"
					( Origin gPackager )
				)
				( objectStatus "U5D1.DF69" )
			)
			( pin "@baseboard_fab2_lib.baseboard_fab2(sch_1):page41_i285:vss(226)"
				( attribute "PN" "DF65"
					( Origin gPackager )
				)
				( objectStatus "U5D1.DF65" )
			)
			( pin "@baseboard_fab2_lib.baseboard_fab2(sch_1):page41_i285:vss(227)"
				( attribute "PN" "DF41"
					( Origin gPackager )
				)
				( objectStatus "U5D1.DF41" )
			)
			( pin "@baseboard_fab2_lib.baseboard_fab2(sch_1):page41_i285:vss(228)"
				( attribute "PN" "DF39"
					( Origin gPackager )
				)
				( objectStatus "U5D1.DF39" )
			)
			( pin "@baseboard_fab2_lib.baseboard_fab2(sch_1):page41_i285:vss(229)"
				( attribute "PN" "DF37"
					( Origin gPackager )
				)
				( objectStatus "U5D1.DF37" )
			)
			( pin "@baseboard_fab2_lib.baseboard_fab2(sch_1):page41_i285:vss(230)"
				( attribute "PN" "DF35"
					( Origin gPackager )
				)
				( objectStatus "U5D1.DF35" )
			)
			( pin "@baseboard_fab2_lib.baseboard_fab2(sch_1):page41_i285:vss(231)"
				( attribute "PN" "DF29"
					( Origin gPackager )
				)
				( objectStatus "U5D1.DF29" )
			)
			( pin "@baseboard_fab2_lib.baseboard_fab2(sch_1):page41_i285:vss(232)"
				( attribute "PN" "DF19"
					( Origin gPackager )
				)
				( objectStatus "U5D1.DF19" )
			)
			( pin "@baseboard_fab2_lib.baseboard_fab2(sch_1):page41_i285:vss(233)"
				( attribute "PN" "H51"
					( Origin gPackager )
				)
				( objectStatus "U5D1.H51" )
			)
			( pin "@baseboard_fab2_lib.baseboard_fab2(sch_1):page41_i285:vss(234)"
				( attribute "PN" "DF7"
					( Origin gPackager )
				)
				( objectStatus "U5D1.DF7" )
			)
			( pin "@baseboard_fab2_lib.baseboard_fab2(sch_1):page41_i285:vss(235)"
				( attribute "PN" "DF5"
					( Origin gPackager )
				)
				( objectStatus "U5D1.DF5" )
			)
			( pin "@baseboard_fab2_lib.baseboard_fab2(sch_1):page41_i285:vss(236)"
				( attribute "PN" "DE78"
					( Origin gPackager )
				)
				( objectStatus "U5D1.DE78" )
			)
			( pin "@baseboard_fab2_lib.baseboard_fab2(sch_1):page41_i285:vss(237)"
				( attribute "PN" "DE72"
					( Origin gPackager )
				)
				( objectStatus "U5D1.DE72" )
			)
			( pin "@baseboard_fab2_lib.baseboard_fab2(sch_1):page41_i285:vss(238)"
				( attribute "PN" "DE70"
					( Origin gPackager )
				)
				( objectStatus "U5D1.DE70" )
			)
			( pin "@baseboard_fab2_lib.baseboard_fab2(sch_1):page41_i285:vss(239)"
				( attribute "PN" "DE64"
					( Origin gPackager )
				)
				( objectStatus "U5D1.DE64" )
			)
			( pin "@baseboard_fab2_lib.baseboard_fab2(sch_1):page41_i285:vss(240)"
				( attribute "PN" "DE36"
					( Origin gPackager )
				)
				( objectStatus "U5D1.DE36" )
			)
			( pin "@baseboard_fab2_lib.baseboard_fab2(sch_1):page41_i285:vss(241)"
				( attribute "PN" "DE34"
					( Origin gPackager )
				)
				( objectStatus "U5D1.DE34" )
			)
			( pin "@baseboard_fab2_lib.baseboard_fab2(sch_1):page41_i285:vss(242)"
				( attribute "PN" "DE30"
					( Origin gPackager )
				)
				( objectStatus "U5D1.DE30" )
			)
			( pin "@baseboard_fab2_lib.baseboard_fab2(sch_1):page41_i285:vss(243)"
				( attribute "PN" "DE28"
					( Origin gPackager )
				)
				( objectStatus "U5D1.DE28" )
			)
			( pin "@baseboard_fab2_lib.baseboard_fab2(sch_1):page41_i285:vss(244)"
				( attribute "PN" "DE24"
					( Origin gPackager )
				)
				( objectStatus "U5D1.DE24" )
			)
			( pin "@baseboard_fab2_lib.baseboard_fab2(sch_1):page41_i285:vss(245)"
				( attribute "PN" "DE20"
					( Origin gPackager )
				)
				( objectStatus "U5D1.DE20" )
			)
			( pin "@baseboard_fab2_lib.baseboard_fab2(sch_1):page41_i285:vss(246)"
				( attribute "PN" "DE18"
					( Origin gPackager )
				)
				( objectStatus "U5D1.DE18" )
			)
			( pin "@baseboard_fab2_lib.baseboard_fab2(sch_1):page41_i285:vss(247)"
				( attribute "PN" "DE8"
					( Origin gPackager )
				)
				( objectStatus "U5D1.DE8" )
			)
			( pin "@baseboard_fab2_lib.baseboard_fab2(sch_1):page41_i285:vss(248)"
				( attribute "PN" "DE6"
					( Origin gPackager )
				)
				( objectStatus "U5D1.DE6" )
			)
			( pin "@baseboard_fab2_lib.baseboard_fab2(sch_1):page41_i285:vss(249)"
				( attribute "PN" "DD83"
					( Origin gPackager )
				)
				( objectStatus "U5D1.DD83" )
			)
			( pin "@baseboard_fab2_lib.baseboard_fab2(sch_1):page41_i285:vss(250)"
				( attribute "PN" "DD81"
					( Origin gPackager )
				)
				( objectStatus "U5D1.DD81" )
			)
			( pin "@baseboard_fab2_lib.baseboard_fab2(sch_1):page41_i285:vss(251)"
				( attribute "PN" "DD75"
					( Origin gPackager )
				)
				( objectStatus "U5D1.DD75" )
			)
			( pin "@baseboard_fab2_lib.baseboard_fab2(sch_1):page41_i285:vss(252)"
				( attribute "PN" "DD73"
					( Origin gPackager )
				)
				( objectStatus "U5D1.DD73" )
			)
			( pin "@baseboard_fab2_lib.baseboard_fab2(sch_1):page41_i285:vss(253)"
				( attribute "PN" "DD71"
					( Origin gPackager )
				)
				( objectStatus "U5D1.DD71" )
			)
			( pin "@baseboard_fab2_lib.baseboard_fab2(sch_1):page41_i285:vss(254)"
				( attribute "PN" "DD37"
					( Origin gPackager )
				)
				( objectStatus "U5D1.DD37" )
			)
			( pin "@baseboard_fab2_lib.baseboard_fab2(sch_1):page41_i285:vss(255)"
				( attribute "PN" "DD33"
					( Origin gPackager )
				)
				( objectStatus "U5D1.DD33" )
			)
			( pin "@baseboard_fab2_lib.baseboard_fab2(sch_1):page41_i285:vss(256)"
				( attribute "PN" "DD31"
					( Origin gPackager )
				)
				( objectStatus "U5D1.DD31" )
			)
			( pin "@baseboard_fab2_lib.baseboard_fab2(sch_1):page41_i285:vss(257)"
				( attribute "PN" "DD27"
					( Origin gPackager )
				)
				( objectStatus "U5D1.DD27" )
			)
			( pin "@baseboard_fab2_lib.baseboard_fab2(sch_1):page41_i285:vss(258)"
				( attribute "PN" "DD23"
					( Origin gPackager )
				)
				( objectStatus "U5D1.DD23" )
			)
			( pin "@baseboard_fab2_lib.baseboard_fab2(sch_1):page41_i285:vss(259)"
				( attribute "PN" "DD11"
					( Origin gPackager )
				)
				( objectStatus "U5D1.DD11" )
			)
			( pin "@baseboard_fab2_lib.baseboard_fab2(sch_1):page41_i285:vss(260)"
				( attribute "PN" "DC86"
					( Origin gPackager )
				)
				( objectStatus "U5D1.DC86" )
			)
			( pin "@baseboard_fab2_lib.baseboard_fab2(sch_1):page41_i285:vss(261)"
				( attribute "PN" "DC84"
					( Origin gPackager )
				)
				( objectStatus "U5D1.DC84" )
			)
			( pin "@baseboard_fab2_lib.baseboard_fab2(sch_1):page41_i285:vss(262)"
				( attribute "PN" "DC78"
					( Origin gPackager )
				)
				( objectStatus "U5D1.DC78" )
			)
			( pin "@baseboard_fab2_lib.baseboard_fab2(sch_1):page41_i285:vss(263)"
				( attribute "PN" "DC70"
					( Origin gPackager )
				)
				( objectStatus "U5D1.DC70" )
			)
			( pin "@baseboard_fab2_lib.baseboard_fab2(sch_1):page41_i285:vss(264)"
				( attribute "PN" "DC68"
					( Origin gPackager )
				)
				( objectStatus "U5D1.DC68" )
			)
			( pin "@baseboard_fab2_lib.baseboard_fab2(sch_1):page41_i285:vss(265)"
				( attribute "PN" "DC66"
					( Origin gPackager )
				)
				( objectStatus "U5D1.DC66" )
			)
			( pin "@baseboard_fab2_lib.baseboard_fab2(sch_1):page41_i285:vss(266)"
				( attribute "PN" "DC64"
					( Origin gPackager )
				)
				( objectStatus "U5D1.DC64" )
			)
			( pin "@baseboard_fab2_lib.baseboard_fab2(sch_1):page41_i285:vss(267)"
				( attribute "PN" "DC42"
					( Origin gPackager )
				)
				( objectStatus "U5D1.DC42" )
			)
			( pin "@baseboard_fab2_lib.baseboard_fab2(sch_1):page41_i285:vss(268)"
				( attribute "PN" "DC38"
					( Origin gPackager )
				)
				( objectStatus "U5D1.DC38" )
			)
			( pin "@baseboard_fab2_lib.baseboard_fab2(sch_1):page41_i285:vss(269)"
				( attribute "PN" "DC32"
					( Origin gPackager )
				)
				( objectStatus "U5D1.DC32" )
			)
			( pin "@baseboard_fab2_lib.baseboard_fab2(sch_1):page41_i285:vss(270)"
				( attribute "PN" "DC26"
					( Origin gPackager )
				)
				( objectStatus "U5D1.DC26" )
			)
			( pin "@baseboard_fab2_lib.baseboard_fab2(sch_1):page41_i285:vss(271)"
				( attribute "PN" "DC24"
					( Origin gPackager )
				)
				( objectStatus "U5D1.DC24" )
			)
			( pin "@baseboard_fab2_lib.baseboard_fab2(sch_1):page41_i285:vss(272)"
				( attribute "PN" "DC14"
					( Origin gPackager )
				)
				( objectStatus "U5D1.DC14" )
			)
			( pin "@baseboard_fab2_lib.baseboard_fab2(sch_1):page41_i285:vss(273)"
				( attribute "PN" "DB85"
					( Origin gPackager )
				)
				( objectStatus "U5D1.DB85" )
			)
			( pin "@baseboard_fab2_lib.baseboard_fab2(sch_1):page41_i285:vss(274)"
				( attribute "PN" "DB83"
					( Origin gPackager )
				)
				( objectStatus "U5D1.DB83" )
			)
			( pin "@baseboard_fab2_lib.baseboard_fab2(sch_1):page41_i285:vss(275)"
				( attribute "PN" "DB77"
					( Origin gPackager )
				)
				( objectStatus "U5D1.DB77" )
			)
			( pin "@baseboard_fab2_lib.baseboard_fab2(sch_1):page41_i285:vss(276)"
				( attribute "PN" "DB73"
					( Origin gPackager )
				)
				( objectStatus "U5D1.DB73" )
			)
			( pin "@baseboard_fab2_lib.baseboard_fab2(sch_1):page41_i285:vss(277)"
				( attribute "PN" "DB49"
					( Origin gPackager )
				)
				( objectStatus "U5D1.DB49" )
			)
			( pin "@baseboard_fab2_lib.baseboard_fab2(sch_1):page41_i285:vss(278)"
				( attribute "PN" "DB47"
					( Origin gPackager )
				)
				( objectStatus "U5D1.DB47" )
			)
			( pin "@baseboard_fab2_lib.baseboard_fab2(sch_1):page41_i285:vss(279)"
				( attribute "PN" "DB41"
					( Origin gPackager )
				)
				( objectStatus "U5D1.DB41" )
			)
			( pin "@baseboard_fab2_lib.baseboard_fab2(sch_1):page41_i285:vss(280)"
				( attribute "PN" "DB39"
					( Origin gPackager )
				)
				( objectStatus "U5D1.DB39" )
			)
			( pin "@baseboard_fab2_lib.baseboard_fab2(sch_1):page41_i285:vss(281)"
				( attribute "PN" "DB25"
					( Origin gPackager )
				)
				( objectStatus "U5D1.DB25" )
			)
			( pin "@baseboard_fab2_lib.baseboard_fab2(sch_1):page41_i285:vss(282)"
				( attribute "PN" "DB23"
					( Origin gPackager )
				)
				( objectStatus "U5D1.DB23" )
			)
			( pin "@baseboard_fab2_lib.baseboard_fab2(sch_1):page41_i285:vss(283)"
				( attribute "PN" "DB17"
					( Origin gPackager )
				)
				( objectStatus "U5D1.DB17" )
			)
			( pin "@baseboard_fab2_lib.baseboard_fab2(sch_1):page41_i285:vss(284)"
				( attribute "PN" "DB13"
					( Origin gPackager )
				)
				( objectStatus "U5D1.DB13" )
			)
			( pin "@baseboard_fab2_lib.baseboard_fab2(sch_1):page41_i285:vss(285)"
				( attribute "PN" "DB3"
					( Origin gPackager )
				)
				( objectStatus "U5D1.DB3" )
			)
			( pin "@baseboard_fab2_lib.baseboard_fab2(sch_1):page41_i285:vss(286)"
				( attribute "PN" "DA80"
					( Origin gPackager )
				)
				( objectStatus "U5D1.DA80" )
			)
			( pin "@baseboard_fab2_lib.baseboard_fab2(sch_1):page41_i285:vss(287)"
				( attribute "PN" "DA78"
					( Origin gPackager )
				)
				( objectStatus "U5D1.DA78" )
			)
			( pin "@baseboard_fab2_lib.baseboard_fab2(sch_1):page41_i285:vss(288)"
				( attribute "PN" "DA76"
					( Origin gPackager )
				)
				( objectStatus "U5D1.DA76" )
			)
			( pin "@baseboard_fab2_lib.baseboard_fab2(sch_1):page41_i285:vss(289)"
				( attribute "PN" "DA74"
					( Origin gPackager )
				)
				( objectStatus "U5D1.DA74" )
			)
			( pin "@baseboard_fab2_lib.baseboard_fab2(sch_1):page41_i285:vss(290)"
				( attribute "PN" "DA70"
					( Origin gPackager )
				)
				( objectStatus "U5D1.DA70" )
			)
			( pin "@baseboard_fab2_lib.baseboard_fab2(sch_1):page41_i285:vss(291)"
				( attribute "PN" "DA64"
					( Origin gPackager )
				)
				( objectStatus "U5D1.DA64" )
			)
			( pin "@baseboard_fab2_lib.baseboard_fab2(sch_1):page41_i285:vss(292)"
				( attribute "PN" "DA50"
					( Origin gPackager )
				)
				( objectStatus "U5D1.DA50" )
			)
			( pin "@baseboard_fab2_lib.baseboard_fab2(sch_1):page41_i285:vss(293)"
				( attribute "PN" "DA48"
					( Origin gPackager )
				)
				( objectStatus "U5D1.DA48" )
			)
			( pin "@baseboard_fab2_lib.baseboard_fab2(sch_1):page41_i286:vss(0)"
				( attribute "PN" "EF79"
					( Origin gPackager )
				)
				( objectStatus "U5D1.EF79" )
			)
			( pin "@baseboard_fab2_lib.baseboard_fab2(sch_1):page41_i286:vss(1)"
				( attribute "PN" "EF75"
					( Origin gPackager )
				)
				( objectStatus "U5D1.EF75" )
			)
			( pin "@baseboard_fab2_lib.baseboard_fab2(sch_1):page41_i286:vss(2)"
				( attribute "PN" "EF71"
					( Origin gPackager )
				)
				( objectStatus "U5D1.EF71" )
			)
			( pin "@baseboard_fab2_lib.baseboard_fab2(sch_1):page41_i286:vss(3)"
				( attribute "PN" "EE78"
					( Origin gPackager )
				)
				( objectStatus "U5D1.EE78" )
			)
			( pin "@baseboard_fab2_lib.baseboard_fab2(sch_1):page41_i286:vss(4)"
				( attribute "PN" "EE76"
					( Origin gPackager )
				)
				( objectStatus "U5D1.EE76" )
			)
			( pin "@baseboard_fab2_lib.baseboard_fab2(sch_1):page41_i286:vss(5)"
				( attribute "PN" "EE70"
					( Origin gPackager )
				)
				( objectStatus "U5D1.EE70" )
			)
			( pin "@baseboard_fab2_lib.baseboard_fab2(sch_1):page41_i286:vss(6)"
				( attribute "PN" "EE36"
					( Origin gPackager )
				)
				( objectStatus "U5D1.EE36" )
			)
			( pin "@baseboard_fab2_lib.baseboard_fab2(sch_1):page41_i286:vss(7)"
				( attribute "PN" "EE34"
					( Origin gPackager )
				)
				( objectStatus "U5D1.EE34" )
			)
			( pin "@baseboard_fab2_lib.baseboard_fab2(sch_1):page41_i286:vss(8)"
				( attribute "PN" "EE30"
					( Origin gPackager )
				)
				( objectStatus "U5D1.EE30" )
			)
			( pin "@baseboard_fab2_lib.baseboard_fab2(sch_1):page41_i286:vss(9)"
				( attribute "PN" "EE28"
					( Origin gPackager )
				)
				( objectStatus "U5D1.EE28" )
			)
			( pin "@baseboard_fab2_lib.baseboard_fab2(sch_1):page41_i286:vss(10)"
				( attribute "PN" "EE24"
					( Origin gPackager )
				)
				( objectStatus "U5D1.EE24" )
			)
			( pin "@baseboard_fab2_lib.baseboard_fab2(sch_1):page41_i286:vss(11)"
				( attribute "PN" "ED77"
					( Origin gPackager )
				)
				( objectStatus "U5D1.ED77" )
			)
			( pin "@baseboard_fab2_lib.baseboard_fab2(sch_1):page41_i286:vss(12)"
				( attribute "PN" "ED35"
					( Origin gPackager )
				)
				( objectStatus "U5D1.ED35" )
			)
			( pin "@baseboard_fab2_lib.baseboard_fab2(sch_1):page41_i286:vss(13)"
				( attribute "PN" "ED29"
					( Origin gPackager )
				)
				( objectStatus "U5D1.ED29" )
			)
			( pin "@baseboard_fab2_lib.baseboard_fab2(sch_1):page41_i286:vss(14)"
				( attribute "PN" "ED23"
					( Origin gPackager )
				)
				( objectStatus "U5D1.ED23" )
			)
			( pin "@baseboard_fab2_lib.baseboard_fab2(sch_1):page41_i286:vss(15)"
				( attribute "PN" "ED15"
					( Origin gPackager )
				)
				( objectStatus "U5D1.ED15" )
			)
			( pin "@baseboard_fab2_lib.baseboard_fab2(sch_1):page41_i286:vss(16)"
				( attribute "PN" "ED11"
					( Origin gPackager )
				)
				( objectStatus "U5D1.ED11" )
			)
			( pin "@baseboard_fab2_lib.baseboard_fab2(sch_1):page41_i286:vss(17)"
				( attribute "PN" "EC76"
					( Origin gPackager )
				)
				( objectStatus "U5D1.EC76" )
			)
			( pin "@baseboard_fab2_lib.baseboard_fab2(sch_1):page41_i286:vss(18)"
				( attribute "PN" "EC74"
					( Origin gPackager )
				)
				( objectStatus "U5D1.EC74" )
			)
			( pin "@baseboard_fab2_lib.baseboard_fab2(sch_1):page41_i286:vss(19)"
				( attribute "PN" "EC72"
					( Origin gPackager )
				)
				( objectStatus "U5D1.EC72" )
			)
			( pin "@baseboard_fab2_lib.baseboard_fab2(sch_1):page41_i286:vss(20)"
				( attribute "PN" "EC70"
					( Origin gPackager )
				)
				( objectStatus "U5D1.EC70" )
			)
			( pin "@baseboard_fab2_lib.baseboard_fab2(sch_1):page41_i286:vss(21)"
				( attribute "PN" "EC10"
					( Origin gPackager )
				)
				( objectStatus "U5D1.EC10" )
			)
			( pin "@baseboard_fab2_lib.baseboard_fab2(sch_1):page41_i286:vss(22)"
				( attribute "PN" "EB69"
					( Origin gPackager )
				)
				( objectStatus "U5D1.EB69" )
			)
			( pin "@baseboard_fab2_lib.baseboard_fab2(sch_1):page41_i286:vss(23)"
				( attribute "PN" "EB65"
					( Origin gPackager )
				)
				( objectStatus "U5D1.EB65" )
			)
			( pin "@baseboard_fab2_lib.baseboard_fab2(sch_1):page41_i286:vss(24)"
				( attribute "PN" "EB41"
					( Origin gPackager )
				)
				( objectStatus "U5D1.EB41" )
			)
			( pin "@baseboard_fab2_lib.baseboard_fab2(sch_1):page41_i286:vss(25)"
				( attribute "PN" "EB39"
					( Origin gPackager )
				)
				( objectStatus "U5D1.EB39" )
			)
			( pin "@baseboard_fab2_lib.baseboard_fab2(sch_1):page41_i286:vss(26)"
				( attribute "PN" "EB37"
					( Origin gPackager )
				)
				( objectStatus "U5D1.EB37" )
			)
			( pin "@baseboard_fab2_lib.baseboard_fab2(sch_1):page41_i286:vss(27)"
				( attribute "PN" "EB35"
					( Origin gPackager )
				)
				( objectStatus "U5D1.EB35" )
			)
			( pin "@baseboard_fab2_lib.baseboard_fab2(sch_1):page41_i286:vss(28)"
				( attribute "PN" "EB33"
					( Origin gPackager )
				)
				( objectStatus "U5D1.EB33" )
			)
			( pin "@baseboard_fab2_lib.baseboard_fab2(sch_1):page41_i286:vss(29)"
				( attribute "PN" "EB31"
					( Origin gPackager )
				)
				( objectStatus "U5D1.EB31" )
			)
			( pin "@baseboard_fab2_lib.baseboard_fab2(sch_1):page41_i286:vss(30)"
				( attribute "PN" "EB29"
					( Origin gPackager )
				)
				( objectStatus "U5D1.EB29" )
			)
			( pin "@baseboard_fab2_lib.baseboard_fab2(sch_1):page41_i286:vss(31)"
				( attribute "PN" "EB27"
					( Origin gPackager )
				)
				( objectStatus "U5D1.EB27" )
			)
			( pin "@baseboard_fab2_lib.baseboard_fab2(sch_1):page41_i286:vss(32)"
				( attribute "PN" "EB25"
					( Origin gPackager )
				)
				( objectStatus "U5D1.EB25" )
			)
			( pin "@baseboard_fab2_lib.baseboard_fab2(sch_1):page41_i286:vss(33)"
				( attribute "PN" "EB23"
					( Origin gPackager )
				)
				( objectStatus "U5D1.EB23" )
			)
			( pin "@baseboard_fab2_lib.baseboard_fab2(sch_1):page41_i286:vss(34)"
				( attribute "PN" "BR18"
					( Origin gPackager )
				)
				( objectStatus "U5D1.BR18" )
			)
			( pin "@baseboard_fab2_lib.baseboard_fab2(sch_1):page41_i286:vss(35)"
				( attribute "PN" "EB13"
					( Origin gPackager )
				)
				( objectStatus "U5D1.EB13" )
			)
			( pin "@baseboard_fab2_lib.baseboard_fab2(sch_1):page41_i286:vss(36)"
				( attribute "PN" "EA82"
					( Origin gPackager )
				)
				( objectStatus "U5D1.EA82" )
			)
			( pin "@baseboard_fab2_lib.baseboard_fab2(sch_1):page41_i286:vss(37)"
				( attribute "PN" "EA80"
					( Origin gPackager )
				)
				( objectStatus "U5D1.EA80" )
			)
			( pin "@baseboard_fab2_lib.baseboard_fab2(sch_1):page41_i286:vss(38)"
				( attribute "PN" "EA78"
					( Origin gPackager )
				)
				( objectStatus "U5D1.EA78" )
			)
			( pin "@baseboard_fab2_lib.baseboard_fab2(sch_1):page41_i286:vss(39)"
				( attribute "PN" "EA76"
					( Origin gPackager )
				)
				( objectStatus "U5D1.EA76" )
			)
			( pin "@baseboard_fab2_lib.baseboard_fab2(sch_1):page41_i286:vss(40)"
				( attribute "PN" "EA70"
					( Origin gPackager )
				)
				( objectStatus "U5D1.EA70" )
			)
			( pin "@baseboard_fab2_lib.baseboard_fab2(sch_1):page41_i286:vss(41)"
				( attribute "PN" "EA64"
					( Origin gPackager )
				)
				( objectStatus "U5D1.EA64" )
			)
			( pin "@baseboard_fab2_lib.baseboard_fab2(sch_1):page41_i286:vss(42)"
				( attribute "PN" "EA42"
					( Origin gPackager )
				)
				( objectStatus "U5D1.EA42" )
			)
			( pin "@baseboard_fab2_lib.baseboard_fab2(sch_1):page41_i286:vss(43)"
				( attribute "PN" "EA22"
					( Origin gPackager )
				)
				( objectStatus "U5D1.EA22" )
			)
			( pin "@baseboard_fab2_lib.baseboard_fab2(sch_1):page41_i286:vss(44)"
				( attribute "PN" "EA20"
					( Origin gPackager )
				)
				( objectStatus "U5D1.EA20" )
			)
			( pin "@baseboard_fab2_lib.baseboard_fab2(sch_1):page41_i286:vss(45)"
				( attribute "PN" "EA16"
					( Origin gPackager )
				)
				( objectStatus "U5D1.EA16" )
			)
			( pin "@baseboard_fab2_lib.baseboard_fab2(sch_1):page41_i286:vss(46)"
				( attribute "PN" "J16"
					( Origin gPackager )
				)
				( objectStatus "U5D1.J16" )
			)
			( pin "@baseboard_fab2_lib.baseboard_fab2(sch_1):page41_i286:vss(47)"
				( attribute "PN" "EA6"
					( Origin gPackager )
				)
				( objectStatus "U5D1.EA6" )
			)
			( pin "@baseboard_fab2_lib.baseboard_fab2(sch_1):page41_i286:vss(48)"
				( attribute "PN" "DY75"
					( Origin gPackager )
				)
				( objectStatus "U5D1.DY75" )
			)
			( pin "@baseboard_fab2_lib.baseboard_fab2(sch_1):page41_i286:vss(49)"
				( attribute "PN" "DY71"
					( Origin gPackager )
				)
				( objectStatus "U5D1.DY71" )
			)
			( pin "@baseboard_fab2_lib.baseboard_fab2(sch_1):page41_i286:vss(50)"
				( attribute "PN" "DY41"
					( Origin gPackager )
				)
				( objectStatus "U5D1.DY41" )
			)
			( pin "@baseboard_fab2_lib.baseboard_fab2(sch_1):page41_i286:vss(51)"
				( attribute "PN" "DY35"
					( Origin gPackager )
				)
				( objectStatus "U5D1.DY35" )
			)
			( pin "@baseboard_fab2_lib.baseboard_fab2(sch_1):page41_i286:vss(52)"
				( attribute "PN" "DY29"
					( Origin gPackager )
				)
				( objectStatus "U5D1.DY29" )
			)
			( pin "@baseboard_fab2_lib.baseboard_fab2(sch_1):page41_i286:vss(53)"
				( attribute "PN" "DY23"
					( Origin gPackager )
				)
				( objectStatus "U5D1.DY23" )
			)
			( pin "@baseboard_fab2_lib.baseboard_fab2(sch_1):page41_i286:vss(54)"
				( attribute "PN" "DY19"
					( Origin gPackager )
				)
				( objectStatus "U5D1.DY19" )
			)
			( pin "@baseboard_fab2_lib.baseboard_fab2(sch_1):page41_i286:vss(55)"
				( attribute "PN" "DY5"
					( Origin gPackager )
				)
				( objectStatus "U5D1.DY5" )
			)
			( pin "@baseboard_fab2_lib.baseboard_fab2(sch_1):page41_i286:vss(56)"
				( attribute "PN" "DW84"
					( Origin gPackager )
				)
				( objectStatus "U5D1.DW84" )
			)
			( pin "@baseboard_fab2_lib.baseboard_fab2(sch_1):page41_i286:vss(57)"
				( attribute "PN" "DW82"
					( Origin gPackager )
				)
				( objectStatus "U5D1.DW82" )
			)
			( pin "@baseboard_fab2_lib.baseboard_fab2(sch_1):page41_i286:vss(58)"
				( attribute "PN" "DW8"
					( Origin gPackager )
				)
				( objectStatus "U5D1.DW8" )
			)
			( pin "@baseboard_fab2_lib.baseboard_fab2(sch_1):page41_i286:vss(59)"
				( attribute "PN" "DW76"
					( Origin gPackager )
				)
				( objectStatus "U5D1.DW76" )
			)
			( pin "@baseboard_fab2_lib.baseboard_fab2(sch_1):page41_i286:vss(60)"
				( attribute "PN" "DW74"
					( Origin gPackager )
				)
				( objectStatus "U5D1.DW74" )
			)
			( pin "@baseboard_fab2_lib.baseboard_fab2(sch_1):page41_i286:vss(61)"
				( attribute "PN" "DW72"
					( Origin gPackager )
				)
				( objectStatus "U5D1.DW72" )
			)
			( pin "@baseboard_fab2_lib.baseboard_fab2(sch_1):page41_i286:vss(62)"
				( attribute "PN" "DW70"
					( Origin gPackager )
				)
				( objectStatus "U5D1.DW70" )
			)
			( pin "@baseboard_fab2_lib.baseboard_fab2(sch_1):page41_i286:vss(63)"
				( attribute "PN" "DW68"
					( Origin gPackager )
				)
				( objectStatus "U5D1.DW68" )
			)
			( pin "@baseboard_fab2_lib.baseboard_fab2(sch_1):page41_i286:vss(64)"
				( attribute "PN" "DW66"
					( Origin gPackager )
				)
				( objectStatus "U5D1.DW66" )
			)
			( pin "@baseboard_fab2_lib.baseboard_fab2(sch_1):page41_i286:vss(65)"
				( attribute "PN" "DW64"
					( Origin gPackager )
				)
				( objectStatus "U5D1.DW64" )
			)
			( pin "@baseboard_fab2_lib.baseboard_fab2(sch_1):page41_i286:vss(66)"
				( attribute "PN" "DW40"
					( Origin gPackager )
				)
				( objectStatus "U5D1.DW40" )
			)
			( pin "@baseboard_fab2_lib.baseboard_fab2(sch_1):page41_i286:vss(67)"
				( attribute "PN" "DW36"
					( Origin gPackager )
				)
				( objectStatus "U5D1.DW36" )
			)
			( pin "@baseboard_fab2_lib.baseboard_fab2(sch_1):page41_i286:vss(68)"
				( attribute "PN" "DW34"
					( Origin gPackager )
				)
				( objectStatus "U5D1.DW34" )
			)
			( pin "@baseboard_fab2_lib.baseboard_fab2(sch_1):page41_i286:vss(69)"
				( attribute "PN" "DW30"
					( Origin gPackager )
				)
				( objectStatus "U5D1.DW30" )
			)
			( pin "@baseboard_fab2_lib.baseboard_fab2(sch_1):page41_i286:vss(70)"
				( attribute "PN" "DW28"
					( Origin gPackager )
				)
				( objectStatus "U5D1.DW28" )
			)
			( pin "@baseboard_fab2_lib.baseboard_fab2(sch_1):page41_i286:vss(71)"
				( attribute "PN" "DW24"
					( Origin gPackager )
				)
				( objectStatus "U5D1.DW24" )
			)
			( pin "@baseboard_fab2_lib.baseboard_fab2(sch_1):page41_i286:vss(72)"
				( attribute "PN" "DW20"
					( Origin gPackager )
				)
				( objectStatus "U5D1.DW20" )
			)
			( pin "@baseboard_fab2_lib.baseboard_fab2(sch_1):page41_i286:vss(73)"
				( attribute "PN" "DW12"
					( Origin gPackager )
				)
				( objectStatus "U5D1.DW12" )
			)
			( pin "@baseboard_fab2_lib.baseboard_fab2(sch_1):page41_i286:vss(74)"
				( attribute "PN" "DV81"
					( Origin gPackager )
				)
				( objectStatus "U5D1.DV81" )
			)
			( pin "@baseboard_fab2_lib.baseboard_fab2(sch_1):page41_i286:vss(75)"
				( attribute "PN" "DV77"
					( Origin gPackager )
				)
				( objectStatus "U5D1.DV77" )
			)
			( pin "@baseboard_fab2_lib.baseboard_fab2(sch_1):page41_i286:vss(76)"
				( attribute "PN" "DV73"
					( Origin gPackager )
				)
				( objectStatus "U5D1.DV73" )
			)
			( pin "@baseboard_fab2_lib.baseboard_fab2(sch_1):page41_i286:vss(77)"
				( attribute "PN" "DV39"
					( Origin gPackager )
				)
				( objectStatus "U5D1.DV39" )
			)
			( pin "@baseboard_fab2_lib.baseboard_fab2(sch_1):page41_i286:vss(78)"
				( attribute "PN" "DV37"
					( Origin gPackager )
				)
				( objectStatus "U5D1.DV37" )
			)
			( pin "@baseboard_fab2_lib.baseboard_fab2(sch_1):page41_i286:vss(79)"
				( attribute "PN" "DV33"
					( Origin gPackager )
				)
				( objectStatus "U5D1.DV33" )
			)
			( pin "@baseboard_fab2_lib.baseboard_fab2(sch_1):page41_i286:vss(80)"
				( attribute "PN" "DV31"
					( Origin gPackager )
				)
				( objectStatus "U5D1.DV31" )
			)
			( pin "@baseboard_fab2_lib.baseboard_fab2(sch_1):page41_i286:vss(81)"
				( attribute "PN" "DV27"
					( Origin gPackager )
				)
				( objectStatus "U5D1.DV27" )
			)
			( pin "@baseboard_fab2_lib.baseboard_fab2(sch_1):page41_i286:vss(82)"
				( attribute "PN" "DV25"
					( Origin gPackager )
				)
				( objectStatus "U5D1.DV25" )
			)
			( pin "@baseboard_fab2_lib.baseboard_fab2(sch_1):page41_i286:vss(83)"
				( attribute "PN" "DV21"
					( Origin gPackager )
				)
				( objectStatus "U5D1.DV21" )
			)
			( pin "@baseboard_fab2_lib.baseboard_fab2(sch_1):page41_i286:vss(84)"
				( attribute "PN" "DU84"
					( Origin gPackager )
				)
				( objectStatus "U5D1.DU84" )
			)
			( pin "@baseboard_fab2_lib.baseboard_fab2(sch_1):page41_i286:vss(85)"
				( attribute "PN" "DU82"
					( Origin gPackager )
				)
				( objectStatus "U5D1.DU82" )
			)
			( pin "@baseboard_fab2_lib.baseboard_fab2(sch_1):page41_i286:vss(86)"
				( attribute "PN" "DU80"
					( Origin gPackager )
				)
				( objectStatus "U5D1.DU80" )
			)
			( pin "@baseboard_fab2_lib.baseboard_fab2(sch_1):page41_i286:vss(87)"
				( attribute "PN" "DU78"
					( Origin gPackager )
				)
				( objectStatus "U5D1.DU78" )
			)
			( pin "@baseboard_fab2_lib.baseboard_fab2(sch_1):page41_i286:vss(88)"
				( attribute "PN" "DU72"
					( Origin gPackager )
				)
				( objectStatus "U5D1.DU72" )
			)
			( pin "@baseboard_fab2_lib.baseboard_fab2(sch_1):page41_i286:vss(89)"
				( attribute "PN" "DU70"
					( Origin gPackager )
				)
				( objectStatus "U5D1.DU70" )
			)
			( pin "@baseboard_fab2_lib.baseboard_fab2(sch_1):page41_i286:vss(90)"
				( attribute "PN" "DU38"
					( Origin gPackager )
				)
				( objectStatus "U5D1.DU38" )
			)
			( pin "@baseboard_fab2_lib.baseboard_fab2(sch_1):page41_i286:vss(91)"
				( attribute "PN" "DU32"
					( Origin gPackager )
				)
				( objectStatus "U5D1.DU32" )
			)
			( pin "@baseboard_fab2_lib.baseboard_fab2(sch_1):page41_i286:vss(92)"
				( attribute "PN" "DU26"
					( Origin gPackager )
				)
				( objectStatus "U5D1.DU26" )
			)
			( pin "@baseboard_fab2_lib.baseboard_fab2(sch_1):page41_i286:vss(93)"
				( attribute "PN" "DU22"
					( Origin gPackager )
				)
				( objectStatus "U5D1.DU22" )
			)
			( pin "@baseboard_fab2_lib.baseboard_fab2(sch_1):page41_i286:vss(94)"
				( attribute "PN" "CN14"
					( Origin gPackager )
				)
				( objectStatus "U5D1.CN14" )
			)
			( pin "@baseboard_fab2_lib.baseboard_fab2(sch_1):page41_i286:vss(95)"
				( attribute "PN" "DU14"
					( Origin gPackager )
				)
				( objectStatus "U5D1.DU14" )
			)
			( pin "@baseboard_fab2_lib.baseboard_fab2(sch_1):page41_i286:vss(96)"
				( attribute "PN" "DU10"
					( Origin gPackager )
				)
				( objectStatus "U5D1.DU10" )
			)
			( pin "@baseboard_fab2_lib.baseboard_fab2(sch_1):page41_i286:vss(97)"
				( attribute "PN" "DT85"
					( Origin gPackager )
				)
				( objectStatus "U5D1.DT85" )
			)
			( pin "@baseboard_fab2_lib.baseboard_fab2(sch_1):page41_i286:vss(98)"
				( attribute "PN" "DT83"
					( Origin gPackager )
				)
				( objectStatus "U5D1.DT83" )
			)
			( pin "@baseboard_fab2_lib.baseboard_fab2(sch_1):page41_i286:vss(99)"
				( attribute "PN" "DT79"
					( Origin gPackager )
				)
				( objectStatus "U5D1.DT79" )
			)
			( pin "@baseboard_fab2_lib.baseboard_fab2(sch_1):page41_i286:vss(100)"
				( attribute "PN" "DT69"
					( Origin gPackager )
				)
				( objectStatus "U5D1.DT69" )
			)
			( pin "@baseboard_fab2_lib.baseboard_fab2(sch_1):page41_i286:vss(101)"
				( attribute "PN" "DT65"
					( Origin gPackager )
				)
				( objectStatus "U5D1.DT65" )
			)
			( pin "@baseboard_fab2_lib.baseboard_fab2(sch_1):page41_i286:vss(102)"
				( attribute "PN" "DH21"
					( Origin gPackager )
				)
				( objectStatus "U5D1.DH21" )
			)
			( pin "@baseboard_fab2_lib.baseboard_fab2(sch_1):page41_i286:vss(103)"
				( attribute "PN" "DT17"
					( Origin gPackager )
				)
				( objectStatus "U5D1.DT17" )
			)
			( pin "@baseboard_fab2_lib.baseboard_fab2(sch_1):page41_i286:vss(104)"
				( attribute "PN" "DT3"
					( Origin gPackager )
				)
				( objectStatus "U5D1.DT3" )
			)
			( pin "@baseboard_fab2_lib.baseboard_fab2(sch_1):page41_i286:vss(105)"
				( attribute "PN" "DR78"
					( Origin gPackager )
				)
				( objectStatus "U5D1.DR78" )
			)
			( pin "@baseboard_fab2_lib.baseboard_fab2(sch_1):page41_i286:vss(106)"
				( attribute "PN" "DR76"
					( Origin gPackager )
				)
				( objectStatus "U5D1.DR76" )
			)
			( pin "@baseboard_fab2_lib.baseboard_fab2(sch_1):page41_i286:vss(107)"
				( attribute "PN" "DR74"
					( Origin gPackager )
				)
				( objectStatus "U5D1.DR74" )
			)
			( pin "@baseboard_fab2_lib.baseboard_fab2(sch_1):page41_i286:vss(108)"
				( attribute "PN" "DR72"
					( Origin gPackager )
				)
				( objectStatus "U5D1.DR72" )
			)
			( pin "@baseboard_fab2_lib.baseboard_fab2(sch_1):page41_i286:vss(109)"
				( attribute "PN" "DR70"
					( Origin gPackager )
				)
				( objectStatus "U5D1.DR70" )
			)
			( pin "@baseboard_fab2_lib.baseboard_fab2(sch_1):page41_i286:vss(110)"
				( attribute "PN" "DR68"
					( Origin gPackager )
				)
				( objectStatus "U5D1.DR68" )
			)
			( pin "@baseboard_fab2_lib.baseboard_fab2(sch_1):page41_i286:vss(111)"
				( attribute "PN" "DR66"
					( Origin gPackager )
				)
				( objectStatus "U5D1.DR66" )
			)
			( pin "@baseboard_fab2_lib.baseboard_fab2(sch_1):page41_i286:vss(112)"
				( attribute "PN" "DR42"
					( Origin gPackager )
				)
				( objectStatus "U5D1.DR42" )
			)
			( pin "@baseboard_fab2_lib.baseboard_fab2(sch_1):page41_i286:vss(113)"
				( attribute "PN" "DR40"
					( Origin gPackager )
				)
				( objectStatus "U5D1.DR40" )
			)
			( pin "@baseboard_fab2_lib.baseboard_fab2(sch_1):page41_i286:vss(114)"
				( attribute "PN" "DR38"
					( Origin gPackager )
				)
				( objectStatus "U5D1.DR38" )
			)
			( pin "@baseboard_fab2_lib.baseboard_fab2(sch_1):page41_i286:vss(115)"
				( attribute "PN" "DR36"
					( Origin gPackager )
				)
				( objectStatus "U5D1.DR36" )
			)
			( pin "@baseboard_fab2_lib.baseboard_fab2(sch_1):page41_i286:vss(116)"
				( attribute "PN" "DR34"
					( Origin gPackager )
				)
				( objectStatus "U5D1.DR34" )
			)
			( pin "@baseboard_fab2_lib.baseboard_fab2(sch_1):page41_i286:vss(117)"
				( attribute "PN" "DR32"
					( Origin gPackager )
				)
				( objectStatus "U5D1.DR32" )
			)
			( pin "@baseboard_fab2_lib.baseboard_fab2(sch_1):page41_i286:vss(118)"
				( attribute "PN" "DR30"
					( Origin gPackager )
				)
				( objectStatus "U5D1.DR30" )
			)
			( pin "@baseboard_fab2_lib.baseboard_fab2(sch_1):page41_i286:vss(119)"
				( attribute "PN" "DR28"
					( Origin gPackager )
				)
				( objectStatus "U5D1.DR28" )
			)
			( pin "@baseboard_fab2_lib.baseboard_fab2(sch_1):page41_i286:vss(120)"
				( attribute "PN" "DR26"
					( Origin gPackager )
				)
				( objectStatus "U5D1.DR26" )
			)
			( pin "@baseboard_fab2_lib.baseboard_fab2(sch_1):page41_i286:vss(121)"
				( attribute "PN" "DR24"
					( Origin gPackager )
				)
				( objectStatus "U5D1.DR24" )
			)
			( pin "@baseboard_fab2_lib.baseboard_fab2(sch_1):page41_i286:vss(122)"
				( attribute "PN" "DR22"
					( Origin gPackager )
				)
				( objectStatus "U5D1.DR22" )
			)
			( pin "@baseboard_fab2_lib.baseboard_fab2(sch_1):page41_i286:vss(123)"
				( attribute "PN" "DR20"
					( Origin gPackager )
				)
				( objectStatus "U5D1.DR20" )
			)
			( pin "@baseboard_fab2_lib.baseboard_fab2(sch_1):page41_i286:vss(124)"
				( attribute "PN" "CL22"
					( Origin gPackager )
				)
				( objectStatus "U5D1.CL22" )
			)
			( pin "@baseboard_fab2_lib.baseboard_fab2(sch_1):page41_i286:vss(125)"
				( attribute "PN" "CA20"
					( Origin gPackager )
				)
				( objectStatus "U5D1.CA20" )
			)
			( pin "@baseboard_fab2_lib.baseboard_fab2(sch_1):page41_i286:vss(126)"
				( attribute "PN" "DR6"
					( Origin gPackager )
				)
				( objectStatus "U5D1.DR6" )
			)
			( pin "@baseboard_fab2_lib.baseboard_fab2(sch_1):page41_i286:vss(127)"
				( attribute "PN" "BR26"
					( Origin gPackager )
				)
				( objectStatus "U5D1.BR26" )
			)
			( pin "@baseboard_fab2_lib.baseboard_fab2(sch_1):page41_i286:vss(128)"
				( attribute "PN" "DP83"
					( Origin gPackager )
				)
				( objectStatus "U5D1.DP83" )
			)
			( pin "@baseboard_fab2_lib.baseboard_fab2(sch_1):page41_i286:vss(129)"
				( attribute "PN" "DP81"
					( Origin gPackager )
				)
				( objectStatus "U5D1.DP81" )
			)
			( pin "@baseboard_fab2_lib.baseboard_fab2(sch_1):page41_i286:vss(130)"
				( attribute "PN" "DP71"
					( Origin gPackager )
				)
				( objectStatus "U5D1.DP71" )
			)
			( pin "@baseboard_fab2_lib.baseboard_fab2(sch_1):page41_i286:vss(131)"
				( attribute "PN" "DP69"
					( Origin gPackager )
				)
				( objectStatus "U5D1.DP69" )
			)
			( pin "@baseboard_fab2_lib.baseboard_fab2(sch_1):page41_i286:vss(132)"
				( attribute "PN" "DP67"
					( Origin gPackager )
				)
				( objectStatus "U5D1.DP67" )
			)
			( pin "@baseboard_fab2_lib.baseboard_fab2(sch_1):page41_i286:vss(133)"
				( attribute "PN" "DN78"
					( Origin gPackager )
				)
				( objectStatus "U5D1.DN78" )
			)
			( pin "@baseboard_fab2_lib.baseboard_fab2(sch_1):page42_i10:a"
				( attribute "PN" "1"
					( Origin gPackager )
				)
				( objectStatus "C4P1.1" )
			)
			( pin "@baseboard_fab2_lib.baseboard_fab2(sch_1):page42_i10:b"
				( attribute "PN" "2"
					( Origin gPackager )
				)
				( objectStatus "C4P1.2" )
			)
			( pin "@baseboard_fab2_lib.baseboard_fab2(sch_1):page42_i12:a"
				( attribute "PN" "1"
					( Origin gPackager )
				)
				( objectStatus "C4P9.1" )
			)
			( pin "@baseboard_fab2_lib.baseboard_fab2(sch_1):page42_i12:b"
				( attribute "PN" "2"
					( Origin gPackager )
				)
				( objectStatus "C4P9.2" )
			)
			( pin "@baseboard_fab2_lib.baseboard_fab2(sch_1):page42_i17:a"
				( attribute "PN" "1"
					( Origin gPackager )
				)
				( objectStatus "C4P10.1" )
			)
			( pin "@baseboard_fab2_lib.baseboard_fab2(sch_1):page42_i17:b"
				( attribute "PN" "2"
					( Origin gPackager )
				)
				( objectStatus "C4P10.2" )
			)
			( pin "@baseboard_fab2_lib.baseboard_fab2(sch_1):page76_i246:a"
				( attribute "PN" "1"
					( Origin gPackager )
				)
				( objectStatus "C8P5.1" )
			)
			( pin "@baseboard_fab2_lib.baseboard_fab2(sch_1):page76_i246:b"
				( attribute "PN" "2"
					( Origin gPackager )
				)
				( objectStatus "C8P5.2" )
			)
			( pin "@baseboard_fab2_lib.baseboard_fab2(sch_1):page42_i215:a"
				( attribute "PN" "1"
					( Origin gPackager )
				)
				( objectStatus "C5P9.1" )
			)
			( pin "@baseboard_fab2_lib.baseboard_fab2(sch_1):page42_i215:b"
				( attribute "PN" "2"
					( Origin gPackager )
				)
				( objectStatus "C5P9.2" )
			)
			( pin "@baseboard_fab2_lib.baseboard_fab2(sch_1):page42_i25:a"
				( attribute "PN" "1"
					( Origin gPackager )
				)
				( objectStatus "C5P7.1" )
			)
			( pin "@baseboard_fab2_lib.baseboard_fab2(sch_1):page42_i25:b"
				( attribute "PN" "2"
					( Origin gPackager )
				)
				( objectStatus "C5P7.2" )
			)
			( pin "@baseboard_fab2_lib.baseboard_fab2(sch_1):page42_i28:a"
				( attribute "PN" "1"
					( Origin gPackager )
				)
				( objectStatus "C5P23.1" )
			)
			( pin "@baseboard_fab2_lib.baseboard_fab2(sch_1):page42_i28:b"
				( attribute "PN" "2"
					( Origin gPackager )
				)
				( objectStatus "C5P23.2" )
			)
			( pin "@baseboard_fab2_lib.baseboard_fab2(sch_1):page42_i33:a"
				( attribute "PN" "1"
					( Origin gPackager )
				)
				( objectStatus "C5P24.1" )
			)
			( pin "@baseboard_fab2_lib.baseboard_fab2(sch_1):page42_i33:b"
				( attribute "PN" "2"
					( Origin gPackager )
				)
				( objectStatus "C5P24.2" )
			)
			( pin "@baseboard_fab2_lib.baseboard_fab2(sch_1):page42_i37:a"
				( attribute "PN" "1"
					( Origin gPackager )
				)
				( objectStatus "C5P25.1" )
			)
			( pin "@baseboard_fab2_lib.baseboard_fab2(sch_1):page42_i37:b"
				( attribute "PN" "2"
					( Origin gPackager )
				)
				( objectStatus "C5P25.2" )
			)
			( pin "@baseboard_fab2_lib.baseboard_fab2(sch_1):page42_i41:a"
				( attribute "PN" "1"
					( Origin gPackager )
				)
				( objectStatus "C5P14.1" )
			)
			( pin "@baseboard_fab2_lib.baseboard_fab2(sch_1):page42_i41:b"
				( attribute "PN" "2"
					( Origin gPackager )
				)
				( objectStatus "C5P14.2" )
			)
			( pin "@baseboard_fab2_lib.baseboard_fab2(sch_1):page42_i44:a"
				( attribute "PN" "1"
					( Origin gPackager )
				)
				( objectStatus "C5P27.1" )
			)
			( pin "@baseboard_fab2_lib.baseboard_fab2(sch_1):page42_i44:b"
				( attribute "PN" "2"
					( Origin gPackager )
				)
				( objectStatus "C5P27.2" )
			)
			( pin "@baseboard_fab2_lib.baseboard_fab2(sch_1):page42_i50:a"
				( attribute "PN" "1"
					( Origin gPackager )
				)
				( objectStatus "C5P33.1" )
			)
			( pin "@baseboard_fab2_lib.baseboard_fab2(sch_1):page42_i50:b"
				( attribute "PN" "2"
					( Origin gPackager )
				)
				( objectStatus "C5P33.2" )
			)
			( pin "@baseboard_fab2_lib.baseboard_fab2(sch_1):page42_i51:a"
				( attribute "PN" "1"
					( Origin gPackager )
				)
				( objectStatus "C5P35.1" )
			)
			( pin "@baseboard_fab2_lib.baseboard_fab2(sch_1):page42_i51:b"
				( attribute "PN" "2"
					( Origin gPackager )
				)
				( objectStatus "C5P35.2" )
			)
			( pin "@baseboard_fab2_lib.baseboard_fab2(sch_1):page42_i53:a"
				( attribute "PN" "1"
					( Origin gPackager )
				)
				( objectStatus "C5P32.1" )
			)
			( pin "@baseboard_fab2_lib.baseboard_fab2(sch_1):page42_i53:b"
				( attribute "PN" "2"
					( Origin gPackager )
				)
				( objectStatus "C5P32.2" )
			)
			( pin "@baseboard_fab2_lib.baseboard_fab2(sch_1):page42_i54:a"
				( attribute "PN" "1"
					( Origin gPackager )
				)
				( objectStatus "C5P34.1" )
			)
			( pin "@baseboard_fab2_lib.baseboard_fab2(sch_1):page42_i54:b"
				( attribute "PN" "2"
					( Origin gPackager )
				)
				( objectStatus "C5P34.2" )
			)
			( pin "@baseboard_fab2_lib.baseboard_fab2(sch_1):page42_i55:a"
				( attribute "PN" "1"
					( Origin gPackager )
				)
				( objectStatus "C5P22.1" )
			)
			( pin "@baseboard_fab2_lib.baseboard_fab2(sch_1):page42_i55:b"
				( attribute "PN" "2"
					( Origin gPackager )
				)
				( objectStatus "C5P22.2" )
			)
			( pin "@baseboard_fab2_lib.baseboard_fab2(sch_1):page42_i56:a"
				( attribute "PN" "1"
					( Origin gPackager )
				)
				( objectStatus "C5P26.1" )
			)
			( pin "@baseboard_fab2_lib.baseboard_fab2(sch_1):page42_i56:b"
				( attribute "PN" "2"
					( Origin gPackager )
				)
				( objectStatus "C5P26.2" )
			)
			( pin "@baseboard_fab2_lib.baseboard_fab2(sch_1):page42_i57:a"
				( attribute "PN" "1"
					( Origin gPackager )
				)
				( objectStatus "C5P40.1" )
			)
			( pin "@baseboard_fab2_lib.baseboard_fab2(sch_1):page42_i57:b"
				( attribute "PN" "2"
					( Origin gPackager )
				)
				( objectStatus "C5P40.2" )
			)
			( pin "@baseboard_fab2_lib.baseboard_fab2(sch_1):page225_i317:a"
				( attribute "PN" "1"
					( Origin gPackager )
				)
				( objectStatus "C8P32.1" )
			)
			( pin "@baseboard_fab2_lib.baseboard_fab2(sch_1):page225_i317:b"
				( attribute "PN" "2"
					( Origin gPackager )
				)
				( objectStatus "C8P32.2" )
			)
			( pin "@baseboard_fab2_lib.baseboard_fab2(sch_1):page225_i318:a"
				( attribute "PN" "1"
					( Origin gPackager )
				)
				( objectStatus "C7P20.1" )
			)
			( pin "@baseboard_fab2_lib.baseboard_fab2(sch_1):page225_i318:b"
				( attribute "PN" "2"
					( Origin gPackager )
				)
				( objectStatus "C7P20.2" )
			)
			( pin "@baseboard_fab2_lib.baseboard_fab2(sch_1):page225_i316:a"
				( attribute "PN" "1"
					( Origin gPackager )
				)
				( objectStatus "C8P33.1" )
			)
			( pin "@baseboard_fab2_lib.baseboard_fab2(sch_1):page225_i316:b"
				( attribute "PN" "2"
					( Origin gPackager )
				)
				( objectStatus "C8P33.2" )
			)
			( pin "@baseboard_fab2_lib.baseboard_fab2(sch_1):page42_i63:a"
				( attribute "PN" "1"
					( Origin gPackager )
				)
				( objectStatus "C5P37.1" )
			)
			( pin "@baseboard_fab2_lib.baseboard_fab2(sch_1):page42_i63:b"
				( attribute "PN" "2"
					( Origin gPackager )
				)
				( objectStatus "C5P37.2" )
			)
			( pin "@baseboard_fab2_lib.baseboard_fab2(sch_1):page42_i65:a"
				( attribute "PN" "1"
					( Origin gPackager )
				)
				( objectStatus "C5P36.1" )
			)
			( pin "@baseboard_fab2_lib.baseboard_fab2(sch_1):page42_i65:b"
				( attribute "PN" "2"
					( Origin gPackager )
				)
				( objectStatus "C5P36.2" )
			)
			( pin "@baseboard_fab2_lib.baseboard_fab2(sch_1):page42_i68:a"
				( attribute "PN" "1"
					( Origin gPackager )
				)
				( objectStatus "C6D8.1" )
			)
			( pin "@baseboard_fab2_lib.baseboard_fab2(sch_1):page42_i68:b"
				( attribute "PN" "2"
					( Origin gPackager )
				)
				( objectStatus "C6D8.2" )
			)
			( pin "@baseboard_fab2_lib.baseboard_fab2(sch_1):page42_i69:a"
				( attribute "PN" "1"
					( Origin gPackager )
				)
				( objectStatus "C5D38.1" )
			)
			( pin "@baseboard_fab2_lib.baseboard_fab2(sch_1):page42_i69:b"
				( attribute "PN" "2"
					( Origin gPackager )
				)
				( objectStatus "C5D38.2" )
			)
			( pin "@baseboard_fab2_lib.baseboard_fab2(sch_1):page42_i70:a"
				( attribute "PN" "1"
					( Origin gPackager )
				)
				( objectStatus "C5D37.1" )
			)
			( pin "@baseboard_fab2_lib.baseboard_fab2(sch_1):page42_i70:b"
				( attribute "PN" "2"
					( Origin gPackager )
				)
				( objectStatus "C5D37.2" )
			)
			( pin "@baseboard_fab2_lib.baseboard_fab2(sch_1):page42_i72:a"
				( attribute "PN" "1"
					( Origin gPackager )
				)
				( objectStatus "C6D7.1" )
			)
			( pin "@baseboard_fab2_lib.baseboard_fab2(sch_1):page42_i72:b"
				( attribute "PN" "2"
					( Origin gPackager )
				)
				( objectStatus "C6D7.2" )
			)
			( pin "@baseboard_fab2_lib.baseboard_fab2(sch_1):page42_i74:a"
				( attribute "PN" "1"
					( Origin gPackager )
				)
				( objectStatus "C6D4.1" )
			)
			( pin "@baseboard_fab2_lib.baseboard_fab2(sch_1):page42_i74:b"
				( attribute "PN" "2"
					( Origin gPackager )
				)
				( objectStatus "C6D4.2" )
			)
			( pin "@baseboard_fab2_lib.baseboard_fab2(sch_1):page42_i75:a"
				( attribute "PN" "1"
					( Origin gPackager )
				)
				( objectStatus "C6D5.1" )
			)
			( pin "@baseboard_fab2_lib.baseboard_fab2(sch_1):page42_i75:b"
				( attribute "PN" "2"
					( Origin gPackager )
				)
				( objectStatus "C6D5.2" )
			)
			( pin "@baseboard_fab2_lib.baseboard_fab2(sch_1):page42_i77:a"
				( attribute "PN" "1"
					( Origin gPackager )
				)
				( objectStatus "C6D2.1" )
			)
			( pin "@baseboard_fab2_lib.baseboard_fab2(sch_1):page42_i77:b"
				( attribute "PN" "2"
					( Origin gPackager )
				)
				( objectStatus "C6D2.2" )
			)
			( pin "@baseboard_fab2_lib.baseboard_fab2(sch_1):page42_i80:a"
				( attribute "PN" "1"
					( Origin gPackager )
				)
				( objectStatus "C6D3.1" )
			)
			( pin "@baseboard_fab2_lib.baseboard_fab2(sch_1):page42_i80:b"
				( attribute "PN" "2"
					( Origin gPackager )
				)
				( objectStatus "C6D3.2" )
			)
			( pin "@baseboard_fab2_lib.baseboard_fab2(sch_1):page42_i81:a"
				( attribute "PN" "1"
					( Origin gPackager )
				)
				( objectStatus "C6D6.1" )
			)
			( pin "@baseboard_fab2_lib.baseboard_fab2(sch_1):page42_i81:b"
				( attribute "PN" "2"
					( Origin gPackager )
				)
				( objectStatus "C6D6.2" )
			)
			( pin "@baseboard_fab2_lib.baseboard_fab2(sch_1):page42_i83:a"
				( attribute "PN" "1"
					( Origin gPackager )
				)
				( objectStatus "C5D51.1" )
			)
			( pin "@baseboard_fab2_lib.baseboard_fab2(sch_1):page42_i83:b"
				( attribute "PN" "2"
					( Origin gPackager )
				)
				( objectStatus "C5D51.2" )
			)
			( pin "@baseboard_fab2_lib.baseboard_fab2(sch_1):page42_i88:a"
				( attribute "PN" "1"
					( Origin gPackager )
				)
				( objectStatus "C5D21.1" )
			)
			( pin "@baseboard_fab2_lib.baseboard_fab2(sch_1):page42_i88:b"
				( attribute "PN" "2"
					( Origin gPackager )
				)
				( objectStatus "C5D21.2" )
			)
			( pin "@baseboard_fab2_lib.baseboard_fab2(sch_1):page42_i89:a"
				( attribute "PN" "1"
					( Origin gPackager )
				)
				( objectStatus "C5D50.1" )
			)
			( pin "@baseboard_fab2_lib.baseboard_fab2(sch_1):page42_i89:b"
				( attribute "PN" "2"
					( Origin gPackager )
				)
				( objectStatus "C5D50.2" )
			)
			( pin "@baseboard_fab2_lib.baseboard_fab2(sch_1):page42_i90:a"
				( attribute "PN" "1"
					( Origin gPackager )
				)
				( objectStatus "C5D48.1" )
			)
			( pin "@baseboard_fab2_lib.baseboard_fab2(sch_1):page42_i90:b"
				( attribute "PN" "2"
					( Origin gPackager )
				)
				( objectStatus "C5D48.2" )
			)
			( pin "@baseboard_fab2_lib.baseboard_fab2(sch_1):page42_i91:a"
				( attribute "PN" "1"
					( Origin gPackager )
				)
				( objectStatus "C5D13.1" )
			)
			( pin "@baseboard_fab2_lib.baseboard_fab2(sch_1):page42_i91:b"
				( attribute "PN" "2"
					( Origin gPackager )
				)
				( objectStatus "C5D13.2" )
			)
			( pin "@baseboard_fab2_lib.baseboard_fab2(sch_1):page42_i93:a"
				( attribute "PN" "1"
					( Origin gPackager )
				)
				( objectStatus "C5D11.1" )
			)
			( pin "@baseboard_fab2_lib.baseboard_fab2(sch_1):page42_i93:b"
				( attribute "PN" "2"
					( Origin gPackager )
				)
				( objectStatus "C5D11.2" )
			)
			( pin "@baseboard_fab2_lib.baseboard_fab2(sch_1):page42_i94:a"
				( attribute "PN" "1"
					( Origin gPackager )
				)
				( objectStatus "C5D12.1" )
			)
			( pin "@baseboard_fab2_lib.baseboard_fab2(sch_1):page42_i94:b"
				( attribute "PN" "2"
					( Origin gPackager )
				)
				( objectStatus "C5D12.2" )
			)
			( pin "@baseboard_fab2_lib.baseboard_fab2(sch_1):page42_i98:a"
				( attribute "PN" "1"
					( Origin gPackager )
				)
				( objectStatus "C5D23.1" )
			)
			( pin "@baseboard_fab2_lib.baseboard_fab2(sch_1):page42_i98:b"
				( attribute "PN" "2"
					( Origin gPackager )
				)
				( objectStatus "C5D23.2" )
			)
			( pin "@baseboard_fab2_lib.baseboard_fab2(sch_1):page42_i100:a"
				( attribute "PN" "1"
					( Origin gPackager )
				)
				( objectStatus "C5D28.1" )
			)
			( pin "@baseboard_fab2_lib.baseboard_fab2(sch_1):page42_i100:b"
				( attribute "PN" "2"
					( Origin gPackager )
				)
				( objectStatus "C5D28.2" )
			)
			( pin "@baseboard_fab2_lib.baseboard_fab2(sch_1):page42_i102:a"
				( attribute "PN" "1"
					( Origin gPackager )
				)
				( objectStatus "C5D29.1" )
			)
			( pin "@baseboard_fab2_lib.baseboard_fab2(sch_1):page42_i102:b"
				( attribute "PN" "2"
					( Origin gPackager )
				)
				( objectStatus "C5D29.2" )
			)
			( pin "@baseboard_fab2_lib.baseboard_fab2(sch_1):page42_i103:a"
				( attribute "PN" "1"
					( Origin gPackager )
				)
				( objectStatus "C5D32.1" )
			)
			( pin "@baseboard_fab2_lib.baseboard_fab2(sch_1):page42_i103:b"
				( attribute "PN" "2"
					( Origin gPackager )
				)
				( objectStatus "C5D32.2" )
			)
			( pin "@baseboard_fab2_lib.baseboard_fab2(sch_1):page42_i104:a"
				( attribute "PN" "1"
					( Origin gPackager )
				)
				( objectStatus "C5D47.1" )
			)
			( pin "@baseboard_fab2_lib.baseboard_fab2(sch_1):page42_i104:b"
				( attribute "PN" "2"
					( Origin gPackager )
				)
				( objectStatus "C5D47.2" )
			)
			( pin "@baseboard_fab2_lib.baseboard_fab2(sch_1):page42_i106:a"
				( attribute "PN" "1"
					( Origin gPackager )
				)
				( objectStatus "C5D31.1" )
			)
			( pin "@baseboard_fab2_lib.baseboard_fab2(sch_1):page42_i106:b"
				( attribute "PN" "2"
					( Origin gPackager )
				)
				( objectStatus "C5D31.2" )
			)
			( pin "@baseboard_fab2_lib.baseboard_fab2(sch_1):page42_i107:a"
				( attribute "PN" "1"
					( Origin gPackager )
				)
				( objectStatus "C5D46.1" )
			)
			( pin "@baseboard_fab2_lib.baseboard_fab2(sch_1):page42_i107:b"
				( attribute "PN" "2"
					( Origin gPackager )
				)
				( objectStatus "C5D46.2" )
			)
			( pin "@baseboard_fab2_lib.baseboard_fab2(sch_1):page42_i108:a"
				( attribute "PN" "1"
					( Origin gPackager )
				)
				( objectStatus "C5D10.1" )
			)
			( pin "@baseboard_fab2_lib.baseboard_fab2(sch_1):page42_i108:b"
				( attribute "PN" "2"
					( Origin gPackager )
				)
				( objectStatus "C5D10.2" )
			)
			( pin "@baseboard_fab2_lib.baseboard_fab2(sch_1):page42_i109:a"
				( attribute "PN" "1"
					( Origin gPackager )
				)
				( objectStatus "C5D27.1" )
			)
			( pin "@baseboard_fab2_lib.baseboard_fab2(sch_1):page42_i109:b"
				( attribute "PN" "2"
					( Origin gPackager )
				)
				( objectStatus "C5D27.2" )
			)
			( pin "@baseboard_fab2_lib.baseboard_fab2(sch_1):page42_i111:a"
				( attribute "PN" "1"
					( Origin gPackager )
				)
				( objectStatus "C5D30.1" )
			)
			( pin "@baseboard_fab2_lib.baseboard_fab2(sch_1):page42_i111:b"
				( attribute "PN" "2"
					( Origin gPackager )
				)
				( objectStatus "C5D30.2" )
			)
			( pin "@baseboard_fab2_lib.baseboard_fab2(sch_1):page217_i272:a"
				( attribute "PN" "1"
					( Origin gPackager )
				)
				( objectStatus "C5D60.1" )
			)
			( pin "@baseboard_fab2_lib.baseboard_fab2(sch_1):page217_i272:b"
				( attribute "PN" "2"
					( Origin gPackager )
				)
				( objectStatus "C5D60.2" )
			)
			( pin "@baseboard_fab2_lib.baseboard_fab2(sch_1):page217_i271:a"
				( attribute "PN" "1"
					( Origin gPackager )
				)
				( objectStatus "C5D59.1" )
			)
			( pin "@baseboard_fab2_lib.baseboard_fab2(sch_1):page217_i271:b"
				( attribute "PN" "2"
					( Origin gPackager )
				)
				( objectStatus "C5D59.2" )
			)
			( pin "@baseboard_fab2_lib.baseboard_fab2(sch_1):page42_i114:a"
				( attribute "PN" "1"
					( Origin gPackager )
				)
				( objectStatus "C5D41.1" )
			)
			( pin "@baseboard_fab2_lib.baseboard_fab2(sch_1):page42_i114:b"
				( attribute "PN" "2"
					( Origin gPackager )
				)
				( objectStatus "C5D41.2" )
			)
			( pin "@baseboard_fab2_lib.baseboard_fab2(sch_1):page42_i115:a"
				( attribute "PN" "1"
					( Origin gPackager )
				)
				( objectStatus "C5D40.1" )
			)
			( pin "@baseboard_fab2_lib.baseboard_fab2(sch_1):page42_i115:b"
				( attribute "PN" "2"
					( Origin gPackager )
				)
				( objectStatus "C5D40.2" )
			)
			( pin "@baseboard_fab2_lib.baseboard_fab2(sch_1):page42_i117:a"
				( attribute "PN" "1"
					( Origin gPackager )
				)
				( objectStatus "C5D14.1" )
			)
			( pin "@baseboard_fab2_lib.baseboard_fab2(sch_1):page42_i117:b"
				( attribute "PN" "2"
					( Origin gPackager )
				)
				( objectStatus "C5D14.2" )
			)
			( pin "@baseboard_fab2_lib.baseboard_fab2(sch_1):page42_i118:a"
				( attribute "PN" "1"
					( Origin gPackager )
				)
				( objectStatus "C5D17.1" )
			)
			( pin "@baseboard_fab2_lib.baseboard_fab2(sch_1):page42_i118:b"
				( attribute "PN" "2"
					( Origin gPackager )
				)
				( objectStatus "C5D17.2" )
			)
			( pin "@baseboard_fab2_lib.baseboard_fab2(sch_1):page217_i270:a"
				( attribute "PN" "1"
					( Origin gPackager )
				)
				( objectStatus "C5D61.1" )
			)
			( pin "@baseboard_fab2_lib.baseboard_fab2(sch_1):page217_i270:b"
				( attribute "PN" "2"
					( Origin gPackager )
				)
				( objectStatus "C5D61.2" )
			)
			( pin "@baseboard_fab2_lib.baseboard_fab2(sch_1):page42_i123:a"
				( attribute "PN" "1"
					( Origin gPackager )
				)
				( objectStatus "C5D16.1" )
			)
			( pin "@baseboard_fab2_lib.baseboard_fab2(sch_1):page42_i123:b"
				( attribute "PN" "2"
					( Origin gPackager )
				)
				( objectStatus "C5D16.2" )
			)
			( pin "@baseboard_fab2_lib.baseboard_fab2(sch_1):page42_i125:a"
				( attribute "PN" "1"
					( Origin gPackager )
				)
				( objectStatus "C5D5.1" )
			)
			( pin "@baseboard_fab2_lib.baseboard_fab2(sch_1):page42_i125:b"
				( attribute "PN" "2"
					( Origin gPackager )
				)
				( objectStatus "C5D5.2" )
			)
			( pin "@baseboard_fab2_lib.baseboard_fab2(sch_1):page220_i252:a"
				( attribute "PN" "1"
					( Origin gPackager )
				)
				( objectStatus "C5D1.1" )
			)
			( pin "@baseboard_fab2_lib.baseboard_fab2(sch_1):page220_i252:b"
				( attribute "PN" "2"
					( Origin gPackager )
				)
				( objectStatus "C5D1.2" )
			)
			( pin "@baseboard_fab2_lib.baseboard_fab2(sch_1):page220_i251:a"
				( attribute "PN" "1"
					( Origin gPackager )
				)
				( objectStatus "C5D2.1" )
			)
			( pin "@baseboard_fab2_lib.baseboard_fab2(sch_1):page220_i251:b"
				( attribute "PN" "2"
					( Origin gPackager )
				)
				( objectStatus "C5D2.2" )
			)
			( pin "@baseboard_fab2_lib.baseboard_fab2(sch_1):page42_i128:a"
				( attribute "PN" "1"
					( Origin gPackager )
				)
				( objectStatus "C5D19.1" )
			)
			( pin "@baseboard_fab2_lib.baseboard_fab2(sch_1):page42_i128:b"
				( attribute "PN" "2"
					( Origin gPackager )
				)
				( objectStatus "C5D19.2" )
			)
			( pin "@baseboard_fab2_lib.baseboard_fab2(sch_1):page217_i269:a"
				( attribute "PN" "1"
					( Origin gPackager )
				)
				( objectStatus "C5D58.1" )
			)
			( pin "@baseboard_fab2_lib.baseboard_fab2(sch_1):page217_i269:b"
				( attribute "PN" "2"
					( Origin gPackager )
				)
				( objectStatus "C5D58.2" )
			)
			( pin "@baseboard_fab2_lib.baseboard_fab2(sch_1):page220_i250:a"
				( attribute "PN" "1"
					( Origin gPackager )
				)
				( objectStatus "C5D3.1" )
			)
			( pin "@baseboard_fab2_lib.baseboard_fab2(sch_1):page220_i250:b"
				( attribute "PN" "2"
					( Origin gPackager )
				)
				( objectStatus "C5D3.2" )
			)
			( pin "@baseboard_fab2_lib.baseboard_fab2(sch_1):page42_i131:a"
				( attribute "PN" "1"
					( Origin gPackager )
				)
				( objectStatus "C5D43.1" )
			)
			( pin "@baseboard_fab2_lib.baseboard_fab2(sch_1):page42_i131:b"
				( attribute "PN" "2"
					( Origin gPackager )
				)
				( objectStatus "C5D43.2" )
			)
			( pin "@baseboard_fab2_lib.baseboard_fab2(sch_1):page42_i132:a"
				( attribute "PN" "1"
					( Origin gPackager )
				)
				( objectStatus "C5D15.1" )
			)
			( pin "@baseboard_fab2_lib.baseboard_fab2(sch_1):page42_i132:b"
				( attribute "PN" "2"
					( Origin gPackager )
				)
				( objectStatus "C5D15.2" )
			)
			( pin "@baseboard_fab2_lib.baseboard_fab2(sch_1):page42_i134:a"
				( attribute "PN" "1"
					( Origin gPackager )
				)
				( objectStatus "C5D18.1" )
			)
			( pin "@baseboard_fab2_lib.baseboard_fab2(sch_1):page42_i134:b"
				( attribute "PN" "2"
					( Origin gPackager )
				)
				( objectStatus "C5D18.2" )
			)
			( pin "@baseboard_fab2_lib.baseboard_fab2(sch_1):page42_i135:a"
				( attribute "PN" "1"
					( Origin gPackager )
				)
				( objectStatus "C5D42.1" )
			)
			( pin "@baseboard_fab2_lib.baseboard_fab2(sch_1):page42_i135:b"
				( attribute "PN" "2"
					( Origin gPackager )
				)
				( objectStatus "C5D42.2" )
			)
			( pin "@baseboard_fab2_lib.baseboard_fab2(sch_1):page220_i249:a"
				( attribute "PN" "1"
					( Origin gPackager )
				)
				( objectStatus "C5D4.1" )
			)
			( pin "@baseboard_fab2_lib.baseboard_fab2(sch_1):page220_i249:b"
				( attribute "PN" "2"
					( Origin gPackager )
				)
				( objectStatus "C5D4.2" )
			)
			( pin "@baseboard_fab2_lib.baseboard_fab2(sch_1):page42_i138:a"
				( attribute "PN" "1"
					( Origin gPackager )
				)
				( objectStatus "C5D24.1" )
			)
			( pin "@baseboard_fab2_lib.baseboard_fab2(sch_1):page42_i138:b"
				( attribute "PN" "2"
					( Origin gPackager )
				)
				( objectStatus "C5D24.2" )
			)
			( pin "@baseboard_fab2_lib.baseboard_fab2(sch_1):page42_i140:a"
				( attribute "PN" "1"
					( Origin gPackager )
				)
				( objectStatus "C5D39.1" )
			)
			( pin "@baseboard_fab2_lib.baseboard_fab2(sch_1):page42_i140:b"
				( attribute "PN" "2"
					( Origin gPackager )
				)
				( objectStatus "C5D39.2" )
			)
			( pin "@baseboard_fab2_lib.baseboard_fab2(sch_1):page42_i142:a"
				( attribute "PN" "1"
					( Origin gPackager )
				)
				( objectStatus "C5D44.1" )
			)
			( pin "@baseboard_fab2_lib.baseboard_fab2(sch_1):page42_i142:b"
				( attribute "PN" "2"
					( Origin gPackager )
				)
				( objectStatus "C5D44.2" )
			)
			( pin "@baseboard_fab2_lib.baseboard_fab2(sch_1):page42_i145:a"
				( attribute "PN" "1"
					( Origin gPackager )
				)
				( objectStatus "C6D9.1" )
			)
			( pin "@baseboard_fab2_lib.baseboard_fab2(sch_1):page42_i145:b"
				( attribute "PN" "2"
					( Origin gPackager )
				)
				( objectStatus "C6D9.2" )
			)
			( pin "@baseboard_fab2_lib.baseboard_fab2(sch_1):page42_i147:a"
				( attribute "PN" "1"
					( Origin gPackager )
				)
				( objectStatus "C6D10.1" )
			)
			( pin "@baseboard_fab2_lib.baseboard_fab2(sch_1):page42_i147:b"
				( attribute "PN" "2"
					( Origin gPackager )
				)
				( objectStatus "C6D10.2" )
			)
			( pin "@baseboard_fab2_lib.baseboard_fab2(sch_1):page42_i151:a"
				( attribute "PN" "1"
					( Origin gPackager )
				)
				( objectStatus "C5D36.1" )
			)
			( pin "@baseboard_fab2_lib.baseboard_fab2(sch_1):page42_i151:b"
				( attribute "PN" "2"
					( Origin gPackager )
				)
				( objectStatus "C5D36.2" )
			)
			( pin "@baseboard_fab2_lib.baseboard_fab2(sch_1):page42_i152:a"
				( attribute "PN" "1"
					( Origin gPackager )
				)
				( objectStatus "C5D49.1" )
			)
			( pin "@baseboard_fab2_lib.baseboard_fab2(sch_1):page42_i152:b"
				( attribute "PN" "2"
					( Origin gPackager )
				)
				( objectStatus "C5D49.2" )
			)
			( pin "@baseboard_fab2_lib.baseboard_fab2(sch_1):page42_i153:a"
				( attribute "PN" "1"
					( Origin gPackager )
				)
				( objectStatus "C5D22.1" )
			)
			( pin "@baseboard_fab2_lib.baseboard_fab2(sch_1):page42_i153:b"
				( attribute "PN" "2"
					( Origin gPackager )
				)
				( objectStatus "C5D22.2" )
			)
			( pin "@baseboard_fab2_lib.baseboard_fab2(sch_1):page42_i154:a"
				( attribute "PN" "1"
					( Origin gPackager )
				)
				( objectStatus "C5D26.1" )
			)
			( pin "@baseboard_fab2_lib.baseboard_fab2(sch_1):page42_i154:b"
				( attribute "PN" "2"
					( Origin gPackager )
				)
				( objectStatus "C5D26.2" )
			)
			( pin "@baseboard_fab2_lib.baseboard_fab2(sch_1):page42_i155:a"
				( attribute "PN" "1"
					( Origin gPackager )
				)
				( objectStatus "C5D25.1" )
			)
			( pin "@baseboard_fab2_lib.baseboard_fab2(sch_1):page42_i155:b"
				( attribute "PN" "2"
					( Origin gPackager )
				)
				( objectStatus "C5D25.2" )
			)
			( pin "@baseboard_fab2_lib.baseboard_fab2(sch_1):page42_i156:a"
				( attribute "PN" "1"
					( Origin gPackager )
				)
				( objectStatus "C5D45.1" )
			)
			( pin "@baseboard_fab2_lib.baseboard_fab2(sch_1):page42_i156:b"
				( attribute "PN" "2"
					( Origin gPackager )
				)
				( objectStatus "C5D45.2" )
			)
			( pin "@baseboard_fab2_lib.baseboard_fab2(sch_1):page42_i164:a"
				( attribute "PN" "1"
					( Origin gPackager )
				)
				( objectStatus "C4P6.1" )
			)
			( pin "@baseboard_fab2_lib.baseboard_fab2(sch_1):page42_i164:b"
				( attribute "PN" "2"
					( Origin gPackager )
				)
				( objectStatus "C4P6.2" )
			)
			( pin "@baseboard_fab2_lib.baseboard_fab2(sch_1):page42_i173:a"
				( attribute "PN" "1"
					( Origin gPackager )
				)
				( objectStatus "C5D20.1" )
			)
			( pin "@baseboard_fab2_lib.baseboard_fab2(sch_1):page42_i173:b"
				( attribute "PN" "2"
					( Origin gPackager )
				)
				( objectStatus "C5D20.2" )
			)
			( pin "@baseboard_fab2_lib.baseboard_fab2(sch_1):page42_i174:a"
				( attribute "PN" "1"
					( Origin gPackager )
				)
				( objectStatus "C5D33.1" )
			)
			( pin "@baseboard_fab2_lib.baseboard_fab2(sch_1):page42_i174:b"
				( attribute "PN" "2"
					( Origin gPackager )
				)
				( objectStatus "C5D33.2" )
			)
			( pin "@baseboard_fab2_lib.baseboard_fab2(sch_1):page42_i175:a"
				( attribute "PN" "1"
					( Origin gPackager )
				)
				( objectStatus "C5D34.1" )
			)
			( pin "@baseboard_fab2_lib.baseboard_fab2(sch_1):page42_i175:b"
				( attribute "PN" "2"
					( Origin gPackager )
				)
				( objectStatus "C5D34.2" )
			)
			( pin "@baseboard_fab2_lib.baseboard_fab2(sch_1):page42_i176:a"
				( attribute "PN" "1"
					( Origin gPackager )
				)
				( objectStatus "C5D35.1" )
			)
			( pin "@baseboard_fab2_lib.baseboard_fab2(sch_1):page42_i176:b"
				( attribute "PN" "2"
					( Origin gPackager )
				)
				( objectStatus "C5D35.2" )
			)
			( pin "@baseboard_fab2_lib.baseboard_fab2(sch_1):page42_i178:a"
				( attribute "PN" "1"
					( Origin gPackager )
				)
				( objectStatus "C4P8.1" )
			)
			( pin "@baseboard_fab2_lib.baseboard_fab2(sch_1):page42_i178:b"
				( attribute "PN" "2"
					( Origin gPackager )
				)
				( objectStatus "C4P8.2" )
			)
			( pin "@baseboard_fab2_lib.baseboard_fab2(sch_1):page42_i179:a"
				( attribute "PN" "1"
					( Origin gPackager )
				)
				( objectStatus "C5D53.1" )
			)
			( pin "@baseboard_fab2_lib.baseboard_fab2(sch_1):page42_i179:b"
				( attribute "PN" "2"
					( Origin gPackager )
				)
				( objectStatus "C5D53.2" )
			)
			( pin "@baseboard_fab2_lib.baseboard_fab2(sch_1):page42_i180:a"
				( attribute "PN" "1"
					( Origin gPackager )
				)
				( objectStatus "C5D52.1" )
			)
			( pin "@baseboard_fab2_lib.baseboard_fab2(sch_1):page42_i180:b"
				( attribute "PN" "2"
					( Origin gPackager )
				)
				( objectStatus "C5D52.2" )
			)
			( pin "@baseboard_fab2_lib.baseboard_fab2(sch_1):page42_i187:a"
				( attribute "PN" "1"
					( Origin gPackager )
				)
				( objectStatus "C5P15.1" )
			)
			( pin "@baseboard_fab2_lib.baseboard_fab2(sch_1):page42_i187:b"
				( attribute "PN" "2"
					( Origin gPackager )
				)
				( objectStatus "C5P15.2" )
			)
			( pin "@baseboard_fab2_lib.baseboard_fab2(sch_1):page42_i188:a"
				( attribute "PN" "1"
					( Origin gPackager )
				)
				( objectStatus "C5P16.1" )
			)
			( pin "@baseboard_fab2_lib.baseboard_fab2(sch_1):page42_i188:b"
				( attribute "PN" "2"
					( Origin gPackager )
				)
				( objectStatus "C5P16.2" )
			)
			( pin "@baseboard_fab2_lib.baseboard_fab2(sch_1):page42_i190:a"
				( attribute "PN" "1"
					( Origin gPackager )
				)
				( objectStatus "C5P17.1" )
			)
			( pin "@baseboard_fab2_lib.baseboard_fab2(sch_1):page42_i190:b"
				( attribute "PN" "2"
					( Origin gPackager )
				)
				( objectStatus "C5P17.2" )
			)
			( pin "@baseboard_fab2_lib.baseboard_fab2(sch_1):page43_i1:a0"
				( attribute "PN" "79"
					( Origin gPackager )
				)
				( objectStatus "J4G1.79" )
			)
			( pin "@baseboard_fab2_lib.baseboard_fab2(sch_1):page43_i1:a1"
				( attribute "PN" "72"
					( Origin gPackager )
				)
				( objectStatus "J4G1.72" )
			)
			( pin "@baseboard_fab2_lib.baseboard_fab2(sch_1):page43_i1:a2"
				( attribute "PN" "216"
					( Origin gPackager )
				)
				( objectStatus "J4G1.216" )
			)
			( pin "@baseboard_fab2_lib.baseboard_fab2(sch_1):page43_i1:a3"
				( attribute "PN" "71"
					( Origin gPackager )
				)
				( objectStatus "J4G1.71" )
			)
			( pin "@baseboard_fab2_lib.baseboard_fab2(sch_1):page43_i1:a4"
				( attribute "PN" "214"
					( Origin gPackager )
				)
				( objectStatus "J4G1.214" )
			)
			( pin "@baseboard_fab2_lib.baseboard_fab2(sch_1):page43_i1:a5"
				( attribute "PN" "213"
					( Origin gPackager )
				)
				( objectStatus "J4G1.213" )
			)
			( pin "@baseboard_fab2_lib.baseboard_fab2(sch_1):page43_i1:a6"
				( attribute "PN" "69"
					( Origin gPackager )
				)
				( objectStatus "J4G1.69" )
			)
			( pin "@baseboard_fab2_lib.baseboard_fab2(sch_1):page43_i1:a7"
				( attribute "PN" "211"
					( Origin gPackager )
				)
				( objectStatus "J4G1.211" )
			)
			( pin "@baseboard_fab2_lib.baseboard_fab2(sch_1):page43_i1:a8"
				( attribute "PN" "68"
					( Origin gPackager )
				)
				( objectStatus "J4G1.68" )
			)
			( pin "@baseboard_fab2_lib.baseboard_fab2(sch_1):page43_i1:a9"
				( attribute "PN" "66"
					( Origin gPackager )
				)
				( objectStatus "J4G1.66" )
			)
			( pin "@baseboard_fab2_lib.baseboard_fab2(sch_1):page43_i1:a10"
				( attribute "PN" "225"
					( Origin gPackager )
				)
				( objectStatus "J4G1.225" )
			)
			( pin "@baseboard_fab2_lib.baseboard_fab2(sch_1):page43_i1:a11"
				( attribute "PN" "210"
					( Origin gPackager )
				)
				( objectStatus "J4G1.210" )
			)
			( pin "@baseboard_fab2_lib.baseboard_fab2(sch_1):page43_i1:a12"
				( attribute "PN" "65"
					( Origin gPackager )
				)
				( objectStatus "J4G1.65" )
			)
			( pin "@baseboard_fab2_lib.baseboard_fab2(sch_1):page43_i1:a13"
				( attribute "PN" "232"
					( Origin gPackager )
				)
				( objectStatus "J4G1.232" )
			)
			( pin "@baseboard_fab2_lib.baseboard_fab2(sch_1):page43_i1:a14_we_n"
				( attribute "PN" "228"
					( Origin gPackager )
				)
				( objectStatus "J4G1.228" )
			)
			( pin "@baseboard_fab2_lib.baseboard_fab2(sch_1):page43_i1:a15_cas_n"
				( attribute "PN" "86"
					( Origin gPackager )
				)
				( objectStatus "J4G1.86" )
			)
			( pin "@baseboard_fab2_lib.baseboard_fab2(sch_1):page43_i1:a16_ras_n"
				( attribute "PN" "82"
					( Origin gPackager )
				)
				( objectStatus "J4G1.82" )
			)
			( pin "@baseboard_fab2_lib.baseboard_fab2(sch_1):page43_i1:a17"
				( attribute "PN" "234"
					( Origin gPackager )
				)
				( objectStatus "J4G1.234" )
			)
			( pin "@baseboard_fab2_lib.baseboard_fab2(sch_1):page43_i1:act_n"
				( attribute "PN" "62"
					( Origin gPackager )
				)
				( objectStatus "J4G1.62" )
			)
			( pin "@baseboard_fab2_lib.baseboard_fab2(sch_1):page43_i1:alert_n"
				( attribute "PN" "208"
					( Origin gPackager )
				)
				( objectStatus "J4G1.208" )
			)
			( pin "@baseboard_fab2_lib.baseboard_fab2(sch_1):page43_i1:ba(0)"
				( attribute "PN" "81"
					( Origin gPackager )
				)
				( objectStatus "J4G1.81" )
			)
			( pin "@baseboard_fab2_lib.baseboard_fab2(sch_1):page43_i1:ba(1)"
				( attribute "PN" "224"
					( Origin gPackager )
				)
				( objectStatus "J4G1.224" )
			)
			( pin "@baseboard_fab2_lib.baseboard_fab2(sch_1):page43_i1:bg(0)"
				( attribute "PN" "63"
					( Origin gPackager )
				)
				( objectStatus "J4G1.63" )
			)
			( pin "@baseboard_fab2_lib.baseboard_fab2(sch_1):page43_i1:bg(1)"
				( attribute "PN" "207"
					( Origin gPackager )
				)
				( objectStatus "J4G1.207" )
			)
			( pin "@baseboard_fab2_lib.baseboard_fab2(sch_1):page43_i1:c(2)"
				( attribute "PN" "235"
					( Origin gPackager )
				)
				( objectStatus "J4G1.235" )
			)
			( pin "@baseboard_fab2_lib.baseboard_fab2(sch_1):page43_i1:cb(0)"
				( attribute "PN" "49"
					( Origin gPackager )
				)
				( objectStatus "J4G1.49" )
			)
			( pin "@baseboard_fab2_lib.baseboard_fab2(sch_1):page43_i1:cb(1)"
				( attribute "PN" "194"
					( Origin gPackager )
				)
				( objectStatus "J4G1.194" )
			)
			( pin "@baseboard_fab2_lib.baseboard_fab2(sch_1):page43_i1:cb(2)"
				( attribute "PN" "56"
					( Origin gPackager )
				)
				( objectStatus "J4G1.56" )
			)
			( pin "@baseboard_fab2_lib.baseboard_fab2(sch_1):page43_i1:cb(3)"
				( attribute "PN" "201"
					( Origin gPackager )
				)
				( objectStatus "J4G1.201" )
			)
			( pin "@baseboard_fab2_lib.baseboard_fab2(sch_1):page43_i1:cb(4)"
				( attribute "PN" "47"
					( Origin gPackager )
				)
				( objectStatus "J4G1.47" )
			)
			( pin "@baseboard_fab2_lib.baseboard_fab2(sch_1):page43_i1:cb(5)"
				( attribute "PN" "192"
					( Origin gPackager )
				)
				( objectStatus "J4G1.192" )
			)
			( pin "@baseboard_fab2_lib.baseboard_fab2(sch_1):page43_i1:cb(6)"
				( attribute "PN" "54"
					( Origin gPackager )
				)
				( objectStatus "J4G1.54" )
			)
			( pin "@baseboard_fab2_lib.baseboard_fab2(sch_1):page43_i1:cb(7)"
				( attribute "PN" "199"
					( Origin gPackager )
				)
				( objectStatus "J4G1.199" )
			)
			( pin "@baseboard_fab2_lib.baseboard_fab2(sch_1):page43_i1:ck0n"
				( attribute "PN" "75"
					( Origin gPackager )
				)
				( objectStatus "J4G1.75" )
			)
			( pin "@baseboard_fab2_lib.baseboard_fab2(sch_1):page43_i1:ck0p"
				( attribute "PN" "74"
					( Origin gPackager )
				)
				( objectStatus "J4G1.74" )
			)
			( pin "@baseboard_fab2_lib.baseboard_fab2(sch_1):page43_i1:ck1n"
				( attribute "PN" "219"
					( Origin gPackager )
				)
				( objectStatus "J4G1.219" )
			)
			( pin "@baseboard_fab2_lib.baseboard_fab2(sch_1):page43_i1:ck1p"
				( attribute "PN" "218"
					( Origin gPackager )
				)
				( objectStatus "J4G1.218" )
			)
			( pin "@baseboard_fab2_lib.baseboard_fab2(sch_1):page43_i1:cke(0)"
				( attribute "PN" "60"
					( Origin gPackager )
				)
				( objectStatus "J4G1.60" )
			)
			( pin "@baseboard_fab2_lib.baseboard_fab2(sch_1):page43_i1:cke(1)"
				( attribute "PN" "203"
					( Origin gPackager )
				)
				( objectStatus "J4G1.203" )
			)
			( pin "@baseboard_fab2_lib.baseboard_fab2(sch_1):page43_i1:dq(0)"
				( attribute "PN" "5"
					( Origin gPackager )
				)
				( objectStatus "J4G1.5" )
			)
			( pin "@baseboard_fab2_lib.baseboard_fab2(sch_1):page43_i1:dq(1)"
				( attribute "PN" "150"
					( Origin gPackager )
				)
				( objectStatus "J4G1.150" )
			)
			( pin "@baseboard_fab2_lib.baseboard_fab2(sch_1):page43_i1:dq(2)"
				( attribute "PN" "12"
					( Origin gPackager )
				)
				( objectStatus "J4G1.12" )
			)
			( pin "@baseboard_fab2_lib.baseboard_fab2(sch_1):page43_i1:dq(3)"
				( attribute "PN" "157"
					( Origin gPackager )
				)
				( objectStatus "J4G1.157" )
			)
			( pin "@baseboard_fab2_lib.baseboard_fab2(sch_1):page43_i1:dq(4)"
				( attribute "PN" "3"
					( Origin gPackager )
				)
				( objectStatus "J4G1.3" )
			)
			( pin "@baseboard_fab2_lib.baseboard_fab2(sch_1):page43_i1:dq(5)"
				( attribute "PN" "148"
					( Origin gPackager )
				)
				( objectStatus "J4G1.148" )
			)
			( pin "@baseboard_fab2_lib.baseboard_fab2(sch_1):page43_i1:dq(6)"
				( attribute "PN" "10"
					( Origin gPackager )
				)
				( objectStatus "J4G1.10" )
			)
			( pin "@baseboard_fab2_lib.baseboard_fab2(sch_1):page43_i1:dq(7)"
				( attribute "PN" "155"
					( Origin gPackager )
				)
				( objectStatus "J4G1.155" )
			)
			( pin "@baseboard_fab2_lib.baseboard_fab2(sch_1):page43_i1:dq(8)"
				( attribute "PN" "16"
					( Origin gPackager )
				)
				( objectStatus "J4G1.16" )
			)
			( pin "@baseboard_fab2_lib.baseboard_fab2(sch_1):page43_i1:dq(9)"
				( attribute "PN" "161"
					( Origin gPackager )
				)
				( objectStatus "J4G1.161" )
			)
			( pin "@baseboard_fab2_lib.baseboard_fab2(sch_1):page43_i1:dq(10)"
				( attribute "PN" "23"
					( Origin gPackager )
				)
				( objectStatus "J4G1.23" )
			)
			( pin "@baseboard_fab2_lib.baseboard_fab2(sch_1):page43_i1:dq(11)"
				( attribute "PN" "168"
					( Origin gPackager )
				)
				( objectStatus "J4G1.168" )
			)
			( pin "@baseboard_fab2_lib.baseboard_fab2(sch_1):page43_i1:dq(12)"
				( attribute "PN" "14"
					( Origin gPackager )
				)
				( objectStatus "J4G1.14" )
			)
			( pin "@baseboard_fab2_lib.baseboard_fab2(sch_1):page43_i1:dq(13)"
				( attribute "PN" "159"
					( Origin gPackager )
				)
				( objectStatus "J4G1.159" )
			)
			( pin "@baseboard_fab2_lib.baseboard_fab2(sch_1):page43_i1:dq(14)"
				( attribute "PN" "21"
					( Origin gPackager )
				)
				( objectStatus "J4G1.21" )
			)
			( pin "@baseboard_fab2_lib.baseboard_fab2(sch_1):page43_i1:dq(15)"
				( attribute "PN" "166"
					( Origin gPackager )
				)
				( objectStatus "J4G1.166" )
			)
			( pin "@baseboard_fab2_lib.baseboard_fab2(sch_1):page43_i1:dq(16)"
				( attribute "PN" "27"
					( Origin gPackager )
				)
				( objectStatus "J4G1.27" )
			)
			( pin "@baseboard_fab2_lib.baseboard_fab2(sch_1):page43_i1:dq(17)"
				( attribute "PN" "172"
					( Origin gPackager )
				)
				( objectStatus "J4G1.172" )
			)
			( pin "@baseboard_fab2_lib.baseboard_fab2(sch_1):page43_i1:dq(18)"
				( attribute "PN" "34"
					( Origin gPackager )
				)
				( objectStatus "J4G1.34" )
			)
			( pin "@baseboard_fab2_lib.baseboard_fab2(sch_1):page43_i1:dq(19)"
				( attribute "PN" "179"
					( Origin gPackager )
				)
				( objectStatus "J4G1.179" )
			)
			( pin "@baseboard_fab2_lib.baseboard_fab2(sch_1):page43_i1:dq(20)"
				( attribute "PN" "25"
					( Origin gPackager )
				)
				( objectStatus "J4G1.25" )
			)
			( pin "@baseboard_fab2_lib.baseboard_fab2(sch_1):page43_i1:dq(21)"
				( attribute "PN" "170"
					( Origin gPackager )
				)
				( objectStatus "J4G1.170" )
			)
			( pin "@baseboard_fab2_lib.baseboard_fab2(sch_1):page43_i1:dq(22)"
				( attribute "PN" "32"
					( Origin gPackager )
				)
				( objectStatus "J4G1.32" )
			)
			( pin "@baseboard_fab2_lib.baseboard_fab2(sch_1):page43_i1:dq(23)"
				( attribute "PN" "177"
					( Origin gPackager )
				)
				( objectStatus "J4G1.177" )
			)
			( pin "@baseboard_fab2_lib.baseboard_fab2(sch_1):page43_i1:dq(24)"
				( attribute "PN" "38"
					( Origin gPackager )
				)
				( objectStatus "J4G1.38" )
			)
			( pin "@baseboard_fab2_lib.baseboard_fab2(sch_1):page43_i1:dq(25)"
				( attribute "PN" "183"
					( Origin gPackager )
				)
				( objectStatus "J4G1.183" )
			)
			( pin "@baseboard_fab2_lib.baseboard_fab2(sch_1):page43_i1:dq(26)"
				( attribute "PN" "45"
					( Origin gPackager )
				)
				( objectStatus "J4G1.45" )
			)
			( pin "@baseboard_fab2_lib.baseboard_fab2(sch_1):page43_i1:dq(27)"
				( attribute "PN" "190"
					( Origin gPackager )
				)
				( objectStatus "J4G1.190" )
			)
			( pin "@baseboard_fab2_lib.baseboard_fab2(sch_1):page43_i1:dq(28)"
				( attribute "PN" "36"
					( Origin gPackager )
				)
				( objectStatus "J4G1.36" )
			)
			( pin "@baseboard_fab2_lib.baseboard_fab2(sch_1):page43_i1:dq(29)"
				( attribute "PN" "181"
					( Origin gPackager )
				)
				( objectStatus "J4G1.181" )
			)
			( pin "@baseboard_fab2_lib.baseboard_fab2(sch_1):page43_i1:dq(30)"
				( attribute "PN" "43"
					( Origin gPackager )
				)
				( objectStatus "J4G1.43" )
			)
			( pin "@baseboard_fab2_lib.baseboard_fab2(sch_1):page43_i1:dq(31)"
				( attribute "PN" "188"
					( Origin gPackager )
				)
				( objectStatus "J4G1.188" )
			)
			( pin "@baseboard_fab2_lib.baseboard_fab2(sch_1):page43_i1:dq(32)"
				( attribute "PN" "97"
					( Origin gPackager )
				)
				( objectStatus "J4G1.97" )
			)
			( pin "@baseboard_fab2_lib.baseboard_fab2(sch_1):page43_i1:dq(33)"
				( attribute "PN" "242"
					( Origin gPackager )
				)
				( objectStatus "J4G1.242" )
			)
			( pin "@baseboard_fab2_lib.baseboard_fab2(sch_1):page43_i1:dq(34)"
				( attribute "PN" "104"
					( Origin gPackager )
				)
				( objectStatus "J4G1.104" )
			)
			( pin "@baseboard_fab2_lib.baseboard_fab2(sch_1):page43_i1:dq(35)"
				( attribute "PN" "249"
					( Origin gPackager )
				)
				( objectStatus "J4G1.249" )
			)
			( pin "@baseboard_fab2_lib.baseboard_fab2(sch_1):page43_i1:dq(36)"
				( attribute "PN" "95"
					( Origin gPackager )
				)
				( objectStatus "J4G1.95" )
			)
			( pin "@baseboard_fab2_lib.baseboard_fab2(sch_1):page43_i1:dq(37)"
				( attribute "PN" "240"
					( Origin gPackager )
				)
				( objectStatus "J4G1.240" )
			)
			( pin "@baseboard_fab2_lib.baseboard_fab2(sch_1):page43_i1:dq(38)"
				( attribute "PN" "102"
					( Origin gPackager )
				)
				( objectStatus "J4G1.102" )
			)
			( pin "@baseboard_fab2_lib.baseboard_fab2(sch_1):page43_i1:dq(39)"
				( attribute "PN" "247"
					( Origin gPackager )
				)
				( objectStatus "J4G1.247" )
			)
			( pin "@baseboard_fab2_lib.baseboard_fab2(sch_1):page43_i1:dq(40)"
				( attribute "PN" "108"
					( Origin gPackager )
				)
				( objectStatus "J4G1.108" )
			)
			( pin "@baseboard_fab2_lib.baseboard_fab2(sch_1):page43_i1:dq(41)"
				( attribute "PN" "253"
					( Origin gPackager )
				)
				( objectStatus "J4G1.253" )
			)
			( pin "@baseboard_fab2_lib.baseboard_fab2(sch_1):page43_i1:dq(42)"
				( attribute "PN" "115"
					( Origin gPackager )
				)
				( objectStatus "J4G1.115" )
			)
			( pin "@baseboard_fab2_lib.baseboard_fab2(sch_1):page43_i1:dq(43)"
				( attribute "PN" "260"
					( Origin gPackager )
				)
				( objectStatus "J4G1.260" )
			)
			( pin "@baseboard_fab2_lib.baseboard_fab2(sch_1):page43_i1:dq(44)"
				( attribute "PN" "106"
					( Origin gPackager )
				)
				( objectStatus "J4G1.106" )
			)
			( pin "@baseboard_fab2_lib.baseboard_fab2(sch_1):page43_i1:dq(45)"
				( attribute "PN" "251"
					( Origin gPackager )
				)
				( objectStatus "J4G1.251" )
			)
			( pin "@baseboard_fab2_lib.baseboard_fab2(sch_1):page43_i1:dq(46)"
				( attribute "PN" "113"
					( Origin gPackager )
				)
				( objectStatus "J4G1.113" )
			)
			( pin "@baseboard_fab2_lib.baseboard_fab2(sch_1):page43_i1:dq(47)"
				( attribute "PN" "258"
					( Origin gPackager )
				)
				( objectStatus "J4G1.258" )
			)
			( pin "@baseboard_fab2_lib.baseboard_fab2(sch_1):page43_i1:dq(48)"
				( attribute "PN" "119"
					( Origin gPackager )
				)
				( objectStatus "J4G1.119" )
			)
			( pin "@baseboard_fab2_lib.baseboard_fab2(sch_1):page43_i1:dq(49)"
				( attribute "PN" "264"
					( Origin gPackager )
				)
				( objectStatus "J4G1.264" )
			)
			( pin "@baseboard_fab2_lib.baseboard_fab2(sch_1):page43_i1:dq(50)"
				( attribute "PN" "126"
					( Origin gPackager )
				)
				( objectStatus "J4G1.126" )
			)
			( pin "@baseboard_fab2_lib.baseboard_fab2(sch_1):page43_i1:dq(51)"
				( attribute "PN" "271"
					( Origin gPackager )
				)
				( objectStatus "J4G1.271" )
			)
			( pin "@baseboard_fab2_lib.baseboard_fab2(sch_1):page43_i1:dq(52)"
				( attribute "PN" "117"
					( Origin gPackager )
				)
				( objectStatus "J4G1.117" )
			)
			( pin "@baseboard_fab2_lib.baseboard_fab2(sch_1):page43_i1:dq(53)"
				( attribute "PN" "262"
					( Origin gPackager )
				)
				( objectStatus "J4G1.262" )
			)
			( pin "@baseboard_fab2_lib.baseboard_fab2(sch_1):page43_i1:dq(54)"
				( attribute "PN" "124"
					( Origin gPackager )
				)
				( objectStatus "J4G1.124" )
			)
			( pin "@baseboard_fab2_lib.baseboard_fab2(sch_1):page43_i1:dq(55)"
				( attribute "PN" "269"
					( Origin gPackager )
				)
				( objectStatus "J4G1.269" )
			)
			( pin "@baseboard_fab2_lib.baseboard_fab2(sch_1):page43_i1:dq(56)"
				( attribute "PN" "130"
					( Origin gPackager )
				)
				( objectStatus "J4G1.130" )
			)
			( pin "@baseboard_fab2_lib.baseboard_fab2(sch_1):page43_i1:dq(57)"
				( attribute "PN" "275"
					( Origin gPackager )
				)
				( objectStatus "J4G1.275" )
			)
			( pin "@baseboard_fab2_lib.baseboard_fab2(sch_1):page43_i1:dq(58)"
				( attribute "PN" "137"
					( Origin gPackager )
				)
				( objectStatus "J4G1.137" )
			)
			( pin "@baseboard_fab2_lib.baseboard_fab2(sch_1):page43_i1:dq(59)"
				( attribute "PN" "282"
					( Origin gPackager )
				)
				( objectStatus "J4G1.282" )
			)
			( pin "@baseboard_fab2_lib.baseboard_fab2(sch_1):page43_i1:dq(60)"
				( attribute "PN" "128"
					( Origin gPackager )
				)
				( objectStatus "J4G1.128" )
			)
			( pin "@baseboard_fab2_lib.baseboard_fab2(sch_1):page43_i1:dq(61)"
				( attribute "PN" "273"
					( Origin gPackager )
				)
				( objectStatus "J4G1.273" )
			)
			( pin "@baseboard_fab2_lib.baseboard_fab2(sch_1):page43_i1:dq(62)"
				( attribute "PN" "135"
					( Origin gPackager )
				)
				( objectStatus "J4G1.135" )
			)
			( pin "@baseboard_fab2_lib.baseboard_fab2(sch_1):page43_i1:dq(63)"
				( attribute "PN" "280"
					( Origin gPackager )
				)
				( objectStatus "J4G1.280" )
			)
			( pin "@baseboard_fab2_lib.baseboard_fab2(sch_1):page43_i1:event_n"
				( attribute "PN" "78"
					( Origin gPackager )
				)
				( objectStatus "J4G1.78" )
			)
			( pin "@baseboard_fab2_lib.baseboard_fab2(sch_1):page43_i1:odt(0)"
				( attribute "PN" "87"
					( Origin gPackager )
				)
				( objectStatus "J4G1.87" )
			)
			( pin "@baseboard_fab2_lib.baseboard_fab2(sch_1):page43_i1:odt(1)"
				( attribute "PN" "91"
					( Origin gPackager )
				)
				( objectStatus "J4G1.91" )
			)
			( pin "@baseboard_fab2_lib.baseboard_fab2(sch_1):page43_i1:par"
				( attribute "PN" "222"
					( Origin gPackager )
				)
				( objectStatus "J4G1.222" )
			)
			( pin "@baseboard_fab2_lib.baseboard_fab2(sch_1):page43_i1:reset_n"
				( attribute "PN" "58"
					( Origin gPackager )
				)
				( objectStatus "J4G1.58" )
			)
			( pin "@baseboard_fab2_lib.baseboard_fab2(sch_1):page43_i1:rfu(0)"
				( attribute "PN" "205"
					( Origin gPackager )
				)
				( objectStatus "J4G1.205" )
			)
			( pin "@baseboard_fab2_lib.baseboard_fab2(sch_1):page43_i1:rfu(1)"
				( attribute "PN" "227"
					( Origin gPackager )
				)
				( objectStatus "J4G1.227" )
			)
			( pin "@baseboard_fab2_lib.baseboard_fab2(sch_1):page43_i1:rfu(2)"
				( attribute "PN" "144"
					( Origin gPackager )
				)
				( objectStatus "J4G1.144" )
			)
			( pin "@baseboard_fab2_lib.baseboard_fab2(sch_1):page43_i1:s0_n"
				( attribute "PN" "84"
					( Origin gPackager )
				)
				( objectStatus "J4G1.84" )
			)
			( pin "@baseboard_fab2_lib.baseboard_fab2(sch_1):page43_i1:s1_n"
				( attribute "PN" "89"
					( Origin gPackager )
				)
				( objectStatus "J4G1.89" )
			)
			( pin "@baseboard_fab2_lib.baseboard_fab2(sch_1):page43_i1:s2_n_c(0)"
				( attribute "PN" "93"
					( Origin gPackager )
				)
				( objectStatus "J4G1.93" )
			)
			( pin "@baseboard_fab2_lib.baseboard_fab2(sch_1):page43_i1:s3_n_c(1)"
				( attribute "PN" "237"
					( Origin gPackager )
				)
				( objectStatus "J4G1.237" )
			)
			( pin "@baseboard_fab2_lib.baseboard_fab2(sch_1):page43_i1:sa(0)"
				( attribute "PN" "139"
					( Origin gPackager )
				)
				( objectStatus "J4G1.139" )
			)
			( pin "@baseboard_fab2_lib.baseboard_fab2(sch_1):page43_i1:sa(1)"
				( attribute "PN" "140"
					( Origin gPackager )
				)
				( objectStatus "J4G1.140" )
			)
			( pin "@baseboard_fab2_lib.baseboard_fab2(sch_1):page43_i1:sa(2)"
				( attribute "PN" "238"
					( Origin gPackager )
				)
				( objectStatus "J4G1.238" )
			)
			( pin "@baseboard_fab2_lib.baseboard_fab2(sch_1):page43_i1:save_n_nc"
				( attribute "PN" "230"
					( Origin gPackager )
				)
				( objectStatus "J4G1.230" )
			)
			( pin "@baseboard_fab2_lib.baseboard_fab2(sch_1):page43_i1:scl"
				( attribute "PN" "141"
					( Origin gPackager )
				)
				( objectStatus "J4G1.141" )
			)
			( pin "@baseboard_fab2_lib.baseboard_fab2(sch_1):page43_i1:sda"
				( attribute "PN" "285"
					( Origin gPackager )
				)
				( objectStatus "J4G1.285" )
			)
			( pin "@baseboard_fab2_lib.baseboard_fab2(sch_1):page43_i1:vddspd"
				( attribute "PN" "284"
					( Origin gPackager )
				)
				( objectStatus "J4G1.284" )
			)
			( pin "@baseboard_fab2_lib.baseboard_fab2(sch_1):page43_i1:vrefca"
				( attribute "PN" "146"
					( Origin gPackager )
				)
				( objectStatus "J4G1.146" )
			)
			( pin "@baseboard_fab2_lib.baseboard_fab2(sch_1):page43_i2:dqs0n"
				( attribute "PN" "152"
					( Origin gPackager )
				)
				( objectStatus "J4G1.152" )
			)
			( pin "@baseboard_fab2_lib.baseboard_fab2(sch_1):page43_i2:dqs0p"
				( attribute "PN" "153"
					( Origin gPackager )
				)
				( objectStatus "J4G1.153" )
			)
			( pin "@baseboard_fab2_lib.baseboard_fab2(sch_1):page43_i2:dqs1n"
				( attribute "PN" "163"
					( Origin gPackager )
				)
				( objectStatus "J4G1.163" )
			)
			( pin "@baseboard_fab2_lib.baseboard_fab2(sch_1):page43_i2:dqs1p"
				( attribute "PN" "164"
					( Origin gPackager )
				)
				( objectStatus "J4G1.164" )
			)
			( pin "@baseboard_fab2_lib.baseboard_fab2(sch_1):page43_i2:dqs2n"
				( attribute "PN" "174"
					( Origin gPackager )
				)
				( objectStatus "J4G1.174" )
			)
			( pin "@baseboard_fab2_lib.baseboard_fab2(sch_1):page43_i2:dqs2p"
				( attribute "PN" "175"
					( Origin gPackager )
				)
				( objectStatus "J4G1.175" )
			)
			( pin "@baseboard_fab2_lib.baseboard_fab2(sch_1):page43_i2:dqs3n"
				( attribute "PN" "185"
					( Origin gPackager )
				)
				( objectStatus "J4G1.185" )
			)
			( pin "@baseboard_fab2_lib.baseboard_fab2(sch_1):page43_i2:dqs3p"
				( attribute "PN" "186"
					( Origin gPackager )
				)
				( objectStatus "J4G1.186" )
			)
			( pin "@baseboard_fab2_lib.baseboard_fab2(sch_1):page43_i2:dqs4n"
				( attribute "PN" "244"
					( Origin gPackager )
				)
				( objectStatus "J4G1.244" )
			)
			( pin "@baseboard_fab2_lib.baseboard_fab2(sch_1):page43_i2:dqs4p"
				( attribute "PN" "245"
					( Origin gPackager )
				)
				( objectStatus "J4G1.245" )
			)
			( pin "@baseboard_fab2_lib.baseboard_fab2(sch_1):page43_i2:dqs5n"
				( attribute "PN" "255"
					( Origin gPackager )
				)
				( objectStatus "J4G1.255" )
			)
			( pin "@baseboard_fab2_lib.baseboard_fab2(sch_1):page43_i2:dqs5p"
				( attribute "PN" "256"
					( Origin gPackager )
				)
				( objectStatus "J4G1.256" )
			)
			( pin "@baseboard_fab2_lib.baseboard_fab2(sch_1):page43_i2:dqs6n"
				( attribute "PN" "266"
					( Origin gPackager )
				)
				( objectStatus "J4G1.266" )
			)
			( pin "@baseboard_fab2_lib.baseboard_fab2(sch_1):page43_i2:dqs6p"
				( attribute "PN" "267"
					( Origin gPackager )
				)
				( objectStatus "J4G1.267" )
			)
			( pin "@baseboard_fab2_lib.baseboard_fab2(sch_1):page43_i2:dqs7n"
				( attribute "PN" "277"
					( Origin gPackager )
				)
				( objectStatus "J4G1.277" )
			)
			( pin "@baseboard_fab2_lib.baseboard_fab2(sch_1):page43_i2:dqs7p"
				( attribute "PN" "278"
					( Origin gPackager )
				)
				( objectStatus "J4G1.278" )
			)
			( pin "@baseboard_fab2_lib.baseboard_fab2(sch_1):page43_i2:dqs8n"
				( attribute "PN" "196"
					( Origin gPackager )
				)
				( objectStatus "J4G1.196" )
			)
			( pin "@baseboard_fab2_lib.baseboard_fab2(sch_1):page43_i2:dqs8p"
				( attribute "PN" "197"
					( Origin gPackager )
				)
				( objectStatus "J4G1.197" )
			)
			( pin "@baseboard_fab2_lib.baseboard_fab2(sch_1):page43_i2:dqs9n"
				( attribute "PN" "8"
					( Origin gPackager )
				)
				( objectStatus "J4G1.8" )
			)
			( pin "@baseboard_fab2_lib.baseboard_fab2(sch_1):page43_i2:dqs9p"
				( attribute "PN" "7"
					( Origin gPackager )
				)
				( objectStatus "J4G1.7" )
			)
			( pin "@baseboard_fab2_lib.baseboard_fab2(sch_1):page43_i2:dqs10n"
				( attribute "PN" "19"
					( Origin gPackager )
				)
				( objectStatus "J4G1.19" )
			)
			( pin "@baseboard_fab2_lib.baseboard_fab2(sch_1):page43_i2:dqs10p"
				( attribute "PN" "18"
					( Origin gPackager )
				)
				( objectStatus "J4G1.18" )
			)
			( pin "@baseboard_fab2_lib.baseboard_fab2(sch_1):page43_i2:dqs11n"
				( attribute "PN" "30"
					( Origin gPackager )
				)
				( objectStatus "J4G1.30" )
			)
			( pin "@baseboard_fab2_lib.baseboard_fab2(sch_1):page43_i2:dqs11p"
				( attribute "PN" "29"
					( Origin gPackager )
				)
				( objectStatus "J4G1.29" )
			)
			( pin "@baseboard_fab2_lib.baseboard_fab2(sch_1):page43_i2:dqs12n"
				( attribute "PN" "41"
					( Origin gPackager )
				)
				( objectStatus "J4G1.41" )
			)
			( pin "@baseboard_fab2_lib.baseboard_fab2(sch_1):page43_i2:dqs12p"
				( attribute "PN" "40"
					( Origin gPackager )
				)
				( objectStatus "J4G1.40" )
			)
			( pin "@baseboard_fab2_lib.baseboard_fab2(sch_1):page43_i2:dqs13n"
				( attribute "PN" "100"
					( Origin gPackager )
				)
				( objectStatus "J4G1.100" )
			)
			( pin "@baseboard_fab2_lib.baseboard_fab2(sch_1):page43_i2:dqs13p"
				( attribute "PN" "99"
					( Origin gPackager )
				)
				( objectStatus "J4G1.99" )
			)
			( pin "@baseboard_fab2_lib.baseboard_fab2(sch_1):page43_i2:dqs14n"
				( attribute "PN" "111"
					( Origin gPackager )
				)
				( objectStatus "J4G1.111" )
			)
			( pin "@baseboard_fab2_lib.baseboard_fab2(sch_1):page43_i2:dqs14p"
				( attribute "PN" "110"
					( Origin gPackager )
				)
				( objectStatus "J4G1.110" )
			)
			( pin "@baseboard_fab2_lib.baseboard_fab2(sch_1):page43_i2:dqs15n"
				( attribute "PN" "122"
					( Origin gPackager )
				)
				( objectStatus "J4G1.122" )
			)
			( pin "@baseboard_fab2_lib.baseboard_fab2(sch_1):page43_i2:dqs15p"
				( attribute "PN" "121"
					( Origin gPackager )
				)
				( objectStatus "J4G1.121" )
			)
			( pin "@baseboard_fab2_lib.baseboard_fab2(sch_1):page43_i2:dqs16n"
				( attribute "PN" "133"
					( Origin gPackager )
				)
				( objectStatus "J4G1.133" )
			)
			( pin "@baseboard_fab2_lib.baseboard_fab2(sch_1):page43_i2:dqs16p"
				( attribute "PN" "132"
					( Origin gPackager )
				)
				( objectStatus "J4G1.132" )
			)
			( pin "@baseboard_fab2_lib.baseboard_fab2(sch_1):page43_i2:dqs17n"
				( attribute "PN" "52"
					( Origin gPackager )
				)
				( objectStatus "J4G1.52" )
			)
			( pin "@baseboard_fab2_lib.baseboard_fab2(sch_1):page43_i2:dqs17p"
				( attribute "PN" "51"
					( Origin gPackager )
				)
				( objectStatus "J4G1.51" )
			)
			( pin "@baseboard_fab2_lib.baseboard_fab2(sch_1):page43_i259:vss(0)"
				( attribute "PN" "283"
					( Origin gPackager )
				)
				( objectStatus "J4G1.283" )
			)
			( pin "@baseboard_fab2_lib.baseboard_fab2(sch_1):page43_i259:vss(1)"
				( attribute "PN" "281"
					( Origin gPackager )
				)
				( objectStatus "J4G1.281" )
			)
			( pin "@baseboard_fab2_lib.baseboard_fab2(sch_1):page43_i259:vss(2)"
				( attribute "PN" "279"
					( Origin gPackager )
				)
				( objectStatus "J4G1.279" )
			)
			( pin "@baseboard_fab2_lib.baseboard_fab2(sch_1):page43_i259:vss(3)"
				( attribute "PN" "276"
					( Origin gPackager )
				)
				( objectStatus "J4G1.276" )
			)
			( pin "@baseboard_fab2_lib.baseboard_fab2(sch_1):page43_i259:vss(4)"
				( attribute "PN" "274"
					( Origin gPackager )
				)
				( objectStatus "J4G1.274" )
			)
			( pin "@baseboard_fab2_lib.baseboard_fab2(sch_1):page43_i259:vss(5)"
				( attribute "PN" "272"
					( Origin gPackager )
				)
				( objectStatus "J4G1.272" )
			)
			( pin "@baseboard_fab2_lib.baseboard_fab2(sch_1):page43_i259:vss(6)"
				( attribute "PN" "270"
					( Origin gPackager )
				)
				( objectStatus "J4G1.270" )
			)
			( pin "@baseboard_fab2_lib.baseboard_fab2(sch_1):page43_i259:vss(7)"
				( attribute "PN" "268"
					( Origin gPackager )
				)
				( objectStatus "J4G1.268" )
			)
			( pin "@baseboard_fab2_lib.baseboard_fab2(sch_1):page43_i259:vss(8)"
				( attribute "PN" "265"
					( Origin gPackager )
				)
				( objectStatus "J4G1.265" )
			)
			( pin "@baseboard_fab2_lib.baseboard_fab2(sch_1):page43_i259:vss(9)"
				( attribute "PN" "263"
					( Origin gPackager )
				)
				( objectStatus "J4G1.263" )
			)
			( pin "@baseboard_fab2_lib.baseboard_fab2(sch_1):page43_i259:vss(10)"
				( attribute "PN" "261"
					( Origin gPackager )
				)
				( objectStatus "J4G1.261" )
			)
			( pin "@baseboard_fab2_lib.baseboard_fab2(sch_1):page43_i259:vss(11)"
				( attribute "PN" "259"
					( Origin gPackager )
				)
				( objectStatus "J4G1.259" )
			)
			( pin "@baseboard_fab2_lib.baseboard_fab2(sch_1):page43_i259:vss(12)"
				( attribute "PN" "257"
					( Origin gPackager )
				)
				( objectStatus "J4G1.257" )
			)
			( pin "@baseboard_fab2_lib.baseboard_fab2(sch_1):page43_i259:vss(13)"
				( attribute "PN" "254"
					( Origin gPackager )
				)
				( objectStatus "J4G1.254" )
			)
			( pin "@baseboard_fab2_lib.baseboard_fab2(sch_1):page43_i259:vss(14)"
				( attribute "PN" "252"
					( Origin gPackager )
				)
				( objectStatus "J4G1.252" )
			)
			( pin "@baseboard_fab2_lib.baseboard_fab2(sch_1):page43_i259:vss(15)"
				( attribute "PN" "250"
					( Origin gPackager )
				)
				( objectStatus "J4G1.250" )
			)
			( pin "@baseboard_fab2_lib.baseboard_fab2(sch_1):page43_i259:vss(16)"
				( attribute "PN" "248"
					( Origin gPackager )
				)
				( objectStatus "J4G1.248" )
			)
			( pin "@baseboard_fab2_lib.baseboard_fab2(sch_1):page43_i259:vss(17)"
				( attribute "PN" "246"
					( Origin gPackager )
				)
				( objectStatus "J4G1.246" )
			)
			( pin "@baseboard_fab2_lib.baseboard_fab2(sch_1):page43_i259:vss(18)"
				( attribute "PN" "243"
					( Origin gPackager )
				)
				( objectStatus "J4G1.243" )
			)
			( pin "@baseboard_fab2_lib.baseboard_fab2(sch_1):page43_i259:vss(19)"
				( attribute "PN" "241"
					( Origin gPackager )
				)
				( objectStatus "J4G1.241" )
			)
			( pin "@baseboard_fab2_lib.baseboard_fab2(sch_1):page43_i259:vss(20)"
				( attribute "PN" "239"
					( Origin gPackager )
				)
				( objectStatus "J4G1.239" )
			)
			( pin "@baseboard_fab2_lib.baseboard_fab2(sch_1):page43_i259:vss(21)"
				( attribute "PN" "202"
					( Origin gPackager )
				)
				( objectStatus "J4G1.202" )
			)
			( pin "@baseboard_fab2_lib.baseboard_fab2(sch_1):page43_i259:vss(22)"
				( attribute "PN" "200"
					( Origin gPackager )
				)
				( objectStatus "J4G1.200" )
			)
			( pin "@baseboard_fab2_lib.baseboard_fab2(sch_1):page43_i259:vss(23)"
				( attribute "PN" "198"
					( Origin gPackager )
				)
				( objectStatus "J4G1.198" )
			)
			( pin "@baseboard_fab2_lib.baseboard_fab2(sch_1):page43_i259:vss(24)"
				( attribute "PN" "195"
					( Origin gPackager )
				)
				( objectStatus "J4G1.195" )
			)
			( pin "@baseboard_fab2_lib.baseboard_fab2(sch_1):page43_i259:vss(25)"
				( attribute "PN" "193"
					( Origin gPackager )
				)
				( objectStatus "J4G1.193" )
			)
			( pin "@baseboard_fab2_lib.baseboard_fab2(sch_1):page43_i259:vss(26)"
				( attribute "PN" "191"
					( Origin gPackager )
				)
				( objectStatus "J4G1.191" )
			)
			( pin "@baseboard_fab2_lib.baseboard_fab2(sch_1):page43_i259:vss(27)"
				( attribute "PN" "189"
					( Origin gPackager )
				)
				( objectStatus "J4G1.189" )
			)
			( pin "@baseboard_fab2_lib.baseboard_fab2(sch_1):page43_i259:vss(28)"
				( attribute "PN" "187"
					( Origin gPackager )
				)
				( objectStatus "J4G1.187" )
			)
			( pin "@baseboard_fab2_lib.baseboard_fab2(sch_1):page43_i259:vss(29)"
				( attribute "PN" "184"
					( Origin gPackager )
				)
				( objectStatus "J4G1.184" )
			)
			( pin "@baseboard_fab2_lib.baseboard_fab2(sch_1):page43_i259:vss(30)"
				( attribute "PN" "182"
					( Origin gPackager )
				)
				( objectStatus "J4G1.182" )
			)
			( pin "@baseboard_fab2_lib.baseboard_fab2(sch_1):page43_i259:vss(31)"
				( attribute "PN" "180"
					( Origin gPackager )
				)
				( objectStatus "J4G1.180" )
			)
			( pin "@baseboard_fab2_lib.baseboard_fab2(sch_1):page43_i259:vss(32)"
				( attribute "PN" "178"
					( Origin gPackager )
				)
				( objectStatus "J4G1.178" )
			)
			( pin "@baseboard_fab2_lib.baseboard_fab2(sch_1):page43_i259:vss(33)"
				( attribute "PN" "176"
					( Origin gPackager )
				)
				( objectStatus "J4G1.176" )
			)
			( pin "@baseboard_fab2_lib.baseboard_fab2(sch_1):page43_i259:vss(34)"
				( attribute "PN" "173"
					( Origin gPackager )
				)
				( objectStatus "J4G1.173" )
			)
			( pin "@baseboard_fab2_lib.baseboard_fab2(sch_1):page43_i259:vss(35)"
				( attribute "PN" "171"
					( Origin gPackager )
				)
				( objectStatus "J4G1.171" )
			)
			( pin "@baseboard_fab2_lib.baseboard_fab2(sch_1):page43_i259:vss(36)"
				( attribute "PN" "169"
					( Origin gPackager )
				)
				( objectStatus "J4G1.169" )
			)
			( pin "@baseboard_fab2_lib.baseboard_fab2(sch_1):page43_i259:vss(37)"
				( attribute "PN" "167"
					( Origin gPackager )
				)
				( objectStatus "J4G1.167" )
			)
			( pin "@baseboard_fab2_lib.baseboard_fab2(sch_1):page43_i259:vss(38)"
				( attribute "PN" "165"
					( Origin gPackager )
				)
				( objectStatus "J4G1.165" )
			)
			( pin "@baseboard_fab2_lib.baseboard_fab2(sch_1):page43_i259:vss(39)"
				( attribute "PN" "162"
					( Origin gPackager )
				)
				( objectStatus "J4G1.162" )
			)
			( pin "@baseboard_fab2_lib.baseboard_fab2(sch_1):page43_i259:vss(40)"
				( attribute "PN" "160"
					( Origin gPackager )
				)
				( objectStatus "J4G1.160" )
			)
			( pin "@baseboard_fab2_lib.baseboard_fab2(sch_1):page43_i259:vss(41)"
				( attribute "PN" "158"
					( Origin gPackager )
				)
				( objectStatus "J4G1.158" )
			)
			( pin "@baseboard_fab2_lib.baseboard_fab2(sch_1):page43_i259:vss(42)"
				( attribute "PN" "156"
					( Origin gPackager )
				)
				( objectStatus "J4G1.156" )
			)
			( pin "@baseboard_fab2_lib.baseboard_fab2(sch_1):page43_i259:vss(43)"
				( attribute "PN" "154"
					( Origin gPackager )
				)
				( objectStatus "J4G1.154" )
			)
			( pin "@baseboard_fab2_lib.baseboard_fab2(sch_1):page43_i259:vss(44)"
				( attribute "PN" "151"
					( Origin gPackager )
				)
				( objectStatus "J4G1.151" )
			)
			( pin "@baseboard_fab2_lib.baseboard_fab2(sch_1):page43_i259:vss(45)"
				( attribute "PN" "149"
					( Origin gPackager )
				)
				( objectStatus "J4G1.149" )
			)
			( pin "@baseboard_fab2_lib.baseboard_fab2(sch_1):page43_i259:vss(46)"
				( attribute "PN" "147"
					( Origin gPackager )
				)
				( objectStatus "J4G1.147" )
			)
			( pin "@baseboard_fab2_lib.baseboard_fab2(sch_1):page43_i259:vss(47)"
				( attribute "PN" "138"
					( Origin gPackager )
				)
				( objectStatus "J4G1.138" )
			)
			( pin "@baseboard_fab2_lib.baseboard_fab2(sch_1):page43_i259:vss(48)"
				( attribute "PN" "136"
					( Origin gPackager )
				)
				( objectStatus "J4G1.136" )
			)
			( pin "@baseboard_fab2_lib.baseboard_fab2(sch_1):page43_i259:vss(49)"
				( attribute "PN" "134"
					( Origin gPackager )
				)
				( objectStatus "J4G1.134" )
			)
			( pin "@baseboard_fab2_lib.baseboard_fab2(sch_1):page43_i259:vss(50)"
				( attribute "PN" "131"
					( Origin gPackager )
				)
				( objectStatus "J4G1.131" )
			)
			( pin "@baseboard_fab2_lib.baseboard_fab2(sch_1):page43_i259:vss(51)"
				( attribute "PN" "129"
					( Origin gPackager )
				)
				( objectStatus "J4G1.129" )
			)
			( pin "@baseboard_fab2_lib.baseboard_fab2(sch_1):page43_i259:vss(52)"
				( attribute "PN" "127"
					( Origin gPackager )
				)
				( objectStatus "J4G1.127" )
			)
			( pin "@baseboard_fab2_lib.baseboard_fab2(sch_1):page43_i259:vss(53)"
				( attribute "PN" "125"
					( Origin gPackager )
				)
				( objectStatus "J4G1.125" )
			)
			( pin "@baseboard_fab2_lib.baseboard_fab2(sch_1):page43_i259:vss(54)"
				( attribute "PN" "123"
					( Origin gPackager )
				)
				( objectStatus "J4G1.123" )
			)
			( pin "@baseboard_fab2_lib.baseboard_fab2(sch_1):page43_i259:vss(55)"
				( attribute "PN" "120"
					( Origin gPackager )
				)
				( objectStatus "J4G1.120" )
			)
			( pin "@baseboard_fab2_lib.baseboard_fab2(sch_1):page43_i259:vss(56)"
				( attribute "PN" "118"
					( Origin gPackager )
				)
				( objectStatus "J4G1.118" )
			)
			( pin "@baseboard_fab2_lib.baseboard_fab2(sch_1):page43_i259:vss(57)"
				( attribute "PN" "116"
					( Origin gPackager )
				)
				( objectStatus "J4G1.116" )
			)
			( pin "@baseboard_fab2_lib.baseboard_fab2(sch_1):page43_i259:vss(58)"
				( attribute "PN" "114"
					( Origin gPackager )
				)
				( objectStatus "J4G1.114" )
			)
			( pin "@baseboard_fab2_lib.baseboard_fab2(sch_1):page43_i259:vss(59)"
				( attribute "PN" "112"
					( Origin gPackager )
				)
				( objectStatus "J4G1.112" )
			)
			( pin "@baseboard_fab2_lib.baseboard_fab2(sch_1):page43_i259:vss(60)"
				( attribute "PN" "109"
					( Origin gPackager )
				)
				( objectStatus "J4G1.109" )
			)
			( pin "@baseboard_fab2_lib.baseboard_fab2(sch_1):page43_i259:vss(61)"
				( attribute "PN" "107"
					( Origin gPackager )
				)
				( objectStatus "J4G1.107" )
			)
			( pin "@baseboard_fab2_lib.baseboard_fab2(sch_1):page43_i259:vss(62)"
				( attribute "PN" "105"
					( Origin gPackager )
				)
				( objectStatus "J4G1.105" )
			)
			( pin "@baseboard_fab2_lib.baseboard_fab2(sch_1):page43_i259:vss(63)"
				( attribute "PN" "103"
					( Origin gPackager )
				)
				( objectStatus "J4G1.103" )
			)
			( pin "@baseboard_fab2_lib.baseboard_fab2(sch_1):page43_i259:vss(64)"
				( attribute "PN" "101"
					( Origin gPackager )
				)
				( objectStatus "J4G1.101" )
			)
			( pin "@baseboard_fab2_lib.baseboard_fab2(sch_1):page43_i259:vss(65)"
				( attribute "PN" "98"
					( Origin gPackager )
				)
				( objectStatus "J4G1.98" )
			)
			( pin "@baseboard_fab2_lib.baseboard_fab2(sch_1):page43_i259:vss(66)"
				( attribute "PN" "96"
					( Origin gPackager )
				)
				( objectStatus "J4G1.96" )
			)
			( pin "@baseboard_fab2_lib.baseboard_fab2(sch_1):page43_i259:vss(67)"
				( attribute "PN" "94"
					( Origin gPackager )
				)
				( objectStatus "J4G1.94" )
			)
			( pin "@baseboard_fab2_lib.baseboard_fab2(sch_1):page43_i259:vss(68)"
				( attribute "PN" "57"
					( Origin gPackager )
				)
				( objectStatus "J4G1.57" )
			)
			( pin "@baseboard_fab2_lib.baseboard_fab2(sch_1):page43_i259:vss(69)"
				( attribute "PN" "55"
					( Origin gPackager )
				)
				( objectStatus "J4G1.55" )
			)
			( pin "@baseboard_fab2_lib.baseboard_fab2(sch_1):page43_i259:vss(70)"
				( attribute "PN" "53"
					( Origin gPackager )
				)
				( objectStatus "J4G1.53" )
			)
			( pin "@baseboard_fab2_lib.baseboard_fab2(sch_1):page43_i259:vss(71)"
				( attribute "PN" "50"
					( Origin gPackager )
				)
				( objectStatus "J4G1.50" )
			)
			( pin "@baseboard_fab2_lib.baseboard_fab2(sch_1):page43_i259:vss(72)"
				( attribute "PN" "48"
					( Origin gPackager )
				)
				( objectStatus "J4G1.48" )
			)
			( pin "@baseboard_fab2_lib.baseboard_fab2(sch_1):page43_i259:vss(73)"
				( attribute "PN" "46"
					( Origin gPackager )
				)
				( objectStatus "J4G1.46" )
			)
			( pin "@baseboard_fab2_lib.baseboard_fab2(sch_1):page43_i259:vss(74)"
				( attribute "PN" "44"
					( Origin gPackager )
				)
				( objectStatus "J4G1.44" )
			)
			( pin "@baseboard_fab2_lib.baseboard_fab2(sch_1):page43_i259:vss(75)"
				( attribute "PN" "42"
					( Origin gPackager )
				)
				( objectStatus "J4G1.42" )
			)
			( pin "@baseboard_fab2_lib.baseboard_fab2(sch_1):page43_i259:vss(76)"
				( attribute "PN" "39"
					( Origin gPackager )
				)
				( objectStatus "J4G1.39" )
			)
			( pin "@baseboard_fab2_lib.baseboard_fab2(sch_1):page43_i259:vss(77)"
				( attribute "PN" "37"
					( Origin gPackager )
				)
				( objectStatus "J4G1.37" )
			)
			( pin "@baseboard_fab2_lib.baseboard_fab2(sch_1):page43_i259:vss(78)"
				( attribute "PN" "35"
					( Origin gPackager )
				)
				( objectStatus "J4G1.35" )
			)
			( pin "@baseboard_fab2_lib.baseboard_fab2(sch_1):page43_i259:vss(79)"
				( attribute "PN" "33"
					( Origin gPackager )
				)
				( objectStatus "J4G1.33" )
			)
			( pin "@baseboard_fab2_lib.baseboard_fab2(sch_1):page43_i259:vss(80)"
				( attribute "PN" "31"
					( Origin gPackager )
				)
				( objectStatus "J4G1.31" )
			)
			( pin "@baseboard_fab2_lib.baseboard_fab2(sch_1):page43_i259:vss(81)"
				( attribute "PN" "28"
					( Origin gPackager )
				)
				( objectStatus "J4G1.28" )
			)
			( pin "@baseboard_fab2_lib.baseboard_fab2(sch_1):page43_i259:vss(82)"
				( attribute "PN" "26"
					( Origin gPackager )
				)
				( objectStatus "J4G1.26" )
			)
			( pin "@baseboard_fab2_lib.baseboard_fab2(sch_1):page43_i259:vss(83)"
				( attribute "PN" "24"
					( Origin gPackager )
				)
				( objectStatus "J4G1.24" )
			)
			( pin "@baseboard_fab2_lib.baseboard_fab2(sch_1):page43_i259:vss(84)"
				( attribute "PN" "22"
					( Origin gPackager )
				)
				( objectStatus "J4G1.22" )
			)
			( pin "@baseboard_fab2_lib.baseboard_fab2(sch_1):page43_i259:vss(85)"
				( attribute "PN" "20"
					( Origin gPackager )
				)
				( objectStatus "J4G1.20" )
			)
			( pin "@baseboard_fab2_lib.baseboard_fab2(sch_1):page43_i259:vss(86)"
				( attribute "PN" "17"
					( Origin gPackager )
				)
				( objectStatus "J4G1.17" )
			)
			( pin "@baseboard_fab2_lib.baseboard_fab2(sch_1):page43_i259:vss(87)"
				( attribute "PN" "15"
					( Origin gPackager )
				)
				( objectStatus "J4G1.15" )
			)
			( pin "@baseboard_fab2_lib.baseboard_fab2(sch_1):page43_i259:vss(88)"
				( attribute "PN" "13"
					( Origin gPackager )
				)
				( objectStatus "J4G1.13" )
			)
			( pin "@baseboard_fab2_lib.baseboard_fab2(sch_1):page43_i259:vss(89)"
				( attribute "PN" "11"
					( Origin gPackager )
				)
				( objectStatus "J4G1.11" )
			)
			( pin "@baseboard_fab2_lib.baseboard_fab2(sch_1):page43_i259:vss(90)"
				( attribute "PN" "9"
					( Origin gPackager )
				)
				( objectStatus "J4G1.9" )
			)
			( pin "@baseboard_fab2_lib.baseboard_fab2(sch_1):page43_i259:vss(91)"
				( attribute "PN" "6"
					( Origin gPackager )
				)
				( objectStatus "J4G1.6" )
			)
			( pin "@baseboard_fab2_lib.baseboard_fab2(sch_1):page43_i259:vss(92)"
				( attribute "PN" "4"
					( Origin gPackager )
				)
				( objectStatus "J4G1.4" )
			)
			( pin "@baseboard_fab2_lib.baseboard_fab2(sch_1):page43_i259:vss(93)"
				( attribute "PN" "2"
					( Origin gPackager )
				)
				( objectStatus "J4G1.2" )
			)
			( pin "@baseboard_fab2_lib.baseboard_fab2(sch_1):page43_i260:\12v\(0)"
				( attribute "PN" "145"
					( Origin gPackager )
				)
				( objectStatus "J4G1.145" )
			)
			( pin "@baseboard_fab2_lib.baseboard_fab2(sch_1):page43_i260:\12v\(1)"
				( attribute "PN" "1"
					( Origin gPackager )
				)
				( objectStatus "J4G1.1" )
			)
			( pin "@baseboard_fab2_lib.baseboard_fab2(sch_1):page43_i260:vdd(0)"
				( attribute "PN" "236"
					( Origin gPackager )
				)
				( objectStatus "J4G1.236" )
			)
			( pin "@baseboard_fab2_lib.baseboard_fab2(sch_1):page43_i260:vdd(1)"
				( attribute "PN" "233"
					( Origin gPackager )
				)
				( objectStatus "J4G1.233" )
			)
			( pin "@baseboard_fab2_lib.baseboard_fab2(sch_1):page43_i260:vdd(2)"
				( attribute "PN" "231"
					( Origin gPackager )
				)
				( objectStatus "J4G1.231" )
			)
			( pin "@baseboard_fab2_lib.baseboard_fab2(sch_1):page43_i260:vdd(3)"
				( attribute "PN" "229"
					( Origin gPackager )
				)
				( objectStatus "J4G1.229" )
			)
			( pin "@baseboard_fab2_lib.baseboard_fab2(sch_1):page43_i260:vdd(4)"
				( attribute "PN" "226"
					( Origin gPackager )
				)
				( objectStatus "J4G1.226" )
			)
			( pin "@baseboard_fab2_lib.baseboard_fab2(sch_1):page43_i260:vdd(5)"
				( attribute "PN" "223"
					( Origin gPackager )
				)
				( objectStatus "J4G1.223" )
			)
			( pin "@baseboard_fab2_lib.baseboard_fab2(sch_1):page43_i260:vdd(6)"
				( attribute "PN" "220"
					( Origin gPackager )
				)
				( objectStatus "J4G1.220" )
			)
			( pin "@baseboard_fab2_lib.baseboard_fab2(sch_1):page43_i260:vdd(7)"
				( attribute "PN" "217"
					( Origin gPackager )
				)
				( objectStatus "J4G1.217" )
			)
			( pin "@baseboard_fab2_lib.baseboard_fab2(sch_1):page43_i260:vdd(8)"
				( attribute "PN" "215"
					( Origin gPackager )
				)
				( objectStatus "J4G1.215" )
			)
			( pin "@baseboard_fab2_lib.baseboard_fab2(sch_1):page43_i260:vdd(9)"
				( attribute "PN" "212"
					( Origin gPackager )
				)
				( objectStatus "J4G1.212" )
			)
			( pin "@baseboard_fab2_lib.baseboard_fab2(sch_1):page43_i260:vdd(10)"
				( attribute "PN" "209"
					( Origin gPackager )
				)
				( objectStatus "J4G1.209" )
			)
			( pin "@baseboard_fab2_lib.baseboard_fab2(sch_1):page43_i260:vdd(11)"
				( attribute "PN" "206"
					( Origin gPackager )
				)
				( objectStatus "J4G1.206" )
			)
			( pin "@baseboard_fab2_lib.baseboard_fab2(sch_1):page43_i260:vdd(12)"
				( attribute "PN" "204"
					( Origin gPackager )
				)
				( objectStatus "J4G1.204" )
			)
			( pin "@baseboard_fab2_lib.baseboard_fab2(sch_1):page43_i260:vdd(13)"
				( attribute "PN" "92"
					( Origin gPackager )
				)
				( objectStatus "J4G1.92" )
			)
			( pin "@baseboard_fab2_lib.baseboard_fab2(sch_1):page43_i260:vdd(14)"
				( attribute "PN" "90"
					( Origin gPackager )
				)
				( objectStatus "J4G1.90" )
			)
			( pin "@baseboard_fab2_lib.baseboard_fab2(sch_1):page43_i260:vdd(15)"
				( attribute "PN" "88"
					( Origin gPackager )
				)
				( objectStatus "J4G1.88" )
			)
			( pin "@baseboard_fab2_lib.baseboard_fab2(sch_1):page43_i260:vdd(16)"
				( attribute "PN" "85"
					( Origin gPackager )
				)
				( objectStatus "J4G1.85" )
			)
			( pin "@baseboard_fab2_lib.baseboard_fab2(sch_1):page43_i260:vdd(17)"
				( attribute "PN" "83"
					( Origin gPackager )
				)
				( objectStatus "J4G1.83" )
			)
			( pin "@baseboard_fab2_lib.baseboard_fab2(sch_1):page43_i260:vdd(18)"
				( attribute "PN" "80"
					( Origin gPackager )
				)
				( objectStatus "J4G1.80" )
			)
			( pin "@baseboard_fab2_lib.baseboard_fab2(sch_1):page43_i260:vdd(19)"
				( attribute "PN" "76"
					( Origin gPackager )
				)
				( objectStatus "J4G1.76" )
			)
			( pin "@baseboard_fab2_lib.baseboard_fab2(sch_1):page43_i260:vdd(20)"
				( attribute "PN" "73"
					( Origin gPackager )
				)
				( objectStatus "J4G1.73" )
			)
			( pin "@baseboard_fab2_lib.baseboard_fab2(sch_1):page43_i260:vdd(21)"
				( attribute "PN" "70"
					( Origin gPackager )
				)
				( objectStatus "J4G1.70" )
			)
			( pin "@baseboard_fab2_lib.baseboard_fab2(sch_1):page43_i260:vdd(22)"
				( attribute "PN" "67"
					( Origin gPackager )
				)
				( objectStatus "J4G1.67" )
			)
			( pin "@baseboard_fab2_lib.baseboard_fab2(sch_1):page43_i260:vdd(23)"
				( attribute "PN" "64"
					( Origin gPackager )
				)
				( objectStatus "J4G1.64" )
			)
			( pin "@baseboard_fab2_lib.baseboard_fab2(sch_1):page43_i260:vdd(24)"
				( attribute "PN" "61"
					( Origin gPackager )
				)
				( objectStatus "J4G1.61" )
			)
			( pin "@baseboard_fab2_lib.baseboard_fab2(sch_1):page43_i260:vdd(25)"
				( attribute "PN" "59"
					( Origin gPackager )
				)
				( objectStatus "J4G1.59" )
			)
			( pin "@baseboard_fab2_lib.baseboard_fab2(sch_1):page43_i260:vpp(0)"
				( attribute "PN" "287"
					( Origin gPackager )
				)
				( objectStatus "J4G1.287" )
			)
			( pin "@baseboard_fab2_lib.baseboard_fab2(sch_1):page43_i260:vpp(1)"
				( attribute "PN" "286"
					( Origin gPackager )
				)
				( objectStatus "J4G1.286" )
			)
			( pin "@baseboard_fab2_lib.baseboard_fab2(sch_1):page43_i260:vpp(2)"
				( attribute "PN" "288"
					( Origin gPackager )
				)
				( objectStatus "J4G1.288" )
			)
			( pin "@baseboard_fab2_lib.baseboard_fab2(sch_1):page43_i260:vpp(3)"
				( attribute "PN" "143"
					( Origin gPackager )
				)
				( objectStatus "J4G1.143" )
			)
			( pin "@baseboard_fab2_lib.baseboard_fab2(sch_1):page43_i260:vpp(4)"
				( attribute "PN" "142"
					( Origin gPackager )
				)
				( objectStatus "J4G1.142" )
			)
			( pin "@baseboard_fab2_lib.baseboard_fab2(sch_1):page43_i260:vtt(0)"
				( attribute "PN" "221"
					( Origin gPackager )
				)
				( objectStatus "J4G1.221" )
			)
			( pin "@baseboard_fab2_lib.baseboard_fab2(sch_1):page43_i260:vtt(1)"
				( attribute "PN" "77"
					( Origin gPackager )
				)
				( objectStatus "J4G1.77" )
			)
			( pin "@baseboard_fab2_lib.baseboard_fab2(sch_1):page43_i272:a"
				( attribute "PN" "1"
					( Origin gPackager )
				)
				( objectStatus "C4F10.1" )
			)
			( pin "@baseboard_fab2_lib.baseboard_fab2(sch_1):page43_i272:b"
				( attribute "PN" "2"
					( Origin gPackager )
				)
				( objectStatus "C4F10.2" )
			)
			( pin "@baseboard_fab2_lib.baseboard_fab2(sch_1):page44_i2:a"
				( attribute "PN" "1"
					( Origin gPackager )
				)
				( objectStatus "C6T1.1" )
			)
			( pin "@baseboard_fab2_lib.baseboard_fab2(sch_1):page44_i2:b"
				( attribute "PN" "2"
					( Origin gPackager )
				)
				( objectStatus "C6T1.2" )
			)
			( pin "@baseboard_fab2_lib.baseboard_fab2(sch_1):page44_i13:a0"
				( attribute "PN" "79"
					( Origin gPackager )
				)
				( objectStatus "J6T1.79" )
			)
			( pin "@baseboard_fab2_lib.baseboard_fab2(sch_1):page44_i13:a1"
				( attribute "PN" "72"
					( Origin gPackager )
				)
				( objectStatus "J6T1.72" )
			)
			( pin "@baseboard_fab2_lib.baseboard_fab2(sch_1):page44_i13:a2"
				( attribute "PN" "216"
					( Origin gPackager )
				)
				( objectStatus "J6T1.216" )
			)
			( pin "@baseboard_fab2_lib.baseboard_fab2(sch_1):page44_i13:a3"
				( attribute "PN" "71"
					( Origin gPackager )
				)
				( objectStatus "J6T1.71" )
			)
			( pin "@baseboard_fab2_lib.baseboard_fab2(sch_1):page44_i13:a4"
				( attribute "PN" "214"
					( Origin gPackager )
				)
				( objectStatus "J6T1.214" )
			)
			( pin "@baseboard_fab2_lib.baseboard_fab2(sch_1):page44_i13:a5"
				( attribute "PN" "213"
					( Origin gPackager )
				)
				( objectStatus "J6T1.213" )
			)
			( pin "@baseboard_fab2_lib.baseboard_fab2(sch_1):page44_i13:a6"
				( attribute "PN" "69"
					( Origin gPackager )
				)
				( objectStatus "J6T1.69" )
			)
			( pin "@baseboard_fab2_lib.baseboard_fab2(sch_1):page44_i13:a7"
				( attribute "PN" "211"
					( Origin gPackager )
				)
				( objectStatus "J6T1.211" )
			)
			( pin "@baseboard_fab2_lib.baseboard_fab2(sch_1):page44_i13:a8"
				( attribute "PN" "68"
					( Origin gPackager )
				)
				( objectStatus "J6T1.68" )
			)
			( pin "@baseboard_fab2_lib.baseboard_fab2(sch_1):page44_i13:a9"
				( attribute "PN" "66"
					( Origin gPackager )
				)
				( objectStatus "J6T1.66" )
			)
			( pin "@baseboard_fab2_lib.baseboard_fab2(sch_1):page44_i13:a10"
				( attribute "PN" "225"
					( Origin gPackager )
				)
				( objectStatus "J6T1.225" )
			)
			( pin "@baseboard_fab2_lib.baseboard_fab2(sch_1):page44_i13:a11"
				( attribute "PN" "210"
					( Origin gPackager )
				)
				( objectStatus "J6T1.210" )
			)
			( pin "@baseboard_fab2_lib.baseboard_fab2(sch_1):page44_i13:a12"
				( attribute "PN" "65"
					( Origin gPackager )
				)
				( objectStatus "J6T1.65" )
			)
			( pin "@baseboard_fab2_lib.baseboard_fab2(sch_1):page44_i13:a13"
				( attribute "PN" "232"
					( Origin gPackager )
				)
				( objectStatus "J6T1.232" )
			)
			( pin "@baseboard_fab2_lib.baseboard_fab2(sch_1):page44_i13:a14_we_n"
				( attribute "PN" "228"
					( Origin gPackager )
				)
				( objectStatus "J6T1.228" )
			)
			( pin "@baseboard_fab2_lib.baseboard_fab2(sch_1):page44_i13:a15_cas_n"
				( attribute "PN" "86"
					( Origin gPackager )
				)
				( objectStatus "J6T1.86" )
			)
			( pin "@baseboard_fab2_lib.baseboard_fab2(sch_1):page44_i13:a16_ras_n"
				( attribute "PN" "82"
					( Origin gPackager )
				)
				( objectStatus "J6T1.82" )
			)
			( pin "@baseboard_fab2_lib.baseboard_fab2(sch_1):page44_i13:a17"
				( attribute "PN" "234"
					( Origin gPackager )
				)
				( objectStatus "J6T1.234" )
			)
			( pin "@baseboard_fab2_lib.baseboard_fab2(sch_1):page44_i13:act_n"
				( attribute "PN" "62"
					( Origin gPackager )
				)
				( objectStatus "J6T1.62" )
			)
			( pin "@baseboard_fab2_lib.baseboard_fab2(sch_1):page44_i13:alert_n"
				( attribute "PN" "208"
					( Origin gPackager )
				)
				( objectStatus "J6T1.208" )
			)
			( pin "@baseboard_fab2_lib.baseboard_fab2(sch_1):page44_i13:ba(0)"
				( attribute "PN" "81"
					( Origin gPackager )
				)
				( objectStatus "J6T1.81" )
			)
			( pin "@baseboard_fab2_lib.baseboard_fab2(sch_1):page44_i13:ba(1)"
				( attribute "PN" "224"
					( Origin gPackager )
				)
				( objectStatus "J6T1.224" )
			)
			( pin "@baseboard_fab2_lib.baseboard_fab2(sch_1):page44_i13:bg(0)"
				( attribute "PN" "63"
					( Origin gPackager )
				)
				( objectStatus "J6T1.63" )
			)
			( pin "@baseboard_fab2_lib.baseboard_fab2(sch_1):page44_i13:bg(1)"
				( attribute "PN" "207"
					( Origin gPackager )
				)
				( objectStatus "J6T1.207" )
			)
			( pin "@baseboard_fab2_lib.baseboard_fab2(sch_1):page44_i13:c(2)"
				( attribute "PN" "235"
					( Origin gPackager )
				)
				( objectStatus "J6T1.235" )
			)
			( pin "@baseboard_fab2_lib.baseboard_fab2(sch_1):page44_i13:cb(0)"
				( attribute "PN" "49"
					( Origin gPackager )
				)
				( objectStatus "J6T1.49" )
			)
			( pin "@baseboard_fab2_lib.baseboard_fab2(sch_1):page44_i13:cb(1)"
				( attribute "PN" "194"
					( Origin gPackager )
				)
				( objectStatus "J6T1.194" )
			)
			( pin "@baseboard_fab2_lib.baseboard_fab2(sch_1):page44_i13:cb(2)"
				( attribute "PN" "56"
					( Origin gPackager )
				)
				( objectStatus "J6T1.56" )
			)
			( pin "@baseboard_fab2_lib.baseboard_fab2(sch_1):page44_i13:cb(3)"
				( attribute "PN" "201"
					( Origin gPackager )
				)
				( objectStatus "J6T1.201" )
			)
			( pin "@baseboard_fab2_lib.baseboard_fab2(sch_1):page44_i13:cb(4)"
				( attribute "PN" "47"
					( Origin gPackager )
				)
				( objectStatus "J6T1.47" )
			)
			( pin "@baseboard_fab2_lib.baseboard_fab2(sch_1):page44_i13:cb(5)"
				( attribute "PN" "192"
					( Origin gPackager )
				)
				( objectStatus "J6T1.192" )
			)
			( pin "@baseboard_fab2_lib.baseboard_fab2(sch_1):page44_i13:cb(6)"
				( attribute "PN" "54"
					( Origin gPackager )
				)
				( objectStatus "J6T1.54" )
			)
			( pin "@baseboard_fab2_lib.baseboard_fab2(sch_1):page44_i13:cb(7)"
				( attribute "PN" "199"
					( Origin gPackager )
				)
				( objectStatus "J6T1.199" )
			)
			( pin "@baseboard_fab2_lib.baseboard_fab2(sch_1):page44_i13:ck0n"
				( attribute "PN" "75"
					( Origin gPackager )
				)
				( objectStatus "J6T1.75" )
			)
			( pin "@baseboard_fab2_lib.baseboard_fab2(sch_1):page44_i13:ck0p"
				( attribute "PN" "74"
					( Origin gPackager )
				)
				( objectStatus "J6T1.74" )
			)
			( pin "@baseboard_fab2_lib.baseboard_fab2(sch_1):page44_i13:ck1n"
				( attribute "PN" "219"
					( Origin gPackager )
				)
				( objectStatus "J6T1.219" )
			)
			( pin "@baseboard_fab2_lib.baseboard_fab2(sch_1):page44_i13:ck1p"
				( attribute "PN" "218"
					( Origin gPackager )
				)
				( objectStatus "J6T1.218" )
			)
			( pin "@baseboard_fab2_lib.baseboard_fab2(sch_1):page44_i13:cke(0)"
				( attribute "PN" "60"
					( Origin gPackager )
				)
				( objectStatus "J6T1.60" )
			)
			( pin "@baseboard_fab2_lib.baseboard_fab2(sch_1):page44_i13:cke(1)"
				( attribute "PN" "203"
					( Origin gPackager )
				)
				( objectStatus "J6T1.203" )
			)
			( pin "@baseboard_fab2_lib.baseboard_fab2(sch_1):page44_i13:dq(0)"
				( attribute "PN" "5"
					( Origin gPackager )
				)
				( objectStatus "J6T1.5" )
			)
			( pin "@baseboard_fab2_lib.baseboard_fab2(sch_1):page44_i13:dq(1)"
				( attribute "PN" "150"
					( Origin gPackager )
				)
				( objectStatus "J6T1.150" )
			)
			( pin "@baseboard_fab2_lib.baseboard_fab2(sch_1):page44_i13:dq(2)"
				( attribute "PN" "12"
					( Origin gPackager )
				)
				( objectStatus "J6T1.12" )
			)
			( pin "@baseboard_fab2_lib.baseboard_fab2(sch_1):page44_i13:dq(3)"
				( attribute "PN" "157"
					( Origin gPackager )
				)
				( objectStatus "J6T1.157" )
			)
			( pin "@baseboard_fab2_lib.baseboard_fab2(sch_1):page44_i13:dq(4)"
				( attribute "PN" "3"
					( Origin gPackager )
				)
				( objectStatus "J6T1.3" )
			)
			( pin "@baseboard_fab2_lib.baseboard_fab2(sch_1):page44_i13:dq(5)"
				( attribute "PN" "148"
					( Origin gPackager )
				)
				( objectStatus "J6T1.148" )
			)
			( pin "@baseboard_fab2_lib.baseboard_fab2(sch_1):page44_i13:dq(6)"
				( attribute "PN" "10"
					( Origin gPackager )
				)
				( objectStatus "J6T1.10" )
			)
			( pin "@baseboard_fab2_lib.baseboard_fab2(sch_1):page44_i13:dq(7)"
				( attribute "PN" "155"
					( Origin gPackager )
				)
				( objectStatus "J6T1.155" )
			)
			( pin "@baseboard_fab2_lib.baseboard_fab2(sch_1):page44_i13:dq(8)"
				( attribute "PN" "16"
					( Origin gPackager )
				)
				( objectStatus "J6T1.16" )
			)
			( pin "@baseboard_fab2_lib.baseboard_fab2(sch_1):page44_i13:dq(9)"
				( attribute "PN" "161"
					( Origin gPackager )
				)
				( objectStatus "J6T1.161" )
			)
			( pin "@baseboard_fab2_lib.baseboard_fab2(sch_1):page44_i13:dq(10)"
				( attribute "PN" "23"
					( Origin gPackager )
				)
				( objectStatus "J6T1.23" )
			)
			( pin "@baseboard_fab2_lib.baseboard_fab2(sch_1):page44_i13:dq(11)"
				( attribute "PN" "168"
					( Origin gPackager )
				)
				( objectStatus "J6T1.168" )
			)
			( pin "@baseboard_fab2_lib.baseboard_fab2(sch_1):page44_i13:dq(12)"
				( attribute "PN" "14"
					( Origin gPackager )
				)
				( objectStatus "J6T1.14" )
			)
			( pin "@baseboard_fab2_lib.baseboard_fab2(sch_1):page44_i13:dq(13)"
				( attribute "PN" "159"
					( Origin gPackager )
				)
				( objectStatus "J6T1.159" )
			)
			( pin "@baseboard_fab2_lib.baseboard_fab2(sch_1):page44_i13:dq(14)"
				( attribute "PN" "21"
					( Origin gPackager )
				)
				( objectStatus "J6T1.21" )
			)
			( pin "@baseboard_fab2_lib.baseboard_fab2(sch_1):page44_i13:dq(15)"
				( attribute "PN" "166"
					( Origin gPackager )
				)
				( objectStatus "J6T1.166" )
			)
			( pin "@baseboard_fab2_lib.baseboard_fab2(sch_1):page44_i13:dq(16)"
				( attribute "PN" "27"
					( Origin gPackager )
				)
				( objectStatus "J6T1.27" )
			)
			( pin "@baseboard_fab2_lib.baseboard_fab2(sch_1):page44_i13:dq(17)"
				( attribute "PN" "172"
					( Origin gPackager )
				)
				( objectStatus "J6T1.172" )
			)
			( pin "@baseboard_fab2_lib.baseboard_fab2(sch_1):page44_i13:dq(18)"
				( attribute "PN" "34"
					( Origin gPackager )
				)
				( objectStatus "J6T1.34" )
			)
			( pin "@baseboard_fab2_lib.baseboard_fab2(sch_1):page44_i13:dq(19)"
				( attribute "PN" "179"
					( Origin gPackager )
				)
				( objectStatus "J6T1.179" )
			)
			( pin "@baseboard_fab2_lib.baseboard_fab2(sch_1):page44_i13:dq(20)"
				( attribute "PN" "25"
					( Origin gPackager )
				)
				( objectStatus "J6T1.25" )
			)
			( pin "@baseboard_fab2_lib.baseboard_fab2(sch_1):page44_i13:dq(21)"
				( attribute "PN" "170"
					( Origin gPackager )
				)
				( objectStatus "J6T1.170" )
			)
			( pin "@baseboard_fab2_lib.baseboard_fab2(sch_1):page44_i13:dq(22)"
				( attribute "PN" "32"
					( Origin gPackager )
				)
				( objectStatus "J6T1.32" )
			)
			( pin "@baseboard_fab2_lib.baseboard_fab2(sch_1):page44_i13:dq(23)"
				( attribute "PN" "177"
					( Origin gPackager )
				)
				( objectStatus "J6T1.177" )
			)
			( pin "@baseboard_fab2_lib.baseboard_fab2(sch_1):page44_i13:dq(24)"
				( attribute "PN" "38"
					( Origin gPackager )
				)
				( objectStatus "J6T1.38" )
			)
			( pin "@baseboard_fab2_lib.baseboard_fab2(sch_1):page44_i13:dq(25)"
				( attribute "PN" "183"
					( Origin gPackager )
				)
				( objectStatus "J6T1.183" )
			)
			( pin "@baseboard_fab2_lib.baseboard_fab2(sch_1):page44_i13:dq(26)"
				( attribute "PN" "45"
					( Origin gPackager )
				)
				( objectStatus "J6T1.45" )
			)
			( pin "@baseboard_fab2_lib.baseboard_fab2(sch_1):page44_i13:dq(27)"
				( attribute "PN" "190"
					( Origin gPackager )
				)
				( objectStatus "J6T1.190" )
			)
			( pin "@baseboard_fab2_lib.baseboard_fab2(sch_1):page44_i13:dq(28)"
				( attribute "PN" "36"
					( Origin gPackager )
				)
				( objectStatus "J6T1.36" )
			)
			( pin "@baseboard_fab2_lib.baseboard_fab2(sch_1):page44_i13:dq(29)"
				( attribute "PN" "181"
					( Origin gPackager )
				)
				( objectStatus "J6T1.181" )
			)
			( pin "@baseboard_fab2_lib.baseboard_fab2(sch_1):page44_i13:dq(30)"
				( attribute "PN" "43"
					( Origin gPackager )
				)
				( objectStatus "J6T1.43" )
			)
			( pin "@baseboard_fab2_lib.baseboard_fab2(sch_1):page44_i13:dq(31)"
				( attribute "PN" "188"
					( Origin gPackager )
				)
				( objectStatus "J6T1.188" )
			)
			( pin "@baseboard_fab2_lib.baseboard_fab2(sch_1):page44_i13:dq(32)"
				( attribute "PN" "97"
					( Origin gPackager )
				)
				( objectStatus "J6T1.97" )
			)
			( pin "@baseboard_fab2_lib.baseboard_fab2(sch_1):page44_i13:dq(33)"
				( attribute "PN" "242"
					( Origin gPackager )
				)
				( objectStatus "J6T1.242" )
			)
			( pin "@baseboard_fab2_lib.baseboard_fab2(sch_1):page44_i13:dq(34)"
				( attribute "PN" "104"
					( Origin gPackager )
				)
				( objectStatus "J6T1.104" )
			)
			( pin "@baseboard_fab2_lib.baseboard_fab2(sch_1):page44_i13:dq(35)"
				( attribute "PN" "249"
					( Origin gPackager )
				)
				( objectStatus "J6T1.249" )
			)
			( pin "@baseboard_fab2_lib.baseboard_fab2(sch_1):page44_i13:dq(36)"
				( attribute "PN" "95"
					( Origin gPackager )
				)
				( objectStatus "J6T1.95" )
			)
			( pin "@baseboard_fab2_lib.baseboard_fab2(sch_1):page44_i13:dq(37)"
				( attribute "PN" "240"
					( Origin gPackager )
				)
				( objectStatus "J6T1.240" )
			)
			( pin "@baseboard_fab2_lib.baseboard_fab2(sch_1):page44_i13:dq(38)"
				( attribute "PN" "102"
					( Origin gPackager )
				)
				( objectStatus "J6T1.102" )
			)
			( pin "@baseboard_fab2_lib.baseboard_fab2(sch_1):page44_i13:dq(39)"
				( attribute "PN" "247"
					( Origin gPackager )
				)
				( objectStatus "J6T1.247" )
			)
			( pin "@baseboard_fab2_lib.baseboard_fab2(sch_1):page44_i13:dq(40)"
				( attribute "PN" "108"
					( Origin gPackager )
				)
				( objectStatus "J6T1.108" )
			)
			( pin "@baseboard_fab2_lib.baseboard_fab2(sch_1):page44_i13:dq(41)"
				( attribute "PN" "253"
					( Origin gPackager )
				)
				( objectStatus "J6T1.253" )
			)
			( pin "@baseboard_fab2_lib.baseboard_fab2(sch_1):page44_i13:dq(42)"
				( attribute "PN" "115"
					( Origin gPackager )
				)
				( objectStatus "J6T1.115" )
			)
			( pin "@baseboard_fab2_lib.baseboard_fab2(sch_1):page44_i13:dq(43)"
				( attribute "PN" "260"
					( Origin gPackager )
				)
				( objectStatus "J6T1.260" )
			)
			( pin "@baseboard_fab2_lib.baseboard_fab2(sch_1):page44_i13:dq(44)"
				( attribute "PN" "106"
					( Origin gPackager )
				)
				( objectStatus "J6T1.106" )
			)
			( pin "@baseboard_fab2_lib.baseboard_fab2(sch_1):page44_i13:dq(45)"
				( attribute "PN" "251"
					( Origin gPackager )
				)
				( objectStatus "J6T1.251" )
			)
			( pin "@baseboard_fab2_lib.baseboard_fab2(sch_1):page44_i13:dq(46)"
				( attribute "PN" "113"
					( Origin gPackager )
				)
				( objectStatus "J6T1.113" )
			)
			( pin "@baseboard_fab2_lib.baseboard_fab2(sch_1):page44_i13:dq(47)"
				( attribute "PN" "258"
					( Origin gPackager )
				)
				( objectStatus "J6T1.258" )
			)
			( pin "@baseboard_fab2_lib.baseboard_fab2(sch_1):page44_i13:dq(48)"
				( attribute "PN" "119"
					( Origin gPackager )
				)
				( objectStatus "J6T1.119" )
			)
			( pin "@baseboard_fab2_lib.baseboard_fab2(sch_1):page44_i13:dq(49)"
				( attribute "PN" "264"
					( Origin gPackager )
				)
				( objectStatus "J6T1.264" )
			)
			( pin "@baseboard_fab2_lib.baseboard_fab2(sch_1):page44_i13:dq(50)"
				( attribute "PN" "126"
					( Origin gPackager )
				)
				( objectStatus "J6T1.126" )
			)
			( pin "@baseboard_fab2_lib.baseboard_fab2(sch_1):page44_i13:dq(51)"
				( attribute "PN" "271"
					( Origin gPackager )
				)
				( objectStatus "J6T1.271" )
			)
			( pin "@baseboard_fab2_lib.baseboard_fab2(sch_1):page44_i13:dq(52)"
				( attribute "PN" "117"
					( Origin gPackager )
				)
				( objectStatus "J6T1.117" )
			)
			( pin "@baseboard_fab2_lib.baseboard_fab2(sch_1):page44_i13:dq(53)"
				( attribute "PN" "262"
					( Origin gPackager )
				)
				( objectStatus "J6T1.262" )
			)
			( pin "@baseboard_fab2_lib.baseboard_fab2(sch_1):page44_i13:dq(54)"
				( attribute "PN" "124"
					( Origin gPackager )
				)
				( objectStatus "J6T1.124" )
			)
			( pin "@baseboard_fab2_lib.baseboard_fab2(sch_1):page44_i13:dq(55)"
				( attribute "PN" "269"
					( Origin gPackager )
				)
				( objectStatus "J6T1.269" )
			)
			( pin "@baseboard_fab2_lib.baseboard_fab2(sch_1):page44_i13:dq(56)"
				( attribute "PN" "130"
					( Origin gPackager )
				)
				( objectStatus "J6T1.130" )
			)
			( pin "@baseboard_fab2_lib.baseboard_fab2(sch_1):page44_i13:dq(57)"
				( attribute "PN" "275"
					( Origin gPackager )
				)
				( objectStatus "J6T1.275" )
			)
			( pin "@baseboard_fab2_lib.baseboard_fab2(sch_1):page44_i13:dq(58)"
				( attribute "PN" "137"
					( Origin gPackager )
				)
				( objectStatus "J6T1.137" )
			)
			( pin "@baseboard_fab2_lib.baseboard_fab2(sch_1):page44_i13:dq(59)"
				( attribute "PN" "282"
					( Origin gPackager )
				)
				( objectStatus "J6T1.282" )
			)
			( pin "@baseboard_fab2_lib.baseboard_fab2(sch_1):page44_i13:dq(60)"
				( attribute "PN" "128"
					( Origin gPackager )
				)
				( objectStatus "J6T1.128" )
			)
			( pin "@baseboard_fab2_lib.baseboard_fab2(sch_1):page44_i13:dq(61)"
				( attribute "PN" "273"
					( Origin gPackager )
				)
				( objectStatus "J6T1.273" )
			)
			( pin "@baseboard_fab2_lib.baseboard_fab2(sch_1):page44_i13:dq(62)"
				( attribute "PN" "135"
					( Origin gPackager )
				)
				( objectStatus "J6T1.135" )
			)
			( pin "@baseboard_fab2_lib.baseboard_fab2(sch_1):page44_i13:dq(63)"
				( attribute "PN" "280"
					( Origin gPackager )
				)
				( objectStatus "J6T1.280" )
			)
			( pin "@baseboard_fab2_lib.baseboard_fab2(sch_1):page44_i13:event_n"
				( attribute "PN" "78"
					( Origin gPackager )
				)
				( objectStatus "J6T1.78" )
			)
			( pin "@baseboard_fab2_lib.baseboard_fab2(sch_1):page44_i13:odt(0)"
				( attribute "PN" "87"
					( Origin gPackager )
				)
				( objectStatus "J6T1.87" )
			)
			( pin "@baseboard_fab2_lib.baseboard_fab2(sch_1):page44_i13:odt(1)"
				( attribute "PN" "91"
					( Origin gPackager )
				)
				( objectStatus "J6T1.91" )
			)
			( pin "@baseboard_fab2_lib.baseboard_fab2(sch_1):page44_i13:par"
				( attribute "PN" "222"
					( Origin gPackager )
				)
				( objectStatus "J6T1.222" )
			)
			( pin "@baseboard_fab2_lib.baseboard_fab2(sch_1):page44_i13:reset_n"
				( attribute "PN" "58"
					( Origin gPackager )
				)
				( objectStatus "J6T1.58" )
			)
			( pin "@baseboard_fab2_lib.baseboard_fab2(sch_1):page44_i13:rfu(0)"
				( attribute "PN" "205"
					( Origin gPackager )
				)
				( objectStatus "J6T1.205" )
			)
			( pin "@baseboard_fab2_lib.baseboard_fab2(sch_1):page44_i13:rfu(1)"
				( attribute "PN" "227"
					( Origin gPackager )
				)
				( objectStatus "J6T1.227" )
			)
			( pin "@baseboard_fab2_lib.baseboard_fab2(sch_1):page44_i13:rfu(2)"
				( attribute "PN" "144"
					( Origin gPackager )
				)
				( objectStatus "J6T1.144" )
			)
			( pin "@baseboard_fab2_lib.baseboard_fab2(sch_1):page44_i13:s0_n"
				( attribute "PN" "84"
					( Origin gPackager )
				)
				( objectStatus "J6T1.84" )
			)
			( pin "@baseboard_fab2_lib.baseboard_fab2(sch_1):page44_i13:s1_n"
				( attribute "PN" "89"
					( Origin gPackager )
				)
				( objectStatus "J6T1.89" )
			)
			( pin "@baseboard_fab2_lib.baseboard_fab2(sch_1):page44_i13:s2_n_c(0)"
				( attribute "PN" "93"
					( Origin gPackager )
				)
				( objectStatus "J6T1.93" )
			)
			( pin "@baseboard_fab2_lib.baseboard_fab2(sch_1):page44_i13:s3_n_c(1)"
				( attribute "PN" "237"
					( Origin gPackager )
				)
				( objectStatus "J6T1.237" )
			)
			( pin "@baseboard_fab2_lib.baseboard_fab2(sch_1):page44_i13:sa(0)"
				( attribute "PN" "139"
					( Origin gPackager )
				)
				( objectStatus "J6T1.139" )
			)
			( pin "@baseboard_fab2_lib.baseboard_fab2(sch_1):page44_i13:sa(1)"
				( attribute "PN" "140"
					( Origin gPackager )
				)
				( objectStatus "J6T1.140" )
			)
			( pin "@baseboard_fab2_lib.baseboard_fab2(sch_1):page44_i13:sa(2)"
				( attribute "PN" "238"
					( Origin gPackager )
				)
				( objectStatus "J6T1.238" )
			)
			( pin "@baseboard_fab2_lib.baseboard_fab2(sch_1):page44_i13:save_n_nc"
				( attribute "PN" "230"
					( Origin gPackager )
				)
				( objectStatus "J6T1.230" )
			)
			( pin "@baseboard_fab2_lib.baseboard_fab2(sch_1):page44_i13:scl"
				( attribute "PN" "141"
					( Origin gPackager )
				)
				( objectStatus "J6T1.141" )
			)
			( pin "@baseboard_fab2_lib.baseboard_fab2(sch_1):page44_i13:sda"
				( attribute "PN" "285"
					( Origin gPackager )
				)
				( objectStatus "J6T1.285" )
			)
			( pin "@baseboard_fab2_lib.baseboard_fab2(sch_1):page44_i13:vddspd"
				( attribute "PN" "284"
					( Origin gPackager )
				)
				( objectStatus "J6T1.284" )
			)
			( pin "@baseboard_fab2_lib.baseboard_fab2(sch_1):page44_i13:vrefca"
				( attribute "PN" "146"
					( Origin gPackager )
				)
				( objectStatus "J6T1.146" )
			)
			( pin "@baseboard_fab2_lib.baseboard_fab2(sch_1):page44_i75:\12v\(0)"
				( attribute "PN" "145"
					( Origin gPackager )
				)
				( objectStatus "J6T1.145" )
			)
			( pin "@baseboard_fab2_lib.baseboard_fab2(sch_1):page44_i75:\12v\(1)"
				( attribute "PN" "1"
					( Origin gPackager )
				)
				( objectStatus "J6T1.1" )
			)
			( pin "@baseboard_fab2_lib.baseboard_fab2(sch_1):page44_i75:vdd(0)"
				( attribute "PN" "236"
					( Origin gPackager )
				)
				( objectStatus "J6T1.236" )
			)
			( pin "@baseboard_fab2_lib.baseboard_fab2(sch_1):page44_i75:vdd(1)"
				( attribute "PN" "233"
					( Origin gPackager )
				)
				( objectStatus "J6T1.233" )
			)
			( pin "@baseboard_fab2_lib.baseboard_fab2(sch_1):page44_i75:vdd(2)"
				( attribute "PN" "231"
					( Origin gPackager )
				)
				( objectStatus "J6T1.231" )
			)
			( pin "@baseboard_fab2_lib.baseboard_fab2(sch_1):page44_i75:vdd(3)"
				( attribute "PN" "229"
					( Origin gPackager )
				)
				( objectStatus "J6T1.229" )
			)
			( pin "@baseboard_fab2_lib.baseboard_fab2(sch_1):page44_i75:vdd(4)"
				( attribute "PN" "226"
					( Origin gPackager )
				)
				( objectStatus "J6T1.226" )
			)
			( pin "@baseboard_fab2_lib.baseboard_fab2(sch_1):page44_i75:vdd(5)"
				( attribute "PN" "223"
					( Origin gPackager )
				)
				( objectStatus "J6T1.223" )
			)
			( pin "@baseboard_fab2_lib.baseboard_fab2(sch_1):page44_i75:vdd(6)"
				( attribute "PN" "220"
					( Origin gPackager )
				)
				( objectStatus "J6T1.220" )
			)
			( pin "@baseboard_fab2_lib.baseboard_fab2(sch_1):page44_i75:vdd(7)"
				( attribute "PN" "217"
					( Origin gPackager )
				)
				( objectStatus "J6T1.217" )
			)
			( pin "@baseboard_fab2_lib.baseboard_fab2(sch_1):page44_i75:vdd(8)"
				( attribute "PN" "215"
					( Origin gPackager )
				)
				( objectStatus "J6T1.215" )
			)
			( pin "@baseboard_fab2_lib.baseboard_fab2(sch_1):page44_i75:vdd(9)"
				( attribute "PN" "212"
					( Origin gPackager )
				)
				( objectStatus "J6T1.212" )
			)
			( pin "@baseboard_fab2_lib.baseboard_fab2(sch_1):page44_i75:vdd(10)"
				( attribute "PN" "209"
					( Origin gPackager )
				)
				( objectStatus "J6T1.209" )
			)
			( pin "@baseboard_fab2_lib.baseboard_fab2(sch_1):page44_i75:vdd(11)"
				( attribute "PN" "206"
					( Origin gPackager )
				)
				( objectStatus "J6T1.206" )
			)
			( pin "@baseboard_fab2_lib.baseboard_fab2(sch_1):page44_i75:vdd(12)"
				( attribute "PN" "204"
					( Origin gPackager )
				)
				( objectStatus "J6T1.204" )
			)
			( pin "@baseboard_fab2_lib.baseboard_fab2(sch_1):page44_i75:vdd(13)"
				( attribute "PN" "92"
					( Origin gPackager )
				)
				( objectStatus "J6T1.92" )
			)
			( pin "@baseboard_fab2_lib.baseboard_fab2(sch_1):page44_i75:vdd(14)"
				( attribute "PN" "90"
					( Origin gPackager )
				)
				( objectStatus "J6T1.90" )
			)
			( pin "@baseboard_fab2_lib.baseboard_fab2(sch_1):page44_i75:vdd(15)"
				( attribute "PN" "88"
					( Origin gPackager )
				)
				( objectStatus "J6T1.88" )
			)
			( pin "@baseboard_fab2_lib.baseboard_fab2(sch_1):page44_i75:vdd(16)"
				( attribute "PN" "85"
					( Origin gPackager )
				)
				( objectStatus "J6T1.85" )
			)
			( pin "@baseboard_fab2_lib.baseboard_fab2(sch_1):page44_i75:vdd(17)"
				( attribute "PN" "83"
					( Origin gPackager )
				)
				( objectStatus "J6T1.83" )
			)
			( pin "@baseboard_fab2_lib.baseboard_fab2(sch_1):page44_i75:vdd(18)"
				( attribute "PN" "80"
					( Origin gPackager )
				)
				( objectStatus "J6T1.80" )
			)
			( pin "@baseboard_fab2_lib.baseboard_fab2(sch_1):page44_i75:vdd(19)"
				( attribute "PN" "76"
					( Origin gPackager )
				)
				( objectStatus "J6T1.76" )
			)
			( pin "@baseboard_fab2_lib.baseboard_fab2(sch_1):page44_i75:vdd(20)"
				( attribute "PN" "73"
					( Origin gPackager )
				)
				( objectStatus "J6T1.73" )
			)
			( pin "@baseboard_fab2_lib.baseboard_fab2(sch_1):page44_i75:vdd(21)"
				( attribute "PN" "70"
					( Origin gPackager )
				)
				( objectStatus "J6T1.70" )
			)
			( pin "@baseboard_fab2_lib.baseboard_fab2(sch_1):page44_i75:vdd(22)"
				( attribute "PN" "67"
					( Origin gPackager )
				)
				( objectStatus "J6T1.67" )
			)
			( pin "@baseboard_fab2_lib.baseboard_fab2(sch_1):page44_i75:vdd(23)"
				( attribute "PN" "64"
					( Origin gPackager )
				)
				( objectStatus "J6T1.64" )
			)
			( pin "@baseboard_fab2_lib.baseboard_fab2(sch_1):page44_i75:vdd(24)"
				( attribute "PN" "61"
					( Origin gPackager )
				)
				( objectStatus "J6T1.61" )
			)
			( pin "@baseboard_fab2_lib.baseboard_fab2(sch_1):page44_i75:vdd(25)"
				( attribute "PN" "59"
					( Origin gPackager )
				)
				( objectStatus "J6T1.59" )
			)
			( pin "@baseboard_fab2_lib.baseboard_fab2(sch_1):page44_i75:vpp(0)"
				( attribute "PN" "287"
					( Origin gPackager )
				)
				( objectStatus "J6T1.287" )
			)
			( pin "@baseboard_fab2_lib.baseboard_fab2(sch_1):page44_i75:vpp(1)"
				( attribute "PN" "286"
					( Origin gPackager )
				)
				( objectStatus "J6T1.286" )
			)
			( pin "@baseboard_fab2_lib.baseboard_fab2(sch_1):page44_i75:vpp(2)"
				( attribute "PN" "288"
					( Origin gPackager )
				)
				( objectStatus "J6T1.288" )
			)
			( pin "@baseboard_fab2_lib.baseboard_fab2(sch_1):page44_i75:vpp(3)"
				( attribute "PN" "143"
					( Origin gPackager )
				)
				( objectStatus "J6T1.143" )
			)
			( pin "@baseboard_fab2_lib.baseboard_fab2(sch_1):page44_i75:vpp(4)"
				( attribute "PN" "142"
					( Origin gPackager )
				)
				( objectStatus "J6T1.142" )
			)
			( pin "@baseboard_fab2_lib.baseboard_fab2(sch_1):page44_i75:vtt(0)"
				( attribute "PN" "221"
					( Origin gPackager )
				)
				( objectStatus "J6T1.221" )
			)
			( pin "@baseboard_fab2_lib.baseboard_fab2(sch_1):page44_i75:vtt(1)"
				( attribute "PN" "77"
					( Origin gPackager )
				)
				( objectStatus "J6T1.77" )
			)
			( pin "@baseboard_fab2_lib.baseboard_fab2(sch_1):page44_i120:dqs0n"
				( attribute "PN" "152"
					( Origin gPackager )
				)
				( objectStatus "J6T1.152" )
			)
			( pin "@baseboard_fab2_lib.baseboard_fab2(sch_1):page44_i120:dqs0p"
				( attribute "PN" "153"
					( Origin gPackager )
				)
				( objectStatus "J6T1.153" )
			)
			( pin "@baseboard_fab2_lib.baseboard_fab2(sch_1):page44_i120:dqs1n"
				( attribute "PN" "163"
					( Origin gPackager )
				)
				( objectStatus "J6T1.163" )
			)
			( pin "@baseboard_fab2_lib.baseboard_fab2(sch_1):page44_i120:dqs1p"
				( attribute "PN" "164"
					( Origin gPackager )
				)
				( objectStatus "J6T1.164" )
			)
			( pin "@baseboard_fab2_lib.baseboard_fab2(sch_1):page44_i120:dqs2n"
				( attribute "PN" "174"
					( Origin gPackager )
				)
				( objectStatus "J6T1.174" )
			)
			( pin "@baseboard_fab2_lib.baseboard_fab2(sch_1):page44_i120:dqs2p"
				( attribute "PN" "175"
					( Origin gPackager )
				)
				( objectStatus "J6T1.175" )
			)
			( pin "@baseboard_fab2_lib.baseboard_fab2(sch_1):page44_i120:dqs3n"
				( attribute "PN" "185"
					( Origin gPackager )
				)
				( objectStatus "J6T1.185" )
			)
			( pin "@baseboard_fab2_lib.baseboard_fab2(sch_1):page44_i120:dqs3p"
				( attribute "PN" "186"
					( Origin gPackager )
				)
				( objectStatus "J6T1.186" )
			)
			( pin "@baseboard_fab2_lib.baseboard_fab2(sch_1):page44_i120:dqs4n"
				( attribute "PN" "244"
					( Origin gPackager )
				)
				( objectStatus "J6T1.244" )
			)
			( pin "@baseboard_fab2_lib.baseboard_fab2(sch_1):page44_i120:dqs4p"
				( attribute "PN" "245"
					( Origin gPackager )
				)
				( objectStatus "J6T1.245" )
			)
			( pin "@baseboard_fab2_lib.baseboard_fab2(sch_1):page44_i120:dqs5n"
				( attribute "PN" "255"
					( Origin gPackager )
				)
				( objectStatus "J6T1.255" )
			)
			( pin "@baseboard_fab2_lib.baseboard_fab2(sch_1):page44_i120:dqs5p"
				( attribute "PN" "256"
					( Origin gPackager )
				)
				( objectStatus "J6T1.256" )
			)
			( pin "@baseboard_fab2_lib.baseboard_fab2(sch_1):page44_i120:dqs6n"
				( attribute "PN" "266"
					( Origin gPackager )
				)
				( objectStatus "J6T1.266" )
			)
			( pin "@baseboard_fab2_lib.baseboard_fab2(sch_1):page44_i120:dqs6p"
				( attribute "PN" "267"
					( Origin gPackager )
				)
				( objectStatus "J6T1.267" )
			)
			( pin "@baseboard_fab2_lib.baseboard_fab2(sch_1):page44_i120:dqs7n"
				( attribute "PN" "277"
					( Origin gPackager )
				)
				( objectStatus "J6T1.277" )
			)
			( pin "@baseboard_fab2_lib.baseboard_fab2(sch_1):page44_i120:dqs7p"
				( attribute "PN" "278"
					( Origin gPackager )
				)
				( objectStatus "J6T1.278" )
			)
			( pin "@baseboard_fab2_lib.baseboard_fab2(sch_1):page44_i120:dqs8n"
				( attribute "PN" "196"
					( Origin gPackager )
				)
				( objectStatus "J6T1.196" )
			)
			( pin "@baseboard_fab2_lib.baseboard_fab2(sch_1):page44_i120:dqs8p"
				( attribute "PN" "197"
					( Origin gPackager )
				)
				( objectStatus "J6T1.197" )
			)
			( pin "@baseboard_fab2_lib.baseboard_fab2(sch_1):page44_i120:dqs9n"
				( attribute "PN" "8"
					( Origin gPackager )
				)
				( objectStatus "J6T1.8" )
			)
			( pin "@baseboard_fab2_lib.baseboard_fab2(sch_1):page44_i120:dqs9p"
				( attribute "PN" "7"
					( Origin gPackager )
				)
				( objectStatus "J6T1.7" )
			)
			( pin "@baseboard_fab2_lib.baseboard_fab2(sch_1):page44_i120:dqs10n"
				( attribute "PN" "19"
					( Origin gPackager )
				)
				( objectStatus "J6T1.19" )
			)
			( pin "@baseboard_fab2_lib.baseboard_fab2(sch_1):page44_i120:dqs10p"
				( attribute "PN" "18"
					( Origin gPackager )
				)
				( objectStatus "J6T1.18" )
			)
			( pin "@baseboard_fab2_lib.baseboard_fab2(sch_1):page44_i120:dqs11n"
				( attribute "PN" "30"
					( Origin gPackager )
				)
				( objectStatus "J6T1.30" )
			)
			( pin "@baseboard_fab2_lib.baseboard_fab2(sch_1):page44_i120:dqs11p"
				( attribute "PN" "29"
					( Origin gPackager )
				)
				( objectStatus "J6T1.29" )
			)
			( pin "@baseboard_fab2_lib.baseboard_fab2(sch_1):page44_i120:dqs12n"
				( attribute "PN" "41"
					( Origin gPackager )
				)
				( objectStatus "J6T1.41" )
			)
			( pin "@baseboard_fab2_lib.baseboard_fab2(sch_1):page44_i120:dqs12p"
				( attribute "PN" "40"
					( Origin gPackager )
				)
				( objectStatus "J6T1.40" )
			)
			( pin "@baseboard_fab2_lib.baseboard_fab2(sch_1):page44_i120:dqs13n"
				( attribute "PN" "100"
					( Origin gPackager )
				)
				( objectStatus "J6T1.100" )
			)
			( pin "@baseboard_fab2_lib.baseboard_fab2(sch_1):page44_i120:dqs13p"
				( attribute "PN" "99"
					( Origin gPackager )
				)
				( objectStatus "J6T1.99" )
			)
			( pin "@baseboard_fab2_lib.baseboard_fab2(sch_1):page44_i120:dqs14n"
				( attribute "PN" "111"
					( Origin gPackager )
				)
				( objectStatus "J6T1.111" )
			)
			( pin "@baseboard_fab2_lib.baseboard_fab2(sch_1):page44_i120:dqs14p"
				( attribute "PN" "110"
					( Origin gPackager )
				)
				( objectStatus "J6T1.110" )
			)
			( pin "@baseboard_fab2_lib.baseboard_fab2(sch_1):page44_i120:dqs15n"
				( attribute "PN" "122"
					( Origin gPackager )
				)
				( objectStatus "J6T1.122" )
			)
			( pin "@baseboard_fab2_lib.baseboard_fab2(sch_1):page44_i120:dqs15p"
				( attribute "PN" "121"
					( Origin gPackager )
				)
				( objectStatus "J6T1.121" )
			)
			( pin "@baseboard_fab2_lib.baseboard_fab2(sch_1):page44_i120:dqs16n"
				( attribute "PN" "133"
					( Origin gPackager )
				)
				( objectStatus "J6T1.133" )
			)
			( pin "@baseboard_fab2_lib.baseboard_fab2(sch_1):page44_i120:dqs16p"
				( attribute "PN" "132"
					( Origin gPackager )
				)
				( objectStatus "J6T1.132" )
			)
			( pin "@baseboard_fab2_lib.baseboard_fab2(sch_1):page44_i120:dqs17n"
				( attribute "PN" "52"
					( Origin gPackager )
				)
				( objectStatus "J6T1.52" )
			)
			( pin "@baseboard_fab2_lib.baseboard_fab2(sch_1):page44_i120:dqs17p"
				( attribute "PN" "51"
					( Origin gPackager )
				)
				( objectStatus "J6T1.51" )
			)
			( pin "@baseboard_fab2_lib.baseboard_fab2(sch_1):page44_i139:vss(0)"
				( attribute "PN" "283"
					( Origin gPackager )
				)
				( objectStatus "J6T1.283" )
			)
			( pin "@baseboard_fab2_lib.baseboard_fab2(sch_1):page44_i139:vss(1)"
				( attribute "PN" "281"
					( Origin gPackager )
				)
				( objectStatus "J6T1.281" )
			)
			( pin "@baseboard_fab2_lib.baseboard_fab2(sch_1):page44_i139:vss(2)"
				( attribute "PN" "279"
					( Origin gPackager )
				)
				( objectStatus "J6T1.279" )
			)
			( pin "@baseboard_fab2_lib.baseboard_fab2(sch_1):page44_i139:vss(3)"
				( attribute "PN" "276"
					( Origin gPackager )
				)
				( objectStatus "J6T1.276" )
			)
			( pin "@baseboard_fab2_lib.baseboard_fab2(sch_1):page44_i139:vss(4)"
				( attribute "PN" "274"
					( Origin gPackager )
				)
				( objectStatus "J6T1.274" )
			)
			( pin "@baseboard_fab2_lib.baseboard_fab2(sch_1):page44_i139:vss(5)"
				( attribute "PN" "272"
					( Origin gPackager )
				)
				( objectStatus "J6T1.272" )
			)
			( pin "@baseboard_fab2_lib.baseboard_fab2(sch_1):page44_i139:vss(6)"
				( attribute "PN" "270"
					( Origin gPackager )
				)
				( objectStatus "J6T1.270" )
			)
			( pin "@baseboard_fab2_lib.baseboard_fab2(sch_1):page44_i139:vss(7)"
				( attribute "PN" "268"
					( Origin gPackager )
				)
				( objectStatus "J6T1.268" )
			)
			( pin "@baseboard_fab2_lib.baseboard_fab2(sch_1):page44_i139:vss(8)"
				( attribute "PN" "265"
					( Origin gPackager )
				)
				( objectStatus "J6T1.265" )
			)
			( pin "@baseboard_fab2_lib.baseboard_fab2(sch_1):page44_i139:vss(9)"
				( attribute "PN" "263"
					( Origin gPackager )
				)
				( objectStatus "J6T1.263" )
			)
			( pin "@baseboard_fab2_lib.baseboard_fab2(sch_1):page44_i139:vss(10)"
				( attribute "PN" "261"
					( Origin gPackager )
				)
				( objectStatus "J6T1.261" )
			)
			( pin "@baseboard_fab2_lib.baseboard_fab2(sch_1):page44_i139:vss(11)"
				( attribute "PN" "259"
					( Origin gPackager )
				)
				( objectStatus "J6T1.259" )
			)
			( pin "@baseboard_fab2_lib.baseboard_fab2(sch_1):page44_i139:vss(12)"
				( attribute "PN" "257"
					( Origin gPackager )
				)
				( objectStatus "J6T1.257" )
			)
			( pin "@baseboard_fab2_lib.baseboard_fab2(sch_1):page44_i139:vss(13)"
				( attribute "PN" "254"
					( Origin gPackager )
				)
				( objectStatus "J6T1.254" )
			)
			( pin "@baseboard_fab2_lib.baseboard_fab2(sch_1):page44_i139:vss(14)"
				( attribute "PN" "252"
					( Origin gPackager )
				)
				( objectStatus "J6T1.252" )
			)
			( pin "@baseboard_fab2_lib.baseboard_fab2(sch_1):page44_i139:vss(15)"
				( attribute "PN" "250"
					( Origin gPackager )
				)
				( objectStatus "J6T1.250" )
			)
			( pin "@baseboard_fab2_lib.baseboard_fab2(sch_1):page44_i139:vss(16)"
				( attribute "PN" "248"
					( Origin gPackager )
				)
				( objectStatus "J6T1.248" )
			)
			( pin "@baseboard_fab2_lib.baseboard_fab2(sch_1):page44_i139:vss(17)"
				( attribute "PN" "246"
					( Origin gPackager )
				)
				( objectStatus "J6T1.246" )
			)
			( pin "@baseboard_fab2_lib.baseboard_fab2(sch_1):page44_i139:vss(18)"
				( attribute "PN" "243"
					( Origin gPackager )
				)
				( objectStatus "J6T1.243" )
			)
			( pin "@baseboard_fab2_lib.baseboard_fab2(sch_1):page44_i139:vss(19)"
				( attribute "PN" "241"
					( Origin gPackager )
				)
				( objectStatus "J6T1.241" )
			)
			( pin "@baseboard_fab2_lib.baseboard_fab2(sch_1):page44_i139:vss(20)"
				( attribute "PN" "239"
					( Origin gPackager )
				)
				( objectStatus "J6T1.239" )
			)
			( pin "@baseboard_fab2_lib.baseboard_fab2(sch_1):page44_i139:vss(21)"
				( attribute "PN" "202"
					( Origin gPackager )
				)
				( objectStatus "J6T1.202" )
			)
			( pin "@baseboard_fab2_lib.baseboard_fab2(sch_1):page44_i139:vss(22)"
				( attribute "PN" "200"
					( Origin gPackager )
				)
				( objectStatus "J6T1.200" )
			)
			( pin "@baseboard_fab2_lib.baseboard_fab2(sch_1):page44_i139:vss(23)"
				( attribute "PN" "198"
					( Origin gPackager )
				)
				( objectStatus "J6T1.198" )
			)
			( pin "@baseboard_fab2_lib.baseboard_fab2(sch_1):page44_i139:vss(24)"
				( attribute "PN" "195"
					( Origin gPackager )
				)
				( objectStatus "J6T1.195" )
			)
			( pin "@baseboard_fab2_lib.baseboard_fab2(sch_1):page44_i139:vss(25)"
				( attribute "PN" "193"
					( Origin gPackager )
				)
				( objectStatus "J6T1.193" )
			)
			( pin "@baseboard_fab2_lib.baseboard_fab2(sch_1):page44_i139:vss(26)"
				( attribute "PN" "191"
					( Origin gPackager )
				)
				( objectStatus "J6T1.191" )
			)
			( pin "@baseboard_fab2_lib.baseboard_fab2(sch_1):page44_i139:vss(27)"
				( attribute "PN" "189"
					( Origin gPackager )
				)
				( objectStatus "J6T1.189" )
			)
			( pin "@baseboard_fab2_lib.baseboard_fab2(sch_1):page44_i139:vss(28)"
				( attribute "PN" "187"
					( Origin gPackager )
				)
				( objectStatus "J6T1.187" )
			)
			( pin "@baseboard_fab2_lib.baseboard_fab2(sch_1):page44_i139:vss(29)"
				( attribute "PN" "184"
					( Origin gPackager )
				)
				( objectStatus "J6T1.184" )
			)
			( pin "@baseboard_fab2_lib.baseboard_fab2(sch_1):page44_i139:vss(30)"
				( attribute "PN" "182"
					( Origin gPackager )
				)
				( objectStatus "J6T1.182" )
			)
			( pin "@baseboard_fab2_lib.baseboard_fab2(sch_1):page44_i139:vss(31)"
				( attribute "PN" "180"
					( Origin gPackager )
				)
				( objectStatus "J6T1.180" )
			)
			( pin "@baseboard_fab2_lib.baseboard_fab2(sch_1):page44_i139:vss(32)"
				( attribute "PN" "178"
					( Origin gPackager )
				)
				( objectStatus "J6T1.178" )
			)
			( pin "@baseboard_fab2_lib.baseboard_fab2(sch_1):page44_i139:vss(33)"
				( attribute "PN" "176"
					( Origin gPackager )
				)
				( objectStatus "J6T1.176" )
			)
			( pin "@baseboard_fab2_lib.baseboard_fab2(sch_1):page44_i139:vss(34)"
				( attribute "PN" "173"
					( Origin gPackager )
				)
				( objectStatus "J6T1.173" )
			)
			( pin "@baseboard_fab2_lib.baseboard_fab2(sch_1):page44_i139:vss(35)"
				( attribute "PN" "171"
					( Origin gPackager )
				)
				( objectStatus "J6T1.171" )
			)
			( pin "@baseboard_fab2_lib.baseboard_fab2(sch_1):page44_i139:vss(36)"
				( attribute "PN" "169"
					( Origin gPackager )
				)
				( objectStatus "J6T1.169" )
			)
			( pin "@baseboard_fab2_lib.baseboard_fab2(sch_1):page44_i139:vss(37)"
				( attribute "PN" "167"
					( Origin gPackager )
				)
				( objectStatus "J6T1.167" )
			)
			( pin "@baseboard_fab2_lib.baseboard_fab2(sch_1):page44_i139:vss(38)"
				( attribute "PN" "165"
					( Origin gPackager )
				)
				( objectStatus "J6T1.165" )
			)
			( pin "@baseboard_fab2_lib.baseboard_fab2(sch_1):page44_i139:vss(39)"
				( attribute "PN" "162"
					( Origin gPackager )
				)
				( objectStatus "J6T1.162" )
			)
			( pin "@baseboard_fab2_lib.baseboard_fab2(sch_1):page44_i139:vss(40)"
				( attribute "PN" "160"
					( Origin gPackager )
				)
				( objectStatus "J6T1.160" )
			)
			( pin "@baseboard_fab2_lib.baseboard_fab2(sch_1):page44_i139:vss(41)"
				( attribute "PN" "158"
					( Origin gPackager )
				)
				( objectStatus "J6T1.158" )
			)
			( pin "@baseboard_fab2_lib.baseboard_fab2(sch_1):page44_i139:vss(42)"
				( attribute "PN" "156"
					( Origin gPackager )
				)
				( objectStatus "J6T1.156" )
			)
			( pin "@baseboard_fab2_lib.baseboard_fab2(sch_1):page44_i139:vss(43)"
				( attribute "PN" "154"
					( Origin gPackager )
				)
				( objectStatus "J6T1.154" )
			)
			( pin "@baseboard_fab2_lib.baseboard_fab2(sch_1):page44_i139:vss(44)"
				( attribute "PN" "151"
					( Origin gPackager )
				)
				( objectStatus "J6T1.151" )
			)
			( pin "@baseboard_fab2_lib.baseboard_fab2(sch_1):page44_i139:vss(45)"
				( attribute "PN" "149"
					( Origin gPackager )
				)
				( objectStatus "J6T1.149" )
			)
			( pin "@baseboard_fab2_lib.baseboard_fab2(sch_1):page44_i139:vss(46)"
				( attribute "PN" "147"
					( Origin gPackager )
				)
				( objectStatus "J6T1.147" )
			)
			( pin "@baseboard_fab2_lib.baseboard_fab2(sch_1):page44_i139:vss(47)"
				( attribute "PN" "138"
					( Origin gPackager )
				)
				( objectStatus "J6T1.138" )
			)
			( pin "@baseboard_fab2_lib.baseboard_fab2(sch_1):page44_i139:vss(48)"
				( attribute "PN" "136"
					( Origin gPackager )
				)
				( objectStatus "J6T1.136" )
			)
			( pin "@baseboard_fab2_lib.baseboard_fab2(sch_1):page44_i139:vss(49)"
				( attribute "PN" "134"
					( Origin gPackager )
				)
				( objectStatus "J6T1.134" )
			)
			( pin "@baseboard_fab2_lib.baseboard_fab2(sch_1):page44_i139:vss(50)"
				( attribute "PN" "131"
					( Origin gPackager )
				)
				( objectStatus "J6T1.131" )
			)
			( pin "@baseboard_fab2_lib.baseboard_fab2(sch_1):page44_i139:vss(51)"
				( attribute "PN" "129"
					( Origin gPackager )
				)
				( objectStatus "J6T1.129" )
			)
			( pin "@baseboard_fab2_lib.baseboard_fab2(sch_1):page44_i139:vss(52)"
				( attribute "PN" "127"
					( Origin gPackager )
				)
				( objectStatus "J6T1.127" )
			)
			( pin "@baseboard_fab2_lib.baseboard_fab2(sch_1):page44_i139:vss(53)"
				( attribute "PN" "125"
					( Origin gPackager )
				)
				( objectStatus "J6T1.125" )
			)
			( pin "@baseboard_fab2_lib.baseboard_fab2(sch_1):page44_i139:vss(54)"
				( attribute "PN" "123"
					( Origin gPackager )
				)
				( objectStatus "J6T1.123" )
			)
			( pin "@baseboard_fab2_lib.baseboard_fab2(sch_1):page44_i139:vss(55)"
				( attribute "PN" "120"
					( Origin gPackager )
				)
				( objectStatus "J6T1.120" )
			)
			( pin "@baseboard_fab2_lib.baseboard_fab2(sch_1):page44_i139:vss(56)"
				( attribute "PN" "118"
					( Origin gPackager )
				)
				( objectStatus "J6T1.118" )
			)
			( pin "@baseboard_fab2_lib.baseboard_fab2(sch_1):page44_i139:vss(57)"
				( attribute "PN" "116"
					( Origin gPackager )
				)
				( objectStatus "J6T1.116" )
			)
			( pin "@baseboard_fab2_lib.baseboard_fab2(sch_1):page44_i139:vss(58)"
				( attribute "PN" "114"
					( Origin gPackager )
				)
				( objectStatus "J6T1.114" )
			)
			( pin "@baseboard_fab2_lib.baseboard_fab2(sch_1):page44_i139:vss(59)"
				( attribute "PN" "112"
					( Origin gPackager )
				)
				( objectStatus "J6T1.112" )
			)
			( pin "@baseboard_fab2_lib.baseboard_fab2(sch_1):page44_i139:vss(60)"
				( attribute "PN" "109"
					( Origin gPackager )
				)
				( objectStatus "J6T1.109" )
			)
			( pin "@baseboard_fab2_lib.baseboard_fab2(sch_1):page44_i139:vss(61)"
				( attribute "PN" "107"
					( Origin gPackager )
				)
				( objectStatus "J6T1.107" )
			)
			( pin "@baseboard_fab2_lib.baseboard_fab2(sch_1):page44_i139:vss(62)"
				( attribute "PN" "105"
					( Origin gPackager )
				)
				( objectStatus "J6T1.105" )
			)
			( pin "@baseboard_fab2_lib.baseboard_fab2(sch_1):page44_i139:vss(63)"
				( attribute "PN" "103"
					( Origin gPackager )
				)
				( objectStatus "J6T1.103" )
			)
			( pin "@baseboard_fab2_lib.baseboard_fab2(sch_1):page44_i139:vss(64)"
				( attribute "PN" "101"
					( Origin gPackager )
				)
				( objectStatus "J6T1.101" )
			)
			( pin "@baseboard_fab2_lib.baseboard_fab2(sch_1):page44_i139:vss(65)"
				( attribute "PN" "98"
					( Origin gPackager )
				)
				( objectStatus "J6T1.98" )
			)
			( pin "@baseboard_fab2_lib.baseboard_fab2(sch_1):page44_i139:vss(66)"
				( attribute "PN" "96"
					( Origin gPackager )
				)
				( objectStatus "J6T1.96" )
			)
			( pin "@baseboard_fab2_lib.baseboard_fab2(sch_1):page44_i139:vss(67)"
				( attribute "PN" "94"
					( Origin gPackager )
				)
				( objectStatus "J6T1.94" )
			)
			( pin "@baseboard_fab2_lib.baseboard_fab2(sch_1):page44_i139:vss(68)"
				( attribute "PN" "57"
					( Origin gPackager )
				)
				( objectStatus "J6T1.57" )
			)
			( pin "@baseboard_fab2_lib.baseboard_fab2(sch_1):page44_i139:vss(69)"
				( attribute "PN" "55"
					( Origin gPackager )
				)
				( objectStatus "J6T1.55" )
			)
			( pin "@baseboard_fab2_lib.baseboard_fab2(sch_1):page44_i139:vss(70)"
				( attribute "PN" "53"
					( Origin gPackager )
				)
				( objectStatus "J6T1.53" )
			)
			( pin "@baseboard_fab2_lib.baseboard_fab2(sch_1):page44_i139:vss(71)"
				( attribute "PN" "50"
					( Origin gPackager )
				)
				( objectStatus "J6T1.50" )
			)
			( pin "@baseboard_fab2_lib.baseboard_fab2(sch_1):page44_i139:vss(72)"
				( attribute "PN" "48"
					( Origin gPackager )
				)
				( objectStatus "J6T1.48" )
			)
			( pin "@baseboard_fab2_lib.baseboard_fab2(sch_1):page44_i139:vss(73)"
				( attribute "PN" "46"
					( Origin gPackager )
				)
				( objectStatus "J6T1.46" )
			)
			( pin "@baseboard_fab2_lib.baseboard_fab2(sch_1):page44_i139:vss(74)"
				( attribute "PN" "44"
					( Origin gPackager )
				)
				( objectStatus "J6T1.44" )
			)
			( pin "@baseboard_fab2_lib.baseboard_fab2(sch_1):page44_i139:vss(75)"
				( attribute "PN" "42"
					( Origin gPackager )
				)
				( objectStatus "J6T1.42" )
			)
			( pin "@baseboard_fab2_lib.baseboard_fab2(sch_1):page44_i139:vss(76)"
				( attribute "PN" "39"
					( Origin gPackager )
				)
				( objectStatus "J6T1.39" )
			)
			( pin "@baseboard_fab2_lib.baseboard_fab2(sch_1):page44_i139:vss(77)"
				( attribute "PN" "37"
					( Origin gPackager )
				)
				( objectStatus "J6T1.37" )
			)
			( pin "@baseboard_fab2_lib.baseboard_fab2(sch_1):page44_i139:vss(78)"
				( attribute "PN" "35"
					( Origin gPackager )
				)
				( objectStatus "J6T1.35" )
			)
			( pin "@baseboard_fab2_lib.baseboard_fab2(sch_1):page44_i139:vss(79)"
				( attribute "PN" "33"
					( Origin gPackager )
				)
				( objectStatus "J6T1.33" )
			)
			( pin "@baseboard_fab2_lib.baseboard_fab2(sch_1):page44_i139:vss(80)"
				( attribute "PN" "31"
					( Origin gPackager )
				)
				( objectStatus "J6T1.31" )
			)
			( pin "@baseboard_fab2_lib.baseboard_fab2(sch_1):page44_i139:vss(81)"
				( attribute "PN" "28"
					( Origin gPackager )
				)
				( objectStatus "J6T1.28" )
			)
			( pin "@baseboard_fab2_lib.baseboard_fab2(sch_1):page44_i139:vss(82)"
				( attribute "PN" "26"
					( Origin gPackager )
				)
				( objectStatus "J6T1.26" )
			)
			( pin "@baseboard_fab2_lib.baseboard_fab2(sch_1):page44_i139:vss(83)"
				( attribute "PN" "24"
					( Origin gPackager )
				)
				( objectStatus "J6T1.24" )
			)
			( pin "@baseboard_fab2_lib.baseboard_fab2(sch_1):page44_i139:vss(84)"
				( attribute "PN" "22"
					( Origin gPackager )
				)
				( objectStatus "J6T1.22" )
			)
			( pin "@baseboard_fab2_lib.baseboard_fab2(sch_1):page44_i139:vss(85)"
				( attribute "PN" "20"
					( Origin gPackager )
				)
				( objectStatus "J6T1.20" )
			)
			( pin "@baseboard_fab2_lib.baseboard_fab2(sch_1):page44_i139:vss(86)"
				( attribute "PN" "17"
					( Origin gPackager )
				)
				( objectStatus "J6T1.17" )
			)
			( pin "@baseboard_fab2_lib.baseboard_fab2(sch_1):page44_i139:vss(87)"
				( attribute "PN" "15"
					( Origin gPackager )
				)
				( objectStatus "J6T1.15" )
			)
			( pin "@baseboard_fab2_lib.baseboard_fab2(sch_1):page44_i139:vss(88)"
				( attribute "PN" "13"
					( Origin gPackager )
				)
				( objectStatus "J6T1.13" )
			)
			( pin "@baseboard_fab2_lib.baseboard_fab2(sch_1):page44_i139:vss(89)"
				( attribute "PN" "11"
					( Origin gPackager )
				)
				( objectStatus "J6T1.11" )
			)
			( pin "@baseboard_fab2_lib.baseboard_fab2(sch_1):page44_i139:vss(90)"
				( attribute "PN" "9"
					( Origin gPackager )
				)
				( objectStatus "J6T1.9" )
			)
			( pin "@baseboard_fab2_lib.baseboard_fab2(sch_1):page44_i139:vss(91)"
				( attribute "PN" "6"
					( Origin gPackager )
				)
				( objectStatus "J6T1.6" )
			)
			( pin "@baseboard_fab2_lib.baseboard_fab2(sch_1):page44_i139:vss(92)"
				( attribute "PN" "4"
					( Origin gPackager )
				)
				( objectStatus "J6T1.4" )
			)
			( pin "@baseboard_fab2_lib.baseboard_fab2(sch_1):page44_i139:vss(93)"
				( attribute "PN" "2"
					( Origin gPackager )
				)
				( objectStatus "J6T1.2" )
			)
			( pin "@baseboard_fab2_lib.baseboard_fab2(sch_1):page45_i43:vss(0)"
				( attribute "PN" "283"
					( Origin gPackager )
				)
				( objectStatus "J4G2.283" )
			)
			( pin "@baseboard_fab2_lib.baseboard_fab2(sch_1):page45_i43:vss(1)"
				( attribute "PN" "281"
					( Origin gPackager )
				)
				( objectStatus "J4G2.281" )
			)
			( pin "@baseboard_fab2_lib.baseboard_fab2(sch_1):page45_i43:vss(2)"
				( attribute "PN" "279"
					( Origin gPackager )
				)
				( objectStatus "J4G2.279" )
			)
			( pin "@baseboard_fab2_lib.baseboard_fab2(sch_1):page45_i43:vss(3)"
				( attribute "PN" "276"
					( Origin gPackager )
				)
				( objectStatus "J4G2.276" )
			)
			( pin "@baseboard_fab2_lib.baseboard_fab2(sch_1):page45_i43:vss(4)"
				( attribute "PN" "274"
					( Origin gPackager )
				)
				( objectStatus "J4G2.274" )
			)
			( pin "@baseboard_fab2_lib.baseboard_fab2(sch_1):page45_i43:vss(5)"
				( attribute "PN" "272"
					( Origin gPackager )
				)
				( objectStatus "J4G2.272" )
			)
			( pin "@baseboard_fab2_lib.baseboard_fab2(sch_1):page45_i43:vss(6)"
				( attribute "PN" "270"
					( Origin gPackager )
				)
				( objectStatus "J4G2.270" )
			)
			( pin "@baseboard_fab2_lib.baseboard_fab2(sch_1):page45_i43:vss(7)"
				( attribute "PN" "268"
					( Origin gPackager )
				)
				( objectStatus "J4G2.268" )
			)
			( pin "@baseboard_fab2_lib.baseboard_fab2(sch_1):page45_i43:vss(8)"
				( attribute "PN" "265"
					( Origin gPackager )
				)
				( objectStatus "J4G2.265" )
			)
			( pin "@baseboard_fab2_lib.baseboard_fab2(sch_1):page45_i43:vss(9)"
				( attribute "PN" "263"
					( Origin gPackager )
				)
				( objectStatus "J4G2.263" )
			)
			( pin "@baseboard_fab2_lib.baseboard_fab2(sch_1):page45_i43:vss(10)"
				( attribute "PN" "261"
					( Origin gPackager )
				)
				( objectStatus "J4G2.261" )
			)
			( pin "@baseboard_fab2_lib.baseboard_fab2(sch_1):page45_i43:vss(11)"
				( attribute "PN" "259"
					( Origin gPackager )
				)
				( objectStatus "J4G2.259" )
			)
			( pin "@baseboard_fab2_lib.baseboard_fab2(sch_1):page45_i43:vss(12)"
				( attribute "PN" "257"
					( Origin gPackager )
				)
				( objectStatus "J4G2.257" )
			)
			( pin "@baseboard_fab2_lib.baseboard_fab2(sch_1):page45_i43:vss(13)"
				( attribute "PN" "254"
					( Origin gPackager )
				)
				( objectStatus "J4G2.254" )
			)
			( pin "@baseboard_fab2_lib.baseboard_fab2(sch_1):page45_i43:vss(14)"
				( attribute "PN" "252"
					( Origin gPackager )
				)
				( objectStatus "J4G2.252" )
			)
			( pin "@baseboard_fab2_lib.baseboard_fab2(sch_1):page45_i43:vss(15)"
				( attribute "PN" "250"
					( Origin gPackager )
				)
				( objectStatus "J4G2.250" )
			)
			( pin "@baseboard_fab2_lib.baseboard_fab2(sch_1):page45_i43:vss(16)"
				( attribute "PN" "248"
					( Origin gPackager )
				)
				( objectStatus "J4G2.248" )
			)
			( pin "@baseboard_fab2_lib.baseboard_fab2(sch_1):page45_i43:vss(17)"
				( attribute "PN" "246"
					( Origin gPackager )
				)
				( objectStatus "J4G2.246" )
			)
			( pin "@baseboard_fab2_lib.baseboard_fab2(sch_1):page45_i43:vss(18)"
				( attribute "PN" "243"
					( Origin gPackager )
				)
				( objectStatus "J4G2.243" )
			)
			( pin "@baseboard_fab2_lib.baseboard_fab2(sch_1):page45_i43:vss(19)"
				( attribute "PN" "241"
					( Origin gPackager )
				)
				( objectStatus "J4G2.241" )
			)
			( pin "@baseboard_fab2_lib.baseboard_fab2(sch_1):page45_i43:vss(20)"
				( attribute "PN" "239"
					( Origin gPackager )
				)
				( objectStatus "J4G2.239" )
			)
			( pin "@baseboard_fab2_lib.baseboard_fab2(sch_1):page45_i43:vss(21)"
				( attribute "PN" "202"
					( Origin gPackager )
				)
				( objectStatus "J4G2.202" )
			)
			( pin "@baseboard_fab2_lib.baseboard_fab2(sch_1):page45_i43:vss(22)"
				( attribute "PN" "200"
					( Origin gPackager )
				)
				( objectStatus "J4G2.200" )
			)
			( pin "@baseboard_fab2_lib.baseboard_fab2(sch_1):page45_i43:vss(23)"
				( attribute "PN" "198"
					( Origin gPackager )
				)
				( objectStatus "J4G2.198" )
			)
			( pin "@baseboard_fab2_lib.baseboard_fab2(sch_1):page45_i43:vss(24)"
				( attribute "PN" "195"
					( Origin gPackager )
				)
				( objectStatus "J4G2.195" )
			)
			( pin "@baseboard_fab2_lib.baseboard_fab2(sch_1):page45_i43:vss(25)"
				( attribute "PN" "193"
					( Origin gPackager )
				)
				( objectStatus "J4G2.193" )
			)
			( pin "@baseboard_fab2_lib.baseboard_fab2(sch_1):page45_i43:vss(26)"
				( attribute "PN" "191"
					( Origin gPackager )
				)
				( objectStatus "J4G2.191" )
			)
			( pin "@baseboard_fab2_lib.baseboard_fab2(sch_1):page45_i43:vss(27)"
				( attribute "PN" "189"
					( Origin gPackager )
				)
				( objectStatus "J4G2.189" )
			)
			( pin "@baseboard_fab2_lib.baseboard_fab2(sch_1):page45_i43:vss(28)"
				( attribute "PN" "187"
					( Origin gPackager )
				)
				( objectStatus "J4G2.187" )
			)
			( pin "@baseboard_fab2_lib.baseboard_fab2(sch_1):page45_i43:vss(29)"
				( attribute "PN" "184"
					( Origin gPackager )
				)
				( objectStatus "J4G2.184" )
			)
			( pin "@baseboard_fab2_lib.baseboard_fab2(sch_1):page45_i43:vss(30)"
				( attribute "PN" "182"
					( Origin gPackager )
				)
				( objectStatus "J4G2.182" )
			)
			( pin "@baseboard_fab2_lib.baseboard_fab2(sch_1):page45_i43:vss(31)"
				( attribute "PN" "180"
					( Origin gPackager )
				)
				( objectStatus "J4G2.180" )
			)
			( pin "@baseboard_fab2_lib.baseboard_fab2(sch_1):page45_i43:vss(32)"
				( attribute "PN" "178"
					( Origin gPackager )
				)
				( objectStatus "J4G2.178" )
			)
			( pin "@baseboard_fab2_lib.baseboard_fab2(sch_1):page45_i43:vss(33)"
				( attribute "PN" "176"
					( Origin gPackager )
				)
				( objectStatus "J4G2.176" )
			)
			( pin "@baseboard_fab2_lib.baseboard_fab2(sch_1):page45_i43:vss(34)"
				( attribute "PN" "173"
					( Origin gPackager )
				)
				( objectStatus "J4G2.173" )
			)
			( pin "@baseboard_fab2_lib.baseboard_fab2(sch_1):page45_i43:vss(35)"
				( attribute "PN" "171"
					( Origin gPackager )
				)
				( objectStatus "J4G2.171" )
			)
			( pin "@baseboard_fab2_lib.baseboard_fab2(sch_1):page45_i43:vss(36)"
				( attribute "PN" "169"
					( Origin gPackager )
				)
				( objectStatus "J4G2.169" )
			)
			( pin "@baseboard_fab2_lib.baseboard_fab2(sch_1):page45_i43:vss(37)"
				( attribute "PN" "167"
					( Origin gPackager )
				)
				( objectStatus "J4G2.167" )
			)
			( pin "@baseboard_fab2_lib.baseboard_fab2(sch_1):page45_i43:vss(38)"
				( attribute "PN" "165"
					( Origin gPackager )
				)
				( objectStatus "J4G2.165" )
			)
			( pin "@baseboard_fab2_lib.baseboard_fab2(sch_1):page45_i43:vss(39)"
				( attribute "PN" "162"
					( Origin gPackager )
				)
				( objectStatus "J4G2.162" )
			)
			( pin "@baseboard_fab2_lib.baseboard_fab2(sch_1):page45_i43:vss(40)"
				( attribute "PN" "160"
					( Origin gPackager )
				)
				( objectStatus "J4G2.160" )
			)
			( pin "@baseboard_fab2_lib.baseboard_fab2(sch_1):page45_i43:vss(41)"
				( attribute "PN" "158"
					( Origin gPackager )
				)
				( objectStatus "J4G2.158" )
			)
			( pin "@baseboard_fab2_lib.baseboard_fab2(sch_1):page45_i43:vss(42)"
				( attribute "PN" "156"
					( Origin gPackager )
				)
				( objectStatus "J4G2.156" )
			)
			( pin "@baseboard_fab2_lib.baseboard_fab2(sch_1):page45_i43:vss(43)"
				( attribute "PN" "154"
					( Origin gPackager )
				)
				( objectStatus "J4G2.154" )
			)
			( pin "@baseboard_fab2_lib.baseboard_fab2(sch_1):page45_i43:vss(44)"
				( attribute "PN" "151"
					( Origin gPackager )
				)
				( objectStatus "J4G2.151" )
			)
			( pin "@baseboard_fab2_lib.baseboard_fab2(sch_1):page45_i43:vss(45)"
				( attribute "PN" "149"
					( Origin gPackager )
				)
				( objectStatus "J4G2.149" )
			)
			( pin "@baseboard_fab2_lib.baseboard_fab2(sch_1):page45_i43:vss(46)"
				( attribute "PN" "147"
					( Origin gPackager )
				)
				( objectStatus "J4G2.147" )
			)
			( pin "@baseboard_fab2_lib.baseboard_fab2(sch_1):page45_i43:vss(47)"
				( attribute "PN" "138"
					( Origin gPackager )
				)
				( objectStatus "J4G2.138" )
			)
			( pin "@baseboard_fab2_lib.baseboard_fab2(sch_1):page45_i43:vss(48)"
				( attribute "PN" "136"
					( Origin gPackager )
				)
				( objectStatus "J4G2.136" )
			)
			( pin "@baseboard_fab2_lib.baseboard_fab2(sch_1):page45_i43:vss(49)"
				( attribute "PN" "134"
					( Origin gPackager )
				)
				( objectStatus "J4G2.134" )
			)
			( pin "@baseboard_fab2_lib.baseboard_fab2(sch_1):page45_i43:vss(50)"
				( attribute "PN" "131"
					( Origin gPackager )
				)
				( objectStatus "J4G2.131" )
			)
			( pin "@baseboard_fab2_lib.baseboard_fab2(sch_1):page45_i43:vss(51)"
				( attribute "PN" "129"
					( Origin gPackager )
				)
				( objectStatus "J4G2.129" )
			)
			( pin "@baseboard_fab2_lib.baseboard_fab2(sch_1):page45_i43:vss(52)"
				( attribute "PN" "127"
					( Origin gPackager )
				)
				( objectStatus "J4G2.127" )
			)
			( pin "@baseboard_fab2_lib.baseboard_fab2(sch_1):page45_i43:vss(53)"
				( attribute "PN" "125"
					( Origin gPackager )
				)
				( objectStatus "J4G2.125" )
			)
			( pin "@baseboard_fab2_lib.baseboard_fab2(sch_1):page45_i43:vss(54)"
				( attribute "PN" "123"
					( Origin gPackager )
				)
				( objectStatus "J4G2.123" )
			)
			( pin "@baseboard_fab2_lib.baseboard_fab2(sch_1):page45_i43:vss(55)"
				( attribute "PN" "120"
					( Origin gPackager )
				)
				( objectStatus "J4G2.120" )
			)
			( pin "@baseboard_fab2_lib.baseboard_fab2(sch_1):page45_i43:vss(56)"
				( attribute "PN" "118"
					( Origin gPackager )
				)
				( objectStatus "J4G2.118" )
			)
			( pin "@baseboard_fab2_lib.baseboard_fab2(sch_1):page45_i43:vss(57)"
				( attribute "PN" "116"
					( Origin gPackager )
				)
				( objectStatus "J4G2.116" )
			)
			( pin "@baseboard_fab2_lib.baseboard_fab2(sch_1):page45_i43:vss(58)"
				( attribute "PN" "114"
					( Origin gPackager )
				)
				( objectStatus "J4G2.114" )
			)
			( pin "@baseboard_fab2_lib.baseboard_fab2(sch_1):page45_i43:vss(59)"
				( attribute "PN" "112"
					( Origin gPackager )
				)
				( objectStatus "J4G2.112" )
			)
			( pin "@baseboard_fab2_lib.baseboard_fab2(sch_1):page45_i43:vss(60)"
				( attribute "PN" "109"
					( Origin gPackager )
				)
				( objectStatus "J4G2.109" )
			)
			( pin "@baseboard_fab2_lib.baseboard_fab2(sch_1):page45_i43:vss(61)"
				( attribute "PN" "107"
					( Origin gPackager )
				)
				( objectStatus "J4G2.107" )
			)
			( pin "@baseboard_fab2_lib.baseboard_fab2(sch_1):page45_i43:vss(62)"
				( attribute "PN" "105"
					( Origin gPackager )
				)
				( objectStatus "J4G2.105" )
			)
			( pin "@baseboard_fab2_lib.baseboard_fab2(sch_1):page45_i43:vss(63)"
				( attribute "PN" "103"
					( Origin gPackager )
				)
				( objectStatus "J4G2.103" )
			)
			( pin "@baseboard_fab2_lib.baseboard_fab2(sch_1):page45_i43:vss(64)"
				( attribute "PN" "101"
					( Origin gPackager )
				)
				( objectStatus "J4G2.101" )
			)
			( pin "@baseboard_fab2_lib.baseboard_fab2(sch_1):page45_i43:vss(65)"
				( attribute "PN" "98"
					( Origin gPackager )
				)
				( objectStatus "J4G2.98" )
			)
			( pin "@baseboard_fab2_lib.baseboard_fab2(sch_1):page45_i43:vss(66)"
				( attribute "PN" "96"
					( Origin gPackager )
				)
				( objectStatus "J4G2.96" )
			)
			( pin "@baseboard_fab2_lib.baseboard_fab2(sch_1):page45_i43:vss(67)"
				( attribute "PN" "94"
					( Origin gPackager )
				)
				( objectStatus "J4G2.94" )
			)
			( pin "@baseboard_fab2_lib.baseboard_fab2(sch_1):page45_i43:vss(68)"
				( attribute "PN" "57"
					( Origin gPackager )
				)
				( objectStatus "J4G2.57" )
			)
			( pin "@baseboard_fab2_lib.baseboard_fab2(sch_1):page45_i43:vss(69)"
				( attribute "PN" "55"
					( Origin gPackager )
				)
				( objectStatus "J4G2.55" )
			)
			( pin "@baseboard_fab2_lib.baseboard_fab2(sch_1):page45_i43:vss(70)"
				( attribute "PN" "53"
					( Origin gPackager )
				)
				( objectStatus "J4G2.53" )
			)
			( pin "@baseboard_fab2_lib.baseboard_fab2(sch_1):page45_i43:vss(71)"
				( attribute "PN" "50"
					( Origin gPackager )
				)
				( objectStatus "J4G2.50" )
			)
			( pin "@baseboard_fab2_lib.baseboard_fab2(sch_1):page45_i43:vss(72)"
				( attribute "PN" "48"
					( Origin gPackager )
				)
				( objectStatus "J4G2.48" )
			)
			( pin "@baseboard_fab2_lib.baseboard_fab2(sch_1):page45_i43:vss(73)"
				( attribute "PN" "46"
					( Origin gPackager )
				)
				( objectStatus "J4G2.46" )
			)
			( pin "@baseboard_fab2_lib.baseboard_fab2(sch_1):page45_i43:vss(74)"
				( attribute "PN" "44"
					( Origin gPackager )
				)
				( objectStatus "J4G2.44" )
			)
			( pin "@baseboard_fab2_lib.baseboard_fab2(sch_1):page45_i43:vss(75)"
				( attribute "PN" "42"
					( Origin gPackager )
				)
				( objectStatus "J4G2.42" )
			)
			( pin "@baseboard_fab2_lib.baseboard_fab2(sch_1):page45_i43:vss(76)"
				( attribute "PN" "39"
					( Origin gPackager )
				)
				( objectStatus "J4G2.39" )
			)
			( pin "@baseboard_fab2_lib.baseboard_fab2(sch_1):page45_i43:vss(77)"
				( attribute "PN" "37"
					( Origin gPackager )
				)
				( objectStatus "J4G2.37" )
			)
			( pin "@baseboard_fab2_lib.baseboard_fab2(sch_1):page45_i43:vss(78)"
				( attribute "PN" "35"
					( Origin gPackager )
				)
				( objectStatus "J4G2.35" )
			)
			( pin "@baseboard_fab2_lib.baseboard_fab2(sch_1):page45_i43:vss(79)"
				( attribute "PN" "33"
					( Origin gPackager )
				)
				( objectStatus "J4G2.33" )
			)
			( pin "@baseboard_fab2_lib.baseboard_fab2(sch_1):page45_i43:vss(80)"
				( attribute "PN" "31"
					( Origin gPackager )
				)
				( objectStatus "J4G2.31" )
			)
			( pin "@baseboard_fab2_lib.baseboard_fab2(sch_1):page45_i43:vss(81)"
				( attribute "PN" "28"
					( Origin gPackager )
				)
				( objectStatus "J4G2.28" )
			)
			( pin "@baseboard_fab2_lib.baseboard_fab2(sch_1):page45_i43:vss(82)"
				( attribute "PN" "26"
					( Origin gPackager )
				)
				( objectStatus "J4G2.26" )
			)
			( pin "@baseboard_fab2_lib.baseboard_fab2(sch_1):page45_i43:vss(83)"
				( attribute "PN" "24"
					( Origin gPackager )
				)
				( objectStatus "J4G2.24" )
			)
			( pin "@baseboard_fab2_lib.baseboard_fab2(sch_1):page45_i43:vss(84)"
				( attribute "PN" "22"
					( Origin gPackager )
				)
				( objectStatus "J4G2.22" )
			)
			( pin "@baseboard_fab2_lib.baseboard_fab2(sch_1):page45_i43:vss(85)"
				( attribute "PN" "20"
					( Origin gPackager )
				)
				( objectStatus "J4G2.20" )
			)
			( pin "@baseboard_fab2_lib.baseboard_fab2(sch_1):page45_i43:vss(86)"
				( attribute "PN" "17"
					( Origin gPackager )
				)
				( objectStatus "J4G2.17" )
			)
			( pin "@baseboard_fab2_lib.baseboard_fab2(sch_1):page45_i43:vss(87)"
				( attribute "PN" "15"
					( Origin gPackager )
				)
				( objectStatus "J4G2.15" )
			)
			( pin "@baseboard_fab2_lib.baseboard_fab2(sch_1):page45_i43:vss(88)"
				( attribute "PN" "13"
					( Origin gPackager )
				)
				( objectStatus "J4G2.13" )
			)
			( pin "@baseboard_fab2_lib.baseboard_fab2(sch_1):page45_i43:vss(89)"
				( attribute "PN" "11"
					( Origin gPackager )
				)
				( objectStatus "J4G2.11" )
			)
			( pin "@baseboard_fab2_lib.baseboard_fab2(sch_1):page45_i43:vss(90)"
				( attribute "PN" "9"
					( Origin gPackager )
				)
				( objectStatus "J4G2.9" )
			)
			( pin "@baseboard_fab2_lib.baseboard_fab2(sch_1):page45_i43:vss(91)"
				( attribute "PN" "6"
					( Origin gPackager )
				)
				( objectStatus "J4G2.6" )
			)
			( pin "@baseboard_fab2_lib.baseboard_fab2(sch_1):page45_i43:vss(92)"
				( attribute "PN" "4"
					( Origin gPackager )
				)
				( objectStatus "J4G2.4" )
			)
			( pin "@baseboard_fab2_lib.baseboard_fab2(sch_1):page45_i43:vss(93)"
				( attribute "PN" "2"
					( Origin gPackager )
				)
				( objectStatus "J4G2.2" )
			)
			( pin "@baseboard_fab2_lib.baseboard_fab2(sch_1):page45_i61:dqs0n"
				( attribute "PN" "152"
					( Origin gPackager )
				)
				( objectStatus "J4G2.152" )
			)
			( pin "@baseboard_fab2_lib.baseboard_fab2(sch_1):page45_i61:dqs0p"
				( attribute "PN" "153"
					( Origin gPackager )
				)
				( objectStatus "J4G2.153" )
			)
			( pin "@baseboard_fab2_lib.baseboard_fab2(sch_1):page45_i61:dqs1n"
				( attribute "PN" "163"
					( Origin gPackager )
				)
				( objectStatus "J4G2.163" )
			)
			( pin "@baseboard_fab2_lib.baseboard_fab2(sch_1):page45_i61:dqs1p"
				( attribute "PN" "164"
					( Origin gPackager )
				)
				( objectStatus "J4G2.164" )
			)
			( pin "@baseboard_fab2_lib.baseboard_fab2(sch_1):page45_i61:dqs2n"
				( attribute "PN" "174"
					( Origin gPackager )
				)
				( objectStatus "J4G2.174" )
			)
			( pin "@baseboard_fab2_lib.baseboard_fab2(sch_1):page45_i61:dqs2p"
				( attribute "PN" "175"
					( Origin gPackager )
				)
				( objectStatus "J4G2.175" )
			)
			( pin "@baseboard_fab2_lib.baseboard_fab2(sch_1):page45_i61:dqs3n"
				( attribute "PN" "185"
					( Origin gPackager )
				)
				( objectStatus "J4G2.185" )
			)
			( pin "@baseboard_fab2_lib.baseboard_fab2(sch_1):page45_i61:dqs3p"
				( attribute "PN" "186"
					( Origin gPackager )
				)
				( objectStatus "J4G2.186" )
			)
			( pin "@baseboard_fab2_lib.baseboard_fab2(sch_1):page45_i61:dqs4n"
				( attribute "PN" "244"
					( Origin gPackager )
				)
				( objectStatus "J4G2.244" )
			)
			( pin "@baseboard_fab2_lib.baseboard_fab2(sch_1):page45_i61:dqs4p"
				( attribute "PN" "245"
					( Origin gPackager )
				)
				( objectStatus "J4G2.245" )
			)
			( pin "@baseboard_fab2_lib.baseboard_fab2(sch_1):page45_i61:dqs5n"
				( attribute "PN" "255"
					( Origin gPackager )
				)
				( objectStatus "J4G2.255" )
			)
			( pin "@baseboard_fab2_lib.baseboard_fab2(sch_1):page45_i61:dqs5p"
				( attribute "PN" "256"
					( Origin gPackager )
				)
				( objectStatus "J4G2.256" )
			)
			( pin "@baseboard_fab2_lib.baseboard_fab2(sch_1):page45_i61:dqs6n"
				( attribute "PN" "266"
					( Origin gPackager )
				)
				( objectStatus "J4G2.266" )
			)
			( pin "@baseboard_fab2_lib.baseboard_fab2(sch_1):page45_i61:dqs6p"
				( attribute "PN" "267"
					( Origin gPackager )
				)
				( objectStatus "J4G2.267" )
			)
			( pin "@baseboard_fab2_lib.baseboard_fab2(sch_1):page45_i61:dqs7n"
				( attribute "PN" "277"
					( Origin gPackager )
				)
				( objectStatus "J4G2.277" )
			)
			( pin "@baseboard_fab2_lib.baseboard_fab2(sch_1):page45_i61:dqs7p"
				( attribute "PN" "278"
					( Origin gPackager )
				)
				( objectStatus "J4G2.278" )
			)
			( pin "@baseboard_fab2_lib.baseboard_fab2(sch_1):page45_i61:dqs8n"
				( attribute "PN" "196"
					( Origin gPackager )
				)
				( objectStatus "J4G2.196" )
			)
			( pin "@baseboard_fab2_lib.baseboard_fab2(sch_1):page45_i61:dqs8p"
				( attribute "PN" "197"
					( Origin gPackager )
				)
				( objectStatus "J4G2.197" )
			)
			( pin "@baseboard_fab2_lib.baseboard_fab2(sch_1):page45_i61:dqs9n"
				( attribute "PN" "8"
					( Origin gPackager )
				)
				( objectStatus "J4G2.8" )
			)
			( pin "@baseboard_fab2_lib.baseboard_fab2(sch_1):page45_i61:dqs9p"
				( attribute "PN" "7"
					( Origin gPackager )
				)
				( objectStatus "J4G2.7" )
			)
			( pin "@baseboard_fab2_lib.baseboard_fab2(sch_1):page45_i61:dqs10n"
				( attribute "PN" "19"
					( Origin gPackager )
				)
				( objectStatus "J4G2.19" )
			)
			( pin "@baseboard_fab2_lib.baseboard_fab2(sch_1):page45_i61:dqs10p"
				( attribute "PN" "18"
					( Origin gPackager )
				)
				( objectStatus "J4G2.18" )
			)
			( pin "@baseboard_fab2_lib.baseboard_fab2(sch_1):page45_i61:dqs11n"
				( attribute "PN" "30"
					( Origin gPackager )
				)
				( objectStatus "J4G2.30" )
			)
			( pin "@baseboard_fab2_lib.baseboard_fab2(sch_1):page45_i61:dqs11p"
				( attribute "PN" "29"
					( Origin gPackager )
				)
				( objectStatus "J4G2.29" )
			)
			( pin "@baseboard_fab2_lib.baseboard_fab2(sch_1):page45_i61:dqs12n"
				( attribute "PN" "41"
					( Origin gPackager )
				)
				( objectStatus "J4G2.41" )
			)
			( pin "@baseboard_fab2_lib.baseboard_fab2(sch_1):page45_i61:dqs12p"
				( attribute "PN" "40"
					( Origin gPackager )
				)
				( objectStatus "J4G2.40" )
			)
			( pin "@baseboard_fab2_lib.baseboard_fab2(sch_1):page45_i61:dqs13n"
				( attribute "PN" "100"
					( Origin gPackager )
				)
				( objectStatus "J4G2.100" )
			)
			( pin "@baseboard_fab2_lib.baseboard_fab2(sch_1):page45_i61:dqs13p"
				( attribute "PN" "99"
					( Origin gPackager )
				)
				( objectStatus "J4G2.99" )
			)
			( pin "@baseboard_fab2_lib.baseboard_fab2(sch_1):page45_i61:dqs14n"
				( attribute "PN" "111"
					( Origin gPackager )
				)
				( objectStatus "J4G2.111" )
			)
			( pin "@baseboard_fab2_lib.baseboard_fab2(sch_1):page45_i61:dqs14p"
				( attribute "PN" "110"
					( Origin gPackager )
				)
				( objectStatus "J4G2.110" )
			)
			( pin "@baseboard_fab2_lib.baseboard_fab2(sch_1):page45_i61:dqs15n"
				( attribute "PN" "122"
					( Origin gPackager )
				)
				( objectStatus "J4G2.122" )
			)
			( pin "@baseboard_fab2_lib.baseboard_fab2(sch_1):page45_i61:dqs15p"
				( attribute "PN" "121"
					( Origin gPackager )
				)
				( objectStatus "J4G2.121" )
			)
			( pin "@baseboard_fab2_lib.baseboard_fab2(sch_1):page45_i61:dqs16n"
				( attribute "PN" "133"
					( Origin gPackager )
				)
				( objectStatus "J4G2.133" )
			)
			( pin "@baseboard_fab2_lib.baseboard_fab2(sch_1):page45_i61:dqs16p"
				( attribute "PN" "132"
					( Origin gPackager )
				)
				( objectStatus "J4G2.132" )
			)
			( pin "@baseboard_fab2_lib.baseboard_fab2(sch_1):page45_i61:dqs17n"
				( attribute "PN" "52"
					( Origin gPackager )
				)
				( objectStatus "J4G2.52" )
			)
			( pin "@baseboard_fab2_lib.baseboard_fab2(sch_1):page45_i61:dqs17p"
				( attribute "PN" "51"
					( Origin gPackager )
				)
				( objectStatus "J4G2.51" )
			)
			( pin "@baseboard_fab2_lib.baseboard_fab2(sch_1):page45_i111:a0"
				( attribute "PN" "79"
					( Origin gPackager )
				)
				( objectStatus "J4G2.79" )
			)
			( pin "@baseboard_fab2_lib.baseboard_fab2(sch_1):page45_i111:a1"
				( attribute "PN" "72"
					( Origin gPackager )
				)
				( objectStatus "J4G2.72" )
			)
			( pin "@baseboard_fab2_lib.baseboard_fab2(sch_1):page45_i111:a2"
				( attribute "PN" "216"
					( Origin gPackager )
				)
				( objectStatus "J4G2.216" )
			)
			( pin "@baseboard_fab2_lib.baseboard_fab2(sch_1):page45_i111:a3"
				( attribute "PN" "71"
					( Origin gPackager )
				)
				( objectStatus "J4G2.71" )
			)
			( pin "@baseboard_fab2_lib.baseboard_fab2(sch_1):page45_i111:a4"
				( attribute "PN" "214"
					( Origin gPackager )
				)
				( objectStatus "J4G2.214" )
			)
			( pin "@baseboard_fab2_lib.baseboard_fab2(sch_1):page45_i111:a5"
				( attribute "PN" "213"
					( Origin gPackager )
				)
				( objectStatus "J4G2.213" )
			)
			( pin "@baseboard_fab2_lib.baseboard_fab2(sch_1):page45_i111:a6"
				( attribute "PN" "69"
					( Origin gPackager )
				)
				( objectStatus "J4G2.69" )
			)
			( pin "@baseboard_fab2_lib.baseboard_fab2(sch_1):page45_i111:a7"
				( attribute "PN" "211"
					( Origin gPackager )
				)
				( objectStatus "J4G2.211" )
			)
			( pin "@baseboard_fab2_lib.baseboard_fab2(sch_1):page45_i111:a8"
				( attribute "PN" "68"
					( Origin gPackager )
				)
				( objectStatus "J4G2.68" )
			)
			( pin "@baseboard_fab2_lib.baseboard_fab2(sch_1):page45_i111:a9"
				( attribute "PN" "66"
					( Origin gPackager )
				)
				( objectStatus "J4G2.66" )
			)
			( pin "@baseboard_fab2_lib.baseboard_fab2(sch_1):page45_i111:a10"
				( attribute "PN" "225"
					( Origin gPackager )
				)
				( objectStatus "J4G2.225" )
			)
			( pin "@baseboard_fab2_lib.baseboard_fab2(sch_1):page45_i111:a11"
				( attribute "PN" "210"
					( Origin gPackager )
				)
				( objectStatus "J4G2.210" )
			)
			( pin "@baseboard_fab2_lib.baseboard_fab2(sch_1):page45_i111:a12"
				( attribute "PN" "65"
					( Origin gPackager )
				)
				( objectStatus "J4G2.65" )
			)
			( pin "@baseboard_fab2_lib.baseboard_fab2(sch_1):page45_i111:a13"
				( attribute "PN" "232"
					( Origin gPackager )
				)
				( objectStatus "J4G2.232" )
			)
			( pin "@baseboard_fab2_lib.baseboard_fab2(sch_1):page45_i111:a14_we_n"
				( attribute "PN" "228"
					( Origin gPackager )
				)
				( objectStatus "J4G2.228" )
			)
			( pin "@baseboard_fab2_lib.baseboard_fab2(sch_1):page45_i111:a15_cas_n"
				( attribute "PN" "86"
					( Origin gPackager )
				)
				( objectStatus "J4G2.86" )
			)
			( pin "@baseboard_fab2_lib.baseboard_fab2(sch_1):page45_i111:a16_ras_n"
				( attribute "PN" "82"
					( Origin gPackager )
				)
				( objectStatus "J4G2.82" )
			)
			( pin "@baseboard_fab2_lib.baseboard_fab2(sch_1):page45_i111:a17"
				( attribute "PN" "234"
					( Origin gPackager )
				)
				( objectStatus "J4G2.234" )
			)
			( pin "@baseboard_fab2_lib.baseboard_fab2(sch_1):page45_i111:act_n"
				( attribute "PN" "62"
					( Origin gPackager )
				)
				( objectStatus "J4G2.62" )
			)
			( pin "@baseboard_fab2_lib.baseboard_fab2(sch_1):page45_i111:alert_n"
				( attribute "PN" "208"
					( Origin gPackager )
				)
				( objectStatus "J4G2.208" )
			)
			( pin "@baseboard_fab2_lib.baseboard_fab2(sch_1):page45_i111:ba(0)"
				( attribute "PN" "81"
					( Origin gPackager )
				)
				( objectStatus "J4G2.81" )
			)
			( pin "@baseboard_fab2_lib.baseboard_fab2(sch_1):page45_i111:ba(1)"
				( attribute "PN" "224"
					( Origin gPackager )
				)
				( objectStatus "J4G2.224" )
			)
			( pin "@baseboard_fab2_lib.baseboard_fab2(sch_1):page45_i111:bg(0)"
				( attribute "PN" "63"
					( Origin gPackager )
				)
				( objectStatus "J4G2.63" )
			)
			( pin "@baseboard_fab2_lib.baseboard_fab2(sch_1):page45_i111:bg(1)"
				( attribute "PN" "207"
					( Origin gPackager )
				)
				( objectStatus "J4G2.207" )
			)
			( pin "@baseboard_fab2_lib.baseboard_fab2(sch_1):page45_i111:c(2)"
				( attribute "PN" "235"
					( Origin gPackager )
				)
				( objectStatus "J4G2.235" )
			)
			( pin "@baseboard_fab2_lib.baseboard_fab2(sch_1):page45_i111:cb(0)"
				( attribute "PN" "49"
					( Origin gPackager )
				)
				( objectStatus "J4G2.49" )
			)
			( pin "@baseboard_fab2_lib.baseboard_fab2(sch_1):page45_i111:cb(1)"
				( attribute "PN" "194"
					( Origin gPackager )
				)
				( objectStatus "J4G2.194" )
			)
			( pin "@baseboard_fab2_lib.baseboard_fab2(sch_1):page45_i111:cb(2)"
				( attribute "PN" "56"
					( Origin gPackager )
				)
				( objectStatus "J4G2.56" )
			)
			( pin "@baseboard_fab2_lib.baseboard_fab2(sch_1):page45_i111:cb(3)"
				( attribute "PN" "201"
					( Origin gPackager )
				)
				( objectStatus "J4G2.201" )
			)
			( pin "@baseboard_fab2_lib.baseboard_fab2(sch_1):page45_i111:cb(4)"
				( attribute "PN" "47"
					( Origin gPackager )
				)
				( objectStatus "J4G2.47" )
			)
			( pin "@baseboard_fab2_lib.baseboard_fab2(sch_1):page45_i111:cb(5)"
				( attribute "PN" "192"
					( Origin gPackager )
				)
				( objectStatus "J4G2.192" )
			)
			( pin "@baseboard_fab2_lib.baseboard_fab2(sch_1):page45_i111:cb(6)"
				( attribute "PN" "54"
					( Origin gPackager )
				)
				( objectStatus "J4G2.54" )
			)
			( pin "@baseboard_fab2_lib.baseboard_fab2(sch_1):page45_i111:cb(7)"
				( attribute "PN" "199"
					( Origin gPackager )
				)
				( objectStatus "J4G2.199" )
			)
			( pin "@baseboard_fab2_lib.baseboard_fab2(sch_1):page45_i111:ck0n"
				( attribute "PN" "75"
					( Origin gPackager )
				)
				( objectStatus "J4G2.75" )
			)
			( pin "@baseboard_fab2_lib.baseboard_fab2(sch_1):page45_i111:ck0p"
				( attribute "PN" "74"
					( Origin gPackager )
				)
				( objectStatus "J4G2.74" )
			)
			( pin "@baseboard_fab2_lib.baseboard_fab2(sch_1):page45_i111:ck1n"
				( attribute "PN" "219"
					( Origin gPackager )
				)
				( objectStatus "J4G2.219" )
			)
			( pin "@baseboard_fab2_lib.baseboard_fab2(sch_1):page45_i111:ck1p"
				( attribute "PN" "218"
					( Origin gPackager )
				)
				( objectStatus "J4G2.218" )
			)
			( pin "@baseboard_fab2_lib.baseboard_fab2(sch_1):page45_i111:cke(0)"
				( attribute "PN" "60"
					( Origin gPackager )
				)
				( objectStatus "J4G2.60" )
			)
			( pin "@baseboard_fab2_lib.baseboard_fab2(sch_1):page45_i111:cke(1)"
				( attribute "PN" "203"
					( Origin gPackager )
				)
				( objectStatus "J4G2.203" )
			)
			( pin "@baseboard_fab2_lib.baseboard_fab2(sch_1):page45_i111:dq(0)"
				( attribute "PN" "5"
					( Origin gPackager )
				)
				( objectStatus "J4G2.5" )
			)
			( pin "@baseboard_fab2_lib.baseboard_fab2(sch_1):page45_i111:dq(1)"
				( attribute "PN" "150"
					( Origin gPackager )
				)
				( objectStatus "J4G2.150" )
			)
			( pin "@baseboard_fab2_lib.baseboard_fab2(sch_1):page45_i111:dq(2)"
				( attribute "PN" "12"
					( Origin gPackager )
				)
				( objectStatus "J4G2.12" )
			)
			( pin "@baseboard_fab2_lib.baseboard_fab2(sch_1):page45_i111:dq(3)"
				( attribute "PN" "157"
					( Origin gPackager )
				)
				( objectStatus "J4G2.157" )
			)
			( pin "@baseboard_fab2_lib.baseboard_fab2(sch_1):page45_i111:dq(4)"
				( attribute "PN" "3"
					( Origin gPackager )
				)
				( objectStatus "J4G2.3" )
			)
			( pin "@baseboard_fab2_lib.baseboard_fab2(sch_1):page45_i111:dq(5)"
				( attribute "PN" "148"
					( Origin gPackager )
				)
				( objectStatus "J4G2.148" )
			)
			( pin "@baseboard_fab2_lib.baseboard_fab2(sch_1):page45_i111:dq(6)"
				( attribute "PN" "10"
					( Origin gPackager )
				)
				( objectStatus "J4G2.10" )
			)
			( pin "@baseboard_fab2_lib.baseboard_fab2(sch_1):page45_i111:dq(7)"
				( attribute "PN" "155"
					( Origin gPackager )
				)
				( objectStatus "J4G2.155" )
			)
			( pin "@baseboard_fab2_lib.baseboard_fab2(sch_1):page45_i111:dq(8)"
				( attribute "PN" "16"
					( Origin gPackager )
				)
				( objectStatus "J4G2.16" )
			)
			( pin "@baseboard_fab2_lib.baseboard_fab2(sch_1):page45_i111:dq(9)"
				( attribute "PN" "161"
					( Origin gPackager )
				)
				( objectStatus "J4G2.161" )
			)
			( pin "@baseboard_fab2_lib.baseboard_fab2(sch_1):page45_i111:dq(10)"
				( attribute "PN" "23"
					( Origin gPackager )
				)
				( objectStatus "J4G2.23" )
			)
			( pin "@baseboard_fab2_lib.baseboard_fab2(sch_1):page45_i111:dq(11)"
				( attribute "PN" "168"
					( Origin gPackager )
				)
				( objectStatus "J4G2.168" )
			)
			( pin "@baseboard_fab2_lib.baseboard_fab2(sch_1):page45_i111:dq(12)"
				( attribute "PN" "14"
					( Origin gPackager )
				)
				( objectStatus "J4G2.14" )
			)
			( pin "@baseboard_fab2_lib.baseboard_fab2(sch_1):page45_i111:dq(13)"
				( attribute "PN" "159"
					( Origin gPackager )
				)
				( objectStatus "J4G2.159" )
			)
			( pin "@baseboard_fab2_lib.baseboard_fab2(sch_1):page45_i111:dq(14)"
				( attribute "PN" "21"
					( Origin gPackager )
				)
				( objectStatus "J4G2.21" )
			)
			( pin "@baseboard_fab2_lib.baseboard_fab2(sch_1):page45_i111:dq(15)"
				( attribute "PN" "166"
					( Origin gPackager )
				)
				( objectStatus "J4G2.166" )
			)
			( pin "@baseboard_fab2_lib.baseboard_fab2(sch_1):page45_i111:dq(16)"
				( attribute "PN" "27"
					( Origin gPackager )
				)
				( objectStatus "J4G2.27" )
			)
			( pin "@baseboard_fab2_lib.baseboard_fab2(sch_1):page45_i111:dq(17)"
				( attribute "PN" "172"
					( Origin gPackager )
				)
				( objectStatus "J4G2.172" )
			)
			( pin "@baseboard_fab2_lib.baseboard_fab2(sch_1):page45_i111:dq(18)"
				( attribute "PN" "34"
					( Origin gPackager )
				)
				( objectStatus "J4G2.34" )
			)
			( pin "@baseboard_fab2_lib.baseboard_fab2(sch_1):page45_i111:dq(19)"
				( attribute "PN" "179"
					( Origin gPackager )
				)
				( objectStatus "J4G2.179" )
			)
			( pin "@baseboard_fab2_lib.baseboard_fab2(sch_1):page45_i111:dq(20)"
				( attribute "PN" "25"
					( Origin gPackager )
				)
				( objectStatus "J4G2.25" )
			)
			( pin "@baseboard_fab2_lib.baseboard_fab2(sch_1):page45_i111:dq(21)"
				( attribute "PN" "170"
					( Origin gPackager )
				)
				( objectStatus "J4G2.170" )
			)
			( pin "@baseboard_fab2_lib.baseboard_fab2(sch_1):page45_i111:dq(22)"
				( attribute "PN" "32"
					( Origin gPackager )
				)
				( objectStatus "J4G2.32" )
			)
			( pin "@baseboard_fab2_lib.baseboard_fab2(sch_1):page45_i111:dq(23)"
				( attribute "PN" "177"
					( Origin gPackager )
				)
				( objectStatus "J4G2.177" )
			)
			( pin "@baseboard_fab2_lib.baseboard_fab2(sch_1):page45_i111:dq(24)"
				( attribute "PN" "38"
					( Origin gPackager )
				)
				( objectStatus "J4G2.38" )
			)
			( pin "@baseboard_fab2_lib.baseboard_fab2(sch_1):page45_i111:dq(25)"
				( attribute "PN" "183"
					( Origin gPackager )
				)
				( objectStatus "J4G2.183" )
			)
			( pin "@baseboard_fab2_lib.baseboard_fab2(sch_1):page45_i111:dq(26)"
				( attribute "PN" "45"
					( Origin gPackager )
				)
				( objectStatus "J4G2.45" )
			)
			( pin "@baseboard_fab2_lib.baseboard_fab2(sch_1):page45_i111:dq(27)"
				( attribute "PN" "190"
					( Origin gPackager )
				)
				( objectStatus "J4G2.190" )
			)
			( pin "@baseboard_fab2_lib.baseboard_fab2(sch_1):page45_i111:dq(28)"
				( attribute "PN" "36"
					( Origin gPackager )
				)
				( objectStatus "J4G2.36" )
			)
			( pin "@baseboard_fab2_lib.baseboard_fab2(sch_1):page45_i111:dq(29)"
				( attribute "PN" "181"
					( Origin gPackager )
				)
				( objectStatus "J4G2.181" )
			)
			( pin "@baseboard_fab2_lib.baseboard_fab2(sch_1):page45_i111:dq(30)"
				( attribute "PN" "43"
					( Origin gPackager )
				)
				( objectStatus "J4G2.43" )
			)
			( pin "@baseboard_fab2_lib.baseboard_fab2(sch_1):page45_i111:dq(31)"
				( attribute "PN" "188"
					( Origin gPackager )
				)
				( objectStatus "J4G2.188" )
			)
			( pin "@baseboard_fab2_lib.baseboard_fab2(sch_1):page45_i111:dq(32)"
				( attribute "PN" "97"
					( Origin gPackager )
				)
				( objectStatus "J4G2.97" )
			)
			( pin "@baseboard_fab2_lib.baseboard_fab2(sch_1):page45_i111:dq(33)"
				( attribute "PN" "242"
					( Origin gPackager )
				)
				( objectStatus "J4G2.242" )
			)
			( pin "@baseboard_fab2_lib.baseboard_fab2(sch_1):page45_i111:dq(34)"
				( attribute "PN" "104"
					( Origin gPackager )
				)
				( objectStatus "J4G2.104" )
			)
			( pin "@baseboard_fab2_lib.baseboard_fab2(sch_1):page45_i111:dq(35)"
				( attribute "PN" "249"
					( Origin gPackager )
				)
				( objectStatus "J4G2.249" )
			)
			( pin "@baseboard_fab2_lib.baseboard_fab2(sch_1):page45_i111:dq(36)"
				( attribute "PN" "95"
					( Origin gPackager )
				)
				( objectStatus "J4G2.95" )
			)
			( pin "@baseboard_fab2_lib.baseboard_fab2(sch_1):page45_i111:dq(37)"
				( attribute "PN" "240"
					( Origin gPackager )
				)
				( objectStatus "J4G2.240" )
			)
			( pin "@baseboard_fab2_lib.baseboard_fab2(sch_1):page45_i111:dq(38)"
				( attribute "PN" "102"
					( Origin gPackager )
				)
				( objectStatus "J4G2.102" )
			)
			( pin "@baseboard_fab2_lib.baseboard_fab2(sch_1):page45_i111:dq(39)"
				( attribute "PN" "247"
					( Origin gPackager )
				)
				( objectStatus "J4G2.247" )
			)
			( pin "@baseboard_fab2_lib.baseboard_fab2(sch_1):page45_i111:dq(40)"
				( attribute "PN" "108"
					( Origin gPackager )
				)
				( objectStatus "J4G2.108" )
			)
			( pin "@baseboard_fab2_lib.baseboard_fab2(sch_1):page45_i111:dq(41)"
				( attribute "PN" "253"
					( Origin gPackager )
				)
				( objectStatus "J4G2.253" )
			)
			( pin "@baseboard_fab2_lib.baseboard_fab2(sch_1):page45_i111:dq(42)"
				( attribute "PN" "115"
					( Origin gPackager )
				)
				( objectStatus "J4G2.115" )
			)
			( pin "@baseboard_fab2_lib.baseboard_fab2(sch_1):page45_i111:dq(43)"
				( attribute "PN" "260"
					( Origin gPackager )
				)
				( objectStatus "J4G2.260" )
			)
			( pin "@baseboard_fab2_lib.baseboard_fab2(sch_1):page45_i111:dq(44)"
				( attribute "PN" "106"
					( Origin gPackager )
				)
				( objectStatus "J4G2.106" )
			)
			( pin "@baseboard_fab2_lib.baseboard_fab2(sch_1):page45_i111:dq(45)"
				( attribute "PN" "251"
					( Origin gPackager )
				)
				( objectStatus "J4G2.251" )
			)
			( pin "@baseboard_fab2_lib.baseboard_fab2(sch_1):page45_i111:dq(46)"
				( attribute "PN" "113"
					( Origin gPackager )
				)
				( objectStatus "J4G2.113" )
			)
			( pin "@baseboard_fab2_lib.baseboard_fab2(sch_1):page45_i111:dq(47)"
				( attribute "PN" "258"
					( Origin gPackager )
				)
				( objectStatus "J4G2.258" )
			)
			( pin "@baseboard_fab2_lib.baseboard_fab2(sch_1):page45_i111:dq(48)"
				( attribute "PN" "119"
					( Origin gPackager )
				)
				( objectStatus "J4G2.119" )
			)
			( pin "@baseboard_fab2_lib.baseboard_fab2(sch_1):page45_i111:dq(49)"
				( attribute "PN" "264"
					( Origin gPackager )
				)
				( objectStatus "J4G2.264" )
			)
			( pin "@baseboard_fab2_lib.baseboard_fab2(sch_1):page45_i111:dq(50)"
				( attribute "PN" "126"
					( Origin gPackager )
				)
				( objectStatus "J4G2.126" )
			)
			( pin "@baseboard_fab2_lib.baseboard_fab2(sch_1):page45_i111:dq(51)"
				( attribute "PN" "271"
					( Origin gPackager )
				)
				( objectStatus "J4G2.271" )
			)
			( pin "@baseboard_fab2_lib.baseboard_fab2(sch_1):page45_i111:dq(52)"
				( attribute "PN" "117"
					( Origin gPackager )
				)
				( objectStatus "J4G2.117" )
			)
			( pin "@baseboard_fab2_lib.baseboard_fab2(sch_1):page45_i111:dq(53)"
				( attribute "PN" "262"
					( Origin gPackager )
				)
				( objectStatus "J4G2.262" )
			)
			( pin "@baseboard_fab2_lib.baseboard_fab2(sch_1):page45_i111:dq(54)"
				( attribute "PN" "124"
					( Origin gPackager )
				)
				( objectStatus "J4G2.124" )
			)
			( pin "@baseboard_fab2_lib.baseboard_fab2(sch_1):page45_i111:dq(55)"
				( attribute "PN" "269"
					( Origin gPackager )
				)
				( objectStatus "J4G2.269" )
			)
			( pin "@baseboard_fab2_lib.baseboard_fab2(sch_1):page45_i111:dq(56)"
				( attribute "PN" "130"
					( Origin gPackager )
				)
				( objectStatus "J4G2.130" )
			)
			( pin "@baseboard_fab2_lib.baseboard_fab2(sch_1):page45_i111:dq(57)"
				( attribute "PN" "275"
					( Origin gPackager )
				)
				( objectStatus "J4G2.275" )
			)
			( pin "@baseboard_fab2_lib.baseboard_fab2(sch_1):page45_i111:dq(58)"
				( attribute "PN" "137"
					( Origin gPackager )
				)
				( objectStatus "J4G2.137" )
			)
			( pin "@baseboard_fab2_lib.baseboard_fab2(sch_1):page45_i111:dq(59)"
				( attribute "PN" "282"
					( Origin gPackager )
				)
				( objectStatus "J4G2.282" )
			)
			( pin "@baseboard_fab2_lib.baseboard_fab2(sch_1):page45_i111:dq(60)"
				( attribute "PN" "128"
					( Origin gPackager )
				)
				( objectStatus "J4G2.128" )
			)
			( pin "@baseboard_fab2_lib.baseboard_fab2(sch_1):page45_i111:dq(61)"
				( attribute "PN" "273"
					( Origin gPackager )
				)
				( objectStatus "J4G2.273" )
			)
			( pin "@baseboard_fab2_lib.baseboard_fab2(sch_1):page45_i111:dq(62)"
				( attribute "PN" "135"
					( Origin gPackager )
				)
				( objectStatus "J4G2.135" )
			)
			( pin "@baseboard_fab2_lib.baseboard_fab2(sch_1):page45_i111:dq(63)"
				( attribute "PN" "280"
					( Origin gPackager )
				)
				( objectStatus "J4G2.280" )
			)
			( pin "@baseboard_fab2_lib.baseboard_fab2(sch_1):page45_i111:event_n"
				( attribute "PN" "78"
					( Origin gPackager )
				)
				( objectStatus "J4G2.78" )
			)
			( pin "@baseboard_fab2_lib.baseboard_fab2(sch_1):page45_i111:odt(0)"
				( attribute "PN" "87"
					( Origin gPackager )
				)
				( objectStatus "J4G2.87" )
			)
			( pin "@baseboard_fab2_lib.baseboard_fab2(sch_1):page45_i111:odt(1)"
				( attribute "PN" "91"
					( Origin gPackager )
				)
				( objectStatus "J4G2.91" )
			)
			( pin "@baseboard_fab2_lib.baseboard_fab2(sch_1):page45_i111:par"
				( attribute "PN" "222"
					( Origin gPackager )
				)
				( objectStatus "J4G2.222" )
			)
			( pin "@baseboard_fab2_lib.baseboard_fab2(sch_1):page45_i111:reset_n"
				( attribute "PN" "58"
					( Origin gPackager )
				)
				( objectStatus "J4G2.58" )
			)
			( pin "@baseboard_fab2_lib.baseboard_fab2(sch_1):page45_i111:rfu(0)"
				( attribute "PN" "205"
					( Origin gPackager )
				)
				( objectStatus "J4G2.205" )
			)
			( pin "@baseboard_fab2_lib.baseboard_fab2(sch_1):page45_i111:rfu(1)"
				( attribute "PN" "227"
					( Origin gPackager )
				)
				( objectStatus "J4G2.227" )
			)
			( pin "@baseboard_fab2_lib.baseboard_fab2(sch_1):page45_i111:rfu(2)"
				( attribute "PN" "144"
					( Origin gPackager )
				)
				( objectStatus "J4G2.144" )
			)
			( pin "@baseboard_fab2_lib.baseboard_fab2(sch_1):page45_i111:s0_n"
				( attribute "PN" "84"
					( Origin gPackager )
				)
				( objectStatus "J4G2.84" )
			)
			( pin "@baseboard_fab2_lib.baseboard_fab2(sch_1):page45_i111:s1_n"
				( attribute "PN" "89"
					( Origin gPackager )
				)
				( objectStatus "J4G2.89" )
			)
			( pin "@baseboard_fab2_lib.baseboard_fab2(sch_1):page45_i111:s2_n_c(0)"
				( attribute "PN" "93"
					( Origin gPackager )
				)
				( objectStatus "J4G2.93" )
			)
			( pin "@baseboard_fab2_lib.baseboard_fab2(sch_1):page45_i111:s3_n_c(1)"
				( attribute "PN" "237"
					( Origin gPackager )
				)
				( objectStatus "J4G2.237" )
			)
			( pin "@baseboard_fab2_lib.baseboard_fab2(sch_1):page45_i111:sa(0)"
				( attribute "PN" "139"
					( Origin gPackager )
				)
				( objectStatus "J4G2.139" )
			)
			( pin "@baseboard_fab2_lib.baseboard_fab2(sch_1):page45_i111:sa(1)"
				( attribute "PN" "140"
					( Origin gPackager )
				)
				( objectStatus "J4G2.140" )
			)
			( pin "@baseboard_fab2_lib.baseboard_fab2(sch_1):page45_i111:sa(2)"
				( attribute "PN" "238"
					( Origin gPackager )
				)
				( objectStatus "J4G2.238" )
			)
			( pin "@baseboard_fab2_lib.baseboard_fab2(sch_1):page45_i111:save_n_nc"
				( attribute "PN" "230"
					( Origin gPackager )
				)
				( objectStatus "J4G2.230" )
			)
			( pin "@baseboard_fab2_lib.baseboard_fab2(sch_1):page45_i111:scl"
				( attribute "PN" "141"
					( Origin gPackager )
				)
				( objectStatus "J4G2.141" )
			)
			( pin "@baseboard_fab2_lib.baseboard_fab2(sch_1):page45_i111:sda"
				( attribute "PN" "285"
					( Origin gPackager )
				)
				( objectStatus "J4G2.285" )
			)
			( pin "@baseboard_fab2_lib.baseboard_fab2(sch_1):page45_i111:vddspd"
				( attribute "PN" "284"
					( Origin gPackager )
				)
				( objectStatus "J4G2.284" )
			)
			( pin "@baseboard_fab2_lib.baseboard_fab2(sch_1):page45_i111:vrefca"
				( attribute "PN" "146"
					( Origin gPackager )
				)
				( objectStatus "J4G2.146" )
			)
			( pin "@baseboard_fab2_lib.baseboard_fab2(sch_1):page45_i169:\12v\(0)"
				( attribute "PN" "145"
					( Origin gPackager )
				)
				( objectStatus "J4G2.145" )
			)
			( pin "@baseboard_fab2_lib.baseboard_fab2(sch_1):page45_i169:\12v\(1)"
				( attribute "PN" "1"
					( Origin gPackager )
				)
				( objectStatus "J4G2.1" )
			)
			( pin "@baseboard_fab2_lib.baseboard_fab2(sch_1):page45_i169:vdd(0)"
				( attribute "PN" "236"
					( Origin gPackager )
				)
				( objectStatus "J4G2.236" )
			)
			( pin "@baseboard_fab2_lib.baseboard_fab2(sch_1):page45_i169:vdd(1)"
				( attribute "PN" "233"
					( Origin gPackager )
				)
				( objectStatus "J4G2.233" )
			)
			( pin "@baseboard_fab2_lib.baseboard_fab2(sch_1):page45_i169:vdd(2)"
				( attribute "PN" "231"
					( Origin gPackager )
				)
				( objectStatus "J4G2.231" )
			)
			( pin "@baseboard_fab2_lib.baseboard_fab2(sch_1):page45_i169:vdd(3)"
				( attribute "PN" "229"
					( Origin gPackager )
				)
				( objectStatus "J4G2.229" )
			)
			( pin "@baseboard_fab2_lib.baseboard_fab2(sch_1):page45_i169:vdd(4)"
				( attribute "PN" "226"
					( Origin gPackager )
				)
				( objectStatus "J4G2.226" )
			)
			( pin "@baseboard_fab2_lib.baseboard_fab2(sch_1):page45_i169:vdd(5)"
				( attribute "PN" "223"
					( Origin gPackager )
				)
				( objectStatus "J4G2.223" )
			)
			( pin "@baseboard_fab2_lib.baseboard_fab2(sch_1):page45_i169:vdd(6)"
				( attribute "PN" "220"
					( Origin gPackager )
				)
				( objectStatus "J4G2.220" )
			)
			( pin "@baseboard_fab2_lib.baseboard_fab2(sch_1):page45_i169:vdd(7)"
				( attribute "PN" "217"
					( Origin gPackager )
				)
				( objectStatus "J4G2.217" )
			)
			( pin "@baseboard_fab2_lib.baseboard_fab2(sch_1):page45_i169:vdd(8)"
				( attribute "PN" "215"
					( Origin gPackager )
				)
				( objectStatus "J4G2.215" )
			)
			( pin "@baseboard_fab2_lib.baseboard_fab2(sch_1):page45_i169:vdd(9)"
				( attribute "PN" "212"
					( Origin gPackager )
				)
				( objectStatus "J4G2.212" )
			)
			( pin "@baseboard_fab2_lib.baseboard_fab2(sch_1):page45_i169:vdd(10)"
				( attribute "PN" "209"
					( Origin gPackager )
				)
				( objectStatus "J4G2.209" )
			)
			( pin "@baseboard_fab2_lib.baseboard_fab2(sch_1):page45_i169:vdd(11)"
				( attribute "PN" "206"
					( Origin gPackager )
				)
				( objectStatus "J4G2.206" )
			)
			( pin "@baseboard_fab2_lib.baseboard_fab2(sch_1):page45_i169:vdd(12)"
				( attribute "PN" "204"
					( Origin gPackager )
				)
				( objectStatus "J4G2.204" )
			)
			( pin "@baseboard_fab2_lib.baseboard_fab2(sch_1):page45_i169:vdd(13)"
				( attribute "PN" "92"
					( Origin gPackager )
				)
				( objectStatus "J4G2.92" )
			)
			( pin "@baseboard_fab2_lib.baseboard_fab2(sch_1):page45_i169:vdd(14)"
				( attribute "PN" "90"
					( Origin gPackager )
				)
				( objectStatus "J4G2.90" )
			)
			( pin "@baseboard_fab2_lib.baseboard_fab2(sch_1):page45_i169:vdd(15)"
				( attribute "PN" "88"
					( Origin gPackager )
				)
				( objectStatus "J4G2.88" )
			)
			( pin "@baseboard_fab2_lib.baseboard_fab2(sch_1):page45_i169:vdd(16)"
				( attribute "PN" "85"
					( Origin gPackager )
				)
				( objectStatus "J4G2.85" )
			)
			( pin "@baseboard_fab2_lib.baseboard_fab2(sch_1):page45_i169:vdd(17)"
				( attribute "PN" "83"
					( Origin gPackager )
				)
				( objectStatus "J4G2.83" )
			)
			( pin "@baseboard_fab2_lib.baseboard_fab2(sch_1):page45_i169:vdd(18)"
				( attribute "PN" "80"
					( Origin gPackager )
				)
				( objectStatus "J4G2.80" )
			)
			( pin "@baseboard_fab2_lib.baseboard_fab2(sch_1):page45_i169:vdd(19)"
				( attribute "PN" "76"
					( Origin gPackager )
				)
				( objectStatus "J4G2.76" )
			)
			( pin "@baseboard_fab2_lib.baseboard_fab2(sch_1):page45_i169:vdd(20)"
				( attribute "PN" "73"
					( Origin gPackager )
				)
				( objectStatus "J4G2.73" )
			)
			( pin "@baseboard_fab2_lib.baseboard_fab2(sch_1):page45_i169:vdd(21)"
				( attribute "PN" "70"
					( Origin gPackager )
				)
				( objectStatus "J4G2.70" )
			)
			( pin "@baseboard_fab2_lib.baseboard_fab2(sch_1):page45_i169:vdd(22)"
				( attribute "PN" "67"
					( Origin gPackager )
				)
				( objectStatus "J4G2.67" )
			)
			( pin "@baseboard_fab2_lib.baseboard_fab2(sch_1):page45_i169:vdd(23)"
				( attribute "PN" "64"
					( Origin gPackager )
				)
				( objectStatus "J4G2.64" )
			)
			( pin "@baseboard_fab2_lib.baseboard_fab2(sch_1):page45_i169:vdd(24)"
				( attribute "PN" "61"
					( Origin gPackager )
				)
				( objectStatus "J4G2.61" )
			)
			( pin "@baseboard_fab2_lib.baseboard_fab2(sch_1):page45_i169:vdd(25)"
				( attribute "PN" "59"
					( Origin gPackager )
				)
				( objectStatus "J4G2.59" )
			)
			( pin "@baseboard_fab2_lib.baseboard_fab2(sch_1):page45_i169:vpp(0)"
				( attribute "PN" "287"
					( Origin gPackager )
				)
				( objectStatus "J4G2.287" )
			)
			( pin "@baseboard_fab2_lib.baseboard_fab2(sch_1):page45_i169:vpp(1)"
				( attribute "PN" "286"
					( Origin gPackager )
				)
				( objectStatus "J4G2.286" )
			)
			( pin "@baseboard_fab2_lib.baseboard_fab2(sch_1):page45_i169:vpp(2)"
				( attribute "PN" "288"
					( Origin gPackager )
				)
				( objectStatus "J4G2.288" )
			)
			( pin "@baseboard_fab2_lib.baseboard_fab2(sch_1):page45_i169:vpp(3)"
				( attribute "PN" "143"
					( Origin gPackager )
				)
				( objectStatus "J4G2.143" )
			)
			( pin "@baseboard_fab2_lib.baseboard_fab2(sch_1):page45_i169:vpp(4)"
				( attribute "PN" "142"
					( Origin gPackager )
				)
				( objectStatus "J4G2.142" )
			)
			( pin "@baseboard_fab2_lib.baseboard_fab2(sch_1):page45_i169:vtt(0)"
				( attribute "PN" "221"
					( Origin gPackager )
				)
				( objectStatus "J4G2.221" )
			)
			( pin "@baseboard_fab2_lib.baseboard_fab2(sch_1):page45_i169:vtt(1)"
				( attribute "PN" "77"
					( Origin gPackager )
				)
				( objectStatus "J4G2.77" )
			)
			( pin "@baseboard_fab2_lib.baseboard_fab2(sch_1):page45_i179:a"
				( attribute "PN" "1"
					( Origin gPackager )
				)
				( objectStatus "C4G3.1" )
			)
			( pin "@baseboard_fab2_lib.baseboard_fab2(sch_1):page45_i179:b"
				( attribute "PN" "2"
					( Origin gPackager )
				)
				( objectStatus "C4G3.2" )
			)
			( pin "@baseboard_fab2_lib.baseboard_fab2(sch_1):page46_i5:a"
				( attribute "PN" "1"
					( Origin gPackager )
				)
				( objectStatus "C6U9.1" )
			)
			( pin "@baseboard_fab2_lib.baseboard_fab2(sch_1):page46_i5:b"
				( attribute "PN" "2"
					( Origin gPackager )
				)
				( objectStatus "C6U9.2" )
			)
			( pin "@baseboard_fab2_lib.baseboard_fab2(sch_1):page46_i14:a0"
				( attribute "PN" "79"
					( Origin gPackager )
				)
				( objectStatus "J6U1.79" )
			)
			( pin "@baseboard_fab2_lib.baseboard_fab2(sch_1):page46_i14:a1"
				( attribute "PN" "72"
					( Origin gPackager )
				)
				( objectStatus "J6U1.72" )
			)
			( pin "@baseboard_fab2_lib.baseboard_fab2(sch_1):page46_i14:a2"
				( attribute "PN" "216"
					( Origin gPackager )
				)
				( objectStatus "J6U1.216" )
			)
			( pin "@baseboard_fab2_lib.baseboard_fab2(sch_1):page46_i14:a3"
				( attribute "PN" "71"
					( Origin gPackager )
				)
				( objectStatus "J6U1.71" )
			)
			( pin "@baseboard_fab2_lib.baseboard_fab2(sch_1):page46_i14:a4"
				( attribute "PN" "214"
					( Origin gPackager )
				)
				( objectStatus "J6U1.214" )
			)
			( pin "@baseboard_fab2_lib.baseboard_fab2(sch_1):page46_i14:a5"
				( attribute "PN" "213"
					( Origin gPackager )
				)
				( objectStatus "J6U1.213" )
			)
			( pin "@baseboard_fab2_lib.baseboard_fab2(sch_1):page46_i14:a6"
				( attribute "PN" "69"
					( Origin gPackager )
				)
				( objectStatus "J6U1.69" )
			)
			( pin "@baseboard_fab2_lib.baseboard_fab2(sch_1):page46_i14:a7"
				( attribute "PN" "211"
					( Origin gPackager )
				)
				( objectStatus "J6U1.211" )
			)
			( pin "@baseboard_fab2_lib.baseboard_fab2(sch_1):page46_i14:a8"
				( attribute "PN" "68"
					( Origin gPackager )
				)
				( objectStatus "J6U1.68" )
			)
			( pin "@baseboard_fab2_lib.baseboard_fab2(sch_1):page46_i14:a9"
				( attribute "PN" "66"
					( Origin gPackager )
				)
				( objectStatus "J6U1.66" )
			)
			( pin "@baseboard_fab2_lib.baseboard_fab2(sch_1):page46_i14:a10"
				( attribute "PN" "225"
					( Origin gPackager )
				)
				( objectStatus "J6U1.225" )
			)
			( pin "@baseboard_fab2_lib.baseboard_fab2(sch_1):page46_i14:a11"
				( attribute "PN" "210"
					( Origin gPackager )
				)
				( objectStatus "J6U1.210" )
			)
			( pin "@baseboard_fab2_lib.baseboard_fab2(sch_1):page46_i14:a12"
				( attribute "PN" "65"
					( Origin gPackager )
				)
				( objectStatus "J6U1.65" )
			)
			( pin "@baseboard_fab2_lib.baseboard_fab2(sch_1):page46_i14:a13"
				( attribute "PN" "232"
					( Origin gPackager )
				)
				( objectStatus "J6U1.232" )
			)
			( pin "@baseboard_fab2_lib.baseboard_fab2(sch_1):page46_i14:a14_we_n"
				( attribute "PN" "228"
					( Origin gPackager )
				)
				( objectStatus "J6U1.228" )
			)
			( pin "@baseboard_fab2_lib.baseboard_fab2(sch_1):page46_i14:a15_cas_n"
				( attribute "PN" "86"
					( Origin gPackager )
				)
				( objectStatus "J6U1.86" )
			)
			( pin "@baseboard_fab2_lib.baseboard_fab2(sch_1):page46_i14:a16_ras_n"
				( attribute "PN" "82"
					( Origin gPackager )
				)
				( objectStatus "J6U1.82" )
			)
			( pin "@baseboard_fab2_lib.baseboard_fab2(sch_1):page46_i14:a17"
				( attribute "PN" "234"
					( Origin gPackager )
				)
				( objectStatus "J6U1.234" )
			)
			( pin "@baseboard_fab2_lib.baseboard_fab2(sch_1):page46_i14:act_n"
				( attribute "PN" "62"
					( Origin gPackager )
				)
				( objectStatus "J6U1.62" )
			)
			( pin "@baseboard_fab2_lib.baseboard_fab2(sch_1):page46_i14:alert_n"
				( attribute "PN" "208"
					( Origin gPackager )
				)
				( objectStatus "J6U1.208" )
			)
			( pin "@baseboard_fab2_lib.baseboard_fab2(sch_1):page46_i14:ba(0)"
				( attribute "PN" "81"
					( Origin gPackager )
				)
				( objectStatus "J6U1.81" )
			)
			( pin "@baseboard_fab2_lib.baseboard_fab2(sch_1):page46_i14:ba(1)"
				( attribute "PN" "224"
					( Origin gPackager )
				)
				( objectStatus "J6U1.224" )
			)
			( pin "@baseboard_fab2_lib.baseboard_fab2(sch_1):page46_i14:bg(0)"
				( attribute "PN" "63"
					( Origin gPackager )
				)
				( objectStatus "J6U1.63" )
			)
			( pin "@baseboard_fab2_lib.baseboard_fab2(sch_1):page46_i14:bg(1)"
				( attribute "PN" "207"
					( Origin gPackager )
				)
				( objectStatus "J6U1.207" )
			)
			( pin "@baseboard_fab2_lib.baseboard_fab2(sch_1):page46_i14:c(2)"
				( attribute "PN" "235"
					( Origin gPackager )
				)
				( objectStatus "J6U1.235" )
			)
			( pin "@baseboard_fab2_lib.baseboard_fab2(sch_1):page46_i14:cb(0)"
				( attribute "PN" "49"
					( Origin gPackager )
				)
				( objectStatus "J6U1.49" )
			)
			( pin "@baseboard_fab2_lib.baseboard_fab2(sch_1):page46_i14:cb(1)"
				( attribute "PN" "194"
					( Origin gPackager )
				)
				( objectStatus "J6U1.194" )
			)
			( pin "@baseboard_fab2_lib.baseboard_fab2(sch_1):page46_i14:cb(2)"
				( attribute "PN" "56"
					( Origin gPackager )
				)
				( objectStatus "J6U1.56" )
			)
			( pin "@baseboard_fab2_lib.baseboard_fab2(sch_1):page46_i14:cb(3)"
				( attribute "PN" "201"
					( Origin gPackager )
				)
				( objectStatus "J6U1.201" )
			)
			( pin "@baseboard_fab2_lib.baseboard_fab2(sch_1):page46_i14:cb(4)"
				( attribute "PN" "47"
					( Origin gPackager )
				)
				( objectStatus "J6U1.47" )
			)
			( pin "@baseboard_fab2_lib.baseboard_fab2(sch_1):page46_i14:cb(5)"
				( attribute "PN" "192"
					( Origin gPackager )
				)
				( objectStatus "J6U1.192" )
			)
			( pin "@baseboard_fab2_lib.baseboard_fab2(sch_1):page46_i14:cb(6)"
				( attribute "PN" "54"
					( Origin gPackager )
				)
				( objectStatus "J6U1.54" )
			)
			( pin "@baseboard_fab2_lib.baseboard_fab2(sch_1):page46_i14:cb(7)"
				( attribute "PN" "199"
					( Origin gPackager )
				)
				( objectStatus "J6U1.199" )
			)
			( pin "@baseboard_fab2_lib.baseboard_fab2(sch_1):page46_i14:ck0n"
				( attribute "PN" "75"
					( Origin gPackager )
				)
				( objectStatus "J6U1.75" )
			)
			( pin "@baseboard_fab2_lib.baseboard_fab2(sch_1):page46_i14:ck0p"
				( attribute "PN" "74"
					( Origin gPackager )
				)
				( objectStatus "J6U1.74" )
			)
			( pin "@baseboard_fab2_lib.baseboard_fab2(sch_1):page46_i14:ck1n"
				( attribute "PN" "219"
					( Origin gPackager )
				)
				( objectStatus "J6U1.219" )
			)
			( pin "@baseboard_fab2_lib.baseboard_fab2(sch_1):page46_i14:ck1p"
				( attribute "PN" "218"
					( Origin gPackager )
				)
				( objectStatus "J6U1.218" )
			)
			( pin "@baseboard_fab2_lib.baseboard_fab2(sch_1):page46_i14:cke(0)"
				( attribute "PN" "60"
					( Origin gPackager )
				)
				( objectStatus "J6U1.60" )
			)
			( pin "@baseboard_fab2_lib.baseboard_fab2(sch_1):page46_i14:cke(1)"
				( attribute "PN" "203"
					( Origin gPackager )
				)
				( objectStatus "J6U1.203" )
			)
			( pin "@baseboard_fab2_lib.baseboard_fab2(sch_1):page46_i14:dq(0)"
				( attribute "PN" "5"
					( Origin gPackager )
				)
				( objectStatus "J6U1.5" )
			)
			( pin "@baseboard_fab2_lib.baseboard_fab2(sch_1):page46_i14:dq(1)"
				( attribute "PN" "150"
					( Origin gPackager )
				)
				( objectStatus "J6U1.150" )
			)
			( pin "@baseboard_fab2_lib.baseboard_fab2(sch_1):page46_i14:dq(2)"
				( attribute "PN" "12"
					( Origin gPackager )
				)
				( objectStatus "J6U1.12" )
			)
			( pin "@baseboard_fab2_lib.baseboard_fab2(sch_1):page46_i14:dq(3)"
				( attribute "PN" "157"
					( Origin gPackager )
				)
				( objectStatus "J6U1.157" )
			)
			( pin "@baseboard_fab2_lib.baseboard_fab2(sch_1):page46_i14:dq(4)"
				( attribute "PN" "3"
					( Origin gPackager )
				)
				( objectStatus "J6U1.3" )
			)
			( pin "@baseboard_fab2_lib.baseboard_fab2(sch_1):page46_i14:dq(5)"
				( attribute "PN" "148"
					( Origin gPackager )
				)
				( objectStatus "J6U1.148" )
			)
			( pin "@baseboard_fab2_lib.baseboard_fab2(sch_1):page46_i14:dq(6)"
				( attribute "PN" "10"
					( Origin gPackager )
				)
				( objectStatus "J6U1.10" )
			)
			( pin "@baseboard_fab2_lib.baseboard_fab2(sch_1):page46_i14:dq(7)"
				( attribute "PN" "155"
					( Origin gPackager )
				)
				( objectStatus "J6U1.155" )
			)
			( pin "@baseboard_fab2_lib.baseboard_fab2(sch_1):page46_i14:dq(8)"
				( attribute "PN" "16"
					( Origin gPackager )
				)
				( objectStatus "J6U1.16" )
			)
			( pin "@baseboard_fab2_lib.baseboard_fab2(sch_1):page46_i14:dq(9)"
				( attribute "PN" "161"
					( Origin gPackager )
				)
				( objectStatus "J6U1.161" )
			)
			( pin "@baseboard_fab2_lib.baseboard_fab2(sch_1):page46_i14:dq(10)"
				( attribute "PN" "23"
					( Origin gPackager )
				)
				( objectStatus "J6U1.23" )
			)
			( pin "@baseboard_fab2_lib.baseboard_fab2(sch_1):page46_i14:dq(11)"
				( attribute "PN" "168"
					( Origin gPackager )
				)
				( objectStatus "J6U1.168" )
			)
			( pin "@baseboard_fab2_lib.baseboard_fab2(sch_1):page46_i14:dq(12)"
				( attribute "PN" "14"
					( Origin gPackager )
				)
				( objectStatus "J6U1.14" )
			)
			( pin "@baseboard_fab2_lib.baseboard_fab2(sch_1):page46_i14:dq(13)"
				( attribute "PN" "159"
					( Origin gPackager )
				)
				( objectStatus "J6U1.159" )
			)
			( pin "@baseboard_fab2_lib.baseboard_fab2(sch_1):page46_i14:dq(14)"
				( attribute "PN" "21"
					( Origin gPackager )
				)
				( objectStatus "J6U1.21" )
			)
			( pin "@baseboard_fab2_lib.baseboard_fab2(sch_1):page46_i14:dq(15)"
				( attribute "PN" "166"
					( Origin gPackager )
				)
				( objectStatus "J6U1.166" )
			)
			( pin "@baseboard_fab2_lib.baseboard_fab2(sch_1):page46_i14:dq(16)"
				( attribute "PN" "27"
					( Origin gPackager )
				)
				( objectStatus "J6U1.27" )
			)
			( pin "@baseboard_fab2_lib.baseboard_fab2(sch_1):page46_i14:dq(17)"
				( attribute "PN" "172"
					( Origin gPackager )
				)
				( objectStatus "J6U1.172" )
			)
			( pin "@baseboard_fab2_lib.baseboard_fab2(sch_1):page46_i14:dq(18)"
				( attribute "PN" "34"
					( Origin gPackager )
				)
				( objectStatus "J6U1.34" )
			)
			( pin "@baseboard_fab2_lib.baseboard_fab2(sch_1):page46_i14:dq(19)"
				( attribute "PN" "179"
					( Origin gPackager )
				)
				( objectStatus "J6U1.179" )
			)
			( pin "@baseboard_fab2_lib.baseboard_fab2(sch_1):page46_i14:dq(20)"
				( attribute "PN" "25"
					( Origin gPackager )
				)
				( objectStatus "J6U1.25" )
			)
			( pin "@baseboard_fab2_lib.baseboard_fab2(sch_1):page46_i14:dq(21)"
				( attribute "PN" "170"
					( Origin gPackager )
				)
				( objectStatus "J6U1.170" )
			)
			( pin "@baseboard_fab2_lib.baseboard_fab2(sch_1):page46_i14:dq(22)"
				( attribute "PN" "32"
					( Origin gPackager )
				)
				( objectStatus "J6U1.32" )
			)
			( pin "@baseboard_fab2_lib.baseboard_fab2(sch_1):page46_i14:dq(23)"
				( attribute "PN" "177"
					( Origin gPackager )
				)
				( objectStatus "J6U1.177" )
			)
			( pin "@baseboard_fab2_lib.baseboard_fab2(sch_1):page46_i14:dq(24)"
				( attribute "PN" "38"
					( Origin gPackager )
				)
				( objectStatus "J6U1.38" )
			)
			( pin "@baseboard_fab2_lib.baseboard_fab2(sch_1):page46_i14:dq(25)"
				( attribute "PN" "183"
					( Origin gPackager )
				)
				( objectStatus "J6U1.183" )
			)
			( pin "@baseboard_fab2_lib.baseboard_fab2(sch_1):page46_i14:dq(26)"
				( attribute "PN" "45"
					( Origin gPackager )
				)
				( objectStatus "J6U1.45" )
			)
			( pin "@baseboard_fab2_lib.baseboard_fab2(sch_1):page46_i14:dq(27)"
				( attribute "PN" "190"
					( Origin gPackager )
				)
				( objectStatus "J6U1.190" )
			)
			( pin "@baseboard_fab2_lib.baseboard_fab2(sch_1):page46_i14:dq(28)"
				( attribute "PN" "36"
					( Origin gPackager )
				)
				( objectStatus "J6U1.36" )
			)
			( pin "@baseboard_fab2_lib.baseboard_fab2(sch_1):page46_i14:dq(29)"
				( attribute "PN" "181"
					( Origin gPackager )
				)
				( objectStatus "J6U1.181" )
			)
			( pin "@baseboard_fab2_lib.baseboard_fab2(sch_1):page46_i14:dq(30)"
				( attribute "PN" "43"
					( Origin gPackager )
				)
				( objectStatus "J6U1.43" )
			)
			( pin "@baseboard_fab2_lib.baseboard_fab2(sch_1):page46_i14:dq(31)"
				( attribute "PN" "188"
					( Origin gPackager )
				)
				( objectStatus "J6U1.188" )
			)
			( pin "@baseboard_fab2_lib.baseboard_fab2(sch_1):page46_i14:dq(32)"
				( attribute "PN" "97"
					( Origin gPackager )
				)
				( objectStatus "J6U1.97" )
			)
			( pin "@baseboard_fab2_lib.baseboard_fab2(sch_1):page46_i14:dq(33)"
				( attribute "PN" "242"
					( Origin gPackager )
				)
				( objectStatus "J6U1.242" )
			)
			( pin "@baseboard_fab2_lib.baseboard_fab2(sch_1):page46_i14:dq(34)"
				( attribute "PN" "104"
					( Origin gPackager )
				)
				( objectStatus "J6U1.104" )
			)
			( pin "@baseboard_fab2_lib.baseboard_fab2(sch_1):page46_i14:dq(35)"
				( attribute "PN" "249"
					( Origin gPackager )
				)
				( objectStatus "J6U1.249" )
			)
			( pin "@baseboard_fab2_lib.baseboard_fab2(sch_1):page46_i14:dq(36)"
				( attribute "PN" "95"
					( Origin gPackager )
				)
				( objectStatus "J6U1.95" )
			)
			( pin "@baseboard_fab2_lib.baseboard_fab2(sch_1):page46_i14:dq(37)"
				( attribute "PN" "240"
					( Origin gPackager )
				)
				( objectStatus "J6U1.240" )
			)
			( pin "@baseboard_fab2_lib.baseboard_fab2(sch_1):page46_i14:dq(38)"
				( attribute "PN" "102"
					( Origin gPackager )
				)
				( objectStatus "J6U1.102" )
			)
			( pin "@baseboard_fab2_lib.baseboard_fab2(sch_1):page46_i14:dq(39)"
				( attribute "PN" "247"
					( Origin gPackager )
				)
				( objectStatus "J6U1.247" )
			)
			( pin "@baseboard_fab2_lib.baseboard_fab2(sch_1):page46_i14:dq(40)"
				( attribute "PN" "108"
					( Origin gPackager )
				)
				( objectStatus "J6U1.108" )
			)
			( pin "@baseboard_fab2_lib.baseboard_fab2(sch_1):page46_i14:dq(41)"
				( attribute "PN" "253"
					( Origin gPackager )
				)
				( objectStatus "J6U1.253" )
			)
			( pin "@baseboard_fab2_lib.baseboard_fab2(sch_1):page46_i14:dq(42)"
				( attribute "PN" "115"
					( Origin gPackager )
				)
				( objectStatus "J6U1.115" )
			)
			( pin "@baseboard_fab2_lib.baseboard_fab2(sch_1):page46_i14:dq(43)"
				( attribute "PN" "260"
					( Origin gPackager )
				)
				( objectStatus "J6U1.260" )
			)
			( pin "@baseboard_fab2_lib.baseboard_fab2(sch_1):page46_i14:dq(44)"
				( attribute "PN" "106"
					( Origin gPackager )
				)
				( objectStatus "J6U1.106" )
			)
			( pin "@baseboard_fab2_lib.baseboard_fab2(sch_1):page46_i14:dq(45)"
				( attribute "PN" "251"
					( Origin gPackager )
				)
				( objectStatus "J6U1.251" )
			)
			( pin "@baseboard_fab2_lib.baseboard_fab2(sch_1):page46_i14:dq(46)"
				( attribute "PN" "113"
					( Origin gPackager )
				)
				( objectStatus "J6U1.113" )
			)
			( pin "@baseboard_fab2_lib.baseboard_fab2(sch_1):page46_i14:dq(47)"
				( attribute "PN" "258"
					( Origin gPackager )
				)
				( objectStatus "J6U1.258" )
			)
			( pin "@baseboard_fab2_lib.baseboard_fab2(sch_1):page46_i14:dq(48)"
				( attribute "PN" "119"
					( Origin gPackager )
				)
				( objectStatus "J6U1.119" )
			)
			( pin "@baseboard_fab2_lib.baseboard_fab2(sch_1):page46_i14:dq(49)"
				( attribute "PN" "264"
					( Origin gPackager )
				)
				( objectStatus "J6U1.264" )
			)
			( pin "@baseboard_fab2_lib.baseboard_fab2(sch_1):page46_i14:dq(50)"
				( attribute "PN" "126"
					( Origin gPackager )
				)
				( objectStatus "J6U1.126" )
			)
			( pin "@baseboard_fab2_lib.baseboard_fab2(sch_1):page46_i14:dq(51)"
				( attribute "PN" "271"
					( Origin gPackager )
				)
				( objectStatus "J6U1.271" )
			)
			( pin "@baseboard_fab2_lib.baseboard_fab2(sch_1):page46_i14:dq(52)"
				( attribute "PN" "117"
					( Origin gPackager )
				)
				( objectStatus "J6U1.117" )
			)
			( pin "@baseboard_fab2_lib.baseboard_fab2(sch_1):page46_i14:dq(53)"
				( attribute "PN" "262"
					( Origin gPackager )
				)
				( objectStatus "J6U1.262" )
			)
			( pin "@baseboard_fab2_lib.baseboard_fab2(sch_1):page46_i14:dq(54)"
				( attribute "PN" "124"
					( Origin gPackager )
				)
				( objectStatus "J6U1.124" )
			)
			( pin "@baseboard_fab2_lib.baseboard_fab2(sch_1):page46_i14:dq(55)"
				( attribute "PN" "269"
					( Origin gPackager )
				)
				( objectStatus "J6U1.269" )
			)
			( pin "@baseboard_fab2_lib.baseboard_fab2(sch_1):page46_i14:dq(56)"
				( attribute "PN" "130"
					( Origin gPackager )
				)
				( objectStatus "J6U1.130" )
			)
			( pin "@baseboard_fab2_lib.baseboard_fab2(sch_1):page46_i14:dq(57)"
				( attribute "PN" "275"
					( Origin gPackager )
				)
				( objectStatus "J6U1.275" )
			)
			( pin "@baseboard_fab2_lib.baseboard_fab2(sch_1):page46_i14:dq(58)"
				( attribute "PN" "137"
					( Origin gPackager )
				)
				( objectStatus "J6U1.137" )
			)
			( pin "@baseboard_fab2_lib.baseboard_fab2(sch_1):page46_i14:dq(59)"
				( attribute "PN" "282"
					( Origin gPackager )
				)
				( objectStatus "J6U1.282" )
			)
			( pin "@baseboard_fab2_lib.baseboard_fab2(sch_1):page46_i14:dq(60)"
				( attribute "PN" "128"
					( Origin gPackager )
				)
				( objectStatus "J6U1.128" )
			)
			( pin "@baseboard_fab2_lib.baseboard_fab2(sch_1):page46_i14:dq(61)"
				( attribute "PN" "273"
					( Origin gPackager )
				)
				( objectStatus "J6U1.273" )
			)
			( pin "@baseboard_fab2_lib.baseboard_fab2(sch_1):page46_i14:dq(62)"
				( attribute "PN" "135"
					( Origin gPackager )
				)
				( objectStatus "J6U1.135" )
			)
			( pin "@baseboard_fab2_lib.baseboard_fab2(sch_1):page46_i14:dq(63)"
				( attribute "PN" "280"
					( Origin gPackager )
				)
				( objectStatus "J6U1.280" )
			)
			( pin "@baseboard_fab2_lib.baseboard_fab2(sch_1):page46_i14:event_n"
				( attribute "PN" "78"
					( Origin gPackager )
				)
				( objectStatus "J6U1.78" )
			)
			( pin "@baseboard_fab2_lib.baseboard_fab2(sch_1):page46_i14:odt(0)"
				( attribute "PN" "87"
					( Origin gPackager )
				)
				( objectStatus "J6U1.87" )
			)
			( pin "@baseboard_fab2_lib.baseboard_fab2(sch_1):page46_i14:odt(1)"
				( attribute "PN" "91"
					( Origin gPackager )
				)
				( objectStatus "J6U1.91" )
			)
			( pin "@baseboard_fab2_lib.baseboard_fab2(sch_1):page46_i14:par"
				( attribute "PN" "222"
					( Origin gPackager )
				)
				( objectStatus "J6U1.222" )
			)
			( pin "@baseboard_fab2_lib.baseboard_fab2(sch_1):page46_i14:reset_n"
				( attribute "PN" "58"
					( Origin gPackager )
				)
				( objectStatus "J6U1.58" )
			)
			( pin "@baseboard_fab2_lib.baseboard_fab2(sch_1):page46_i14:rfu(0)"
				( attribute "PN" "205"
					( Origin gPackager )
				)
				( objectStatus "J6U1.205" )
			)
			( pin "@baseboard_fab2_lib.baseboard_fab2(sch_1):page46_i14:rfu(1)"
				( attribute "PN" "227"
					( Origin gPackager )
				)
				( objectStatus "J6U1.227" )
			)
			( pin "@baseboard_fab2_lib.baseboard_fab2(sch_1):page46_i14:rfu(2)"
				( attribute "PN" "144"
					( Origin gPackager )
				)
				( objectStatus "J6U1.144" )
			)
			( pin "@baseboard_fab2_lib.baseboard_fab2(sch_1):page46_i14:s0_n"
				( attribute "PN" "84"
					( Origin gPackager )
				)
				( objectStatus "J6U1.84" )
			)
			( pin "@baseboard_fab2_lib.baseboard_fab2(sch_1):page46_i14:s1_n"
				( attribute "PN" "89"
					( Origin gPackager )
				)
				( objectStatus "J6U1.89" )
			)
			( pin "@baseboard_fab2_lib.baseboard_fab2(sch_1):page46_i14:s2_n_c(0)"
				( attribute "PN" "93"
					( Origin gPackager )
				)
				( objectStatus "J6U1.93" )
			)
			( pin "@baseboard_fab2_lib.baseboard_fab2(sch_1):page46_i14:s3_n_c(1)"
				( attribute "PN" "237"
					( Origin gPackager )
				)
				( objectStatus "J6U1.237" )
			)
			( pin "@baseboard_fab2_lib.baseboard_fab2(sch_1):page46_i14:sa(0)"
				( attribute "PN" "139"
					( Origin gPackager )
				)
				( objectStatus "J6U1.139" )
			)
			( pin "@baseboard_fab2_lib.baseboard_fab2(sch_1):page46_i14:sa(1)"
				( attribute "PN" "140"
					( Origin gPackager )
				)
				( objectStatus "J6U1.140" )
			)
			( pin "@baseboard_fab2_lib.baseboard_fab2(sch_1):page46_i14:sa(2)"
				( attribute "PN" "238"
					( Origin gPackager )
				)
				( objectStatus "J6U1.238" )
			)
			( pin "@baseboard_fab2_lib.baseboard_fab2(sch_1):page46_i14:save_n_nc"
				( attribute "PN" "230"
					( Origin gPackager )
				)
				( objectStatus "J6U1.230" )
			)
			( pin "@baseboard_fab2_lib.baseboard_fab2(sch_1):page46_i14:scl"
				( attribute "PN" "141"
					( Origin gPackager )
				)
				( objectStatus "J6U1.141" )
			)
			( pin "@baseboard_fab2_lib.baseboard_fab2(sch_1):page46_i14:sda"
				( attribute "PN" "285"
					( Origin gPackager )
				)
				( objectStatus "J6U1.285" )
			)
			( pin "@baseboard_fab2_lib.baseboard_fab2(sch_1):page46_i14:vddspd"
				( attribute "PN" "284"
					( Origin gPackager )
				)
				( objectStatus "J6U1.284" )
			)
			( pin "@baseboard_fab2_lib.baseboard_fab2(sch_1):page46_i14:vrefca"
				( attribute "PN" "146"
					( Origin gPackager )
				)
				( objectStatus "J6U1.146" )
			)
			( pin "@baseboard_fab2_lib.baseboard_fab2(sch_1):page46_i67:\12v\(0)"
				( attribute "PN" "145"
					( Origin gPackager )
				)
				( objectStatus "J6U1.145" )
			)
			( pin "@baseboard_fab2_lib.baseboard_fab2(sch_1):page46_i67:\12v\(1)"
				( attribute "PN" "1"
					( Origin gPackager )
				)
				( objectStatus "J6U1.1" )
			)
			( pin "@baseboard_fab2_lib.baseboard_fab2(sch_1):page46_i67:vdd(0)"
				( attribute "PN" "236"
					( Origin gPackager )
				)
				( objectStatus "J6U1.236" )
			)
			( pin "@baseboard_fab2_lib.baseboard_fab2(sch_1):page46_i67:vdd(1)"
				( attribute "PN" "233"
					( Origin gPackager )
				)
				( objectStatus "J6U1.233" )
			)
			( pin "@baseboard_fab2_lib.baseboard_fab2(sch_1):page46_i67:vdd(2)"
				( attribute "PN" "231"
					( Origin gPackager )
				)
				( objectStatus "J6U1.231" )
			)
			( pin "@baseboard_fab2_lib.baseboard_fab2(sch_1):page46_i67:vdd(3)"
				( attribute "PN" "229"
					( Origin gPackager )
				)
				( objectStatus "J6U1.229" )
			)
			( pin "@baseboard_fab2_lib.baseboard_fab2(sch_1):page46_i67:vdd(4)"
				( attribute "PN" "226"
					( Origin gPackager )
				)
				( objectStatus "J6U1.226" )
			)
			( pin "@baseboard_fab2_lib.baseboard_fab2(sch_1):page46_i67:vdd(5)"
				( attribute "PN" "223"
					( Origin gPackager )
				)
				( objectStatus "J6U1.223" )
			)
			( pin "@baseboard_fab2_lib.baseboard_fab2(sch_1):page46_i67:vdd(6)"
				( attribute "PN" "220"
					( Origin gPackager )
				)
				( objectStatus "J6U1.220" )
			)
			( pin "@baseboard_fab2_lib.baseboard_fab2(sch_1):page46_i67:vdd(7)"
				( attribute "PN" "217"
					( Origin gPackager )
				)
				( objectStatus "J6U1.217" )
			)
			( pin "@baseboard_fab2_lib.baseboard_fab2(sch_1):page46_i67:vdd(8)"
				( attribute "PN" "215"
					( Origin gPackager )
				)
				( objectStatus "J6U1.215" )
			)
			( pin "@baseboard_fab2_lib.baseboard_fab2(sch_1):page46_i67:vdd(9)"
				( attribute "PN" "212"
					( Origin gPackager )
				)
				( objectStatus "J6U1.212" )
			)
			( pin "@baseboard_fab2_lib.baseboard_fab2(sch_1):page46_i67:vdd(10)"
				( attribute "PN" "209"
					( Origin gPackager )
				)
				( objectStatus "J6U1.209" )
			)
			( pin "@baseboard_fab2_lib.baseboard_fab2(sch_1):page46_i67:vdd(11)"
				( attribute "PN" "206"
					( Origin gPackager )
				)
				( objectStatus "J6U1.206" )
			)
			( pin "@baseboard_fab2_lib.baseboard_fab2(sch_1):page46_i67:vdd(12)"
				( attribute "PN" "204"
					( Origin gPackager )
				)
				( objectStatus "J6U1.204" )
			)
			( pin "@baseboard_fab2_lib.baseboard_fab2(sch_1):page46_i67:vdd(13)"
				( attribute "PN" "92"
					( Origin gPackager )
				)
				( objectStatus "J6U1.92" )
			)
			( pin "@baseboard_fab2_lib.baseboard_fab2(sch_1):page46_i67:vdd(14)"
				( attribute "PN" "90"
					( Origin gPackager )
				)
				( objectStatus "J6U1.90" )
			)
			( pin "@baseboard_fab2_lib.baseboard_fab2(sch_1):page46_i67:vdd(15)"
				( attribute "PN" "88"
					( Origin gPackager )
				)
				( objectStatus "J6U1.88" )
			)
			( pin "@baseboard_fab2_lib.baseboard_fab2(sch_1):page46_i67:vdd(16)"
				( attribute "PN" "85"
					( Origin gPackager )
				)
				( objectStatus "J6U1.85" )
			)
			( pin "@baseboard_fab2_lib.baseboard_fab2(sch_1):page46_i67:vdd(17)"
				( attribute "PN" "83"
					( Origin gPackager )
				)
				( objectStatus "J6U1.83" )
			)
			( pin "@baseboard_fab2_lib.baseboard_fab2(sch_1):page46_i67:vdd(18)"
				( attribute "PN" "80"
					( Origin gPackager )
				)
				( objectStatus "J6U1.80" )
			)
			( pin "@baseboard_fab2_lib.baseboard_fab2(sch_1):page46_i67:vdd(19)"
				( attribute "PN" "76"
					( Origin gPackager )
				)
				( objectStatus "J6U1.76" )
			)
			( pin "@baseboard_fab2_lib.baseboard_fab2(sch_1):page46_i67:vdd(20)"
				( attribute "PN" "73"
					( Origin gPackager )
				)
				( objectStatus "J6U1.73" )
			)
			( pin "@baseboard_fab2_lib.baseboard_fab2(sch_1):page46_i67:vdd(21)"
				( attribute "PN" "70"
					( Origin gPackager )
				)
				( objectStatus "J6U1.70" )
			)
			( pin "@baseboard_fab2_lib.baseboard_fab2(sch_1):page46_i67:vdd(22)"
				( attribute "PN" "67"
					( Origin gPackager )
				)
				( objectStatus "J6U1.67" )
			)
			( pin "@baseboard_fab2_lib.baseboard_fab2(sch_1):page46_i67:vdd(23)"
				( attribute "PN" "64"
					( Origin gPackager )
				)
				( objectStatus "J6U1.64" )
			)
			( pin "@baseboard_fab2_lib.baseboard_fab2(sch_1):page46_i67:vdd(24)"
				( attribute "PN" "61"
					( Origin gPackager )
				)
				( objectStatus "J6U1.61" )
			)
			( pin "@baseboard_fab2_lib.baseboard_fab2(sch_1):page46_i67:vdd(25)"
				( attribute "PN" "59"
					( Origin gPackager )
				)
				( objectStatus "J6U1.59" )
			)
			( pin "@baseboard_fab2_lib.baseboard_fab2(sch_1):page46_i67:vpp(0)"
				( attribute "PN" "287"
					( Origin gPackager )
				)
				( objectStatus "J6U1.287" )
			)
			( pin "@baseboard_fab2_lib.baseboard_fab2(sch_1):page46_i67:vpp(1)"
				( attribute "PN" "286"
					( Origin gPackager )
				)
				( objectStatus "J6U1.286" )
			)
			( pin "@baseboard_fab2_lib.baseboard_fab2(sch_1):page46_i67:vpp(2)"
				( attribute "PN" "288"
					( Origin gPackager )
				)
				( objectStatus "J6U1.288" )
			)
			( pin "@baseboard_fab2_lib.baseboard_fab2(sch_1):page46_i67:vpp(3)"
				( attribute "PN" "143"
					( Origin gPackager )
				)
				( objectStatus "J6U1.143" )
			)
			( pin "@baseboard_fab2_lib.baseboard_fab2(sch_1):page46_i67:vpp(4)"
				( attribute "PN" "142"
					( Origin gPackager )
				)
				( objectStatus "J6U1.142" )
			)
			( pin "@baseboard_fab2_lib.baseboard_fab2(sch_1):page46_i67:vtt(0)"
				( attribute "PN" "221"
					( Origin gPackager )
				)
				( objectStatus "J6U1.221" )
			)
			( pin "@baseboard_fab2_lib.baseboard_fab2(sch_1):page46_i67:vtt(1)"
				( attribute "PN" "77"
					( Origin gPackager )
				)
				( objectStatus "J6U1.77" )
			)
			( pin "@baseboard_fab2_lib.baseboard_fab2(sch_1):page46_i112:dqs0n"
				( attribute "PN" "152"
					( Origin gPackager )
				)
				( objectStatus "J6U1.152" )
			)
			( pin "@baseboard_fab2_lib.baseboard_fab2(sch_1):page46_i112:dqs0p"
				( attribute "PN" "153"
					( Origin gPackager )
				)
				( objectStatus "J6U1.153" )
			)
			( pin "@baseboard_fab2_lib.baseboard_fab2(sch_1):page46_i112:dqs1n"
				( attribute "PN" "163"
					( Origin gPackager )
				)
				( objectStatus "J6U1.163" )
			)
			( pin "@baseboard_fab2_lib.baseboard_fab2(sch_1):page46_i112:dqs1p"
				( attribute "PN" "164"
					( Origin gPackager )
				)
				( objectStatus "J6U1.164" )
			)
			( pin "@baseboard_fab2_lib.baseboard_fab2(sch_1):page46_i112:dqs2n"
				( attribute "PN" "174"
					( Origin gPackager )
				)
				( objectStatus "J6U1.174" )
			)
			( pin "@baseboard_fab2_lib.baseboard_fab2(sch_1):page46_i112:dqs2p"
				( attribute "PN" "175"
					( Origin gPackager )
				)
				( objectStatus "J6U1.175" )
			)
			( pin "@baseboard_fab2_lib.baseboard_fab2(sch_1):page46_i112:dqs3n"
				( attribute "PN" "185"
					( Origin gPackager )
				)
				( objectStatus "J6U1.185" )
			)
			( pin "@baseboard_fab2_lib.baseboard_fab2(sch_1):page46_i112:dqs3p"
				( attribute "PN" "186"
					( Origin gPackager )
				)
				( objectStatus "J6U1.186" )
			)
			( pin "@baseboard_fab2_lib.baseboard_fab2(sch_1):page46_i112:dqs4n"
				( attribute "PN" "244"
					( Origin gPackager )
				)
				( objectStatus "J6U1.244" )
			)
			( pin "@baseboard_fab2_lib.baseboard_fab2(sch_1):page46_i112:dqs4p"
				( attribute "PN" "245"
					( Origin gPackager )
				)
				( objectStatus "J6U1.245" )
			)
			( pin "@baseboard_fab2_lib.baseboard_fab2(sch_1):page46_i112:dqs5n"
				( attribute "PN" "255"
					( Origin gPackager )
				)
				( objectStatus "J6U1.255" )
			)
			( pin "@baseboard_fab2_lib.baseboard_fab2(sch_1):page46_i112:dqs5p"
				( attribute "PN" "256"
					( Origin gPackager )
				)
				( objectStatus "J6U1.256" )
			)
			( pin "@baseboard_fab2_lib.baseboard_fab2(sch_1):page46_i112:dqs6n"
				( attribute "PN" "266"
					( Origin gPackager )
				)
				( objectStatus "J6U1.266" )
			)
			( pin "@baseboard_fab2_lib.baseboard_fab2(sch_1):page46_i112:dqs6p"
				( attribute "PN" "267"
					( Origin gPackager )
				)
				( objectStatus "J6U1.267" )
			)
			( pin "@baseboard_fab2_lib.baseboard_fab2(sch_1):page46_i112:dqs7n"
				( attribute "PN" "277"
					( Origin gPackager )
				)
				( objectStatus "J6U1.277" )
			)
			( pin "@baseboard_fab2_lib.baseboard_fab2(sch_1):page46_i112:dqs7p"
				( attribute "PN" "278"
					( Origin gPackager )
				)
				( objectStatus "J6U1.278" )
			)
			( pin "@baseboard_fab2_lib.baseboard_fab2(sch_1):page46_i112:dqs8n"
				( attribute "PN" "196"
					( Origin gPackager )
				)
				( objectStatus "J6U1.196" )
			)
			( pin "@baseboard_fab2_lib.baseboard_fab2(sch_1):page46_i112:dqs8p"
				( attribute "PN" "197"
					( Origin gPackager )
				)
				( objectStatus "J6U1.197" )
			)
			( pin "@baseboard_fab2_lib.baseboard_fab2(sch_1):page46_i112:dqs9n"
				( attribute "PN" "8"
					( Origin gPackager )
				)
				( objectStatus "J6U1.8" )
			)
			( pin "@baseboard_fab2_lib.baseboard_fab2(sch_1):page46_i112:dqs9p"
				( attribute "PN" "7"
					( Origin gPackager )
				)
				( objectStatus "J6U1.7" )
			)
			( pin "@baseboard_fab2_lib.baseboard_fab2(sch_1):page46_i112:dqs10n"
				( attribute "PN" "19"
					( Origin gPackager )
				)
				( objectStatus "J6U1.19" )
			)
			( pin "@baseboard_fab2_lib.baseboard_fab2(sch_1):page46_i112:dqs10p"
				( attribute "PN" "18"
					( Origin gPackager )
				)
				( objectStatus "J6U1.18" )
			)
			( pin "@baseboard_fab2_lib.baseboard_fab2(sch_1):page46_i112:dqs11n"
				( attribute "PN" "30"
					( Origin gPackager )
				)
				( objectStatus "J6U1.30" )
			)
			( pin "@baseboard_fab2_lib.baseboard_fab2(sch_1):page46_i112:dqs11p"
				( attribute "PN" "29"
					( Origin gPackager )
				)
				( objectStatus "J6U1.29" )
			)
			( pin "@baseboard_fab2_lib.baseboard_fab2(sch_1):page46_i112:dqs12n"
				( attribute "PN" "41"
					( Origin gPackager )
				)
				( objectStatus "J6U1.41" )
			)
			( pin "@baseboard_fab2_lib.baseboard_fab2(sch_1):page46_i112:dqs12p"
				( attribute "PN" "40"
					( Origin gPackager )
				)
				( objectStatus "J6U1.40" )
			)
			( pin "@baseboard_fab2_lib.baseboard_fab2(sch_1):page46_i112:dqs13n"
				( attribute "PN" "100"
					( Origin gPackager )
				)
				( objectStatus "J6U1.100" )
			)
			( pin "@baseboard_fab2_lib.baseboard_fab2(sch_1):page46_i112:dqs13p"
				( attribute "PN" "99"
					( Origin gPackager )
				)
				( objectStatus "J6U1.99" )
			)
			( pin "@baseboard_fab2_lib.baseboard_fab2(sch_1):page46_i112:dqs14n"
				( attribute "PN" "111"
					( Origin gPackager )
				)
				( objectStatus "J6U1.111" )
			)
			( pin "@baseboard_fab2_lib.baseboard_fab2(sch_1):page46_i112:dqs14p"
				( attribute "PN" "110"
					( Origin gPackager )
				)
				( objectStatus "J6U1.110" )
			)
			( pin "@baseboard_fab2_lib.baseboard_fab2(sch_1):page46_i112:dqs15n"
				( attribute "PN" "122"
					( Origin gPackager )
				)
				( objectStatus "J6U1.122" )
			)
			( pin "@baseboard_fab2_lib.baseboard_fab2(sch_1):page46_i112:dqs15p"
				( attribute "PN" "121"
					( Origin gPackager )
				)
				( objectStatus "J6U1.121" )
			)
			( pin "@baseboard_fab2_lib.baseboard_fab2(sch_1):page46_i112:dqs16n"
				( attribute "PN" "133"
					( Origin gPackager )
				)
				( objectStatus "J6U1.133" )
			)
			( pin "@baseboard_fab2_lib.baseboard_fab2(sch_1):page46_i112:dqs16p"
				( attribute "PN" "132"
					( Origin gPackager )
				)
				( objectStatus "J6U1.132" )
			)
			( pin "@baseboard_fab2_lib.baseboard_fab2(sch_1):page46_i112:dqs17n"
				( attribute "PN" "52"
					( Origin gPackager )
				)
				( objectStatus "J6U1.52" )
			)
			( pin "@baseboard_fab2_lib.baseboard_fab2(sch_1):page46_i112:dqs17p"
				( attribute "PN" "51"
					( Origin gPackager )
				)
				( objectStatus "J6U1.51" )
			)
			( pin "@baseboard_fab2_lib.baseboard_fab2(sch_1):page46_i138:vss(0)"
				( attribute "PN" "283"
					( Origin gPackager )
				)
				( objectStatus "J6U1.283" )
			)
			( pin "@baseboard_fab2_lib.baseboard_fab2(sch_1):page46_i138:vss(1)"
				( attribute "PN" "281"
					( Origin gPackager )
				)
				( objectStatus "J6U1.281" )
			)
			( pin "@baseboard_fab2_lib.baseboard_fab2(sch_1):page46_i138:vss(2)"
				( attribute "PN" "279"
					( Origin gPackager )
				)
				( objectStatus "J6U1.279" )
			)
			( pin "@baseboard_fab2_lib.baseboard_fab2(sch_1):page46_i138:vss(3)"
				( attribute "PN" "276"
					( Origin gPackager )
				)
				( objectStatus "J6U1.276" )
			)
			( pin "@baseboard_fab2_lib.baseboard_fab2(sch_1):page46_i138:vss(4)"
				( attribute "PN" "274"
					( Origin gPackager )
				)
				( objectStatus "J6U1.274" )
			)
			( pin "@baseboard_fab2_lib.baseboard_fab2(sch_1):page46_i138:vss(5)"
				( attribute "PN" "272"
					( Origin gPackager )
				)
				( objectStatus "J6U1.272" )
			)
			( pin "@baseboard_fab2_lib.baseboard_fab2(sch_1):page46_i138:vss(6)"
				( attribute "PN" "270"
					( Origin gPackager )
				)
				( objectStatus "J6U1.270" )
			)
			( pin "@baseboard_fab2_lib.baseboard_fab2(sch_1):page46_i138:vss(7)"
				( attribute "PN" "268"
					( Origin gPackager )
				)
				( objectStatus "J6U1.268" )
			)
			( pin "@baseboard_fab2_lib.baseboard_fab2(sch_1):page46_i138:vss(8)"
				( attribute "PN" "265"
					( Origin gPackager )
				)
				( objectStatus "J6U1.265" )
			)
			( pin "@baseboard_fab2_lib.baseboard_fab2(sch_1):page46_i138:vss(9)"
				( attribute "PN" "263"
					( Origin gPackager )
				)
				( objectStatus "J6U1.263" )
			)
			( pin "@baseboard_fab2_lib.baseboard_fab2(sch_1):page46_i138:vss(10)"
				( attribute "PN" "261"
					( Origin gPackager )
				)
				( objectStatus "J6U1.261" )
			)
			( pin "@baseboard_fab2_lib.baseboard_fab2(sch_1):page46_i138:vss(11)"
				( attribute "PN" "259"
					( Origin gPackager )
				)
				( objectStatus "J6U1.259" )
			)
			( pin "@baseboard_fab2_lib.baseboard_fab2(sch_1):page46_i138:vss(12)"
				( attribute "PN" "257"
					( Origin gPackager )
				)
				( objectStatus "J6U1.257" )
			)
			( pin "@baseboard_fab2_lib.baseboard_fab2(sch_1):page46_i138:vss(13)"
				( attribute "PN" "254"
					( Origin gPackager )
				)
				( objectStatus "J6U1.254" )
			)
			( pin "@baseboard_fab2_lib.baseboard_fab2(sch_1):page46_i138:vss(14)"
				( attribute "PN" "252"
					( Origin gPackager )
				)
				( objectStatus "J6U1.252" )
			)
			( pin "@baseboard_fab2_lib.baseboard_fab2(sch_1):page46_i138:vss(15)"
				( attribute "PN" "250"
					( Origin gPackager )
				)
				( objectStatus "J6U1.250" )
			)
			( pin "@baseboard_fab2_lib.baseboard_fab2(sch_1):page46_i138:vss(16)"
				( attribute "PN" "248"
					( Origin gPackager )
				)
				( objectStatus "J6U1.248" )
			)
			( pin "@baseboard_fab2_lib.baseboard_fab2(sch_1):page46_i138:vss(17)"
				( attribute "PN" "246"
					( Origin gPackager )
				)
				( objectStatus "J6U1.246" )
			)
			( pin "@baseboard_fab2_lib.baseboard_fab2(sch_1):page46_i138:vss(18)"
				( attribute "PN" "243"
					( Origin gPackager )
				)
				( objectStatus "J6U1.243" )
			)
			( pin "@baseboard_fab2_lib.baseboard_fab2(sch_1):page46_i138:vss(19)"
				( attribute "PN" "241"
					( Origin gPackager )
				)
				( objectStatus "J6U1.241" )
			)
			( pin "@baseboard_fab2_lib.baseboard_fab2(sch_1):page46_i138:vss(20)"
				( attribute "PN" "239"
					( Origin gPackager )
				)
				( objectStatus "J6U1.239" )
			)
			( pin "@baseboard_fab2_lib.baseboard_fab2(sch_1):page46_i138:vss(21)"
				( attribute "PN" "202"
					( Origin gPackager )
				)
				( objectStatus "J6U1.202" )
			)
			( pin "@baseboard_fab2_lib.baseboard_fab2(sch_1):page46_i138:vss(22)"
				( attribute "PN" "200"
					( Origin gPackager )
				)
				( objectStatus "J6U1.200" )
			)
			( pin "@baseboard_fab2_lib.baseboard_fab2(sch_1):page46_i138:vss(23)"
				( attribute "PN" "198"
					( Origin gPackager )
				)
				( objectStatus "J6U1.198" )
			)
			( pin "@baseboard_fab2_lib.baseboard_fab2(sch_1):page46_i138:vss(24)"
				( attribute "PN" "195"
					( Origin gPackager )
				)
				( objectStatus "J6U1.195" )
			)
			( pin "@baseboard_fab2_lib.baseboard_fab2(sch_1):page46_i138:vss(25)"
				( attribute "PN" "193"
					( Origin gPackager )
				)
				( objectStatus "J6U1.193" )
			)
			( pin "@baseboard_fab2_lib.baseboard_fab2(sch_1):page46_i138:vss(26)"
				( attribute "PN" "191"
					( Origin gPackager )
				)
				( objectStatus "J6U1.191" )
			)
			( pin "@baseboard_fab2_lib.baseboard_fab2(sch_1):page46_i138:vss(27)"
				( attribute "PN" "189"
					( Origin gPackager )
				)
				( objectStatus "J6U1.189" )
			)
			( pin "@baseboard_fab2_lib.baseboard_fab2(sch_1):page46_i138:vss(28)"
				( attribute "PN" "187"
					( Origin gPackager )
				)
				( objectStatus "J6U1.187" )
			)
			( pin "@baseboard_fab2_lib.baseboard_fab2(sch_1):page46_i138:vss(29)"
				( attribute "PN" "184"
					( Origin gPackager )
				)
				( objectStatus "J6U1.184" )
			)
			( pin "@baseboard_fab2_lib.baseboard_fab2(sch_1):page46_i138:vss(30)"
				( attribute "PN" "182"
					( Origin gPackager )
				)
				( objectStatus "J6U1.182" )
			)
			( pin "@baseboard_fab2_lib.baseboard_fab2(sch_1):page46_i138:vss(31)"
				( attribute "PN" "180"
					( Origin gPackager )
				)
				( objectStatus "J6U1.180" )
			)
			( pin "@baseboard_fab2_lib.baseboard_fab2(sch_1):page46_i138:vss(32)"
				( attribute "PN" "178"
					( Origin gPackager )
				)
				( objectStatus "J6U1.178" )
			)
			( pin "@baseboard_fab2_lib.baseboard_fab2(sch_1):page46_i138:vss(33)"
				( attribute "PN" "176"
					( Origin gPackager )
				)
				( objectStatus "J6U1.176" )
			)
			( pin "@baseboard_fab2_lib.baseboard_fab2(sch_1):page46_i138:vss(34)"
				( attribute "PN" "173"
					( Origin gPackager )
				)
				( objectStatus "J6U1.173" )
			)
			( pin "@baseboard_fab2_lib.baseboard_fab2(sch_1):page46_i138:vss(35)"
				( attribute "PN" "171"
					( Origin gPackager )
				)
				( objectStatus "J6U1.171" )
			)
			( pin "@baseboard_fab2_lib.baseboard_fab2(sch_1):page46_i138:vss(36)"
				( attribute "PN" "169"
					( Origin gPackager )
				)
				( objectStatus "J6U1.169" )
			)
			( pin "@baseboard_fab2_lib.baseboard_fab2(sch_1):page46_i138:vss(37)"
				( attribute "PN" "167"
					( Origin gPackager )
				)
				( objectStatus "J6U1.167" )
			)
			( pin "@baseboard_fab2_lib.baseboard_fab2(sch_1):page46_i138:vss(38)"
				( attribute "PN" "165"
					( Origin gPackager )
				)
				( objectStatus "J6U1.165" )
			)
			( pin "@baseboard_fab2_lib.baseboard_fab2(sch_1):page46_i138:vss(39)"
				( attribute "PN" "162"
					( Origin gPackager )
				)
				( objectStatus "J6U1.162" )
			)
			( pin "@baseboard_fab2_lib.baseboard_fab2(sch_1):page46_i138:vss(40)"
				( attribute "PN" "160"
					( Origin gPackager )
				)
				( objectStatus "J6U1.160" )
			)
			( pin "@baseboard_fab2_lib.baseboard_fab2(sch_1):page46_i138:vss(41)"
				( attribute "PN" "158"
					( Origin gPackager )
				)
				( objectStatus "J6U1.158" )
			)
			( pin "@baseboard_fab2_lib.baseboard_fab2(sch_1):page46_i138:vss(42)"
				( attribute "PN" "156"
					( Origin gPackager )
				)
				( objectStatus "J6U1.156" )
			)
			( pin "@baseboard_fab2_lib.baseboard_fab2(sch_1):page46_i138:vss(43)"
				( attribute "PN" "154"
					( Origin gPackager )
				)
				( objectStatus "J6U1.154" )
			)
			( pin "@baseboard_fab2_lib.baseboard_fab2(sch_1):page46_i138:vss(44)"
				( attribute "PN" "151"
					( Origin gPackager )
				)
				( objectStatus "J6U1.151" )
			)
			( pin "@baseboard_fab2_lib.baseboard_fab2(sch_1):page46_i138:vss(45)"
				( attribute "PN" "149"
					( Origin gPackager )
				)
				( objectStatus "J6U1.149" )
			)
			( pin "@baseboard_fab2_lib.baseboard_fab2(sch_1):page46_i138:vss(46)"
				( attribute "PN" "147"
					( Origin gPackager )
				)
				( objectStatus "J6U1.147" )
			)
			( pin "@baseboard_fab2_lib.baseboard_fab2(sch_1):page46_i138:vss(47)"
				( attribute "PN" "138"
					( Origin gPackager )
				)
				( objectStatus "J6U1.138" )
			)
			( pin "@baseboard_fab2_lib.baseboard_fab2(sch_1):page46_i138:vss(48)"
				( attribute "PN" "136"
					( Origin gPackager )
				)
				( objectStatus "J6U1.136" )
			)
			( pin "@baseboard_fab2_lib.baseboard_fab2(sch_1):page46_i138:vss(49)"
				( attribute "PN" "134"
					( Origin gPackager )
				)
				( objectStatus "J6U1.134" )
			)
			( pin "@baseboard_fab2_lib.baseboard_fab2(sch_1):page46_i138:vss(50)"
				( attribute "PN" "131"
					( Origin gPackager )
				)
				( objectStatus "J6U1.131" )
			)
			( pin "@baseboard_fab2_lib.baseboard_fab2(sch_1):page46_i138:vss(51)"
				( attribute "PN" "129"
					( Origin gPackager )
				)
				( objectStatus "J6U1.129" )
			)
			( pin "@baseboard_fab2_lib.baseboard_fab2(sch_1):page46_i138:vss(52)"
				( attribute "PN" "127"
					( Origin gPackager )
				)
				( objectStatus "J6U1.127" )
			)
			( pin "@baseboard_fab2_lib.baseboard_fab2(sch_1):page46_i138:vss(53)"
				( attribute "PN" "125"
					( Origin gPackager )
				)
				( objectStatus "J6U1.125" )
			)
			( pin "@baseboard_fab2_lib.baseboard_fab2(sch_1):page46_i138:vss(54)"
				( attribute "PN" "123"
					( Origin gPackager )
				)
				( objectStatus "J6U1.123" )
			)
			( pin "@baseboard_fab2_lib.baseboard_fab2(sch_1):page46_i138:vss(55)"
				( attribute "PN" "120"
					( Origin gPackager )
				)
				( objectStatus "J6U1.120" )
			)
			( pin "@baseboard_fab2_lib.baseboard_fab2(sch_1):page46_i138:vss(56)"
				( attribute "PN" "118"
					( Origin gPackager )
				)
				( objectStatus "J6U1.118" )
			)
			( pin "@baseboard_fab2_lib.baseboard_fab2(sch_1):page46_i138:vss(57)"
				( attribute "PN" "116"
					( Origin gPackager )
				)
				( objectStatus "J6U1.116" )
			)
			( pin "@baseboard_fab2_lib.baseboard_fab2(sch_1):page46_i138:vss(58)"
				( attribute "PN" "114"
					( Origin gPackager )
				)
				( objectStatus "J6U1.114" )
			)
			( pin "@baseboard_fab2_lib.baseboard_fab2(sch_1):page46_i138:vss(59)"
				( attribute "PN" "112"
					( Origin gPackager )
				)
				( objectStatus "J6U1.112" )
			)
			( pin "@baseboard_fab2_lib.baseboard_fab2(sch_1):page46_i138:vss(60)"
				( attribute "PN" "109"
					( Origin gPackager )
				)
				( objectStatus "J6U1.109" )
			)
			( pin "@baseboard_fab2_lib.baseboard_fab2(sch_1):page46_i138:vss(61)"
				( attribute "PN" "107"
					( Origin gPackager )
				)
				( objectStatus "J6U1.107" )
			)
			( pin "@baseboard_fab2_lib.baseboard_fab2(sch_1):page46_i138:vss(62)"
				( attribute "PN" "105"
					( Origin gPackager )
				)
				( objectStatus "J6U1.105" )
			)
			( pin "@baseboard_fab2_lib.baseboard_fab2(sch_1):page46_i138:vss(63)"
				( attribute "PN" "103"
					( Origin gPackager )
				)
				( objectStatus "J6U1.103" )
			)
			( pin "@baseboard_fab2_lib.baseboard_fab2(sch_1):page46_i138:vss(64)"
				( attribute "PN" "101"
					( Origin gPackager )
				)
				( objectStatus "J6U1.101" )
			)
			( pin "@baseboard_fab2_lib.baseboard_fab2(sch_1):page46_i138:vss(65)"
				( attribute "PN" "98"
					( Origin gPackager )
				)
				( objectStatus "J6U1.98" )
			)
			( pin "@baseboard_fab2_lib.baseboard_fab2(sch_1):page46_i138:vss(66)"
				( attribute "PN" "96"
					( Origin gPackager )
				)
				( objectStatus "J6U1.96" )
			)
			( pin "@baseboard_fab2_lib.baseboard_fab2(sch_1):page46_i138:vss(67)"
				( attribute "PN" "94"
					( Origin gPackager )
				)
				( objectStatus "J6U1.94" )
			)
			( pin "@baseboard_fab2_lib.baseboard_fab2(sch_1):page46_i138:vss(68)"
				( attribute "PN" "57"
					( Origin gPackager )
				)
				( objectStatus "J6U1.57" )
			)
			( pin "@baseboard_fab2_lib.baseboard_fab2(sch_1):page46_i138:vss(69)"
				( attribute "PN" "55"
					( Origin gPackager )
				)
				( objectStatus "J6U1.55" )
			)
			( pin "@baseboard_fab2_lib.baseboard_fab2(sch_1):page46_i138:vss(70)"
				( attribute "PN" "53"
					( Origin gPackager )
				)
				( objectStatus "J6U1.53" )
			)
			( pin "@baseboard_fab2_lib.baseboard_fab2(sch_1):page46_i138:vss(71)"
				( attribute "PN" "50"
					( Origin gPackager )
				)
				( objectStatus "J6U1.50" )
			)
			( pin "@baseboard_fab2_lib.baseboard_fab2(sch_1):page46_i138:vss(72)"
				( attribute "PN" "48"
					( Origin gPackager )
				)
				( objectStatus "J6U1.48" )
			)
			( pin "@baseboard_fab2_lib.baseboard_fab2(sch_1):page46_i138:vss(73)"
				( attribute "PN" "46"
					( Origin gPackager )
				)
				( objectStatus "J6U1.46" )
			)
			( pin "@baseboard_fab2_lib.baseboard_fab2(sch_1):page46_i138:vss(74)"
				( attribute "PN" "44"
					( Origin gPackager )
				)
				( objectStatus "J6U1.44" )
			)
			( pin "@baseboard_fab2_lib.baseboard_fab2(sch_1):page46_i138:vss(75)"
				( attribute "PN" "42"
					( Origin gPackager )
				)
				( objectStatus "J6U1.42" )
			)
			( pin "@baseboard_fab2_lib.baseboard_fab2(sch_1):page46_i138:vss(76)"
				( attribute "PN" "39"
					( Origin gPackager )
				)
				( objectStatus "J6U1.39" )
			)
			( pin "@baseboard_fab2_lib.baseboard_fab2(sch_1):page46_i138:vss(77)"
				( attribute "PN" "37"
					( Origin gPackager )
				)
				( objectStatus "J6U1.37" )
			)
			( pin "@baseboard_fab2_lib.baseboard_fab2(sch_1):page46_i138:vss(78)"
				( attribute "PN" "35"
					( Origin gPackager )
				)
				( objectStatus "J6U1.35" )
			)
			( pin "@baseboard_fab2_lib.baseboard_fab2(sch_1):page46_i138:vss(79)"
				( attribute "PN" "33"
					( Origin gPackager )
				)
				( objectStatus "J6U1.33" )
			)
			( pin "@baseboard_fab2_lib.baseboard_fab2(sch_1):page46_i138:vss(80)"
				( attribute "PN" "31"
					( Origin gPackager )
				)
				( objectStatus "J6U1.31" )
			)
			( pin "@baseboard_fab2_lib.baseboard_fab2(sch_1):page46_i138:vss(81)"
				( attribute "PN" "28"
					( Origin gPackager )
				)
				( objectStatus "J6U1.28" )
			)
			( pin "@baseboard_fab2_lib.baseboard_fab2(sch_1):page46_i138:vss(82)"
				( attribute "PN" "26"
					( Origin gPackager )
				)
				( objectStatus "J6U1.26" )
			)
			( pin "@baseboard_fab2_lib.baseboard_fab2(sch_1):page46_i138:vss(83)"
				( attribute "PN" "24"
					( Origin gPackager )
				)
				( objectStatus "J6U1.24" )
			)
			( pin "@baseboard_fab2_lib.baseboard_fab2(sch_1):page46_i138:vss(84)"
				( attribute "PN" "22"
					( Origin gPackager )
				)
				( objectStatus "J6U1.22" )
			)
			( pin "@baseboard_fab2_lib.baseboard_fab2(sch_1):page46_i138:vss(85)"
				( attribute "PN" "20"
					( Origin gPackager )
				)
				( objectStatus "J6U1.20" )
			)
			( pin "@baseboard_fab2_lib.baseboard_fab2(sch_1):page46_i138:vss(86)"
				( attribute "PN" "17"
					( Origin gPackager )
				)
				( objectStatus "J6U1.17" )
			)
			( pin "@baseboard_fab2_lib.baseboard_fab2(sch_1):page46_i138:vss(87)"
				( attribute "PN" "15"
					( Origin gPackager )
				)
				( objectStatus "J6U1.15" )
			)
			( pin "@baseboard_fab2_lib.baseboard_fab2(sch_1):page46_i138:vss(88)"
				( attribute "PN" "13"
					( Origin gPackager )
				)
				( objectStatus "J6U1.13" )
			)
			( pin "@baseboard_fab2_lib.baseboard_fab2(sch_1):page46_i138:vss(89)"
				( attribute "PN" "11"
					( Origin gPackager )
				)
				( objectStatus "J6U1.11" )
			)
			( pin "@baseboard_fab2_lib.baseboard_fab2(sch_1):page46_i138:vss(90)"
				( attribute "PN" "9"
					( Origin gPackager )
				)
				( objectStatus "J6U1.9" )
			)
			( pin "@baseboard_fab2_lib.baseboard_fab2(sch_1):page46_i138:vss(91)"
				( attribute "PN" "6"
					( Origin gPackager )
				)
				( objectStatus "J6U1.6" )
			)
			( pin "@baseboard_fab2_lib.baseboard_fab2(sch_1):page46_i138:vss(92)"
				( attribute "PN" "4"
					( Origin gPackager )
				)
				( objectStatus "J6U1.4" )
			)
			( pin "@baseboard_fab2_lib.baseboard_fab2(sch_1):page46_i138:vss(93)"
				( attribute "PN" "2"
					( Origin gPackager )
				)
				( objectStatus "J6U1.2" )
			)
			( pin "@baseboard_fab2_lib.baseboard_fab2(sch_1):page47_i43:vss(0)"
				( attribute "PN" "283"
					( Origin gPackager )
				)
				( objectStatus "J4G3.283" )
			)
			( pin "@baseboard_fab2_lib.baseboard_fab2(sch_1):page47_i43:vss(1)"
				( attribute "PN" "281"
					( Origin gPackager )
				)
				( objectStatus "J4G3.281" )
			)
			( pin "@baseboard_fab2_lib.baseboard_fab2(sch_1):page47_i43:vss(2)"
				( attribute "PN" "279"
					( Origin gPackager )
				)
				( objectStatus "J4G3.279" )
			)
			( pin "@baseboard_fab2_lib.baseboard_fab2(sch_1):page47_i43:vss(3)"
				( attribute "PN" "276"
					( Origin gPackager )
				)
				( objectStatus "J4G3.276" )
			)
			( pin "@baseboard_fab2_lib.baseboard_fab2(sch_1):page47_i43:vss(4)"
				( attribute "PN" "274"
					( Origin gPackager )
				)
				( objectStatus "J4G3.274" )
			)
			( pin "@baseboard_fab2_lib.baseboard_fab2(sch_1):page47_i43:vss(5)"
				( attribute "PN" "272"
					( Origin gPackager )
				)
				( objectStatus "J4G3.272" )
			)
			( pin "@baseboard_fab2_lib.baseboard_fab2(sch_1):page47_i43:vss(6)"
				( attribute "PN" "270"
					( Origin gPackager )
				)
				( objectStatus "J4G3.270" )
			)
			( pin "@baseboard_fab2_lib.baseboard_fab2(sch_1):page47_i43:vss(7)"
				( attribute "PN" "268"
					( Origin gPackager )
				)
				( objectStatus "J4G3.268" )
			)
			( pin "@baseboard_fab2_lib.baseboard_fab2(sch_1):page47_i43:vss(8)"
				( attribute "PN" "265"
					( Origin gPackager )
				)
				( objectStatus "J4G3.265" )
			)
			( pin "@baseboard_fab2_lib.baseboard_fab2(sch_1):page47_i43:vss(9)"
				( attribute "PN" "263"
					( Origin gPackager )
				)
				( objectStatus "J4G3.263" )
			)
			( pin "@baseboard_fab2_lib.baseboard_fab2(sch_1):page47_i43:vss(10)"
				( attribute "PN" "261"
					( Origin gPackager )
				)
				( objectStatus "J4G3.261" )
			)
			( pin "@baseboard_fab2_lib.baseboard_fab2(sch_1):page47_i43:vss(11)"
				( attribute "PN" "259"
					( Origin gPackager )
				)
				( objectStatus "J4G3.259" )
			)
			( pin "@baseboard_fab2_lib.baseboard_fab2(sch_1):page47_i43:vss(12)"
				( attribute "PN" "257"
					( Origin gPackager )
				)
				( objectStatus "J4G3.257" )
			)
			( pin "@baseboard_fab2_lib.baseboard_fab2(sch_1):page47_i43:vss(13)"
				( attribute "PN" "254"
					( Origin gPackager )
				)
				( objectStatus "J4G3.254" )
			)
			( pin "@baseboard_fab2_lib.baseboard_fab2(sch_1):page47_i43:vss(14)"
				( attribute "PN" "252"
					( Origin gPackager )
				)
				( objectStatus "J4G3.252" )
			)
			( pin "@baseboard_fab2_lib.baseboard_fab2(sch_1):page47_i43:vss(15)"
				( attribute "PN" "250"
					( Origin gPackager )
				)
				( objectStatus "J4G3.250" )
			)
			( pin "@baseboard_fab2_lib.baseboard_fab2(sch_1):page47_i43:vss(16)"
				( attribute "PN" "248"
					( Origin gPackager )
				)
				( objectStatus "J4G3.248" )
			)
			( pin "@baseboard_fab2_lib.baseboard_fab2(sch_1):page47_i43:vss(17)"
				( attribute "PN" "246"
					( Origin gPackager )
				)
				( objectStatus "J4G3.246" )
			)
			( pin "@baseboard_fab2_lib.baseboard_fab2(sch_1):page47_i43:vss(18)"
				( attribute "PN" "243"
					( Origin gPackager )
				)
				( objectStatus "J4G3.243" )
			)
			( pin "@baseboard_fab2_lib.baseboard_fab2(sch_1):page47_i43:vss(19)"
				( attribute "PN" "241"
					( Origin gPackager )
				)
				( objectStatus "J4G3.241" )
			)
			( pin "@baseboard_fab2_lib.baseboard_fab2(sch_1):page47_i43:vss(20)"
				( attribute "PN" "239"
					( Origin gPackager )
				)
				( objectStatus "J4G3.239" )
			)
			( pin "@baseboard_fab2_lib.baseboard_fab2(sch_1):page47_i43:vss(21)"
				( attribute "PN" "202"
					( Origin gPackager )
				)
				( objectStatus "J4G3.202" )
			)
			( pin "@baseboard_fab2_lib.baseboard_fab2(sch_1):page47_i43:vss(22)"
				( attribute "PN" "200"
					( Origin gPackager )
				)
				( objectStatus "J4G3.200" )
			)
			( pin "@baseboard_fab2_lib.baseboard_fab2(sch_1):page47_i43:vss(23)"
				( attribute "PN" "198"
					( Origin gPackager )
				)
				( objectStatus "J4G3.198" )
			)
			( pin "@baseboard_fab2_lib.baseboard_fab2(sch_1):page47_i43:vss(24)"
				( attribute "PN" "195"
					( Origin gPackager )
				)
				( objectStatus "J4G3.195" )
			)
			( pin "@baseboard_fab2_lib.baseboard_fab2(sch_1):page47_i43:vss(25)"
				( attribute "PN" "193"
					( Origin gPackager )
				)
				( objectStatus "J4G3.193" )
			)
			( pin "@baseboard_fab2_lib.baseboard_fab2(sch_1):page47_i43:vss(26)"
				( attribute "PN" "191"
					( Origin gPackager )
				)
				( objectStatus "J4G3.191" )
			)
			( pin "@baseboard_fab2_lib.baseboard_fab2(sch_1):page47_i43:vss(27)"
				( attribute "PN" "189"
					( Origin gPackager )
				)
				( objectStatus "J4G3.189" )
			)
			( pin "@baseboard_fab2_lib.baseboard_fab2(sch_1):page47_i43:vss(28)"
				( attribute "PN" "187"
					( Origin gPackager )
				)
				( objectStatus "J4G3.187" )
			)
			( pin "@baseboard_fab2_lib.baseboard_fab2(sch_1):page47_i43:vss(29)"
				( attribute "PN" "184"
					( Origin gPackager )
				)
				( objectStatus "J4G3.184" )
			)
			( pin "@baseboard_fab2_lib.baseboard_fab2(sch_1):page47_i43:vss(30)"
				( attribute "PN" "182"
					( Origin gPackager )
				)
				( objectStatus "J4G3.182" )
			)
			( pin "@baseboard_fab2_lib.baseboard_fab2(sch_1):page47_i43:vss(31)"
				( attribute "PN" "180"
					( Origin gPackager )
				)
				( objectStatus "J4G3.180" )
			)
			( pin "@baseboard_fab2_lib.baseboard_fab2(sch_1):page47_i43:vss(32)"
				( attribute "PN" "178"
					( Origin gPackager )
				)
				( objectStatus "J4G3.178" )
			)
			( pin "@baseboard_fab2_lib.baseboard_fab2(sch_1):page47_i43:vss(33)"
				( attribute "PN" "176"
					( Origin gPackager )
				)
				( objectStatus "J4G3.176" )
			)
			( pin "@baseboard_fab2_lib.baseboard_fab2(sch_1):page47_i43:vss(34)"
				( attribute "PN" "173"
					( Origin gPackager )
				)
				( objectStatus "J4G3.173" )
			)
			( pin "@baseboard_fab2_lib.baseboard_fab2(sch_1):page47_i43:vss(35)"
				( attribute "PN" "171"
					( Origin gPackager )
				)
				( objectStatus "J4G3.171" )
			)
			( pin "@baseboard_fab2_lib.baseboard_fab2(sch_1):page47_i43:vss(36)"
				( attribute "PN" "169"
					( Origin gPackager )
				)
				( objectStatus "J4G3.169" )
			)
			( pin "@baseboard_fab2_lib.baseboard_fab2(sch_1):page47_i43:vss(37)"
				( attribute "PN" "167"
					( Origin gPackager )
				)
				( objectStatus "J4G3.167" )
			)
			( pin "@baseboard_fab2_lib.baseboard_fab2(sch_1):page47_i43:vss(38)"
				( attribute "PN" "165"
					( Origin gPackager )
				)
				( objectStatus "J4G3.165" )
			)
			( pin "@baseboard_fab2_lib.baseboard_fab2(sch_1):page47_i43:vss(39)"
				( attribute "PN" "162"
					( Origin gPackager )
				)
				( objectStatus "J4G3.162" )
			)
			( pin "@baseboard_fab2_lib.baseboard_fab2(sch_1):page47_i43:vss(40)"
				( attribute "PN" "160"
					( Origin gPackager )
				)
				( objectStatus "J4G3.160" )
			)
			( pin "@baseboard_fab2_lib.baseboard_fab2(sch_1):page47_i43:vss(41)"
				( attribute "PN" "158"
					( Origin gPackager )
				)
				( objectStatus "J4G3.158" )
			)
			( pin "@baseboard_fab2_lib.baseboard_fab2(sch_1):page47_i43:vss(42)"
				( attribute "PN" "156"
					( Origin gPackager )
				)
				( objectStatus "J4G3.156" )
			)
			( pin "@baseboard_fab2_lib.baseboard_fab2(sch_1):page47_i43:vss(43)"
				( attribute "PN" "154"
					( Origin gPackager )
				)
				( objectStatus "J4G3.154" )
			)
			( pin "@baseboard_fab2_lib.baseboard_fab2(sch_1):page47_i43:vss(44)"
				( attribute "PN" "151"
					( Origin gPackager )
				)
				( objectStatus "J4G3.151" )
			)
			( pin "@baseboard_fab2_lib.baseboard_fab2(sch_1):page47_i43:vss(45)"
				( attribute "PN" "149"
					( Origin gPackager )
				)
				( objectStatus "J4G3.149" )
			)
			( pin "@baseboard_fab2_lib.baseboard_fab2(sch_1):page47_i43:vss(46)"
				( attribute "PN" "147"
					( Origin gPackager )
				)
				( objectStatus "J4G3.147" )
			)
			( pin "@baseboard_fab2_lib.baseboard_fab2(sch_1):page47_i43:vss(47)"
				( attribute "PN" "138"
					( Origin gPackager )
				)
				( objectStatus "J4G3.138" )
			)
			( pin "@baseboard_fab2_lib.baseboard_fab2(sch_1):page47_i43:vss(48)"
				( attribute "PN" "136"
					( Origin gPackager )
				)
				( objectStatus "J4G3.136" )
			)
			( pin "@baseboard_fab2_lib.baseboard_fab2(sch_1):page47_i43:vss(49)"
				( attribute "PN" "134"
					( Origin gPackager )
				)
				( objectStatus "J4G3.134" )
			)
			( pin "@baseboard_fab2_lib.baseboard_fab2(sch_1):page47_i43:vss(50)"
				( attribute "PN" "131"
					( Origin gPackager )
				)
				( objectStatus "J4G3.131" )
			)
			( pin "@baseboard_fab2_lib.baseboard_fab2(sch_1):page47_i43:vss(51)"
				( attribute "PN" "129"
					( Origin gPackager )
				)
				( objectStatus "J4G3.129" )
			)
			( pin "@baseboard_fab2_lib.baseboard_fab2(sch_1):page47_i43:vss(52)"
				( attribute "PN" "127"
					( Origin gPackager )
				)
				( objectStatus "J4G3.127" )
			)
			( pin "@baseboard_fab2_lib.baseboard_fab2(sch_1):page47_i43:vss(53)"
				( attribute "PN" "125"
					( Origin gPackager )
				)
				( objectStatus "J4G3.125" )
			)
			( pin "@baseboard_fab2_lib.baseboard_fab2(sch_1):page47_i43:vss(54)"
				( attribute "PN" "123"
					( Origin gPackager )
				)
				( objectStatus "J4G3.123" )
			)
			( pin "@baseboard_fab2_lib.baseboard_fab2(sch_1):page47_i43:vss(55)"
				( attribute "PN" "120"
					( Origin gPackager )
				)
				( objectStatus "J4G3.120" )
			)
			( pin "@baseboard_fab2_lib.baseboard_fab2(sch_1):page47_i43:vss(56)"
				( attribute "PN" "118"
					( Origin gPackager )
				)
				( objectStatus "J4G3.118" )
			)
			( pin "@baseboard_fab2_lib.baseboard_fab2(sch_1):page47_i43:vss(57)"
				( attribute "PN" "116"
					( Origin gPackager )
				)
				( objectStatus "J4G3.116" )
			)
			( pin "@baseboard_fab2_lib.baseboard_fab2(sch_1):page47_i43:vss(58)"
				( attribute "PN" "114"
					( Origin gPackager )
				)
				( objectStatus "J4G3.114" )
			)
			( pin "@baseboard_fab2_lib.baseboard_fab2(sch_1):page47_i43:vss(59)"
				( attribute "PN" "112"
					( Origin gPackager )
				)
				( objectStatus "J4G3.112" )
			)
			( pin "@baseboard_fab2_lib.baseboard_fab2(sch_1):page47_i43:vss(60)"
				( attribute "PN" "109"
					( Origin gPackager )
				)
				( objectStatus "J4G3.109" )
			)
			( pin "@baseboard_fab2_lib.baseboard_fab2(sch_1):page47_i43:vss(61)"
				( attribute "PN" "107"
					( Origin gPackager )
				)
				( objectStatus "J4G3.107" )
			)
			( pin "@baseboard_fab2_lib.baseboard_fab2(sch_1):page47_i43:vss(62)"
				( attribute "PN" "105"
					( Origin gPackager )
				)
				( objectStatus "J4G3.105" )
			)
			( pin "@baseboard_fab2_lib.baseboard_fab2(sch_1):page47_i43:vss(63)"
				( attribute "PN" "103"
					( Origin gPackager )
				)
				( objectStatus "J4G3.103" )
			)
			( pin "@baseboard_fab2_lib.baseboard_fab2(sch_1):page47_i43:vss(64)"
				( attribute "PN" "101"
					( Origin gPackager )
				)
				( objectStatus "J4G3.101" )
			)
			( pin "@baseboard_fab2_lib.baseboard_fab2(sch_1):page47_i43:vss(65)"
				( attribute "PN" "98"
					( Origin gPackager )
				)
				( objectStatus "J4G3.98" )
			)
			( pin "@baseboard_fab2_lib.baseboard_fab2(sch_1):page47_i43:vss(66)"
				( attribute "PN" "96"
					( Origin gPackager )
				)
				( objectStatus "J4G3.96" )
			)
			( pin "@baseboard_fab2_lib.baseboard_fab2(sch_1):page47_i43:vss(67)"
				( attribute "PN" "94"
					( Origin gPackager )
				)
				( objectStatus "J4G3.94" )
			)
			( pin "@baseboard_fab2_lib.baseboard_fab2(sch_1):page47_i43:vss(68)"
				( attribute "PN" "57"
					( Origin gPackager )
				)
				( objectStatus "J4G3.57" )
			)
			( pin "@baseboard_fab2_lib.baseboard_fab2(sch_1):page47_i43:vss(69)"
				( attribute "PN" "55"
					( Origin gPackager )
				)
				( objectStatus "J4G3.55" )
			)
			( pin "@baseboard_fab2_lib.baseboard_fab2(sch_1):page47_i43:vss(70)"
				( attribute "PN" "53"
					( Origin gPackager )
				)
				( objectStatus "J4G3.53" )
			)
			( pin "@baseboard_fab2_lib.baseboard_fab2(sch_1):page47_i43:vss(71)"
				( attribute "PN" "50"
					( Origin gPackager )
				)
				( objectStatus "J4G3.50" )
			)
			( pin "@baseboard_fab2_lib.baseboard_fab2(sch_1):page47_i43:vss(72)"
				( attribute "PN" "48"
					( Origin gPackager )
				)
				( objectStatus "J4G3.48" )
			)
			( pin "@baseboard_fab2_lib.baseboard_fab2(sch_1):page47_i43:vss(73)"
				( attribute "PN" "46"
					( Origin gPackager )
				)
				( objectStatus "J4G3.46" )
			)
			( pin "@baseboard_fab2_lib.baseboard_fab2(sch_1):page47_i43:vss(74)"
				( attribute "PN" "44"
					( Origin gPackager )
				)
				( objectStatus "J4G3.44" )
			)
			( pin "@baseboard_fab2_lib.baseboard_fab2(sch_1):page47_i43:vss(75)"
				( attribute "PN" "42"
					( Origin gPackager )
				)
				( objectStatus "J4G3.42" )
			)
			( pin "@baseboard_fab2_lib.baseboard_fab2(sch_1):page47_i43:vss(76)"
				( attribute "PN" "39"
					( Origin gPackager )
				)
				( objectStatus "J4G3.39" )
			)
			( pin "@baseboard_fab2_lib.baseboard_fab2(sch_1):page47_i43:vss(77)"
				( attribute "PN" "37"
					( Origin gPackager )
				)
				( objectStatus "J4G3.37" )
			)
			( pin "@baseboard_fab2_lib.baseboard_fab2(sch_1):page47_i43:vss(78)"
				( attribute "PN" "35"
					( Origin gPackager )
				)
				( objectStatus "J4G3.35" )
			)
			( pin "@baseboard_fab2_lib.baseboard_fab2(sch_1):page47_i43:vss(79)"
				( attribute "PN" "33"
					( Origin gPackager )
				)
				( objectStatus "J4G3.33" )
			)
			( pin "@baseboard_fab2_lib.baseboard_fab2(sch_1):page47_i43:vss(80)"
				( attribute "PN" "31"
					( Origin gPackager )
				)
				( objectStatus "J4G3.31" )
			)
			( pin "@baseboard_fab2_lib.baseboard_fab2(sch_1):page47_i43:vss(81)"
				( attribute "PN" "28"
					( Origin gPackager )
				)
				( objectStatus "J4G3.28" )
			)
			( pin "@baseboard_fab2_lib.baseboard_fab2(sch_1):page47_i43:vss(82)"
				( attribute "PN" "26"
					( Origin gPackager )
				)
				( objectStatus "J4G3.26" )
			)
			( pin "@baseboard_fab2_lib.baseboard_fab2(sch_1):page47_i43:vss(83)"
				( attribute "PN" "24"
					( Origin gPackager )
				)
				( objectStatus "J4G3.24" )
			)
			( pin "@baseboard_fab2_lib.baseboard_fab2(sch_1):page47_i43:vss(84)"
				( attribute "PN" "22"
					( Origin gPackager )
				)
				( objectStatus "J4G3.22" )
			)
			( pin "@baseboard_fab2_lib.baseboard_fab2(sch_1):page47_i43:vss(85)"
				( attribute "PN" "20"
					( Origin gPackager )
				)
				( objectStatus "J4G3.20" )
			)
			( pin "@baseboard_fab2_lib.baseboard_fab2(sch_1):page47_i43:vss(86)"
				( attribute "PN" "17"
					( Origin gPackager )
				)
				( objectStatus "J4G3.17" )
			)
			( pin "@baseboard_fab2_lib.baseboard_fab2(sch_1):page47_i43:vss(87)"
				( attribute "PN" "15"
					( Origin gPackager )
				)
				( objectStatus "J4G3.15" )
			)
			( pin "@baseboard_fab2_lib.baseboard_fab2(sch_1):page47_i43:vss(88)"
				( attribute "PN" "13"
					( Origin gPackager )
				)
				( objectStatus "J4G3.13" )
			)
			( pin "@baseboard_fab2_lib.baseboard_fab2(sch_1):page47_i43:vss(89)"
				( attribute "PN" "11"
					( Origin gPackager )
				)
				( objectStatus "J4G3.11" )
			)
			( pin "@baseboard_fab2_lib.baseboard_fab2(sch_1):page47_i43:vss(90)"
				( attribute "PN" "9"
					( Origin gPackager )
				)
				( objectStatus "J4G3.9" )
			)
			( pin "@baseboard_fab2_lib.baseboard_fab2(sch_1):page47_i43:vss(91)"
				( attribute "PN" "6"
					( Origin gPackager )
				)
				( objectStatus "J4G3.6" )
			)
			( pin "@baseboard_fab2_lib.baseboard_fab2(sch_1):page47_i43:vss(92)"
				( attribute "PN" "4"
					( Origin gPackager )
				)
				( objectStatus "J4G3.4" )
			)
			( pin "@baseboard_fab2_lib.baseboard_fab2(sch_1):page47_i43:vss(93)"
				( attribute "PN" "2"
					( Origin gPackager )
				)
				( objectStatus "J4G3.2" )
			)
			( pin "@baseboard_fab2_lib.baseboard_fab2(sch_1):page47_i61:dqs0n"
				( attribute "PN" "152"
					( Origin gPackager )
				)
				( objectStatus "J4G3.152" )
			)
			( pin "@baseboard_fab2_lib.baseboard_fab2(sch_1):page47_i61:dqs0p"
				( attribute "PN" "153"
					( Origin gPackager )
				)
				( objectStatus "J4G3.153" )
			)
			( pin "@baseboard_fab2_lib.baseboard_fab2(sch_1):page47_i61:dqs1n"
				( attribute "PN" "163"
					( Origin gPackager )
				)
				( objectStatus "J4G3.163" )
			)
			( pin "@baseboard_fab2_lib.baseboard_fab2(sch_1):page47_i61:dqs1p"
				( attribute "PN" "164"
					( Origin gPackager )
				)
				( objectStatus "J4G3.164" )
			)
			( pin "@baseboard_fab2_lib.baseboard_fab2(sch_1):page47_i61:dqs2n"
				( attribute "PN" "174"
					( Origin gPackager )
				)
				( objectStatus "J4G3.174" )
			)
			( pin "@baseboard_fab2_lib.baseboard_fab2(sch_1):page47_i61:dqs2p"
				( attribute "PN" "175"
					( Origin gPackager )
				)
				( objectStatus "J4G3.175" )
			)
			( pin "@baseboard_fab2_lib.baseboard_fab2(sch_1):page47_i61:dqs3n"
				( attribute "PN" "185"
					( Origin gPackager )
				)
				( objectStatus "J4G3.185" )
			)
			( pin "@baseboard_fab2_lib.baseboard_fab2(sch_1):page47_i61:dqs3p"
				( attribute "PN" "186"
					( Origin gPackager )
				)
				( objectStatus "J4G3.186" )
			)
			( pin "@baseboard_fab2_lib.baseboard_fab2(sch_1):page47_i61:dqs4n"
				( attribute "PN" "244"
					( Origin gPackager )
				)
				( objectStatus "J4G3.244" )
			)
			( pin "@baseboard_fab2_lib.baseboard_fab2(sch_1):page47_i61:dqs4p"
				( attribute "PN" "245"
					( Origin gPackager )
				)
				( objectStatus "J4G3.245" )
			)
			( pin "@baseboard_fab2_lib.baseboard_fab2(sch_1):page47_i61:dqs5n"
				( attribute "PN" "255"
					( Origin gPackager )
				)
				( objectStatus "J4G3.255" )
			)
			( pin "@baseboard_fab2_lib.baseboard_fab2(sch_1):page47_i61:dqs5p"
				( attribute "PN" "256"
					( Origin gPackager )
				)
				( objectStatus "J4G3.256" )
			)
			( pin "@baseboard_fab2_lib.baseboard_fab2(sch_1):page47_i61:dqs6n"
				( attribute "PN" "266"
					( Origin gPackager )
				)
				( objectStatus "J4G3.266" )
			)
			( pin "@baseboard_fab2_lib.baseboard_fab2(sch_1):page47_i61:dqs6p"
				( attribute "PN" "267"
					( Origin gPackager )
				)
				( objectStatus "J4G3.267" )
			)
			( pin "@baseboard_fab2_lib.baseboard_fab2(sch_1):page47_i61:dqs7n"
				( attribute "PN" "277"
					( Origin gPackager )
				)
				( objectStatus "J4G3.277" )
			)
			( pin "@baseboard_fab2_lib.baseboard_fab2(sch_1):page47_i61:dqs7p"
				( attribute "PN" "278"
					( Origin gPackager )
				)
				( objectStatus "J4G3.278" )
			)
			( pin "@baseboard_fab2_lib.baseboard_fab2(sch_1):page47_i61:dqs8n"
				( attribute "PN" "196"
					( Origin gPackager )
				)
				( objectStatus "J4G3.196" )
			)
			( pin "@baseboard_fab2_lib.baseboard_fab2(sch_1):page47_i61:dqs8p"
				( attribute "PN" "197"
					( Origin gPackager )
				)
				( objectStatus "J4G3.197" )
			)
			( pin "@baseboard_fab2_lib.baseboard_fab2(sch_1):page47_i61:dqs9n"
				( attribute "PN" "8"
					( Origin gPackager )
				)
				( objectStatus "J4G3.8" )
			)
			( pin "@baseboard_fab2_lib.baseboard_fab2(sch_1):page47_i61:dqs9p"
				( attribute "PN" "7"
					( Origin gPackager )
				)
				( objectStatus "J4G3.7" )
			)
			( pin "@baseboard_fab2_lib.baseboard_fab2(sch_1):page47_i61:dqs10n"
				( attribute "PN" "19"
					( Origin gPackager )
				)
				( objectStatus "J4G3.19" )
			)
			( pin "@baseboard_fab2_lib.baseboard_fab2(sch_1):page47_i61:dqs10p"
				( attribute "PN" "18"
					( Origin gPackager )
				)
				( objectStatus "J4G3.18" )
			)
			( pin "@baseboard_fab2_lib.baseboard_fab2(sch_1):page47_i61:dqs11n"
				( attribute "PN" "30"
					( Origin gPackager )
				)
				( objectStatus "J4G3.30" )
			)
			( pin "@baseboard_fab2_lib.baseboard_fab2(sch_1):page47_i61:dqs11p"
				( attribute "PN" "29"
					( Origin gPackager )
				)
				( objectStatus "J4G3.29" )
			)
			( pin "@baseboard_fab2_lib.baseboard_fab2(sch_1):page47_i61:dqs12n"
				( attribute "PN" "41"
					( Origin gPackager )
				)
				( objectStatus "J4G3.41" )
			)
			( pin "@baseboard_fab2_lib.baseboard_fab2(sch_1):page47_i61:dqs12p"
				( attribute "PN" "40"
					( Origin gPackager )
				)
				( objectStatus "J4G3.40" )
			)
			( pin "@baseboard_fab2_lib.baseboard_fab2(sch_1):page47_i61:dqs13n"
				( attribute "PN" "100"
					( Origin gPackager )
				)
				( objectStatus "J4G3.100" )
			)
			( pin "@baseboard_fab2_lib.baseboard_fab2(sch_1):page47_i61:dqs13p"
				( attribute "PN" "99"
					( Origin gPackager )
				)
				( objectStatus "J4G3.99" )
			)
			( pin "@baseboard_fab2_lib.baseboard_fab2(sch_1):page47_i61:dqs14n"
				( attribute "PN" "111"
					( Origin gPackager )
				)
				( objectStatus "J4G3.111" )
			)
			( pin "@baseboard_fab2_lib.baseboard_fab2(sch_1):page47_i61:dqs14p"
				( attribute "PN" "110"
					( Origin gPackager )
				)
				( objectStatus "J4G3.110" )
			)
			( pin "@baseboard_fab2_lib.baseboard_fab2(sch_1):page47_i61:dqs15n"
				( attribute "PN" "122"
					( Origin gPackager )
				)
				( objectStatus "J4G3.122" )
			)
			( pin "@baseboard_fab2_lib.baseboard_fab2(sch_1):page47_i61:dqs15p"
				( attribute "PN" "121"
					( Origin gPackager )
				)
				( objectStatus "J4G3.121" )
			)
			( pin "@baseboard_fab2_lib.baseboard_fab2(sch_1):page47_i61:dqs16n"
				( attribute "PN" "133"
					( Origin gPackager )
				)
				( objectStatus "J4G3.133" )
			)
			( pin "@baseboard_fab2_lib.baseboard_fab2(sch_1):page47_i61:dqs16p"
				( attribute "PN" "132"
					( Origin gPackager )
				)
				( objectStatus "J4G3.132" )
			)
			( pin "@baseboard_fab2_lib.baseboard_fab2(sch_1):page47_i61:dqs17n"
				( attribute "PN" "52"
					( Origin gPackager )
				)
				( objectStatus "J4G3.52" )
			)
			( pin "@baseboard_fab2_lib.baseboard_fab2(sch_1):page47_i61:dqs17p"
				( attribute "PN" "51"
					( Origin gPackager )
				)
				( objectStatus "J4G3.51" )
			)
			( pin "@baseboard_fab2_lib.baseboard_fab2(sch_1):page47_i111:a0"
				( attribute "PN" "79"
					( Origin gPackager )
				)
				( objectStatus "J4G3.79" )
			)
			( pin "@baseboard_fab2_lib.baseboard_fab2(sch_1):page47_i111:a1"
				( attribute "PN" "72"
					( Origin gPackager )
				)
				( objectStatus "J4G3.72" )
			)
			( pin "@baseboard_fab2_lib.baseboard_fab2(sch_1):page47_i111:a2"
				( attribute "PN" "216"
					( Origin gPackager )
				)
				( objectStatus "J4G3.216" )
			)
			( pin "@baseboard_fab2_lib.baseboard_fab2(sch_1):page47_i111:a3"
				( attribute "PN" "71"
					( Origin gPackager )
				)
				( objectStatus "J4G3.71" )
			)
			( pin "@baseboard_fab2_lib.baseboard_fab2(sch_1):page47_i111:a4"
				( attribute "PN" "214"
					( Origin gPackager )
				)
				( objectStatus "J4G3.214" )
			)
			( pin "@baseboard_fab2_lib.baseboard_fab2(sch_1):page47_i111:a5"
				( attribute "PN" "213"
					( Origin gPackager )
				)
				( objectStatus "J4G3.213" )
			)
			( pin "@baseboard_fab2_lib.baseboard_fab2(sch_1):page47_i111:a6"
				( attribute "PN" "69"
					( Origin gPackager )
				)
				( objectStatus "J4G3.69" )
			)
			( pin "@baseboard_fab2_lib.baseboard_fab2(sch_1):page47_i111:a7"
				( attribute "PN" "211"
					( Origin gPackager )
				)
				( objectStatus "J4G3.211" )
			)
			( pin "@baseboard_fab2_lib.baseboard_fab2(sch_1):page47_i111:a8"
				( attribute "PN" "68"
					( Origin gPackager )
				)
				( objectStatus "J4G3.68" )
			)
			( pin "@baseboard_fab2_lib.baseboard_fab2(sch_1):page47_i111:a9"
				( attribute "PN" "66"
					( Origin gPackager )
				)
				( objectStatus "J4G3.66" )
			)
			( pin "@baseboard_fab2_lib.baseboard_fab2(sch_1):page47_i111:a10"
				( attribute "PN" "225"
					( Origin gPackager )
				)
				( objectStatus "J4G3.225" )
			)
			( pin "@baseboard_fab2_lib.baseboard_fab2(sch_1):page47_i111:a11"
				( attribute "PN" "210"
					( Origin gPackager )
				)
				( objectStatus "J4G3.210" )
			)
			( pin "@baseboard_fab2_lib.baseboard_fab2(sch_1):page47_i111:a12"
				( attribute "PN" "65"
					( Origin gPackager )
				)
				( objectStatus "J4G3.65" )
			)
			( pin "@baseboard_fab2_lib.baseboard_fab2(sch_1):page47_i111:a13"
				( attribute "PN" "232"
					( Origin gPackager )
				)
				( objectStatus "J4G3.232" )
			)
			( pin "@baseboard_fab2_lib.baseboard_fab2(sch_1):page47_i111:a14_we_n"
				( attribute "PN" "228"
					( Origin gPackager )
				)
				( objectStatus "J4G3.228" )
			)
			( pin "@baseboard_fab2_lib.baseboard_fab2(sch_1):page47_i111:a15_cas_n"
				( attribute "PN" "86"
					( Origin gPackager )
				)
				( objectStatus "J4G3.86" )
			)
			( pin "@baseboard_fab2_lib.baseboard_fab2(sch_1):page47_i111:a16_ras_n"
				( attribute "PN" "82"
					( Origin gPackager )
				)
				( objectStatus "J4G3.82" )
			)
			( pin "@baseboard_fab2_lib.baseboard_fab2(sch_1):page47_i111:a17"
				( attribute "PN" "234"
					( Origin gPackager )
				)
				( objectStatus "J4G3.234" )
			)
			( pin "@baseboard_fab2_lib.baseboard_fab2(sch_1):page47_i111:act_n"
				( attribute "PN" "62"
					( Origin gPackager )
				)
				( objectStatus "J4G3.62" )
			)
			( pin "@baseboard_fab2_lib.baseboard_fab2(sch_1):page47_i111:alert_n"
				( attribute "PN" "208"
					( Origin gPackager )
				)
				( objectStatus "J4G3.208" )
			)
			( pin "@baseboard_fab2_lib.baseboard_fab2(sch_1):page47_i111:ba(0)"
				( attribute "PN" "81"
					( Origin gPackager )
				)
				( objectStatus "J4G3.81" )
			)
			( pin "@baseboard_fab2_lib.baseboard_fab2(sch_1):page47_i111:ba(1)"
				( attribute "PN" "224"
					( Origin gPackager )
				)
				( objectStatus "J4G3.224" )
			)
			( pin "@baseboard_fab2_lib.baseboard_fab2(sch_1):page47_i111:bg(0)"
				( attribute "PN" "63"
					( Origin gPackager )
				)
				( objectStatus "J4G3.63" )
			)
			( pin "@baseboard_fab2_lib.baseboard_fab2(sch_1):page47_i111:bg(1)"
				( attribute "PN" "207"
					( Origin gPackager )
				)
				( objectStatus "J4G3.207" )
			)
			( pin "@baseboard_fab2_lib.baseboard_fab2(sch_1):page47_i111:c(2)"
				( attribute "PN" "235"
					( Origin gPackager )
				)
				( objectStatus "J4G3.235" )
			)
			( pin "@baseboard_fab2_lib.baseboard_fab2(sch_1):page47_i111:cb(0)"
				( attribute "PN" "49"
					( Origin gPackager )
				)
				( objectStatus "J4G3.49" )
			)
			( pin "@baseboard_fab2_lib.baseboard_fab2(sch_1):page47_i111:cb(1)"
				( attribute "PN" "194"
					( Origin gPackager )
				)
				( objectStatus "J4G3.194" )
			)
			( pin "@baseboard_fab2_lib.baseboard_fab2(sch_1):page47_i111:cb(2)"
				( attribute "PN" "56"
					( Origin gPackager )
				)
				( objectStatus "J4G3.56" )
			)
			( pin "@baseboard_fab2_lib.baseboard_fab2(sch_1):page47_i111:cb(3)"
				( attribute "PN" "201"
					( Origin gPackager )
				)
				( objectStatus "J4G3.201" )
			)
			( pin "@baseboard_fab2_lib.baseboard_fab2(sch_1):page47_i111:cb(4)"
				( attribute "PN" "47"
					( Origin gPackager )
				)
				( objectStatus "J4G3.47" )
			)
			( pin "@baseboard_fab2_lib.baseboard_fab2(sch_1):page47_i111:cb(5)"
				( attribute "PN" "192"
					( Origin gPackager )
				)
				( objectStatus "J4G3.192" )
			)
			( pin "@baseboard_fab2_lib.baseboard_fab2(sch_1):page47_i111:cb(6)"
				( attribute "PN" "54"
					( Origin gPackager )
				)
				( objectStatus "J4G3.54" )
			)
			( pin "@baseboard_fab2_lib.baseboard_fab2(sch_1):page47_i111:cb(7)"
				( attribute "PN" "199"
					( Origin gPackager )
				)
				( objectStatus "J4G3.199" )
			)
			( pin "@baseboard_fab2_lib.baseboard_fab2(sch_1):page47_i111:ck0n"
				( attribute "PN" "75"
					( Origin gPackager )
				)
				( objectStatus "J4G3.75" )
			)
			( pin "@baseboard_fab2_lib.baseboard_fab2(sch_1):page47_i111:ck0p"
				( attribute "PN" "74"
					( Origin gPackager )
				)
				( objectStatus "J4G3.74" )
			)
			( pin "@baseboard_fab2_lib.baseboard_fab2(sch_1):page47_i111:ck1n"
				( attribute "PN" "219"
					( Origin gPackager )
				)
				( objectStatus "J4G3.219" )
			)
			( pin "@baseboard_fab2_lib.baseboard_fab2(sch_1):page47_i111:ck1p"
				( attribute "PN" "218"
					( Origin gPackager )
				)
				( objectStatus "J4G3.218" )
			)
			( pin "@baseboard_fab2_lib.baseboard_fab2(sch_1):page47_i111:cke(0)"
				( attribute "PN" "60"
					( Origin gPackager )
				)
				( objectStatus "J4G3.60" )
			)
			( pin "@baseboard_fab2_lib.baseboard_fab2(sch_1):page47_i111:cke(1)"
				( attribute "PN" "203"
					( Origin gPackager )
				)
				( objectStatus "J4G3.203" )
			)
			( pin "@baseboard_fab2_lib.baseboard_fab2(sch_1):page47_i111:dq(0)"
				( attribute "PN" "5"
					( Origin gPackager )
				)
				( objectStatus "J4G3.5" )
			)
			( pin "@baseboard_fab2_lib.baseboard_fab2(sch_1):page47_i111:dq(1)"
				( attribute "PN" "150"
					( Origin gPackager )
				)
				( objectStatus "J4G3.150" )
			)
			( pin "@baseboard_fab2_lib.baseboard_fab2(sch_1):page47_i111:dq(2)"
				( attribute "PN" "12"
					( Origin gPackager )
				)
				( objectStatus "J4G3.12" )
			)
			( pin "@baseboard_fab2_lib.baseboard_fab2(sch_1):page47_i111:dq(3)"
				( attribute "PN" "157"
					( Origin gPackager )
				)
				( objectStatus "J4G3.157" )
			)
			( pin "@baseboard_fab2_lib.baseboard_fab2(sch_1):page47_i111:dq(4)"
				( attribute "PN" "3"
					( Origin gPackager )
				)
				( objectStatus "J4G3.3" )
			)
			( pin "@baseboard_fab2_lib.baseboard_fab2(sch_1):page47_i111:dq(5)"
				( attribute "PN" "148"
					( Origin gPackager )
				)
				( objectStatus "J4G3.148" )
			)
			( pin "@baseboard_fab2_lib.baseboard_fab2(sch_1):page47_i111:dq(6)"
				( attribute "PN" "10"
					( Origin gPackager )
				)
				( objectStatus "J4G3.10" )
			)
			( pin "@baseboard_fab2_lib.baseboard_fab2(sch_1):page47_i111:dq(7)"
				( attribute "PN" "155"
					( Origin gPackager )
				)
				( objectStatus "J4G3.155" )
			)
			( pin "@baseboard_fab2_lib.baseboard_fab2(sch_1):page47_i111:dq(8)"
				( attribute "PN" "16"
					( Origin gPackager )
				)
				( objectStatus "J4G3.16" )
			)
			( pin "@baseboard_fab2_lib.baseboard_fab2(sch_1):page47_i111:dq(9)"
				( attribute "PN" "161"
					( Origin gPackager )
				)
				( objectStatus "J4G3.161" )
			)
			( pin "@baseboard_fab2_lib.baseboard_fab2(sch_1):page47_i111:dq(10)"
				( attribute "PN" "23"
					( Origin gPackager )
				)
				( objectStatus "J4G3.23" )
			)
			( pin "@baseboard_fab2_lib.baseboard_fab2(sch_1):page47_i111:dq(11)"
				( attribute "PN" "168"
					( Origin gPackager )
				)
				( objectStatus "J4G3.168" )
			)
			( pin "@baseboard_fab2_lib.baseboard_fab2(sch_1):page47_i111:dq(12)"
				( attribute "PN" "14"
					( Origin gPackager )
				)
				( objectStatus "J4G3.14" )
			)
			( pin "@baseboard_fab2_lib.baseboard_fab2(sch_1):page47_i111:dq(13)"
				( attribute "PN" "159"
					( Origin gPackager )
				)
				( objectStatus "J4G3.159" )
			)
			( pin "@baseboard_fab2_lib.baseboard_fab2(sch_1):page47_i111:dq(14)"
				( attribute "PN" "21"
					( Origin gPackager )
				)
				( objectStatus "J4G3.21" )
			)
			( pin "@baseboard_fab2_lib.baseboard_fab2(sch_1):page47_i111:dq(15)"
				( attribute "PN" "166"
					( Origin gPackager )
				)
				( objectStatus "J4G3.166" )
			)
			( pin "@baseboard_fab2_lib.baseboard_fab2(sch_1):page47_i111:dq(16)"
				( attribute "PN" "27"
					( Origin gPackager )
				)
				( objectStatus "J4G3.27" )
			)
			( pin "@baseboard_fab2_lib.baseboard_fab2(sch_1):page47_i111:dq(17)"
				( attribute "PN" "172"
					( Origin gPackager )
				)
				( objectStatus "J4G3.172" )
			)
			( pin "@baseboard_fab2_lib.baseboard_fab2(sch_1):page47_i111:dq(18)"
				( attribute "PN" "34"
					( Origin gPackager )
				)
				( objectStatus "J4G3.34" )
			)
			( pin "@baseboard_fab2_lib.baseboard_fab2(sch_1):page47_i111:dq(19)"
				( attribute "PN" "179"
					( Origin gPackager )
				)
				( objectStatus "J4G3.179" )
			)
			( pin "@baseboard_fab2_lib.baseboard_fab2(sch_1):page47_i111:dq(20)"
				( attribute "PN" "25"
					( Origin gPackager )
				)
				( objectStatus "J4G3.25" )
			)
			( pin "@baseboard_fab2_lib.baseboard_fab2(sch_1):page47_i111:dq(21)"
				( attribute "PN" "170"
					( Origin gPackager )
				)
				( objectStatus "J4G3.170" )
			)
			( pin "@baseboard_fab2_lib.baseboard_fab2(sch_1):page47_i111:dq(22)"
				( attribute "PN" "32"
					( Origin gPackager )
				)
				( objectStatus "J4G3.32" )
			)
			( pin "@baseboard_fab2_lib.baseboard_fab2(sch_1):page47_i111:dq(23)"
				( attribute "PN" "177"
					( Origin gPackager )
				)
				( objectStatus "J4G3.177" )
			)
			( pin "@baseboard_fab2_lib.baseboard_fab2(sch_1):page47_i111:dq(24)"
				( attribute "PN" "38"
					( Origin gPackager )
				)
				( objectStatus "J4G3.38" )
			)
			( pin "@baseboard_fab2_lib.baseboard_fab2(sch_1):page47_i111:dq(25)"
				( attribute "PN" "183"
					( Origin gPackager )
				)
				( objectStatus "J4G3.183" )
			)
			( pin "@baseboard_fab2_lib.baseboard_fab2(sch_1):page47_i111:dq(26)"
				( attribute "PN" "45"
					( Origin gPackager )
				)
				( objectStatus "J4G3.45" )
			)
			( pin "@baseboard_fab2_lib.baseboard_fab2(sch_1):page47_i111:dq(27)"
				( attribute "PN" "190"
					( Origin gPackager )
				)
				( objectStatus "J4G3.190" )
			)
			( pin "@baseboard_fab2_lib.baseboard_fab2(sch_1):page47_i111:dq(28)"
				( attribute "PN" "36"
					( Origin gPackager )
				)
				( objectStatus "J4G3.36" )
			)
			( pin "@baseboard_fab2_lib.baseboard_fab2(sch_1):page47_i111:dq(29)"
				( attribute "PN" "181"
					( Origin gPackager )
				)
				( objectStatus "J4G3.181" )
			)
			( pin "@baseboard_fab2_lib.baseboard_fab2(sch_1):page47_i111:dq(30)"
				( attribute "PN" "43"
					( Origin gPackager )
				)
				( objectStatus "J4G3.43" )
			)
			( pin "@baseboard_fab2_lib.baseboard_fab2(sch_1):page47_i111:dq(31)"
				( attribute "PN" "188"
					( Origin gPackager )
				)
				( objectStatus "J4G3.188" )
			)
			( pin "@baseboard_fab2_lib.baseboard_fab2(sch_1):page47_i111:dq(32)"
				( attribute "PN" "97"
					( Origin gPackager )
				)
				( objectStatus "J4G3.97" )
			)
			( pin "@baseboard_fab2_lib.baseboard_fab2(sch_1):page47_i111:dq(33)"
				( attribute "PN" "242"
					( Origin gPackager )
				)
				( objectStatus "J4G3.242" )
			)
			( pin "@baseboard_fab2_lib.baseboard_fab2(sch_1):page47_i111:dq(34)"
				( attribute "PN" "104"
					( Origin gPackager )
				)
				( objectStatus "J4G3.104" )
			)
			( pin "@baseboard_fab2_lib.baseboard_fab2(sch_1):page47_i111:dq(35)"
				( attribute "PN" "249"
					( Origin gPackager )
				)
				( objectStatus "J4G3.249" )
			)
			( pin "@baseboard_fab2_lib.baseboard_fab2(sch_1):page47_i111:dq(36)"
				( attribute "PN" "95"
					( Origin gPackager )
				)
				( objectStatus "J4G3.95" )
			)
			( pin "@baseboard_fab2_lib.baseboard_fab2(sch_1):page47_i111:dq(37)"
				( attribute "PN" "240"
					( Origin gPackager )
				)
				( objectStatus "J4G3.240" )
			)
			( pin "@baseboard_fab2_lib.baseboard_fab2(sch_1):page47_i111:dq(38)"
				( attribute "PN" "102"
					( Origin gPackager )
				)
				( objectStatus "J4G3.102" )
			)
			( pin "@baseboard_fab2_lib.baseboard_fab2(sch_1):page47_i111:dq(39)"
				( attribute "PN" "247"
					( Origin gPackager )
				)
				( objectStatus "J4G3.247" )
			)
			( pin "@baseboard_fab2_lib.baseboard_fab2(sch_1):page47_i111:dq(40)"
				( attribute "PN" "108"
					( Origin gPackager )
				)
				( objectStatus "J4G3.108" )
			)
			( pin "@baseboard_fab2_lib.baseboard_fab2(sch_1):page47_i111:dq(41)"
				( attribute "PN" "253"
					( Origin gPackager )
				)
				( objectStatus "J4G3.253" )
			)
			( pin "@baseboard_fab2_lib.baseboard_fab2(sch_1):page47_i111:dq(42)"
				( attribute "PN" "115"
					( Origin gPackager )
				)
				( objectStatus "J4G3.115" )
			)
			( pin "@baseboard_fab2_lib.baseboard_fab2(sch_1):page47_i111:dq(43)"
				( attribute "PN" "260"
					( Origin gPackager )
				)
				( objectStatus "J4G3.260" )
			)
			( pin "@baseboard_fab2_lib.baseboard_fab2(sch_1):page47_i111:dq(44)"
				( attribute "PN" "106"
					( Origin gPackager )
				)
				( objectStatus "J4G3.106" )
			)
			( pin "@baseboard_fab2_lib.baseboard_fab2(sch_1):page47_i111:dq(45)"
				( attribute "PN" "251"
					( Origin gPackager )
				)
				( objectStatus "J4G3.251" )
			)
			( pin "@baseboard_fab2_lib.baseboard_fab2(sch_1):page47_i111:dq(46)"
				( attribute "PN" "113"
					( Origin gPackager )
				)
				( objectStatus "J4G3.113" )
			)
			( pin "@baseboard_fab2_lib.baseboard_fab2(sch_1):page47_i111:dq(47)"
				( attribute "PN" "258"
					( Origin gPackager )
				)
				( objectStatus "J4G3.258" )
			)
			( pin "@baseboard_fab2_lib.baseboard_fab2(sch_1):page47_i111:dq(48)"
				( attribute "PN" "119"
					( Origin gPackager )
				)
				( objectStatus "J4G3.119" )
			)
			( pin "@baseboard_fab2_lib.baseboard_fab2(sch_1):page47_i111:dq(49)"
				( attribute "PN" "264"
					( Origin gPackager )
				)
				( objectStatus "J4G3.264" )
			)
			( pin "@baseboard_fab2_lib.baseboard_fab2(sch_1):page47_i111:dq(50)"
				( attribute "PN" "126"
					( Origin gPackager )
				)
				( objectStatus "J4G3.126" )
			)
			( pin "@baseboard_fab2_lib.baseboard_fab2(sch_1):page47_i111:dq(51)"
				( attribute "PN" "271"
					( Origin gPackager )
				)
				( objectStatus "J4G3.271" )
			)
			( pin "@baseboard_fab2_lib.baseboard_fab2(sch_1):page47_i111:dq(52)"
				( attribute "PN" "117"
					( Origin gPackager )
				)
				( objectStatus "J4G3.117" )
			)
			( pin "@baseboard_fab2_lib.baseboard_fab2(sch_1):page47_i111:dq(53)"
				( attribute "PN" "262"
					( Origin gPackager )
				)
				( objectStatus "J4G3.262" )
			)
			( pin "@baseboard_fab2_lib.baseboard_fab2(sch_1):page47_i111:dq(54)"
				( attribute "PN" "124"
					( Origin gPackager )
				)
				( objectStatus "J4G3.124" )
			)
			( pin "@baseboard_fab2_lib.baseboard_fab2(sch_1):page47_i111:dq(55)"
				( attribute "PN" "269"
					( Origin gPackager )
				)
				( objectStatus "J4G3.269" )
			)
			( pin "@baseboard_fab2_lib.baseboard_fab2(sch_1):page47_i111:dq(56)"
				( attribute "PN" "130"
					( Origin gPackager )
				)
				( objectStatus "J4G3.130" )
			)
			( pin "@baseboard_fab2_lib.baseboard_fab2(sch_1):page47_i111:dq(57)"
				( attribute "PN" "275"
					( Origin gPackager )
				)
				( objectStatus "J4G3.275" )
			)
			( pin "@baseboard_fab2_lib.baseboard_fab2(sch_1):page47_i111:dq(58)"
				( attribute "PN" "137"
					( Origin gPackager )
				)
				( objectStatus "J4G3.137" )
			)
			( pin "@baseboard_fab2_lib.baseboard_fab2(sch_1):page47_i111:dq(59)"
				( attribute "PN" "282"
					( Origin gPackager )
				)
				( objectStatus "J4G3.282" )
			)
			( pin "@baseboard_fab2_lib.baseboard_fab2(sch_1):page47_i111:dq(60)"
				( attribute "PN" "128"
					( Origin gPackager )
				)
				( objectStatus "J4G3.128" )
			)
			( pin "@baseboard_fab2_lib.baseboard_fab2(sch_1):page47_i111:dq(61)"
				( attribute "PN" "273"
					( Origin gPackager )
				)
				( objectStatus "J4G3.273" )
			)
			( pin "@baseboard_fab2_lib.baseboard_fab2(sch_1):page47_i111:dq(62)"
				( attribute "PN" "135"
					( Origin gPackager )
				)
				( objectStatus "J4G3.135" )
			)
			( pin "@baseboard_fab2_lib.baseboard_fab2(sch_1):page47_i111:dq(63)"
				( attribute "PN" "280"
					( Origin gPackager )
				)
				( objectStatus "J4G3.280" )
			)
			( pin "@baseboard_fab2_lib.baseboard_fab2(sch_1):page47_i111:event_n"
				( attribute "PN" "78"
					( Origin gPackager )
				)
				( objectStatus "J4G3.78" )
			)
			( pin "@baseboard_fab2_lib.baseboard_fab2(sch_1):page47_i111:odt(0)"
				( attribute "PN" "87"
					( Origin gPackager )
				)
				( objectStatus "J4G3.87" )
			)
			( pin "@baseboard_fab2_lib.baseboard_fab2(sch_1):page47_i111:odt(1)"
				( attribute "PN" "91"
					( Origin gPackager )
				)
				( objectStatus "J4G3.91" )
			)
			( pin "@baseboard_fab2_lib.baseboard_fab2(sch_1):page47_i111:par"
				( attribute "PN" "222"
					( Origin gPackager )
				)
				( objectStatus "J4G3.222" )
			)
			( pin "@baseboard_fab2_lib.baseboard_fab2(sch_1):page47_i111:reset_n"
				( attribute "PN" "58"
					( Origin gPackager )
				)
				( objectStatus "J4G3.58" )
			)
			( pin "@baseboard_fab2_lib.baseboard_fab2(sch_1):page47_i111:rfu(0)"
				( attribute "PN" "205"
					( Origin gPackager )
				)
				( objectStatus "J4G3.205" )
			)
			( pin "@baseboard_fab2_lib.baseboard_fab2(sch_1):page47_i111:rfu(1)"
				( attribute "PN" "227"
					( Origin gPackager )
				)
				( objectStatus "J4G3.227" )
			)
			( pin "@baseboard_fab2_lib.baseboard_fab2(sch_1):page47_i111:rfu(2)"
				( attribute "PN" "144"
					( Origin gPackager )
				)
				( objectStatus "J4G3.144" )
			)
			( pin "@baseboard_fab2_lib.baseboard_fab2(sch_1):page47_i111:s0_n"
				( attribute "PN" "84"
					( Origin gPackager )
				)
				( objectStatus "J4G3.84" )
			)
			( pin "@baseboard_fab2_lib.baseboard_fab2(sch_1):page47_i111:s1_n"
				( attribute "PN" "89"
					( Origin gPackager )
				)
				( objectStatus "J4G3.89" )
			)
			( pin "@baseboard_fab2_lib.baseboard_fab2(sch_1):page47_i111:s2_n_c(0)"
				( attribute "PN" "93"
					( Origin gPackager )
				)
				( objectStatus "J4G3.93" )
			)
			( pin "@baseboard_fab2_lib.baseboard_fab2(sch_1):page47_i111:s3_n_c(1)"
				( attribute "PN" "237"
					( Origin gPackager )
				)
				( objectStatus "J4G3.237" )
			)
			( pin "@baseboard_fab2_lib.baseboard_fab2(sch_1):page47_i111:sa(0)"
				( attribute "PN" "139"
					( Origin gPackager )
				)
				( objectStatus "J4G3.139" )
			)
			( pin "@baseboard_fab2_lib.baseboard_fab2(sch_1):page47_i111:sa(1)"
				( attribute "PN" "140"
					( Origin gPackager )
				)
				( objectStatus "J4G3.140" )
			)
			( pin "@baseboard_fab2_lib.baseboard_fab2(sch_1):page47_i111:sa(2)"
				( attribute "PN" "238"
					( Origin gPackager )
				)
				( objectStatus "J4G3.238" )
			)
			( pin "@baseboard_fab2_lib.baseboard_fab2(sch_1):page47_i111:save_n_nc"
				( attribute "PN" "230"
					( Origin gPackager )
				)
				( objectStatus "J4G3.230" )
			)
			( pin "@baseboard_fab2_lib.baseboard_fab2(sch_1):page47_i111:scl"
				( attribute "PN" "141"
					( Origin gPackager )
				)
				( objectStatus "J4G3.141" )
			)
			( pin "@baseboard_fab2_lib.baseboard_fab2(sch_1):page47_i111:sda"
				( attribute "PN" "285"
					( Origin gPackager )
				)
				( objectStatus "J4G3.285" )
			)
			( pin "@baseboard_fab2_lib.baseboard_fab2(sch_1):page47_i111:vddspd"
				( attribute "PN" "284"
					( Origin gPackager )
				)
				( objectStatus "J4G3.284" )
			)
			( pin "@baseboard_fab2_lib.baseboard_fab2(sch_1):page47_i111:vrefca"
				( attribute "PN" "146"
					( Origin gPackager )
				)
				( objectStatus "J4G3.146" )
			)
			( pin "@baseboard_fab2_lib.baseboard_fab2(sch_1):page47_i179:\12v\(0)"
				( attribute "PN" "145"
					( Origin gPackager )
				)
				( objectStatus "J4G3.145" )
			)
			( pin "@baseboard_fab2_lib.baseboard_fab2(sch_1):page47_i179:\12v\(1)"
				( attribute "PN" "1"
					( Origin gPackager )
				)
				( objectStatus "J4G3.1" )
			)
			( pin "@baseboard_fab2_lib.baseboard_fab2(sch_1):page47_i179:vdd(0)"
				( attribute "PN" "236"
					( Origin gPackager )
				)
				( objectStatus "J4G3.236" )
			)
			( pin "@baseboard_fab2_lib.baseboard_fab2(sch_1):page47_i179:vdd(1)"
				( attribute "PN" "233"
					( Origin gPackager )
				)
				( objectStatus "J4G3.233" )
			)
			( pin "@baseboard_fab2_lib.baseboard_fab2(sch_1):page47_i179:vdd(2)"
				( attribute "PN" "231"
					( Origin gPackager )
				)
				( objectStatus "J4G3.231" )
			)
			( pin "@baseboard_fab2_lib.baseboard_fab2(sch_1):page47_i179:vdd(3)"
				( attribute "PN" "229"
					( Origin gPackager )
				)
				( objectStatus "J4G3.229" )
			)
			( pin "@baseboard_fab2_lib.baseboard_fab2(sch_1):page47_i179:vdd(4)"
				( attribute "PN" "226"
					( Origin gPackager )
				)
				( objectStatus "J4G3.226" )
			)
			( pin "@baseboard_fab2_lib.baseboard_fab2(sch_1):page47_i179:vdd(5)"
				( attribute "PN" "223"
					( Origin gPackager )
				)
				( objectStatus "J4G3.223" )
			)
			( pin "@baseboard_fab2_lib.baseboard_fab2(sch_1):page47_i179:vdd(6)"
				( attribute "PN" "220"
					( Origin gPackager )
				)
				( objectStatus "J4G3.220" )
			)
			( pin "@baseboard_fab2_lib.baseboard_fab2(sch_1):page47_i179:vdd(7)"
				( attribute "PN" "217"
					( Origin gPackager )
				)
				( objectStatus "J4G3.217" )
			)
			( pin "@baseboard_fab2_lib.baseboard_fab2(sch_1):page47_i179:vdd(8)"
				( attribute "PN" "215"
					( Origin gPackager )
				)
				( objectStatus "J4G3.215" )
			)
			( pin "@baseboard_fab2_lib.baseboard_fab2(sch_1):page47_i179:vdd(9)"
				( attribute "PN" "212"
					( Origin gPackager )
				)
				( objectStatus "J4G3.212" )
			)
			( pin "@baseboard_fab2_lib.baseboard_fab2(sch_1):page47_i179:vdd(10)"
				( attribute "PN" "209"
					( Origin gPackager )
				)
				( objectStatus "J4G3.209" )
			)
			( pin "@baseboard_fab2_lib.baseboard_fab2(sch_1):page47_i179:vdd(11)"
				( attribute "PN" "206"
					( Origin gPackager )
				)
				( objectStatus "J4G3.206" )
			)
			( pin "@baseboard_fab2_lib.baseboard_fab2(sch_1):page47_i179:vdd(12)"
				( attribute "PN" "204"
					( Origin gPackager )
				)
				( objectStatus "J4G3.204" )
			)
			( pin "@baseboard_fab2_lib.baseboard_fab2(sch_1):page47_i179:vdd(13)"
				( attribute "PN" "92"
					( Origin gPackager )
				)
				( objectStatus "J4G3.92" )
			)
			( pin "@baseboard_fab2_lib.baseboard_fab2(sch_1):page47_i179:vdd(14)"
				( attribute "PN" "90"
					( Origin gPackager )
				)
				( objectStatus "J4G3.90" )
			)
			( pin "@baseboard_fab2_lib.baseboard_fab2(sch_1):page47_i179:vdd(15)"
				( attribute "PN" "88"
					( Origin gPackager )
				)
				( objectStatus "J4G3.88" )
			)
			( pin "@baseboard_fab2_lib.baseboard_fab2(sch_1):page47_i179:vdd(16)"
				( attribute "PN" "85"
					( Origin gPackager )
				)
				( objectStatus "J4G3.85" )
			)
			( pin "@baseboard_fab2_lib.baseboard_fab2(sch_1):page47_i179:vdd(17)"
				( attribute "PN" "83"
					( Origin gPackager )
				)
				( objectStatus "J4G3.83" )
			)
			( pin "@baseboard_fab2_lib.baseboard_fab2(sch_1):page47_i179:vdd(18)"
				( attribute "PN" "80"
					( Origin gPackager )
				)
				( objectStatus "J4G3.80" )
			)
			( pin "@baseboard_fab2_lib.baseboard_fab2(sch_1):page47_i179:vdd(19)"
				( attribute "PN" "76"
					( Origin gPackager )
				)
				( objectStatus "J4G3.76" )
			)
			( pin "@baseboard_fab2_lib.baseboard_fab2(sch_1):page47_i179:vdd(20)"
				( attribute "PN" "73"
					( Origin gPackager )
				)
				( objectStatus "J4G3.73" )
			)
			( pin "@baseboard_fab2_lib.baseboard_fab2(sch_1):page47_i179:vdd(21)"
				( attribute "PN" "70"
					( Origin gPackager )
				)
				( objectStatus "J4G3.70" )
			)
			( pin "@baseboard_fab2_lib.baseboard_fab2(sch_1):page47_i179:vdd(22)"
				( attribute "PN" "67"
					( Origin gPackager )
				)
				( objectStatus "J4G3.67" )
			)
			( pin "@baseboard_fab2_lib.baseboard_fab2(sch_1):page47_i179:vdd(23)"
				( attribute "PN" "64"
					( Origin gPackager )
				)
				( objectStatus "J4G3.64" )
			)
			( pin "@baseboard_fab2_lib.baseboard_fab2(sch_1):page47_i179:vdd(24)"
				( attribute "PN" "61"
					( Origin gPackager )
				)
				( objectStatus "J4G3.61" )
			)
			( pin "@baseboard_fab2_lib.baseboard_fab2(sch_1):page47_i179:vdd(25)"
				( attribute "PN" "59"
					( Origin gPackager )
				)
				( objectStatus "J4G3.59" )
			)
			( pin "@baseboard_fab2_lib.baseboard_fab2(sch_1):page47_i179:vpp(0)"
				( attribute "PN" "287"
					( Origin gPackager )
				)
				( objectStatus "J4G3.287" )
			)
			( pin "@baseboard_fab2_lib.baseboard_fab2(sch_1):page47_i179:vpp(1)"
				( attribute "PN" "286"
					( Origin gPackager )
				)
				( objectStatus "J4G3.286" )
			)
			( pin "@baseboard_fab2_lib.baseboard_fab2(sch_1):page47_i179:vpp(2)"
				( attribute "PN" "288"
					( Origin gPackager )
				)
				( objectStatus "J4G3.288" )
			)
			( pin "@baseboard_fab2_lib.baseboard_fab2(sch_1):page47_i179:vpp(3)"
				( attribute "PN" "143"
					( Origin gPackager )
				)
				( objectStatus "J4G3.143" )
			)
			( pin "@baseboard_fab2_lib.baseboard_fab2(sch_1):page47_i179:vpp(4)"
				( attribute "PN" "142"
					( Origin gPackager )
				)
				( objectStatus "J4G3.142" )
			)
			( pin "@baseboard_fab2_lib.baseboard_fab2(sch_1):page47_i179:vtt(0)"
				( attribute "PN" "221"
					( Origin gPackager )
				)
				( objectStatus "J4G3.221" )
			)
			( pin "@baseboard_fab2_lib.baseboard_fab2(sch_1):page47_i179:vtt(1)"
				( attribute "PN" "77"
					( Origin gPackager )
				)
				( objectStatus "J4G3.77" )
			)
			( pin "@baseboard_fab2_lib.baseboard_fab2(sch_1):page47_i188:a"
				( attribute "PN" "1"
					( Origin gPackager )
				)
				( objectStatus "C4G19.1" )
			)
			( pin "@baseboard_fab2_lib.baseboard_fab2(sch_1):page47_i188:b"
				( attribute "PN" "2"
					( Origin gPackager )
				)
				( objectStatus "C4G19.2" )
			)
			( pin "@baseboard_fab2_lib.baseboard_fab2(sch_1):page48_i43:vss(0)"
				( attribute "PN" "283"
					( Origin gPackager )
				)
				( objectStatus "J6U2.283" )
			)
			( pin "@baseboard_fab2_lib.baseboard_fab2(sch_1):page48_i43:vss(1)"
				( attribute "PN" "281"
					( Origin gPackager )
				)
				( objectStatus "J6U2.281" )
			)
			( pin "@baseboard_fab2_lib.baseboard_fab2(sch_1):page48_i43:vss(2)"
				( attribute "PN" "279"
					( Origin gPackager )
				)
				( objectStatus "J6U2.279" )
			)
			( pin "@baseboard_fab2_lib.baseboard_fab2(sch_1):page48_i43:vss(3)"
				( attribute "PN" "276"
					( Origin gPackager )
				)
				( objectStatus "J6U2.276" )
			)
			( pin "@baseboard_fab2_lib.baseboard_fab2(sch_1):page48_i43:vss(4)"
				( attribute "PN" "274"
					( Origin gPackager )
				)
				( objectStatus "J6U2.274" )
			)
			( pin "@baseboard_fab2_lib.baseboard_fab2(sch_1):page48_i43:vss(5)"
				( attribute "PN" "272"
					( Origin gPackager )
				)
				( objectStatus "J6U2.272" )
			)
			( pin "@baseboard_fab2_lib.baseboard_fab2(sch_1):page48_i43:vss(6)"
				( attribute "PN" "270"
					( Origin gPackager )
				)
				( objectStatus "J6U2.270" )
			)
			( pin "@baseboard_fab2_lib.baseboard_fab2(sch_1):page48_i43:vss(7)"
				( attribute "PN" "268"
					( Origin gPackager )
				)
				( objectStatus "J6U2.268" )
			)
			( pin "@baseboard_fab2_lib.baseboard_fab2(sch_1):page48_i43:vss(8)"
				( attribute "PN" "265"
					( Origin gPackager )
				)
				( objectStatus "J6U2.265" )
			)
			( pin "@baseboard_fab2_lib.baseboard_fab2(sch_1):page48_i43:vss(9)"
				( attribute "PN" "263"
					( Origin gPackager )
				)
				( objectStatus "J6U2.263" )
			)
			( pin "@baseboard_fab2_lib.baseboard_fab2(sch_1):page48_i43:vss(10)"
				( attribute "PN" "261"
					( Origin gPackager )
				)
				( objectStatus "J6U2.261" )
			)
			( pin "@baseboard_fab2_lib.baseboard_fab2(sch_1):page48_i43:vss(11)"
				( attribute "PN" "259"
					( Origin gPackager )
				)
				( objectStatus "J6U2.259" )
			)
			( pin "@baseboard_fab2_lib.baseboard_fab2(sch_1):page48_i43:vss(12)"
				( attribute "PN" "257"
					( Origin gPackager )
				)
				( objectStatus "J6U2.257" )
			)
			( pin "@baseboard_fab2_lib.baseboard_fab2(sch_1):page48_i43:vss(13)"
				( attribute "PN" "254"
					( Origin gPackager )
				)
				( objectStatus "J6U2.254" )
			)
			( pin "@baseboard_fab2_lib.baseboard_fab2(sch_1):page48_i43:vss(14)"
				( attribute "PN" "252"
					( Origin gPackager )
				)
				( objectStatus "J6U2.252" )
			)
			( pin "@baseboard_fab2_lib.baseboard_fab2(sch_1):page48_i43:vss(15)"
				( attribute "PN" "250"
					( Origin gPackager )
				)
				( objectStatus "J6U2.250" )
			)
			( pin "@baseboard_fab2_lib.baseboard_fab2(sch_1):page48_i43:vss(16)"
				( attribute "PN" "248"
					( Origin gPackager )
				)
				( objectStatus "J6U2.248" )
			)
			( pin "@baseboard_fab2_lib.baseboard_fab2(sch_1):page48_i43:vss(17)"
				( attribute "PN" "246"
					( Origin gPackager )
				)
				( objectStatus "J6U2.246" )
			)
			( pin "@baseboard_fab2_lib.baseboard_fab2(sch_1):page48_i43:vss(18)"
				( attribute "PN" "243"
					( Origin gPackager )
				)
				( objectStatus "J6U2.243" )
			)
			( pin "@baseboard_fab2_lib.baseboard_fab2(sch_1):page48_i43:vss(19)"
				( attribute "PN" "241"
					( Origin gPackager )
				)
				( objectStatus "J6U2.241" )
			)
			( pin "@baseboard_fab2_lib.baseboard_fab2(sch_1):page48_i43:vss(20)"
				( attribute "PN" "239"
					( Origin gPackager )
				)
				( objectStatus "J6U2.239" )
			)
			( pin "@baseboard_fab2_lib.baseboard_fab2(sch_1):page48_i43:vss(21)"
				( attribute "PN" "202"
					( Origin gPackager )
				)
				( objectStatus "J6U2.202" )
			)
			( pin "@baseboard_fab2_lib.baseboard_fab2(sch_1):page48_i43:vss(22)"
				( attribute "PN" "200"
					( Origin gPackager )
				)
				( objectStatus "J6U2.200" )
			)
			( pin "@baseboard_fab2_lib.baseboard_fab2(sch_1):page48_i43:vss(23)"
				( attribute "PN" "198"
					( Origin gPackager )
				)
				( objectStatus "J6U2.198" )
			)
			( pin "@baseboard_fab2_lib.baseboard_fab2(sch_1):page48_i43:vss(24)"
				( attribute "PN" "195"
					( Origin gPackager )
				)
				( objectStatus "J6U2.195" )
			)
			( pin "@baseboard_fab2_lib.baseboard_fab2(sch_1):page48_i43:vss(25)"
				( attribute "PN" "193"
					( Origin gPackager )
				)
				( objectStatus "J6U2.193" )
			)
			( pin "@baseboard_fab2_lib.baseboard_fab2(sch_1):page48_i43:vss(26)"
				( attribute "PN" "191"
					( Origin gPackager )
				)
				( objectStatus "J6U2.191" )
			)
			( pin "@baseboard_fab2_lib.baseboard_fab2(sch_1):page48_i43:vss(27)"
				( attribute "PN" "189"
					( Origin gPackager )
				)
				( objectStatus "J6U2.189" )
			)
			( pin "@baseboard_fab2_lib.baseboard_fab2(sch_1):page48_i43:vss(28)"
				( attribute "PN" "187"
					( Origin gPackager )
				)
				( objectStatus "J6U2.187" )
			)
			( pin "@baseboard_fab2_lib.baseboard_fab2(sch_1):page48_i43:vss(29)"
				( attribute "PN" "184"
					( Origin gPackager )
				)
				( objectStatus "J6U2.184" )
			)
			( pin "@baseboard_fab2_lib.baseboard_fab2(sch_1):page48_i43:vss(30)"
				( attribute "PN" "182"
					( Origin gPackager )
				)
				( objectStatus "J6U2.182" )
			)
			( pin "@baseboard_fab2_lib.baseboard_fab2(sch_1):page48_i43:vss(31)"
				( attribute "PN" "180"
					( Origin gPackager )
				)
				( objectStatus "J6U2.180" )
			)
			( pin "@baseboard_fab2_lib.baseboard_fab2(sch_1):page48_i43:vss(32)"
				( attribute "PN" "178"
					( Origin gPackager )
				)
				( objectStatus "J6U2.178" )
			)
			( pin "@baseboard_fab2_lib.baseboard_fab2(sch_1):page48_i43:vss(33)"
				( attribute "PN" "176"
					( Origin gPackager )
				)
				( objectStatus "J6U2.176" )
			)
			( pin "@baseboard_fab2_lib.baseboard_fab2(sch_1):page48_i43:vss(34)"
				( attribute "PN" "173"
					( Origin gPackager )
				)
				( objectStatus "J6U2.173" )
			)
			( pin "@baseboard_fab2_lib.baseboard_fab2(sch_1):page48_i43:vss(35)"
				( attribute "PN" "171"
					( Origin gPackager )
				)
				( objectStatus "J6U2.171" )
			)
			( pin "@baseboard_fab2_lib.baseboard_fab2(sch_1):page48_i43:vss(36)"
				( attribute "PN" "169"
					( Origin gPackager )
				)
				( objectStatus "J6U2.169" )
			)
			( pin "@baseboard_fab2_lib.baseboard_fab2(sch_1):page48_i43:vss(37)"
				( attribute "PN" "167"
					( Origin gPackager )
				)
				( objectStatus "J6U2.167" )
			)
			( pin "@baseboard_fab2_lib.baseboard_fab2(sch_1):page48_i43:vss(38)"
				( attribute "PN" "165"
					( Origin gPackager )
				)
				( objectStatus "J6U2.165" )
			)
			( pin "@baseboard_fab2_lib.baseboard_fab2(sch_1):page48_i43:vss(39)"
				( attribute "PN" "162"
					( Origin gPackager )
				)
				( objectStatus "J6U2.162" )
			)
			( pin "@baseboard_fab2_lib.baseboard_fab2(sch_1):page48_i43:vss(40)"
				( attribute "PN" "160"
					( Origin gPackager )
				)
				( objectStatus "J6U2.160" )
			)
			( pin "@baseboard_fab2_lib.baseboard_fab2(sch_1):page48_i43:vss(41)"
				( attribute "PN" "158"
					( Origin gPackager )
				)
				( objectStatus "J6U2.158" )
			)
			( pin "@baseboard_fab2_lib.baseboard_fab2(sch_1):page48_i43:vss(42)"
				( attribute "PN" "156"
					( Origin gPackager )
				)
				( objectStatus "J6U2.156" )
			)
			( pin "@baseboard_fab2_lib.baseboard_fab2(sch_1):page48_i43:vss(43)"
				( attribute "PN" "154"
					( Origin gPackager )
				)
				( objectStatus "J6U2.154" )
			)
			( pin "@baseboard_fab2_lib.baseboard_fab2(sch_1):page48_i43:vss(44)"
				( attribute "PN" "151"
					( Origin gPackager )
				)
				( objectStatus "J6U2.151" )
			)
			( pin "@baseboard_fab2_lib.baseboard_fab2(sch_1):page48_i43:vss(45)"
				( attribute "PN" "149"
					( Origin gPackager )
				)
				( objectStatus "J6U2.149" )
			)
			( pin "@baseboard_fab2_lib.baseboard_fab2(sch_1):page48_i43:vss(46)"
				( attribute "PN" "147"
					( Origin gPackager )
				)
				( objectStatus "J6U2.147" )
			)
			( pin "@baseboard_fab2_lib.baseboard_fab2(sch_1):page48_i43:vss(47)"
				( attribute "PN" "138"
					( Origin gPackager )
				)
				( objectStatus "J6U2.138" )
			)
			( pin "@baseboard_fab2_lib.baseboard_fab2(sch_1):page48_i43:vss(48)"
				( attribute "PN" "136"
					( Origin gPackager )
				)
				( objectStatus "J6U2.136" )
			)
			( pin "@baseboard_fab2_lib.baseboard_fab2(sch_1):page48_i43:vss(49)"
				( attribute "PN" "134"
					( Origin gPackager )
				)
				( objectStatus "J6U2.134" )
			)
			( pin "@baseboard_fab2_lib.baseboard_fab2(sch_1):page48_i43:vss(50)"
				( attribute "PN" "131"
					( Origin gPackager )
				)
				( objectStatus "J6U2.131" )
			)
			( pin "@baseboard_fab2_lib.baseboard_fab2(sch_1):page48_i43:vss(51)"
				( attribute "PN" "129"
					( Origin gPackager )
				)
				( objectStatus "J6U2.129" )
			)
			( pin "@baseboard_fab2_lib.baseboard_fab2(sch_1):page48_i43:vss(52)"
				( attribute "PN" "127"
					( Origin gPackager )
				)
				( objectStatus "J6U2.127" )
			)
			( pin "@baseboard_fab2_lib.baseboard_fab2(sch_1):page48_i43:vss(53)"
				( attribute "PN" "125"
					( Origin gPackager )
				)
				( objectStatus "J6U2.125" )
			)
			( pin "@baseboard_fab2_lib.baseboard_fab2(sch_1):page48_i43:vss(54)"
				( attribute "PN" "123"
					( Origin gPackager )
				)
				( objectStatus "J6U2.123" )
			)
			( pin "@baseboard_fab2_lib.baseboard_fab2(sch_1):page48_i43:vss(55)"
				( attribute "PN" "120"
					( Origin gPackager )
				)
				( objectStatus "J6U2.120" )
			)
			( pin "@baseboard_fab2_lib.baseboard_fab2(sch_1):page48_i43:vss(56)"
				( attribute "PN" "118"
					( Origin gPackager )
				)
				( objectStatus "J6U2.118" )
			)
			( pin "@baseboard_fab2_lib.baseboard_fab2(sch_1):page48_i43:vss(57)"
				( attribute "PN" "116"
					( Origin gPackager )
				)
				( objectStatus "J6U2.116" )
			)
			( pin "@baseboard_fab2_lib.baseboard_fab2(sch_1):page48_i43:vss(58)"
				( attribute "PN" "114"
					( Origin gPackager )
				)
				( objectStatus "J6U2.114" )
			)
			( pin "@baseboard_fab2_lib.baseboard_fab2(sch_1):page48_i43:vss(59)"
				( attribute "PN" "112"
					( Origin gPackager )
				)
				( objectStatus "J6U2.112" )
			)
			( pin "@baseboard_fab2_lib.baseboard_fab2(sch_1):page48_i43:vss(60)"
				( attribute "PN" "109"
					( Origin gPackager )
				)
				( objectStatus "J6U2.109" )
			)
			( pin "@baseboard_fab2_lib.baseboard_fab2(sch_1):page48_i43:vss(61)"
				( attribute "PN" "107"
					( Origin gPackager )
				)
				( objectStatus "J6U2.107" )
			)
			( pin "@baseboard_fab2_lib.baseboard_fab2(sch_1):page48_i43:vss(62)"
				( attribute "PN" "105"
					( Origin gPackager )
				)
				( objectStatus "J6U2.105" )
			)
			( pin "@baseboard_fab2_lib.baseboard_fab2(sch_1):page48_i43:vss(63)"
				( attribute "PN" "103"
					( Origin gPackager )
				)
				( objectStatus "J6U2.103" )
			)
			( pin "@baseboard_fab2_lib.baseboard_fab2(sch_1):page48_i43:vss(64)"
				( attribute "PN" "101"
					( Origin gPackager )
				)
				( objectStatus "J6U2.101" )
			)
			( pin "@baseboard_fab2_lib.baseboard_fab2(sch_1):page48_i43:vss(65)"
				( attribute "PN" "98"
					( Origin gPackager )
				)
				( objectStatus "J6U2.98" )
			)
			( pin "@baseboard_fab2_lib.baseboard_fab2(sch_1):page48_i43:vss(66)"
				( attribute "PN" "96"
					( Origin gPackager )
				)
				( objectStatus "J6U2.96" )
			)
			( pin "@baseboard_fab2_lib.baseboard_fab2(sch_1):page48_i43:vss(67)"
				( attribute "PN" "94"
					( Origin gPackager )
				)
				( objectStatus "J6U2.94" )
			)
			( pin "@baseboard_fab2_lib.baseboard_fab2(sch_1):page48_i43:vss(68)"
				( attribute "PN" "57"
					( Origin gPackager )
				)
				( objectStatus "J6U2.57" )
			)
			( pin "@baseboard_fab2_lib.baseboard_fab2(sch_1):page48_i43:vss(69)"
				( attribute "PN" "55"
					( Origin gPackager )
				)
				( objectStatus "J6U2.55" )
			)
			( pin "@baseboard_fab2_lib.baseboard_fab2(sch_1):page48_i43:vss(70)"
				( attribute "PN" "53"
					( Origin gPackager )
				)
				( objectStatus "J6U2.53" )
			)
			( pin "@baseboard_fab2_lib.baseboard_fab2(sch_1):page48_i43:vss(71)"
				( attribute "PN" "50"
					( Origin gPackager )
				)
				( objectStatus "J6U2.50" )
			)
			( pin "@baseboard_fab2_lib.baseboard_fab2(sch_1):page48_i43:vss(72)"
				( attribute "PN" "48"
					( Origin gPackager )
				)
				( objectStatus "J6U2.48" )
			)
			( pin "@baseboard_fab2_lib.baseboard_fab2(sch_1):page48_i43:vss(73)"
				( attribute "PN" "46"
					( Origin gPackager )
				)
				( objectStatus "J6U2.46" )
			)
			( pin "@baseboard_fab2_lib.baseboard_fab2(sch_1):page48_i43:vss(74)"
				( attribute "PN" "44"
					( Origin gPackager )
				)
				( objectStatus "J6U2.44" )
			)
			( pin "@baseboard_fab2_lib.baseboard_fab2(sch_1):page48_i43:vss(75)"
				( attribute "PN" "42"
					( Origin gPackager )
				)
				( objectStatus "J6U2.42" )
			)
			( pin "@baseboard_fab2_lib.baseboard_fab2(sch_1):page48_i43:vss(76)"
				( attribute "PN" "39"
					( Origin gPackager )
				)
				( objectStatus "J6U2.39" )
			)
			( pin "@baseboard_fab2_lib.baseboard_fab2(sch_1):page48_i43:vss(77)"
				( attribute "PN" "37"
					( Origin gPackager )
				)
				( objectStatus "J6U2.37" )
			)
			( pin "@baseboard_fab2_lib.baseboard_fab2(sch_1):page48_i43:vss(78)"
				( attribute "PN" "35"
					( Origin gPackager )
				)
				( objectStatus "J6U2.35" )
			)
			( pin "@baseboard_fab2_lib.baseboard_fab2(sch_1):page48_i43:vss(79)"
				( attribute "PN" "33"
					( Origin gPackager )
				)
				( objectStatus "J6U2.33" )
			)
			( pin "@baseboard_fab2_lib.baseboard_fab2(sch_1):page48_i43:vss(80)"
				( attribute "PN" "31"
					( Origin gPackager )
				)
				( objectStatus "J6U2.31" )
			)
			( pin "@baseboard_fab2_lib.baseboard_fab2(sch_1):page48_i43:vss(81)"
				( attribute "PN" "28"
					( Origin gPackager )
				)
				( objectStatus "J6U2.28" )
			)
			( pin "@baseboard_fab2_lib.baseboard_fab2(sch_1):page48_i43:vss(82)"
				( attribute "PN" "26"
					( Origin gPackager )
				)
				( objectStatus "J6U2.26" )
			)
			( pin "@baseboard_fab2_lib.baseboard_fab2(sch_1):page48_i43:vss(83)"
				( attribute "PN" "24"
					( Origin gPackager )
				)
				( objectStatus "J6U2.24" )
			)
			( pin "@baseboard_fab2_lib.baseboard_fab2(sch_1):page48_i43:vss(84)"
				( attribute "PN" "22"
					( Origin gPackager )
				)
				( objectStatus "J6U2.22" )
			)
			( pin "@baseboard_fab2_lib.baseboard_fab2(sch_1):page48_i43:vss(85)"
				( attribute "PN" "20"
					( Origin gPackager )
				)
				( objectStatus "J6U2.20" )
			)
			( pin "@baseboard_fab2_lib.baseboard_fab2(sch_1):page48_i43:vss(86)"
				( attribute "PN" "17"
					( Origin gPackager )
				)
				( objectStatus "J6U2.17" )
			)
			( pin "@baseboard_fab2_lib.baseboard_fab2(sch_1):page48_i43:vss(87)"
				( attribute "PN" "15"
					( Origin gPackager )
				)
				( objectStatus "J6U2.15" )
			)
			( pin "@baseboard_fab2_lib.baseboard_fab2(sch_1):page48_i43:vss(88)"
				( attribute "PN" "13"
					( Origin gPackager )
				)
				( objectStatus "J6U2.13" )
			)
			( pin "@baseboard_fab2_lib.baseboard_fab2(sch_1):page48_i43:vss(89)"
				( attribute "PN" "11"
					( Origin gPackager )
				)
				( objectStatus "J6U2.11" )
			)
			( pin "@baseboard_fab2_lib.baseboard_fab2(sch_1):page48_i43:vss(90)"
				( attribute "PN" "9"
					( Origin gPackager )
				)
				( objectStatus "J6U2.9" )
			)
			( pin "@baseboard_fab2_lib.baseboard_fab2(sch_1):page48_i43:vss(91)"
				( attribute "PN" "6"
					( Origin gPackager )
				)
				( objectStatus "J6U2.6" )
			)
			( pin "@baseboard_fab2_lib.baseboard_fab2(sch_1):page48_i43:vss(92)"
				( attribute "PN" "4"
					( Origin gPackager )
				)
				( objectStatus "J6U2.4" )
			)
			( pin "@baseboard_fab2_lib.baseboard_fab2(sch_1):page48_i43:vss(93)"
				( attribute "PN" "2"
					( Origin gPackager )
				)
				( objectStatus "J6U2.2" )
			)
			( pin "@baseboard_fab2_lib.baseboard_fab2(sch_1):page48_i61:dqs0n"
				( attribute "PN" "152"
					( Origin gPackager )
				)
				( objectStatus "J6U2.152" )
			)
			( pin "@baseboard_fab2_lib.baseboard_fab2(sch_1):page48_i61:dqs0p"
				( attribute "PN" "153"
					( Origin gPackager )
				)
				( objectStatus "J6U2.153" )
			)
			( pin "@baseboard_fab2_lib.baseboard_fab2(sch_1):page48_i61:dqs1n"
				( attribute "PN" "163"
					( Origin gPackager )
				)
				( objectStatus "J6U2.163" )
			)
			( pin "@baseboard_fab2_lib.baseboard_fab2(sch_1):page48_i61:dqs1p"
				( attribute "PN" "164"
					( Origin gPackager )
				)
				( objectStatus "J6U2.164" )
			)
			( pin "@baseboard_fab2_lib.baseboard_fab2(sch_1):page48_i61:dqs2n"
				( attribute "PN" "174"
					( Origin gPackager )
				)
				( objectStatus "J6U2.174" )
			)
			( pin "@baseboard_fab2_lib.baseboard_fab2(sch_1):page48_i61:dqs2p"
				( attribute "PN" "175"
					( Origin gPackager )
				)
				( objectStatus "J6U2.175" )
			)
			( pin "@baseboard_fab2_lib.baseboard_fab2(sch_1):page48_i61:dqs3n"
				( attribute "PN" "185"
					( Origin gPackager )
				)
				( objectStatus "J6U2.185" )
			)
			( pin "@baseboard_fab2_lib.baseboard_fab2(sch_1):page48_i61:dqs3p"
				( attribute "PN" "186"
					( Origin gPackager )
				)
				( objectStatus "J6U2.186" )
			)
			( pin "@baseboard_fab2_lib.baseboard_fab2(sch_1):page48_i61:dqs4n"
				( attribute "PN" "244"
					( Origin gPackager )
				)
				( objectStatus "J6U2.244" )
			)
			( pin "@baseboard_fab2_lib.baseboard_fab2(sch_1):page48_i61:dqs4p"
				( attribute "PN" "245"
					( Origin gPackager )
				)
				( objectStatus "J6U2.245" )
			)
			( pin "@baseboard_fab2_lib.baseboard_fab2(sch_1):page48_i61:dqs5n"
				( attribute "PN" "255"
					( Origin gPackager )
				)
				( objectStatus "J6U2.255" )
			)
			( pin "@baseboard_fab2_lib.baseboard_fab2(sch_1):page48_i61:dqs5p"
				( attribute "PN" "256"
					( Origin gPackager )
				)
				( objectStatus "J6U2.256" )
			)
			( pin "@baseboard_fab2_lib.baseboard_fab2(sch_1):page48_i61:dqs6n"
				( attribute "PN" "266"
					( Origin gPackager )
				)
				( objectStatus "J6U2.266" )
			)
			( pin "@baseboard_fab2_lib.baseboard_fab2(sch_1):page48_i61:dqs6p"
				( attribute "PN" "267"
					( Origin gPackager )
				)
				( objectStatus "J6U2.267" )
			)
			( pin "@baseboard_fab2_lib.baseboard_fab2(sch_1):page48_i61:dqs7n"
				( attribute "PN" "277"
					( Origin gPackager )
				)
				( objectStatus "J6U2.277" )
			)
			( pin "@baseboard_fab2_lib.baseboard_fab2(sch_1):page48_i61:dqs7p"
				( attribute "PN" "278"
					( Origin gPackager )
				)
				( objectStatus "J6U2.278" )
			)
			( pin "@baseboard_fab2_lib.baseboard_fab2(sch_1):page48_i61:dqs8n"
				( attribute "PN" "196"
					( Origin gPackager )
				)
				( objectStatus "J6U2.196" )
			)
			( pin "@baseboard_fab2_lib.baseboard_fab2(sch_1):page48_i61:dqs8p"
				( attribute "PN" "197"
					( Origin gPackager )
				)
				( objectStatus "J6U2.197" )
			)
			( pin "@baseboard_fab2_lib.baseboard_fab2(sch_1):page48_i61:dqs9n"
				( attribute "PN" "8"
					( Origin gPackager )
				)
				( objectStatus "J6U2.8" )
			)
			( pin "@baseboard_fab2_lib.baseboard_fab2(sch_1):page48_i61:dqs9p"
				( attribute "PN" "7"
					( Origin gPackager )
				)
				( objectStatus "J6U2.7" )
			)
			( pin "@baseboard_fab2_lib.baseboard_fab2(sch_1):page48_i61:dqs10n"
				( attribute "PN" "19"
					( Origin gPackager )
				)
				( objectStatus "J6U2.19" )
			)
			( pin "@baseboard_fab2_lib.baseboard_fab2(sch_1):page48_i61:dqs10p"
				( attribute "PN" "18"
					( Origin gPackager )
				)
				( objectStatus "J6U2.18" )
			)
			( pin "@baseboard_fab2_lib.baseboard_fab2(sch_1):page48_i61:dqs11n"
				( attribute "PN" "30"
					( Origin gPackager )
				)
				( objectStatus "J6U2.30" )
			)
			( pin "@baseboard_fab2_lib.baseboard_fab2(sch_1):page48_i61:dqs11p"
				( attribute "PN" "29"
					( Origin gPackager )
				)
				( objectStatus "J6U2.29" )
			)
			( pin "@baseboard_fab2_lib.baseboard_fab2(sch_1):page48_i61:dqs12n"
				( attribute "PN" "41"
					( Origin gPackager )
				)
				( objectStatus "J6U2.41" )
			)
			( pin "@baseboard_fab2_lib.baseboard_fab2(sch_1):page48_i61:dqs12p"
				( attribute "PN" "40"
					( Origin gPackager )
				)
				( objectStatus "J6U2.40" )
			)
			( pin "@baseboard_fab2_lib.baseboard_fab2(sch_1):page48_i61:dqs13n"
				( attribute "PN" "100"
					( Origin gPackager )
				)
				( objectStatus "J6U2.100" )
			)
			( pin "@baseboard_fab2_lib.baseboard_fab2(sch_1):page48_i61:dqs13p"
				( attribute "PN" "99"
					( Origin gPackager )
				)
				( objectStatus "J6U2.99" )
			)
			( pin "@baseboard_fab2_lib.baseboard_fab2(sch_1):page48_i61:dqs14n"
				( attribute "PN" "111"
					( Origin gPackager )
				)
				( objectStatus "J6U2.111" )
			)
			( pin "@baseboard_fab2_lib.baseboard_fab2(sch_1):page48_i61:dqs14p"
				( attribute "PN" "110"
					( Origin gPackager )
				)
				( objectStatus "J6U2.110" )
			)
			( pin "@baseboard_fab2_lib.baseboard_fab2(sch_1):page48_i61:dqs15n"
				( attribute "PN" "122"
					( Origin gPackager )
				)
				( objectStatus "J6U2.122" )
			)
			( pin "@baseboard_fab2_lib.baseboard_fab2(sch_1):page48_i61:dqs15p"
				( attribute "PN" "121"
					( Origin gPackager )
				)
				( objectStatus "J6U2.121" )
			)
			( pin "@baseboard_fab2_lib.baseboard_fab2(sch_1):page48_i61:dqs16n"
				( attribute "PN" "133"
					( Origin gPackager )
				)
				( objectStatus "J6U2.133" )
			)
			( pin "@baseboard_fab2_lib.baseboard_fab2(sch_1):page48_i61:dqs16p"
				( attribute "PN" "132"
					( Origin gPackager )
				)
				( objectStatus "J6U2.132" )
			)
			( pin "@baseboard_fab2_lib.baseboard_fab2(sch_1):page48_i61:dqs17n"
				( attribute "PN" "52"
					( Origin gPackager )
				)
				( objectStatus "J6U2.52" )
			)
			( pin "@baseboard_fab2_lib.baseboard_fab2(sch_1):page48_i61:dqs17p"
				( attribute "PN" "51"
					( Origin gPackager )
				)
				( objectStatus "J6U2.51" )
			)
			( pin "@baseboard_fab2_lib.baseboard_fab2(sch_1):page48_i111:a0"
				( attribute "PN" "79"
					( Origin gPackager )
				)
				( objectStatus "J6U2.79" )
			)
			( pin "@baseboard_fab2_lib.baseboard_fab2(sch_1):page48_i111:a1"
				( attribute "PN" "72"
					( Origin gPackager )
				)
				( objectStatus "J6U2.72" )
			)
			( pin "@baseboard_fab2_lib.baseboard_fab2(sch_1):page48_i111:a2"
				( attribute "PN" "216"
					( Origin gPackager )
				)
				( objectStatus "J6U2.216" )
			)
			( pin "@baseboard_fab2_lib.baseboard_fab2(sch_1):page48_i111:a3"
				( attribute "PN" "71"
					( Origin gPackager )
				)
				( objectStatus "J6U2.71" )
			)
			( pin "@baseboard_fab2_lib.baseboard_fab2(sch_1):page48_i111:a4"
				( attribute "PN" "214"
					( Origin gPackager )
				)
				( objectStatus "J6U2.214" )
			)
			( pin "@baseboard_fab2_lib.baseboard_fab2(sch_1):page48_i111:a5"
				( attribute "PN" "213"
					( Origin gPackager )
				)
				( objectStatus "J6U2.213" )
			)
			( pin "@baseboard_fab2_lib.baseboard_fab2(sch_1):page48_i111:a6"
				( attribute "PN" "69"
					( Origin gPackager )
				)
				( objectStatus "J6U2.69" )
			)
			( pin "@baseboard_fab2_lib.baseboard_fab2(sch_1):page48_i111:a7"
				( attribute "PN" "211"
					( Origin gPackager )
				)
				( objectStatus "J6U2.211" )
			)
			( pin "@baseboard_fab2_lib.baseboard_fab2(sch_1):page48_i111:a8"
				( attribute "PN" "68"
					( Origin gPackager )
				)
				( objectStatus "J6U2.68" )
			)
			( pin "@baseboard_fab2_lib.baseboard_fab2(sch_1):page48_i111:a9"
				( attribute "PN" "66"
					( Origin gPackager )
				)
				( objectStatus "J6U2.66" )
			)
			( pin "@baseboard_fab2_lib.baseboard_fab2(sch_1):page48_i111:a10"
				( attribute "PN" "225"
					( Origin gPackager )
				)
				( objectStatus "J6U2.225" )
			)
			( pin "@baseboard_fab2_lib.baseboard_fab2(sch_1):page48_i111:a11"
				( attribute "PN" "210"
					( Origin gPackager )
				)
				( objectStatus "J6U2.210" )
			)
			( pin "@baseboard_fab2_lib.baseboard_fab2(sch_1):page48_i111:a12"
				( attribute "PN" "65"
					( Origin gPackager )
				)
				( objectStatus "J6U2.65" )
			)
			( pin "@baseboard_fab2_lib.baseboard_fab2(sch_1):page48_i111:a13"
				( attribute "PN" "232"
					( Origin gPackager )
				)
				( objectStatus "J6U2.232" )
			)
			( pin "@baseboard_fab2_lib.baseboard_fab2(sch_1):page48_i111:a14_we_n"
				( attribute "PN" "228"
					( Origin gPackager )
				)
				( objectStatus "J6U2.228" )
			)
			( pin "@baseboard_fab2_lib.baseboard_fab2(sch_1):page48_i111:a15_cas_n"
				( attribute "PN" "86"
					( Origin gPackager )
				)
				( objectStatus "J6U2.86" )
			)
			( pin "@baseboard_fab2_lib.baseboard_fab2(sch_1):page48_i111:a16_ras_n"
				( attribute "PN" "82"
					( Origin gPackager )
				)
				( objectStatus "J6U2.82" )
			)
			( pin "@baseboard_fab2_lib.baseboard_fab2(sch_1):page48_i111:a17"
				( attribute "PN" "234"
					( Origin gPackager )
				)
				( objectStatus "J6U2.234" )
			)
			( pin "@baseboard_fab2_lib.baseboard_fab2(sch_1):page48_i111:act_n"
				( attribute "PN" "62"
					( Origin gPackager )
				)
				( objectStatus "J6U2.62" )
			)
			( pin "@baseboard_fab2_lib.baseboard_fab2(sch_1):page48_i111:alert_n"
				( attribute "PN" "208"
					( Origin gPackager )
				)
				( objectStatus "J6U2.208" )
			)
			( pin "@baseboard_fab2_lib.baseboard_fab2(sch_1):page48_i111:ba(0)"
				( attribute "PN" "81"
					( Origin gPackager )
				)
				( objectStatus "J6U2.81" )
			)
			( pin "@baseboard_fab2_lib.baseboard_fab2(sch_1):page48_i111:ba(1)"
				( attribute "PN" "224"
					( Origin gPackager )
				)
				( objectStatus "J6U2.224" )
			)
			( pin "@baseboard_fab2_lib.baseboard_fab2(sch_1):page48_i111:bg(0)"
				( attribute "PN" "63"
					( Origin gPackager )
				)
				( objectStatus "J6U2.63" )
			)
			( pin "@baseboard_fab2_lib.baseboard_fab2(sch_1):page48_i111:bg(1)"
				( attribute "PN" "207"
					( Origin gPackager )
				)
				( objectStatus "J6U2.207" )
			)
			( pin "@baseboard_fab2_lib.baseboard_fab2(sch_1):page48_i111:c(2)"
				( attribute "PN" "235"
					( Origin gPackager )
				)
				( objectStatus "J6U2.235" )
			)
			( pin "@baseboard_fab2_lib.baseboard_fab2(sch_1):page48_i111:cb(0)"
				( attribute "PN" "49"
					( Origin gPackager )
				)
				( objectStatus "J6U2.49" )
			)
			( pin "@baseboard_fab2_lib.baseboard_fab2(sch_1):page48_i111:cb(1)"
				( attribute "PN" "194"
					( Origin gPackager )
				)
				( objectStatus "J6U2.194" )
			)
			( pin "@baseboard_fab2_lib.baseboard_fab2(sch_1):page48_i111:cb(2)"
				( attribute "PN" "56"
					( Origin gPackager )
				)
				( objectStatus "J6U2.56" )
			)
			( pin "@baseboard_fab2_lib.baseboard_fab2(sch_1):page48_i111:cb(3)"
				( attribute "PN" "201"
					( Origin gPackager )
				)
				( objectStatus "J6U2.201" )
			)
			( pin "@baseboard_fab2_lib.baseboard_fab2(sch_1):page48_i111:cb(4)"
				( attribute "PN" "47"
					( Origin gPackager )
				)
				( objectStatus "J6U2.47" )
			)
			( pin "@baseboard_fab2_lib.baseboard_fab2(sch_1):page48_i111:cb(5)"
				( attribute "PN" "192"
					( Origin gPackager )
				)
				( objectStatus "J6U2.192" )
			)
			( pin "@baseboard_fab2_lib.baseboard_fab2(sch_1):page48_i111:cb(6)"
				( attribute "PN" "54"
					( Origin gPackager )
				)
				( objectStatus "J6U2.54" )
			)
			( pin "@baseboard_fab2_lib.baseboard_fab2(sch_1):page48_i111:cb(7)"
				( attribute "PN" "199"
					( Origin gPackager )
				)
				( objectStatus "J6U2.199" )
			)
			( pin "@baseboard_fab2_lib.baseboard_fab2(sch_1):page48_i111:ck0n"
				( attribute "PN" "75"
					( Origin gPackager )
				)
				( objectStatus "J6U2.75" )
			)
			( pin "@baseboard_fab2_lib.baseboard_fab2(sch_1):page48_i111:ck0p"
				( attribute "PN" "74"
					( Origin gPackager )
				)
				( objectStatus "J6U2.74" )
			)
			( pin "@baseboard_fab2_lib.baseboard_fab2(sch_1):page48_i111:ck1n"
				( attribute "PN" "219"
					( Origin gPackager )
				)
				( objectStatus "J6U2.219" )
			)
			( pin "@baseboard_fab2_lib.baseboard_fab2(sch_1):page48_i111:ck1p"
				( attribute "PN" "218"
					( Origin gPackager )
				)
				( objectStatus "J6U2.218" )
			)
			( pin "@baseboard_fab2_lib.baseboard_fab2(sch_1):page48_i111:cke(0)"
				( attribute "PN" "60"
					( Origin gPackager )
				)
				( objectStatus "J6U2.60" )
			)
			( pin "@baseboard_fab2_lib.baseboard_fab2(sch_1):page48_i111:cke(1)"
				( attribute "PN" "203"
					( Origin gPackager )
				)
				( objectStatus "J6U2.203" )
			)
			( pin "@baseboard_fab2_lib.baseboard_fab2(sch_1):page48_i111:dq(0)"
				( attribute "PN" "5"
					( Origin gPackager )
				)
				( objectStatus "J6U2.5" )
			)
			( pin "@baseboard_fab2_lib.baseboard_fab2(sch_1):page48_i111:dq(1)"
				( attribute "PN" "150"
					( Origin gPackager )
				)
				( objectStatus "J6U2.150" )
			)
			( pin "@baseboard_fab2_lib.baseboard_fab2(sch_1):page48_i111:dq(2)"
				( attribute "PN" "12"
					( Origin gPackager )
				)
				( objectStatus "J6U2.12" )
			)
			( pin "@baseboard_fab2_lib.baseboard_fab2(sch_1):page48_i111:dq(3)"
				( attribute "PN" "157"
					( Origin gPackager )
				)
				( objectStatus "J6U2.157" )
			)
			( pin "@baseboard_fab2_lib.baseboard_fab2(sch_1):page48_i111:dq(4)"
				( attribute "PN" "3"
					( Origin gPackager )
				)
				( objectStatus "J6U2.3" )
			)
			( pin "@baseboard_fab2_lib.baseboard_fab2(sch_1):page48_i111:dq(5)"
				( attribute "PN" "148"
					( Origin gPackager )
				)
				( objectStatus "J6U2.148" )
			)
			( pin "@baseboard_fab2_lib.baseboard_fab2(sch_1):page48_i111:dq(6)"
				( attribute "PN" "10"
					( Origin gPackager )
				)
				( objectStatus "J6U2.10" )
			)
			( pin "@baseboard_fab2_lib.baseboard_fab2(sch_1):page48_i111:dq(7)"
				( attribute "PN" "155"
					( Origin gPackager )
				)
				( objectStatus "J6U2.155" )
			)
			( pin "@baseboard_fab2_lib.baseboard_fab2(sch_1):page48_i111:dq(8)"
				( attribute "PN" "16"
					( Origin gPackager )
				)
				( objectStatus "J6U2.16" )
			)
			( pin "@baseboard_fab2_lib.baseboard_fab2(sch_1):page48_i111:dq(9)"
				( attribute "PN" "161"
					( Origin gPackager )
				)
				( objectStatus "J6U2.161" )
			)
			( pin "@baseboard_fab2_lib.baseboard_fab2(sch_1):page48_i111:dq(10)"
				( attribute "PN" "23"
					( Origin gPackager )
				)
				( objectStatus "J6U2.23" )
			)
			( pin "@baseboard_fab2_lib.baseboard_fab2(sch_1):page48_i111:dq(11)"
				( attribute "PN" "168"
					( Origin gPackager )
				)
				( objectStatus "J6U2.168" )
			)
			( pin "@baseboard_fab2_lib.baseboard_fab2(sch_1):page48_i111:dq(12)"
				( attribute "PN" "14"
					( Origin gPackager )
				)
				( objectStatus "J6U2.14" )
			)
			( pin "@baseboard_fab2_lib.baseboard_fab2(sch_1):page48_i111:dq(13)"
				( attribute "PN" "159"
					( Origin gPackager )
				)
				( objectStatus "J6U2.159" )
			)
			( pin "@baseboard_fab2_lib.baseboard_fab2(sch_1):page48_i111:dq(14)"
				( attribute "PN" "21"
					( Origin gPackager )
				)
				( objectStatus "J6U2.21" )
			)
			( pin "@baseboard_fab2_lib.baseboard_fab2(sch_1):page48_i111:dq(15)"
				( attribute "PN" "166"
					( Origin gPackager )
				)
				( objectStatus "J6U2.166" )
			)
			( pin "@baseboard_fab2_lib.baseboard_fab2(sch_1):page48_i111:dq(16)"
				( attribute "PN" "27"
					( Origin gPackager )
				)
				( objectStatus "J6U2.27" )
			)
			( pin "@baseboard_fab2_lib.baseboard_fab2(sch_1):page48_i111:dq(17)"
				( attribute "PN" "172"
					( Origin gPackager )
				)
				( objectStatus "J6U2.172" )
			)
			( pin "@baseboard_fab2_lib.baseboard_fab2(sch_1):page48_i111:dq(18)"
				( attribute "PN" "34"
					( Origin gPackager )
				)
				( objectStatus "J6U2.34" )
			)
			( pin "@baseboard_fab2_lib.baseboard_fab2(sch_1):page48_i111:dq(19)"
				( attribute "PN" "179"
					( Origin gPackager )
				)
				( objectStatus "J6U2.179" )
			)
			( pin "@baseboard_fab2_lib.baseboard_fab2(sch_1):page48_i111:dq(20)"
				( attribute "PN" "25"
					( Origin gPackager )
				)
				( objectStatus "J6U2.25" )
			)
			( pin "@baseboard_fab2_lib.baseboard_fab2(sch_1):page48_i111:dq(21)"
				( attribute "PN" "170"
					( Origin gPackager )
				)
				( objectStatus "J6U2.170" )
			)
			( pin "@baseboard_fab2_lib.baseboard_fab2(sch_1):page48_i111:dq(22)"
				( attribute "PN" "32"
					( Origin gPackager )
				)
				( objectStatus "J6U2.32" )
			)
			( pin "@baseboard_fab2_lib.baseboard_fab2(sch_1):page48_i111:dq(23)"
				( attribute "PN" "177"
					( Origin gPackager )
				)
				( objectStatus "J6U2.177" )
			)
			( pin "@baseboard_fab2_lib.baseboard_fab2(sch_1):page48_i111:dq(24)"
				( attribute "PN" "38"
					( Origin gPackager )
				)
				( objectStatus "J6U2.38" )
			)
			( pin "@baseboard_fab2_lib.baseboard_fab2(sch_1):page48_i111:dq(25)"
				( attribute "PN" "183"
					( Origin gPackager )
				)
				( objectStatus "J6U2.183" )
			)
			( pin "@baseboard_fab2_lib.baseboard_fab2(sch_1):page48_i111:dq(26)"
				( attribute "PN" "45"
					( Origin gPackager )
				)
				( objectStatus "J6U2.45" )
			)
			( pin "@baseboard_fab2_lib.baseboard_fab2(sch_1):page48_i111:dq(27)"
				( attribute "PN" "190"
					( Origin gPackager )
				)
				( objectStatus "J6U2.190" )
			)
			( pin "@baseboard_fab2_lib.baseboard_fab2(sch_1):page48_i111:dq(28)"
				( attribute "PN" "36"
					( Origin gPackager )
				)
				( objectStatus "J6U2.36" )
			)
			( pin "@baseboard_fab2_lib.baseboard_fab2(sch_1):page48_i111:dq(29)"
				( attribute "PN" "181"
					( Origin gPackager )
				)
				( objectStatus "J6U2.181" )
			)
			( pin "@baseboard_fab2_lib.baseboard_fab2(sch_1):page48_i111:dq(30)"
				( attribute "PN" "43"
					( Origin gPackager )
				)
				( objectStatus "J6U2.43" )
			)
			( pin "@baseboard_fab2_lib.baseboard_fab2(sch_1):page48_i111:dq(31)"
				( attribute "PN" "188"
					( Origin gPackager )
				)
				( objectStatus "J6U2.188" )
			)
			( pin "@baseboard_fab2_lib.baseboard_fab2(sch_1):page48_i111:dq(32)"
				( attribute "PN" "97"
					( Origin gPackager )
				)
				( objectStatus "J6U2.97" )
			)
			( pin "@baseboard_fab2_lib.baseboard_fab2(sch_1):page48_i111:dq(33)"
				( attribute "PN" "242"
					( Origin gPackager )
				)
				( objectStatus "J6U2.242" )
			)
			( pin "@baseboard_fab2_lib.baseboard_fab2(sch_1):page48_i111:dq(34)"
				( attribute "PN" "104"
					( Origin gPackager )
				)
				( objectStatus "J6U2.104" )
			)
			( pin "@baseboard_fab2_lib.baseboard_fab2(sch_1):page48_i111:dq(35)"
				( attribute "PN" "249"
					( Origin gPackager )
				)
				( objectStatus "J6U2.249" )
			)
			( pin "@baseboard_fab2_lib.baseboard_fab2(sch_1):page48_i111:dq(36)"
				( attribute "PN" "95"
					( Origin gPackager )
				)
				( objectStatus "J6U2.95" )
			)
			( pin "@baseboard_fab2_lib.baseboard_fab2(sch_1):page48_i111:dq(37)"
				( attribute "PN" "240"
					( Origin gPackager )
				)
				( objectStatus "J6U2.240" )
			)
			( pin "@baseboard_fab2_lib.baseboard_fab2(sch_1):page48_i111:dq(38)"
				( attribute "PN" "102"
					( Origin gPackager )
				)
				( objectStatus "J6U2.102" )
			)
			( pin "@baseboard_fab2_lib.baseboard_fab2(sch_1):page48_i111:dq(39)"
				( attribute "PN" "247"
					( Origin gPackager )
				)
				( objectStatus "J6U2.247" )
			)
			( pin "@baseboard_fab2_lib.baseboard_fab2(sch_1):page48_i111:dq(40)"
				( attribute "PN" "108"
					( Origin gPackager )
				)
				( objectStatus "J6U2.108" )
			)
			( pin "@baseboard_fab2_lib.baseboard_fab2(sch_1):page48_i111:dq(41)"
				( attribute "PN" "253"
					( Origin gPackager )
				)
				( objectStatus "J6U2.253" )
			)
			( pin "@baseboard_fab2_lib.baseboard_fab2(sch_1):page48_i111:dq(42)"
				( attribute "PN" "115"
					( Origin gPackager )
				)
				( objectStatus "J6U2.115" )
			)
			( pin "@baseboard_fab2_lib.baseboard_fab2(sch_1):page48_i111:dq(43)"
				( attribute "PN" "260"
					( Origin gPackager )
				)
				( objectStatus "J6U2.260" )
			)
			( pin "@baseboard_fab2_lib.baseboard_fab2(sch_1):page48_i111:dq(44)"
				( attribute "PN" "106"
					( Origin gPackager )
				)
				( objectStatus "J6U2.106" )
			)
			( pin "@baseboard_fab2_lib.baseboard_fab2(sch_1):page48_i111:dq(45)"
				( attribute "PN" "251"
					( Origin gPackager )
				)
				( objectStatus "J6U2.251" )
			)
			( pin "@baseboard_fab2_lib.baseboard_fab2(sch_1):page48_i111:dq(46)"
				( attribute "PN" "113"
					( Origin gPackager )
				)
				( objectStatus "J6U2.113" )
			)
			( pin "@baseboard_fab2_lib.baseboard_fab2(sch_1):page48_i111:dq(47)"
				( attribute "PN" "258"
					( Origin gPackager )
				)
				( objectStatus "J6U2.258" )
			)
			( pin "@baseboard_fab2_lib.baseboard_fab2(sch_1):page48_i111:dq(48)"
				( attribute "PN" "119"
					( Origin gPackager )
				)
				( objectStatus "J6U2.119" )
			)
			( pin "@baseboard_fab2_lib.baseboard_fab2(sch_1):page48_i111:dq(49)"
				( attribute "PN" "264"
					( Origin gPackager )
				)
				( objectStatus "J6U2.264" )
			)
			( pin "@baseboard_fab2_lib.baseboard_fab2(sch_1):page48_i111:dq(50)"
				( attribute "PN" "126"
					( Origin gPackager )
				)
				( objectStatus "J6U2.126" )
			)
			( pin "@baseboard_fab2_lib.baseboard_fab2(sch_1):page48_i111:dq(51)"
				( attribute "PN" "271"
					( Origin gPackager )
				)
				( objectStatus "J6U2.271" )
			)
			( pin "@baseboard_fab2_lib.baseboard_fab2(sch_1):page48_i111:dq(52)"
				( attribute "PN" "117"
					( Origin gPackager )
				)
				( objectStatus "J6U2.117" )
			)
			( pin "@baseboard_fab2_lib.baseboard_fab2(sch_1):page48_i111:dq(53)"
				( attribute "PN" "262"
					( Origin gPackager )
				)
				( objectStatus "J6U2.262" )
			)
			( pin "@baseboard_fab2_lib.baseboard_fab2(sch_1):page48_i111:dq(54)"
				( attribute "PN" "124"
					( Origin gPackager )
				)
				( objectStatus "J6U2.124" )
			)
			( pin "@baseboard_fab2_lib.baseboard_fab2(sch_1):page48_i111:dq(55)"
				( attribute "PN" "269"
					( Origin gPackager )
				)
				( objectStatus "J6U2.269" )
			)
			( pin "@baseboard_fab2_lib.baseboard_fab2(sch_1):page48_i111:dq(56)"
				( attribute "PN" "130"
					( Origin gPackager )
				)
				( objectStatus "J6U2.130" )
			)
			( pin "@baseboard_fab2_lib.baseboard_fab2(sch_1):page48_i111:dq(57)"
				( attribute "PN" "275"
					( Origin gPackager )
				)
				( objectStatus "J6U2.275" )
			)
			( pin "@baseboard_fab2_lib.baseboard_fab2(sch_1):page48_i111:dq(58)"
				( attribute "PN" "137"
					( Origin gPackager )
				)
				( objectStatus "J6U2.137" )
			)
			( pin "@baseboard_fab2_lib.baseboard_fab2(sch_1):page48_i111:dq(59)"
				( attribute "PN" "282"
					( Origin gPackager )
				)
				( objectStatus "J6U2.282" )
			)
			( pin "@baseboard_fab2_lib.baseboard_fab2(sch_1):page48_i111:dq(60)"
				( attribute "PN" "128"
					( Origin gPackager )
				)
				( objectStatus "J6U2.128" )
			)
			( pin "@baseboard_fab2_lib.baseboard_fab2(sch_1):page48_i111:dq(61)"
				( attribute "PN" "273"
					( Origin gPackager )
				)
				( objectStatus "J6U2.273" )
			)
			( pin "@baseboard_fab2_lib.baseboard_fab2(sch_1):page48_i111:dq(62)"
				( attribute "PN" "135"
					( Origin gPackager )
				)
				( objectStatus "J6U2.135" )
			)
			( pin "@baseboard_fab2_lib.baseboard_fab2(sch_1):page48_i111:dq(63)"
				( attribute "PN" "280"
					( Origin gPackager )
				)
				( objectStatus "J6U2.280" )
			)
			( pin "@baseboard_fab2_lib.baseboard_fab2(sch_1):page48_i111:event_n"
				( attribute "PN" "78"
					( Origin gPackager )
				)
				( objectStatus "J6U2.78" )
			)
			( pin "@baseboard_fab2_lib.baseboard_fab2(sch_1):page48_i111:odt(0)"
				( attribute "PN" "87"
					( Origin gPackager )
				)
				( objectStatus "J6U2.87" )
			)
			( pin "@baseboard_fab2_lib.baseboard_fab2(sch_1):page48_i111:odt(1)"
				( attribute "PN" "91"
					( Origin gPackager )
				)
				( objectStatus "J6U2.91" )
			)
			( pin "@baseboard_fab2_lib.baseboard_fab2(sch_1):page48_i111:par"
				( attribute "PN" "222"
					( Origin gPackager )
				)
				( objectStatus "J6U2.222" )
			)
			( pin "@baseboard_fab2_lib.baseboard_fab2(sch_1):page48_i111:reset_n"
				( attribute "PN" "58"
					( Origin gPackager )
				)
				( objectStatus "J6U2.58" )
			)
			( pin "@baseboard_fab2_lib.baseboard_fab2(sch_1):page48_i111:rfu(0)"
				( attribute "PN" "205"
					( Origin gPackager )
				)
				( objectStatus "J6U2.205" )
			)
			( pin "@baseboard_fab2_lib.baseboard_fab2(sch_1):page48_i111:rfu(1)"
				( attribute "PN" "227"
					( Origin gPackager )
				)
				( objectStatus "J6U2.227" )
			)
			( pin "@baseboard_fab2_lib.baseboard_fab2(sch_1):page48_i111:rfu(2)"
				( attribute "PN" "144"
					( Origin gPackager )
				)
				( objectStatus "J6U2.144" )
			)
			( pin "@baseboard_fab2_lib.baseboard_fab2(sch_1):page48_i111:s0_n"
				( attribute "PN" "84"
					( Origin gPackager )
				)
				( objectStatus "J6U2.84" )
			)
			( pin "@baseboard_fab2_lib.baseboard_fab2(sch_1):page48_i111:s1_n"
				( attribute "PN" "89"
					( Origin gPackager )
				)
				( objectStatus "J6U2.89" )
			)
			( pin "@baseboard_fab2_lib.baseboard_fab2(sch_1):page48_i111:s2_n_c(0)"
				( attribute "PN" "93"
					( Origin gPackager )
				)
				( objectStatus "J6U2.93" )
			)
			( pin "@baseboard_fab2_lib.baseboard_fab2(sch_1):page48_i111:s3_n_c(1)"
				( attribute "PN" "237"
					( Origin gPackager )
				)
				( objectStatus "J6U2.237" )
			)
			( pin "@baseboard_fab2_lib.baseboard_fab2(sch_1):page48_i111:sa(0)"
				( attribute "PN" "139"
					( Origin gPackager )
				)
				( objectStatus "J6U2.139" )
			)
			( pin "@baseboard_fab2_lib.baseboard_fab2(sch_1):page48_i111:sa(1)"
				( attribute "PN" "140"
					( Origin gPackager )
				)
				( objectStatus "J6U2.140" )
			)
			( pin "@baseboard_fab2_lib.baseboard_fab2(sch_1):page48_i111:sa(2)"
				( attribute "PN" "238"
					( Origin gPackager )
				)
				( objectStatus "J6U2.238" )
			)
			( pin "@baseboard_fab2_lib.baseboard_fab2(sch_1):page48_i111:save_n_nc"
				( attribute "PN" "230"
					( Origin gPackager )
				)
				( objectStatus "J6U2.230" )
			)
			( pin "@baseboard_fab2_lib.baseboard_fab2(sch_1):page48_i111:scl"
				( attribute "PN" "141"
					( Origin gPackager )
				)
				( objectStatus "J6U2.141" )
			)
			( pin "@baseboard_fab2_lib.baseboard_fab2(sch_1):page48_i111:sda"
				( attribute "PN" "285"
					( Origin gPackager )
				)
				( objectStatus "J6U2.285" )
			)
			( pin "@baseboard_fab2_lib.baseboard_fab2(sch_1):page48_i111:vddspd"
				( attribute "PN" "284"
					( Origin gPackager )
				)
				( objectStatus "J6U2.284" )
			)
			( pin "@baseboard_fab2_lib.baseboard_fab2(sch_1):page48_i111:vrefca"
				( attribute "PN" "146"
					( Origin gPackager )
				)
				( objectStatus "J6U2.146" )
			)
			( pin "@baseboard_fab2_lib.baseboard_fab2(sch_1):page48_i171:\12v\(0)"
				( attribute "PN" "145"
					( Origin gPackager )
				)
				( objectStatus "J6U2.145" )
			)
			( pin "@baseboard_fab2_lib.baseboard_fab2(sch_1):page48_i171:\12v\(1)"
				( attribute "PN" "1"
					( Origin gPackager )
				)
				( objectStatus "J6U2.1" )
			)
			( pin "@baseboard_fab2_lib.baseboard_fab2(sch_1):page48_i171:vdd(0)"
				( attribute "PN" "236"
					( Origin gPackager )
				)
				( objectStatus "J6U2.236" )
			)
			( pin "@baseboard_fab2_lib.baseboard_fab2(sch_1):page48_i171:vdd(1)"
				( attribute "PN" "233"
					( Origin gPackager )
				)
				( objectStatus "J6U2.233" )
			)
			( pin "@baseboard_fab2_lib.baseboard_fab2(sch_1):page48_i171:vdd(2)"
				( attribute "PN" "231"
					( Origin gPackager )
				)
				( objectStatus "J6U2.231" )
			)
			( pin "@baseboard_fab2_lib.baseboard_fab2(sch_1):page48_i171:vdd(3)"
				( attribute "PN" "229"
					( Origin gPackager )
				)
				( objectStatus "J6U2.229" )
			)
			( pin "@baseboard_fab2_lib.baseboard_fab2(sch_1):page48_i171:vdd(4)"
				( attribute "PN" "226"
					( Origin gPackager )
				)
				( objectStatus "J6U2.226" )
			)
			( pin "@baseboard_fab2_lib.baseboard_fab2(sch_1):page48_i171:vdd(5)"
				( attribute "PN" "223"
					( Origin gPackager )
				)
				( objectStatus "J6U2.223" )
			)
			( pin "@baseboard_fab2_lib.baseboard_fab2(sch_1):page48_i171:vdd(6)"
				( attribute "PN" "220"
					( Origin gPackager )
				)
				( objectStatus "J6U2.220" )
			)
			( pin "@baseboard_fab2_lib.baseboard_fab2(sch_1):page48_i171:vdd(7)"
				( attribute "PN" "217"
					( Origin gPackager )
				)
				( objectStatus "J6U2.217" )
			)
			( pin "@baseboard_fab2_lib.baseboard_fab2(sch_1):page48_i171:vdd(8)"
				( attribute "PN" "215"
					( Origin gPackager )
				)
				( objectStatus "J6U2.215" )
			)
			( pin "@baseboard_fab2_lib.baseboard_fab2(sch_1):page48_i171:vdd(9)"
				( attribute "PN" "212"
					( Origin gPackager )
				)
				( objectStatus "J6U2.212" )
			)
			( pin "@baseboard_fab2_lib.baseboard_fab2(sch_1):page48_i171:vdd(10)"
				( attribute "PN" "209"
					( Origin gPackager )
				)
				( objectStatus "J6U2.209" )
			)
			( pin "@baseboard_fab2_lib.baseboard_fab2(sch_1):page48_i171:vdd(11)"
				( attribute "PN" "206"
					( Origin gPackager )
				)
				( objectStatus "J6U2.206" )
			)
			( pin "@baseboard_fab2_lib.baseboard_fab2(sch_1):page48_i171:vdd(12)"
				( attribute "PN" "204"
					( Origin gPackager )
				)
				( objectStatus "J6U2.204" )
			)
			( pin "@baseboard_fab2_lib.baseboard_fab2(sch_1):page48_i171:vdd(13)"
				( attribute "PN" "92"
					( Origin gPackager )
				)
				( objectStatus "J6U2.92" )
			)
			( pin "@baseboard_fab2_lib.baseboard_fab2(sch_1):page48_i171:vdd(14)"
				( attribute "PN" "90"
					( Origin gPackager )
				)
				( objectStatus "J6U2.90" )
			)
			( pin "@baseboard_fab2_lib.baseboard_fab2(sch_1):page48_i171:vdd(15)"
				( attribute "PN" "88"
					( Origin gPackager )
				)
				( objectStatus "J6U2.88" )
			)
			( pin "@baseboard_fab2_lib.baseboard_fab2(sch_1):page48_i171:vdd(16)"
				( attribute "PN" "85"
					( Origin gPackager )
				)
				( objectStatus "J6U2.85" )
			)
			( pin "@baseboard_fab2_lib.baseboard_fab2(sch_1):page48_i171:vdd(17)"
				( attribute "PN" "83"
					( Origin gPackager )
				)
				( objectStatus "J6U2.83" )
			)
			( pin "@baseboard_fab2_lib.baseboard_fab2(sch_1):page48_i171:vdd(18)"
				( attribute "PN" "80"
					( Origin gPackager )
				)
				( objectStatus "J6U2.80" )
			)
			( pin "@baseboard_fab2_lib.baseboard_fab2(sch_1):page48_i171:vdd(19)"
				( attribute "PN" "76"
					( Origin gPackager )
				)
				( objectStatus "J6U2.76" )
			)
			( pin "@baseboard_fab2_lib.baseboard_fab2(sch_1):page48_i171:vdd(20)"
				( attribute "PN" "73"
					( Origin gPackager )
				)
				( objectStatus "J6U2.73" )
			)
			( pin "@baseboard_fab2_lib.baseboard_fab2(sch_1):page48_i171:vdd(21)"
				( attribute "PN" "70"
					( Origin gPackager )
				)
				( objectStatus "J6U2.70" )
			)
			( pin "@baseboard_fab2_lib.baseboard_fab2(sch_1):page48_i171:vdd(22)"
				( attribute "PN" "67"
					( Origin gPackager )
				)
				( objectStatus "J6U2.67" )
			)
			( pin "@baseboard_fab2_lib.baseboard_fab2(sch_1):page48_i171:vdd(23)"
				( attribute "PN" "64"
					( Origin gPackager )
				)
				( objectStatus "J6U2.64" )
			)
			( pin "@baseboard_fab2_lib.baseboard_fab2(sch_1):page48_i171:vdd(24)"
				( attribute "PN" "61"
					( Origin gPackager )
				)
				( objectStatus "J6U2.61" )
			)
			( pin "@baseboard_fab2_lib.baseboard_fab2(sch_1):page48_i171:vdd(25)"
				( attribute "PN" "59"
					( Origin gPackager )
				)
				( objectStatus "J6U2.59" )
			)
			( pin "@baseboard_fab2_lib.baseboard_fab2(sch_1):page48_i171:vpp(0)"
				( attribute "PN" "287"
					( Origin gPackager )
				)
				( objectStatus "J6U2.287" )
			)
			( pin "@baseboard_fab2_lib.baseboard_fab2(sch_1):page48_i171:vpp(1)"
				( attribute "PN" "286"
					( Origin gPackager )
				)
				( objectStatus "J6U2.286" )
			)
			( pin "@baseboard_fab2_lib.baseboard_fab2(sch_1):page48_i171:vpp(2)"
				( attribute "PN" "288"
					( Origin gPackager )
				)
				( objectStatus "J6U2.288" )
			)
			( pin "@baseboard_fab2_lib.baseboard_fab2(sch_1):page48_i171:vpp(3)"
				( attribute "PN" "143"
					( Origin gPackager )
				)
				( objectStatus "J6U2.143" )
			)
			( pin "@baseboard_fab2_lib.baseboard_fab2(sch_1):page48_i171:vpp(4)"
				( attribute "PN" "142"
					( Origin gPackager )
				)
				( objectStatus "J6U2.142" )
			)
			( pin "@baseboard_fab2_lib.baseboard_fab2(sch_1):page48_i171:vtt(0)"
				( attribute "PN" "221"
					( Origin gPackager )
				)
				( objectStatus "J6U2.221" )
			)
			( pin "@baseboard_fab2_lib.baseboard_fab2(sch_1):page48_i171:vtt(1)"
				( attribute "PN" "77"
					( Origin gPackager )
				)
				( objectStatus "J6U2.77" )
			)
			( pin "@baseboard_fab2_lib.baseboard_fab2(sch_1):page48_i176:a"
				( attribute "PN" "1"
					( Origin gPackager )
				)
				( objectStatus "C6U17.1" )
			)
			( pin "@baseboard_fab2_lib.baseboard_fab2(sch_1):page48_i176:b"
				( attribute "PN" "2"
					( Origin gPackager )
				)
				( objectStatus "C6U17.2" )
			)
			( pin "@baseboard_fab2_lib.baseboard_fab2(sch_1):page49_i43:vss(0)"
				( attribute "PN" "283"
					( Origin gPackager )
				)
				( objectStatus "J4B1.283" )
			)
			( pin "@baseboard_fab2_lib.baseboard_fab2(sch_1):page49_i43:vss(1)"
				( attribute "PN" "281"
					( Origin gPackager )
				)
				( objectStatus "J4B1.281" )
			)
			( pin "@baseboard_fab2_lib.baseboard_fab2(sch_1):page49_i43:vss(2)"
				( attribute "PN" "279"
					( Origin gPackager )
				)
				( objectStatus "J4B1.279" )
			)
			( pin "@baseboard_fab2_lib.baseboard_fab2(sch_1):page49_i43:vss(3)"
				( attribute "PN" "276"
					( Origin gPackager )
				)
				( objectStatus "J4B1.276" )
			)
			( pin "@baseboard_fab2_lib.baseboard_fab2(sch_1):page49_i43:vss(4)"
				( attribute "PN" "274"
					( Origin gPackager )
				)
				( objectStatus "J4B1.274" )
			)
			( pin "@baseboard_fab2_lib.baseboard_fab2(sch_1):page49_i43:vss(5)"
				( attribute "PN" "272"
					( Origin gPackager )
				)
				( objectStatus "J4B1.272" )
			)
			( pin "@baseboard_fab2_lib.baseboard_fab2(sch_1):page49_i43:vss(6)"
				( attribute "PN" "270"
					( Origin gPackager )
				)
				( objectStatus "J4B1.270" )
			)
			( pin "@baseboard_fab2_lib.baseboard_fab2(sch_1):page49_i43:vss(7)"
				( attribute "PN" "268"
					( Origin gPackager )
				)
				( objectStatus "J4B1.268" )
			)
			( pin "@baseboard_fab2_lib.baseboard_fab2(sch_1):page49_i43:vss(8)"
				( attribute "PN" "265"
					( Origin gPackager )
				)
				( objectStatus "J4B1.265" )
			)
			( pin "@baseboard_fab2_lib.baseboard_fab2(sch_1):page49_i43:vss(9)"
				( attribute "PN" "263"
					( Origin gPackager )
				)
				( objectStatus "J4B1.263" )
			)
			( pin "@baseboard_fab2_lib.baseboard_fab2(sch_1):page49_i43:vss(10)"
				( attribute "PN" "261"
					( Origin gPackager )
				)
				( objectStatus "J4B1.261" )
			)
			( pin "@baseboard_fab2_lib.baseboard_fab2(sch_1):page49_i43:vss(11)"
				( attribute "PN" "259"
					( Origin gPackager )
				)
				( objectStatus "J4B1.259" )
			)
			( pin "@baseboard_fab2_lib.baseboard_fab2(sch_1):page49_i43:vss(12)"
				( attribute "PN" "257"
					( Origin gPackager )
				)
				( objectStatus "J4B1.257" )
			)
			( pin "@baseboard_fab2_lib.baseboard_fab2(sch_1):page49_i43:vss(13)"
				( attribute "PN" "254"
					( Origin gPackager )
				)
				( objectStatus "J4B1.254" )
			)
			( pin "@baseboard_fab2_lib.baseboard_fab2(sch_1):page49_i43:vss(14)"
				( attribute "PN" "252"
					( Origin gPackager )
				)
				( objectStatus "J4B1.252" )
			)
			( pin "@baseboard_fab2_lib.baseboard_fab2(sch_1):page49_i43:vss(15)"
				( attribute "PN" "250"
					( Origin gPackager )
				)
				( objectStatus "J4B1.250" )
			)
			( pin "@baseboard_fab2_lib.baseboard_fab2(sch_1):page49_i43:vss(16)"
				( attribute "PN" "248"
					( Origin gPackager )
				)
				( objectStatus "J4B1.248" )
			)
			( pin "@baseboard_fab2_lib.baseboard_fab2(sch_1):page49_i43:vss(17)"
				( attribute "PN" "246"
					( Origin gPackager )
				)
				( objectStatus "J4B1.246" )
			)
			( pin "@baseboard_fab2_lib.baseboard_fab2(sch_1):page49_i43:vss(18)"
				( attribute "PN" "243"
					( Origin gPackager )
				)
				( objectStatus "J4B1.243" )
			)
			( pin "@baseboard_fab2_lib.baseboard_fab2(sch_1):page49_i43:vss(19)"
				( attribute "PN" "241"
					( Origin gPackager )
				)
				( objectStatus "J4B1.241" )
			)
			( pin "@baseboard_fab2_lib.baseboard_fab2(sch_1):page49_i43:vss(20)"
				( attribute "PN" "239"
					( Origin gPackager )
				)
				( objectStatus "J4B1.239" )
			)
			( pin "@baseboard_fab2_lib.baseboard_fab2(sch_1):page49_i43:vss(21)"
				( attribute "PN" "202"
					( Origin gPackager )
				)
				( objectStatus "J4B1.202" )
			)
			( pin "@baseboard_fab2_lib.baseboard_fab2(sch_1):page49_i43:vss(22)"
				( attribute "PN" "200"
					( Origin gPackager )
				)
				( objectStatus "J4B1.200" )
			)
			( pin "@baseboard_fab2_lib.baseboard_fab2(sch_1):page49_i43:vss(23)"
				( attribute "PN" "198"
					( Origin gPackager )
				)
				( objectStatus "J4B1.198" )
			)
			( pin "@baseboard_fab2_lib.baseboard_fab2(sch_1):page49_i43:vss(24)"
				( attribute "PN" "195"
					( Origin gPackager )
				)
				( objectStatus "J4B1.195" )
			)
			( pin "@baseboard_fab2_lib.baseboard_fab2(sch_1):page49_i43:vss(25)"
				( attribute "PN" "193"
					( Origin gPackager )
				)
				( objectStatus "J4B1.193" )
			)
			( pin "@baseboard_fab2_lib.baseboard_fab2(sch_1):page49_i43:vss(26)"
				( attribute "PN" "191"
					( Origin gPackager )
				)
				( objectStatus "J4B1.191" )
			)
			( pin "@baseboard_fab2_lib.baseboard_fab2(sch_1):page49_i43:vss(27)"
				( attribute "PN" "189"
					( Origin gPackager )
				)
				( objectStatus "J4B1.189" )
			)
			( pin "@baseboard_fab2_lib.baseboard_fab2(sch_1):page49_i43:vss(28)"
				( attribute "PN" "187"
					( Origin gPackager )
				)
				( objectStatus "J4B1.187" )
			)
			( pin "@baseboard_fab2_lib.baseboard_fab2(sch_1):page49_i43:vss(29)"
				( attribute "PN" "184"
					( Origin gPackager )
				)
				( objectStatus "J4B1.184" )
			)
			( pin "@baseboard_fab2_lib.baseboard_fab2(sch_1):page49_i43:vss(30)"
				( attribute "PN" "182"
					( Origin gPackager )
				)
				( objectStatus "J4B1.182" )
			)
			( pin "@baseboard_fab2_lib.baseboard_fab2(sch_1):page49_i43:vss(31)"
				( attribute "PN" "180"
					( Origin gPackager )
				)
				( objectStatus "J4B1.180" )
			)
			( pin "@baseboard_fab2_lib.baseboard_fab2(sch_1):page49_i43:vss(32)"
				( attribute "PN" "178"
					( Origin gPackager )
				)
				( objectStatus "J4B1.178" )
			)
			( pin "@baseboard_fab2_lib.baseboard_fab2(sch_1):page49_i43:vss(33)"
				( attribute "PN" "176"
					( Origin gPackager )
				)
				( objectStatus "J4B1.176" )
			)
			( pin "@baseboard_fab2_lib.baseboard_fab2(sch_1):page49_i43:vss(34)"
				( attribute "PN" "173"
					( Origin gPackager )
				)
				( objectStatus "J4B1.173" )
			)
			( pin "@baseboard_fab2_lib.baseboard_fab2(sch_1):page49_i43:vss(35)"
				( attribute "PN" "171"
					( Origin gPackager )
				)
				( objectStatus "J4B1.171" )
			)
			( pin "@baseboard_fab2_lib.baseboard_fab2(sch_1):page49_i43:vss(36)"
				( attribute "PN" "169"
					( Origin gPackager )
				)
				( objectStatus "J4B1.169" )
			)
			( pin "@baseboard_fab2_lib.baseboard_fab2(sch_1):page49_i43:vss(37)"
				( attribute "PN" "167"
					( Origin gPackager )
				)
				( objectStatus "J4B1.167" )
			)
			( pin "@baseboard_fab2_lib.baseboard_fab2(sch_1):page49_i43:vss(38)"
				( attribute "PN" "165"
					( Origin gPackager )
				)
				( objectStatus "J4B1.165" )
			)
			( pin "@baseboard_fab2_lib.baseboard_fab2(sch_1):page49_i43:vss(39)"
				( attribute "PN" "162"
					( Origin gPackager )
				)
				( objectStatus "J4B1.162" )
			)
			( pin "@baseboard_fab2_lib.baseboard_fab2(sch_1):page49_i43:vss(40)"
				( attribute "PN" "160"
					( Origin gPackager )
				)
				( objectStatus "J4B1.160" )
			)
			( pin "@baseboard_fab2_lib.baseboard_fab2(sch_1):page49_i43:vss(41)"
				( attribute "PN" "158"
					( Origin gPackager )
				)
				( objectStatus "J4B1.158" )
			)
			( pin "@baseboard_fab2_lib.baseboard_fab2(sch_1):page49_i43:vss(42)"
				( attribute "PN" "156"
					( Origin gPackager )
				)
				( objectStatus "J4B1.156" )
			)
			( pin "@baseboard_fab2_lib.baseboard_fab2(sch_1):page49_i43:vss(43)"
				( attribute "PN" "154"
					( Origin gPackager )
				)
				( objectStatus "J4B1.154" )
			)
			( pin "@baseboard_fab2_lib.baseboard_fab2(sch_1):page49_i43:vss(44)"
				( attribute "PN" "151"
					( Origin gPackager )
				)
				( objectStatus "J4B1.151" )
			)
			( pin "@baseboard_fab2_lib.baseboard_fab2(sch_1):page49_i43:vss(45)"
				( attribute "PN" "149"
					( Origin gPackager )
				)
				( objectStatus "J4B1.149" )
			)
			( pin "@baseboard_fab2_lib.baseboard_fab2(sch_1):page49_i43:vss(46)"
				( attribute "PN" "147"
					( Origin gPackager )
				)
				( objectStatus "J4B1.147" )
			)
			( pin "@baseboard_fab2_lib.baseboard_fab2(sch_1):page49_i43:vss(47)"
				( attribute "PN" "138"
					( Origin gPackager )
				)
				( objectStatus "J4B1.138" )
			)
			( pin "@baseboard_fab2_lib.baseboard_fab2(sch_1):page49_i43:vss(48)"
				( attribute "PN" "136"
					( Origin gPackager )
				)
				( objectStatus "J4B1.136" )
			)
			( pin "@baseboard_fab2_lib.baseboard_fab2(sch_1):page49_i43:vss(49)"
				( attribute "PN" "134"
					( Origin gPackager )
				)
				( objectStatus "J4B1.134" )
			)
			( pin "@baseboard_fab2_lib.baseboard_fab2(sch_1):page49_i43:vss(50)"
				( attribute "PN" "131"
					( Origin gPackager )
				)
				( objectStatus "J4B1.131" )
			)
			( pin "@baseboard_fab2_lib.baseboard_fab2(sch_1):page49_i43:vss(51)"
				( attribute "PN" "129"
					( Origin gPackager )
				)
				( objectStatus "J4B1.129" )
			)
			( pin "@baseboard_fab2_lib.baseboard_fab2(sch_1):page49_i43:vss(52)"
				( attribute "PN" "127"
					( Origin gPackager )
				)
				( objectStatus "J4B1.127" )
			)
			( pin "@baseboard_fab2_lib.baseboard_fab2(sch_1):page49_i43:vss(53)"
				( attribute "PN" "125"
					( Origin gPackager )
				)
				( objectStatus "J4B1.125" )
			)
			( pin "@baseboard_fab2_lib.baseboard_fab2(sch_1):page49_i43:vss(54)"
				( attribute "PN" "123"
					( Origin gPackager )
				)
				( objectStatus "J4B1.123" )
			)
			( pin "@baseboard_fab2_lib.baseboard_fab2(sch_1):page49_i43:vss(55)"
				( attribute "PN" "120"
					( Origin gPackager )
				)
				( objectStatus "J4B1.120" )
			)
			( pin "@baseboard_fab2_lib.baseboard_fab2(sch_1):page49_i43:vss(56)"
				( attribute "PN" "118"
					( Origin gPackager )
				)
				( objectStatus "J4B1.118" )
			)
			( pin "@baseboard_fab2_lib.baseboard_fab2(sch_1):page49_i43:vss(57)"
				( attribute "PN" "116"
					( Origin gPackager )
				)
				( objectStatus "J4B1.116" )
			)
			( pin "@baseboard_fab2_lib.baseboard_fab2(sch_1):page49_i43:vss(58)"
				( attribute "PN" "114"
					( Origin gPackager )
				)
				( objectStatus "J4B1.114" )
			)
			( pin "@baseboard_fab2_lib.baseboard_fab2(sch_1):page49_i43:vss(59)"
				( attribute "PN" "112"
					( Origin gPackager )
				)
				( objectStatus "J4B1.112" )
			)
			( pin "@baseboard_fab2_lib.baseboard_fab2(sch_1):page49_i43:vss(60)"
				( attribute "PN" "109"
					( Origin gPackager )
				)
				( objectStatus "J4B1.109" )
			)
			( pin "@baseboard_fab2_lib.baseboard_fab2(sch_1):page49_i43:vss(61)"
				( attribute "PN" "107"
					( Origin gPackager )
				)
				( objectStatus "J4B1.107" )
			)
			( pin "@baseboard_fab2_lib.baseboard_fab2(sch_1):page49_i43:vss(62)"
				( attribute "PN" "105"
					( Origin gPackager )
				)
				( objectStatus "J4B1.105" )
			)
			( pin "@baseboard_fab2_lib.baseboard_fab2(sch_1):page49_i43:vss(63)"
				( attribute "PN" "103"
					( Origin gPackager )
				)
				( objectStatus "J4B1.103" )
			)
			( pin "@baseboard_fab2_lib.baseboard_fab2(sch_1):page49_i43:vss(64)"
				( attribute "PN" "101"
					( Origin gPackager )
				)
				( objectStatus "J4B1.101" )
			)
			( pin "@baseboard_fab2_lib.baseboard_fab2(sch_1):page49_i43:vss(65)"
				( attribute "PN" "98"
					( Origin gPackager )
				)
				( objectStatus "J4B1.98" )
			)
			( pin "@baseboard_fab2_lib.baseboard_fab2(sch_1):page49_i43:vss(66)"
				( attribute "PN" "96"
					( Origin gPackager )
				)
				( objectStatus "J4B1.96" )
			)
			( pin "@baseboard_fab2_lib.baseboard_fab2(sch_1):page49_i43:vss(67)"
				( attribute "PN" "94"
					( Origin gPackager )
				)
				( objectStatus "J4B1.94" )
			)
			( pin "@baseboard_fab2_lib.baseboard_fab2(sch_1):page49_i43:vss(68)"
				( attribute "PN" "57"
					( Origin gPackager )
				)
				( objectStatus "J4B1.57" )
			)
			( pin "@baseboard_fab2_lib.baseboard_fab2(sch_1):page49_i43:vss(69)"
				( attribute "PN" "55"
					( Origin gPackager )
				)
				( objectStatus "J4B1.55" )
			)
			( pin "@baseboard_fab2_lib.baseboard_fab2(sch_1):page49_i43:vss(70)"
				( attribute "PN" "53"
					( Origin gPackager )
				)
				( objectStatus "J4B1.53" )
			)
			( pin "@baseboard_fab2_lib.baseboard_fab2(sch_1):page49_i43:vss(71)"
				( attribute "PN" "50"
					( Origin gPackager )
				)
				( objectStatus "J4B1.50" )
			)
			( pin "@baseboard_fab2_lib.baseboard_fab2(sch_1):page49_i43:vss(72)"
				( attribute "PN" "48"
					( Origin gPackager )
				)
				( objectStatus "J4B1.48" )
			)
			( pin "@baseboard_fab2_lib.baseboard_fab2(sch_1):page49_i43:vss(73)"
				( attribute "PN" "46"
					( Origin gPackager )
				)
				( objectStatus "J4B1.46" )
			)
			( pin "@baseboard_fab2_lib.baseboard_fab2(sch_1):page49_i43:vss(74)"
				( attribute "PN" "44"
					( Origin gPackager )
				)
				( objectStatus "J4B1.44" )
			)
			( pin "@baseboard_fab2_lib.baseboard_fab2(sch_1):page49_i43:vss(75)"
				( attribute "PN" "42"
					( Origin gPackager )
				)
				( objectStatus "J4B1.42" )
			)
			( pin "@baseboard_fab2_lib.baseboard_fab2(sch_1):page49_i43:vss(76)"
				( attribute "PN" "39"
					( Origin gPackager )
				)
				( objectStatus "J4B1.39" )
			)
			( pin "@baseboard_fab2_lib.baseboard_fab2(sch_1):page49_i43:vss(77)"
				( attribute "PN" "37"
					( Origin gPackager )
				)
				( objectStatus "J4B1.37" )
			)
			( pin "@baseboard_fab2_lib.baseboard_fab2(sch_1):page49_i43:vss(78)"
				( attribute "PN" "35"
					( Origin gPackager )
				)
				( objectStatus "J4B1.35" )
			)
			( pin "@baseboard_fab2_lib.baseboard_fab2(sch_1):page49_i43:vss(79)"
				( attribute "PN" "33"
					( Origin gPackager )
				)
				( objectStatus "J4B1.33" )
			)
			( pin "@baseboard_fab2_lib.baseboard_fab2(sch_1):page49_i43:vss(80)"
				( attribute "PN" "31"
					( Origin gPackager )
				)
				( objectStatus "J4B1.31" )
			)
			( pin "@baseboard_fab2_lib.baseboard_fab2(sch_1):page49_i43:vss(81)"
				( attribute "PN" "28"
					( Origin gPackager )
				)
				( objectStatus "J4B1.28" )
			)
			( pin "@baseboard_fab2_lib.baseboard_fab2(sch_1):page49_i43:vss(82)"
				( attribute "PN" "26"
					( Origin gPackager )
				)
				( objectStatus "J4B1.26" )
			)
			( pin "@baseboard_fab2_lib.baseboard_fab2(sch_1):page49_i43:vss(83)"
				( attribute "PN" "24"
					( Origin gPackager )
				)
				( objectStatus "J4B1.24" )
			)
			( pin "@baseboard_fab2_lib.baseboard_fab2(sch_1):page49_i43:vss(84)"
				( attribute "PN" "22"
					( Origin gPackager )
				)
				( objectStatus "J4B1.22" )
			)
			( pin "@baseboard_fab2_lib.baseboard_fab2(sch_1):page49_i43:vss(85)"
				( attribute "PN" "20"
					( Origin gPackager )
				)
				( objectStatus "J4B1.20" )
			)
			( pin "@baseboard_fab2_lib.baseboard_fab2(sch_1):page49_i43:vss(86)"
				( attribute "PN" "17"
					( Origin gPackager )
				)
				( objectStatus "J4B1.17" )
			)
			( pin "@baseboard_fab2_lib.baseboard_fab2(sch_1):page49_i43:vss(87)"
				( attribute "PN" "15"
					( Origin gPackager )
				)
				( objectStatus "J4B1.15" )
			)
			( pin "@baseboard_fab2_lib.baseboard_fab2(sch_1):page49_i43:vss(88)"
				( attribute "PN" "13"
					( Origin gPackager )
				)
				( objectStatus "J4B1.13" )
			)
			( pin "@baseboard_fab2_lib.baseboard_fab2(sch_1):page49_i43:vss(89)"
				( attribute "PN" "11"
					( Origin gPackager )
				)
				( objectStatus "J4B1.11" )
			)
			( pin "@baseboard_fab2_lib.baseboard_fab2(sch_1):page49_i43:vss(90)"
				( attribute "PN" "9"
					( Origin gPackager )
				)
				( objectStatus "J4B1.9" )
			)
			( pin "@baseboard_fab2_lib.baseboard_fab2(sch_1):page49_i43:vss(91)"
				( attribute "PN" "6"
					( Origin gPackager )
				)
				( objectStatus "J4B1.6" )
			)
			( pin "@baseboard_fab2_lib.baseboard_fab2(sch_1):page49_i43:vss(92)"
				( attribute "PN" "4"
					( Origin gPackager )
				)
				( objectStatus "J4B1.4" )
			)
			( pin "@baseboard_fab2_lib.baseboard_fab2(sch_1):page49_i43:vss(93)"
				( attribute "PN" "2"
					( Origin gPackager )
				)
				( objectStatus "J4B1.2" )
			)
			( pin "@baseboard_fab2_lib.baseboard_fab2(sch_1):page49_i66:dqs0n"
				( attribute "PN" "152"
					( Origin gPackager )
				)
				( objectStatus "J4B1.152" )
			)
			( pin "@baseboard_fab2_lib.baseboard_fab2(sch_1):page49_i66:dqs0p"
				( attribute "PN" "153"
					( Origin gPackager )
				)
				( objectStatus "J4B1.153" )
			)
			( pin "@baseboard_fab2_lib.baseboard_fab2(sch_1):page49_i66:dqs1n"
				( attribute "PN" "163"
					( Origin gPackager )
				)
				( objectStatus "J4B1.163" )
			)
			( pin "@baseboard_fab2_lib.baseboard_fab2(sch_1):page49_i66:dqs1p"
				( attribute "PN" "164"
					( Origin gPackager )
				)
				( objectStatus "J4B1.164" )
			)
			( pin "@baseboard_fab2_lib.baseboard_fab2(sch_1):page49_i66:dqs2n"
				( attribute "PN" "174"
					( Origin gPackager )
				)
				( objectStatus "J4B1.174" )
			)
			( pin "@baseboard_fab2_lib.baseboard_fab2(sch_1):page49_i66:dqs2p"
				( attribute "PN" "175"
					( Origin gPackager )
				)
				( objectStatus "J4B1.175" )
			)
			( pin "@baseboard_fab2_lib.baseboard_fab2(sch_1):page49_i66:dqs3n"
				( attribute "PN" "185"
					( Origin gPackager )
				)
				( objectStatus "J4B1.185" )
			)
			( pin "@baseboard_fab2_lib.baseboard_fab2(sch_1):page49_i66:dqs3p"
				( attribute "PN" "186"
					( Origin gPackager )
				)
				( objectStatus "J4B1.186" )
			)
			( pin "@baseboard_fab2_lib.baseboard_fab2(sch_1):page49_i66:dqs4n"
				( attribute "PN" "244"
					( Origin gPackager )
				)
				( objectStatus "J4B1.244" )
			)
			( pin "@baseboard_fab2_lib.baseboard_fab2(sch_1):page49_i66:dqs4p"
				( attribute "PN" "245"
					( Origin gPackager )
				)
				( objectStatus "J4B1.245" )
			)
			( pin "@baseboard_fab2_lib.baseboard_fab2(sch_1):page49_i66:dqs5n"
				( attribute "PN" "255"
					( Origin gPackager )
				)
				( objectStatus "J4B1.255" )
			)
			( pin "@baseboard_fab2_lib.baseboard_fab2(sch_1):page49_i66:dqs5p"
				( attribute "PN" "256"
					( Origin gPackager )
				)
				( objectStatus "J4B1.256" )
			)
			( pin "@baseboard_fab2_lib.baseboard_fab2(sch_1):page49_i66:dqs6n"
				( attribute "PN" "266"
					( Origin gPackager )
				)
				( objectStatus "J4B1.266" )
			)
			( pin "@baseboard_fab2_lib.baseboard_fab2(sch_1):page49_i66:dqs6p"
				( attribute "PN" "267"
					( Origin gPackager )
				)
				( objectStatus "J4B1.267" )
			)
			( pin "@baseboard_fab2_lib.baseboard_fab2(sch_1):page49_i66:dqs7n"
				( attribute "PN" "277"
					( Origin gPackager )
				)
				( objectStatus "J4B1.277" )
			)
			( pin "@baseboard_fab2_lib.baseboard_fab2(sch_1):page49_i66:dqs7p"
				( attribute "PN" "278"
					( Origin gPackager )
				)
				( objectStatus "J4B1.278" )
			)
			( pin "@baseboard_fab2_lib.baseboard_fab2(sch_1):page49_i66:dqs8n"
				( attribute "PN" "196"
					( Origin gPackager )
				)
				( objectStatus "J4B1.196" )
			)
			( pin "@baseboard_fab2_lib.baseboard_fab2(sch_1):page49_i66:dqs8p"
				( attribute "PN" "197"
					( Origin gPackager )
				)
				( objectStatus "J4B1.197" )
			)
			( pin "@baseboard_fab2_lib.baseboard_fab2(sch_1):page49_i66:dqs9n"
				( attribute "PN" "8"
					( Origin gPackager )
				)
				( objectStatus "J4B1.8" )
			)
			( pin "@baseboard_fab2_lib.baseboard_fab2(sch_1):page49_i66:dqs9p"
				( attribute "PN" "7"
					( Origin gPackager )
				)
				( objectStatus "J4B1.7" )
			)
			( pin "@baseboard_fab2_lib.baseboard_fab2(sch_1):page49_i66:dqs10n"
				( attribute "PN" "19"
					( Origin gPackager )
				)
				( objectStatus "J4B1.19" )
			)
			( pin "@baseboard_fab2_lib.baseboard_fab2(sch_1):page49_i66:dqs10p"
				( attribute "PN" "18"
					( Origin gPackager )
				)
				( objectStatus "J4B1.18" )
			)
			( pin "@baseboard_fab2_lib.baseboard_fab2(sch_1):page49_i66:dqs11n"
				( attribute "PN" "30"
					( Origin gPackager )
				)
				( objectStatus "J4B1.30" )
			)
			( pin "@baseboard_fab2_lib.baseboard_fab2(sch_1):page49_i66:dqs11p"
				( attribute "PN" "29"
					( Origin gPackager )
				)
				( objectStatus "J4B1.29" )
			)
			( pin "@baseboard_fab2_lib.baseboard_fab2(sch_1):page49_i66:dqs12n"
				( attribute "PN" "41"
					( Origin gPackager )
				)
				( objectStatus "J4B1.41" )
			)
			( pin "@baseboard_fab2_lib.baseboard_fab2(sch_1):page49_i66:dqs12p"
				( attribute "PN" "40"
					( Origin gPackager )
				)
				( objectStatus "J4B1.40" )
			)
			( pin "@baseboard_fab2_lib.baseboard_fab2(sch_1):page49_i66:dqs13n"
				( attribute "PN" "100"
					( Origin gPackager )
				)
				( objectStatus "J4B1.100" )
			)
			( pin "@baseboard_fab2_lib.baseboard_fab2(sch_1):page49_i66:dqs13p"
				( attribute "PN" "99"
					( Origin gPackager )
				)
				( objectStatus "J4B1.99" )
			)
			( pin "@baseboard_fab2_lib.baseboard_fab2(sch_1):page49_i66:dqs14n"
				( attribute "PN" "111"
					( Origin gPackager )
				)
				( objectStatus "J4B1.111" )
			)
			( pin "@baseboard_fab2_lib.baseboard_fab2(sch_1):page49_i66:dqs14p"
				( attribute "PN" "110"
					( Origin gPackager )
				)
				( objectStatus "J4B1.110" )
			)
			( pin "@baseboard_fab2_lib.baseboard_fab2(sch_1):page49_i66:dqs15n"
				( attribute "PN" "122"
					( Origin gPackager )
				)
				( objectStatus "J4B1.122" )
			)
			( pin "@baseboard_fab2_lib.baseboard_fab2(sch_1):page49_i66:dqs15p"
				( attribute "PN" "121"
					( Origin gPackager )
				)
				( objectStatus "J4B1.121" )
			)
			( pin "@baseboard_fab2_lib.baseboard_fab2(sch_1):page49_i66:dqs16n"
				( attribute "PN" "133"
					( Origin gPackager )
				)
				( objectStatus "J4B1.133" )
			)
			( pin "@baseboard_fab2_lib.baseboard_fab2(sch_1):page49_i66:dqs16p"
				( attribute "PN" "132"
					( Origin gPackager )
				)
				( objectStatus "J4B1.132" )
			)
			( pin "@baseboard_fab2_lib.baseboard_fab2(sch_1):page49_i66:dqs17n"
				( attribute "PN" "52"
					( Origin gPackager )
				)
				( objectStatus "J4B1.52" )
			)
			( pin "@baseboard_fab2_lib.baseboard_fab2(sch_1):page49_i66:dqs17p"
				( attribute "PN" "51"
					( Origin gPackager )
				)
				( objectStatus "J4B1.51" )
			)
			( pin "@baseboard_fab2_lib.baseboard_fab2(sch_1):page49_i111:a0"
				( attribute "PN" "79"
					( Origin gPackager )
				)
				( objectStatus "J4B1.79" )
			)
			( pin "@baseboard_fab2_lib.baseboard_fab2(sch_1):page49_i111:a1"
				( attribute "PN" "72"
					( Origin gPackager )
				)
				( objectStatus "J4B1.72" )
			)
			( pin "@baseboard_fab2_lib.baseboard_fab2(sch_1):page49_i111:a2"
				( attribute "PN" "216"
					( Origin gPackager )
				)
				( objectStatus "J4B1.216" )
			)
			( pin "@baseboard_fab2_lib.baseboard_fab2(sch_1):page49_i111:a3"
				( attribute "PN" "71"
					( Origin gPackager )
				)
				( objectStatus "J4B1.71" )
			)
			( pin "@baseboard_fab2_lib.baseboard_fab2(sch_1):page49_i111:a4"
				( attribute "PN" "214"
					( Origin gPackager )
				)
				( objectStatus "J4B1.214" )
			)
			( pin "@baseboard_fab2_lib.baseboard_fab2(sch_1):page49_i111:a5"
				( attribute "PN" "213"
					( Origin gPackager )
				)
				( objectStatus "J4B1.213" )
			)
			( pin "@baseboard_fab2_lib.baseboard_fab2(sch_1):page49_i111:a6"
				( attribute "PN" "69"
					( Origin gPackager )
				)
				( objectStatus "J4B1.69" )
			)
			( pin "@baseboard_fab2_lib.baseboard_fab2(sch_1):page49_i111:a7"
				( attribute "PN" "211"
					( Origin gPackager )
				)
				( objectStatus "J4B1.211" )
			)
			( pin "@baseboard_fab2_lib.baseboard_fab2(sch_1):page49_i111:a8"
				( attribute "PN" "68"
					( Origin gPackager )
				)
				( objectStatus "J4B1.68" )
			)
			( pin "@baseboard_fab2_lib.baseboard_fab2(sch_1):page49_i111:a9"
				( attribute "PN" "66"
					( Origin gPackager )
				)
				( objectStatus "J4B1.66" )
			)
			( pin "@baseboard_fab2_lib.baseboard_fab2(sch_1):page49_i111:a10"
				( attribute "PN" "225"
					( Origin gPackager )
				)
				( objectStatus "J4B1.225" )
			)
			( pin "@baseboard_fab2_lib.baseboard_fab2(sch_1):page49_i111:a11"
				( attribute "PN" "210"
					( Origin gPackager )
				)
				( objectStatus "J4B1.210" )
			)
			( pin "@baseboard_fab2_lib.baseboard_fab2(sch_1):page49_i111:a12"
				( attribute "PN" "65"
					( Origin gPackager )
				)
				( objectStatus "J4B1.65" )
			)
			( pin "@baseboard_fab2_lib.baseboard_fab2(sch_1):page49_i111:a13"
				( attribute "PN" "232"
					( Origin gPackager )
				)
				( objectStatus "J4B1.232" )
			)
			( pin "@baseboard_fab2_lib.baseboard_fab2(sch_1):page49_i111:a14_we_n"
				( attribute "PN" "228"
					( Origin gPackager )
				)
				( objectStatus "J4B1.228" )
			)
			( pin "@baseboard_fab2_lib.baseboard_fab2(sch_1):page49_i111:a15_cas_n"
				( attribute "PN" "86"
					( Origin gPackager )
				)
				( objectStatus "J4B1.86" )
			)
			( pin "@baseboard_fab2_lib.baseboard_fab2(sch_1):page49_i111:a16_ras_n"
				( attribute "PN" "82"
					( Origin gPackager )
				)
				( objectStatus "J4B1.82" )
			)
			( pin "@baseboard_fab2_lib.baseboard_fab2(sch_1):page49_i111:a17"
				( attribute "PN" "234"
					( Origin gPackager )
				)
				( objectStatus "J4B1.234" )
			)
			( pin "@baseboard_fab2_lib.baseboard_fab2(sch_1):page49_i111:act_n"
				( attribute "PN" "62"
					( Origin gPackager )
				)
				( objectStatus "J4B1.62" )
			)
			( pin "@baseboard_fab2_lib.baseboard_fab2(sch_1):page49_i111:alert_n"
				( attribute "PN" "208"
					( Origin gPackager )
				)
				( objectStatus "J4B1.208" )
			)
			( pin "@baseboard_fab2_lib.baseboard_fab2(sch_1):page49_i111:ba(0)"
				( attribute "PN" "81"
					( Origin gPackager )
				)
				( objectStatus "J4B1.81" )
			)
			( pin "@baseboard_fab2_lib.baseboard_fab2(sch_1):page49_i111:ba(1)"
				( attribute "PN" "224"
					( Origin gPackager )
				)
				( objectStatus "J4B1.224" )
			)
			( pin "@baseboard_fab2_lib.baseboard_fab2(sch_1):page49_i111:bg(0)"
				( attribute "PN" "63"
					( Origin gPackager )
				)
				( objectStatus "J4B1.63" )
			)
			( pin "@baseboard_fab2_lib.baseboard_fab2(sch_1):page49_i111:bg(1)"
				( attribute "PN" "207"
					( Origin gPackager )
				)
				( objectStatus "J4B1.207" )
			)
			( pin "@baseboard_fab2_lib.baseboard_fab2(sch_1):page49_i111:c(2)"
				( attribute "PN" "235"
					( Origin gPackager )
				)
				( objectStatus "J4B1.235" )
			)
			( pin "@baseboard_fab2_lib.baseboard_fab2(sch_1):page49_i111:cb(0)"
				( attribute "PN" "49"
					( Origin gPackager )
				)
				( objectStatus "J4B1.49" )
			)
			( pin "@baseboard_fab2_lib.baseboard_fab2(sch_1):page49_i111:cb(1)"
				( attribute "PN" "194"
					( Origin gPackager )
				)
				( objectStatus "J4B1.194" )
			)
			( pin "@baseboard_fab2_lib.baseboard_fab2(sch_1):page49_i111:cb(2)"
				( attribute "PN" "56"
					( Origin gPackager )
				)
				( objectStatus "J4B1.56" )
			)
			( pin "@baseboard_fab2_lib.baseboard_fab2(sch_1):page49_i111:cb(3)"
				( attribute "PN" "201"
					( Origin gPackager )
				)
				( objectStatus "J4B1.201" )
			)
			( pin "@baseboard_fab2_lib.baseboard_fab2(sch_1):page49_i111:cb(4)"
				( attribute "PN" "47"
					( Origin gPackager )
				)
				( objectStatus "J4B1.47" )
			)
			( pin "@baseboard_fab2_lib.baseboard_fab2(sch_1):page49_i111:cb(5)"
				( attribute "PN" "192"
					( Origin gPackager )
				)
				( objectStatus "J4B1.192" )
			)
			( pin "@baseboard_fab2_lib.baseboard_fab2(sch_1):page49_i111:cb(6)"
				( attribute "PN" "54"
					( Origin gPackager )
				)
				( objectStatus "J4B1.54" )
			)
			( pin "@baseboard_fab2_lib.baseboard_fab2(sch_1):page49_i111:cb(7)"
				( attribute "PN" "199"
					( Origin gPackager )
				)
				( objectStatus "J4B1.199" )
			)
			( pin "@baseboard_fab2_lib.baseboard_fab2(sch_1):page49_i111:ck0n"
				( attribute "PN" "75"
					( Origin gPackager )
				)
				( objectStatus "J4B1.75" )
			)
			( pin "@baseboard_fab2_lib.baseboard_fab2(sch_1):page49_i111:ck0p"
				( attribute "PN" "74"
					( Origin gPackager )
				)
				( objectStatus "J4B1.74" )
			)
			( pin "@baseboard_fab2_lib.baseboard_fab2(sch_1):page49_i111:ck1n"
				( attribute "PN" "219"
					( Origin gPackager )
				)
				( objectStatus "J4B1.219" )
			)
			( pin "@baseboard_fab2_lib.baseboard_fab2(sch_1):page49_i111:ck1p"
				( attribute "PN" "218"
					( Origin gPackager )
				)
				( objectStatus "J4B1.218" )
			)
			( pin "@baseboard_fab2_lib.baseboard_fab2(sch_1):page49_i111:cke(0)"
				( attribute "PN" "60"
					( Origin gPackager )
				)
				( objectStatus "J4B1.60" )
			)
			( pin "@baseboard_fab2_lib.baseboard_fab2(sch_1):page49_i111:cke(1)"
				( attribute "PN" "203"
					( Origin gPackager )
				)
				( objectStatus "J4B1.203" )
			)
			( pin "@baseboard_fab2_lib.baseboard_fab2(sch_1):page49_i111:dq(0)"
				( attribute "PN" "5"
					( Origin gPackager )
				)
				( objectStatus "J4B1.5" )
			)
			( pin "@baseboard_fab2_lib.baseboard_fab2(sch_1):page49_i111:dq(1)"
				( attribute "PN" "150"
					( Origin gPackager )
				)
				( objectStatus "J4B1.150" )
			)
			( pin "@baseboard_fab2_lib.baseboard_fab2(sch_1):page49_i111:dq(2)"
				( attribute "PN" "12"
					( Origin gPackager )
				)
				( objectStatus "J4B1.12" )
			)
			( pin "@baseboard_fab2_lib.baseboard_fab2(sch_1):page49_i111:dq(3)"
				( attribute "PN" "157"
					( Origin gPackager )
				)
				( objectStatus "J4B1.157" )
			)
			( pin "@baseboard_fab2_lib.baseboard_fab2(sch_1):page49_i111:dq(4)"
				( attribute "PN" "3"
					( Origin gPackager )
				)
				( objectStatus "J4B1.3" )
			)
			( pin "@baseboard_fab2_lib.baseboard_fab2(sch_1):page49_i111:dq(5)"
				( attribute "PN" "148"
					( Origin gPackager )
				)
				( objectStatus "J4B1.148" )
			)
			( pin "@baseboard_fab2_lib.baseboard_fab2(sch_1):page49_i111:dq(6)"
				( attribute "PN" "10"
					( Origin gPackager )
				)
				( objectStatus "J4B1.10" )
			)
			( pin "@baseboard_fab2_lib.baseboard_fab2(sch_1):page49_i111:dq(7)"
				( attribute "PN" "155"
					( Origin gPackager )
				)
				( objectStatus "J4B1.155" )
			)
			( pin "@baseboard_fab2_lib.baseboard_fab2(sch_1):page49_i111:dq(8)"
				( attribute "PN" "16"
					( Origin gPackager )
				)
				( objectStatus "J4B1.16" )
			)
			( pin "@baseboard_fab2_lib.baseboard_fab2(sch_1):page49_i111:dq(9)"
				( attribute "PN" "161"
					( Origin gPackager )
				)
				( objectStatus "J4B1.161" )
			)
			( pin "@baseboard_fab2_lib.baseboard_fab2(sch_1):page49_i111:dq(10)"
				( attribute "PN" "23"
					( Origin gPackager )
				)
				( objectStatus "J4B1.23" )
			)
			( pin "@baseboard_fab2_lib.baseboard_fab2(sch_1):page49_i111:dq(11)"
				( attribute "PN" "168"
					( Origin gPackager )
				)
				( objectStatus "J4B1.168" )
			)
			( pin "@baseboard_fab2_lib.baseboard_fab2(sch_1):page49_i111:dq(12)"
				( attribute "PN" "14"
					( Origin gPackager )
				)
				( objectStatus "J4B1.14" )
			)
			( pin "@baseboard_fab2_lib.baseboard_fab2(sch_1):page49_i111:dq(13)"
				( attribute "PN" "159"
					( Origin gPackager )
				)
				( objectStatus "J4B1.159" )
			)
			( pin "@baseboard_fab2_lib.baseboard_fab2(sch_1):page49_i111:dq(14)"
				( attribute "PN" "21"
					( Origin gPackager )
				)
				( objectStatus "J4B1.21" )
			)
			( pin "@baseboard_fab2_lib.baseboard_fab2(sch_1):page49_i111:dq(15)"
				( attribute "PN" "166"
					( Origin gPackager )
				)
				( objectStatus "J4B1.166" )
			)
			( pin "@baseboard_fab2_lib.baseboard_fab2(sch_1):page49_i111:dq(16)"
				( attribute "PN" "27"
					( Origin gPackager )
				)
				( objectStatus "J4B1.27" )
			)
			( pin "@baseboard_fab2_lib.baseboard_fab2(sch_1):page49_i111:dq(17)"
				( attribute "PN" "172"
					( Origin gPackager )
				)
				( objectStatus "J4B1.172" )
			)
			( pin "@baseboard_fab2_lib.baseboard_fab2(sch_1):page49_i111:dq(18)"
				( attribute "PN" "34"
					( Origin gPackager )
				)
				( objectStatus "J4B1.34" )
			)
			( pin "@baseboard_fab2_lib.baseboard_fab2(sch_1):page49_i111:dq(19)"
				( attribute "PN" "179"
					( Origin gPackager )
				)
				( objectStatus "J4B1.179" )
			)
			( pin "@baseboard_fab2_lib.baseboard_fab2(sch_1):page49_i111:dq(20)"
				( attribute "PN" "25"
					( Origin gPackager )
				)
				( objectStatus "J4B1.25" )
			)
			( pin "@baseboard_fab2_lib.baseboard_fab2(sch_1):page49_i111:dq(21)"
				( attribute "PN" "170"
					( Origin gPackager )
				)
				( objectStatus "J4B1.170" )
			)
			( pin "@baseboard_fab2_lib.baseboard_fab2(sch_1):page49_i111:dq(22)"
				( attribute "PN" "32"
					( Origin gPackager )
				)
				( objectStatus "J4B1.32" )
			)
			( pin "@baseboard_fab2_lib.baseboard_fab2(sch_1):page49_i111:dq(23)"
				( attribute "PN" "177"
					( Origin gPackager )
				)
				( objectStatus "J4B1.177" )
			)
			( pin "@baseboard_fab2_lib.baseboard_fab2(sch_1):page49_i111:dq(24)"
				( attribute "PN" "38"
					( Origin gPackager )
				)
				( objectStatus "J4B1.38" )
			)
			( pin "@baseboard_fab2_lib.baseboard_fab2(sch_1):page49_i111:dq(25)"
				( attribute "PN" "183"
					( Origin gPackager )
				)
				( objectStatus "J4B1.183" )
			)
			( pin "@baseboard_fab2_lib.baseboard_fab2(sch_1):page49_i111:dq(26)"
				( attribute "PN" "45"
					( Origin gPackager )
				)
				( objectStatus "J4B1.45" )
			)
			( pin "@baseboard_fab2_lib.baseboard_fab2(sch_1):page49_i111:dq(27)"
				( attribute "PN" "190"
					( Origin gPackager )
				)
				( objectStatus "J4B1.190" )
			)
			( pin "@baseboard_fab2_lib.baseboard_fab2(sch_1):page49_i111:dq(28)"
				( attribute "PN" "36"
					( Origin gPackager )
				)
				( objectStatus "J4B1.36" )
			)
			( pin "@baseboard_fab2_lib.baseboard_fab2(sch_1):page49_i111:dq(29)"
				( attribute "PN" "181"
					( Origin gPackager )
				)
				( objectStatus "J4B1.181" )
			)
			( pin "@baseboard_fab2_lib.baseboard_fab2(sch_1):page49_i111:dq(30)"
				( attribute "PN" "43"
					( Origin gPackager )
				)
				( objectStatus "J4B1.43" )
			)
			( pin "@baseboard_fab2_lib.baseboard_fab2(sch_1):page49_i111:dq(31)"
				( attribute "PN" "188"
					( Origin gPackager )
				)
				( objectStatus "J4B1.188" )
			)
			( pin "@baseboard_fab2_lib.baseboard_fab2(sch_1):page49_i111:dq(32)"
				( attribute "PN" "97"
					( Origin gPackager )
				)
				( objectStatus "J4B1.97" )
			)
			( pin "@baseboard_fab2_lib.baseboard_fab2(sch_1):page49_i111:dq(33)"
				( attribute "PN" "242"
					( Origin gPackager )
				)
				( objectStatus "J4B1.242" )
			)
			( pin "@baseboard_fab2_lib.baseboard_fab2(sch_1):page49_i111:dq(34)"
				( attribute "PN" "104"
					( Origin gPackager )
				)
				( objectStatus "J4B1.104" )
			)
			( pin "@baseboard_fab2_lib.baseboard_fab2(sch_1):page49_i111:dq(35)"
				( attribute "PN" "249"
					( Origin gPackager )
				)
				( objectStatus "J4B1.249" )
			)
			( pin "@baseboard_fab2_lib.baseboard_fab2(sch_1):page49_i111:dq(36)"
				( attribute "PN" "95"
					( Origin gPackager )
				)
				( objectStatus "J4B1.95" )
			)
			( pin "@baseboard_fab2_lib.baseboard_fab2(sch_1):page49_i111:dq(37)"
				( attribute "PN" "240"
					( Origin gPackager )
				)
				( objectStatus "J4B1.240" )
			)
			( pin "@baseboard_fab2_lib.baseboard_fab2(sch_1):page49_i111:dq(38)"
				( attribute "PN" "102"
					( Origin gPackager )
				)
				( objectStatus "J4B1.102" )
			)
			( pin "@baseboard_fab2_lib.baseboard_fab2(sch_1):page49_i111:dq(39)"
				( attribute "PN" "247"
					( Origin gPackager )
				)
				( objectStatus "J4B1.247" )
			)
			( pin "@baseboard_fab2_lib.baseboard_fab2(sch_1):page49_i111:dq(40)"
				( attribute "PN" "108"
					( Origin gPackager )
				)
				( objectStatus "J4B1.108" )
			)
			( pin "@baseboard_fab2_lib.baseboard_fab2(sch_1):page49_i111:dq(41)"
				( attribute "PN" "253"
					( Origin gPackager )
				)
				( objectStatus "J4B1.253" )
			)
			( pin "@baseboard_fab2_lib.baseboard_fab2(sch_1):page49_i111:dq(42)"
				( attribute "PN" "115"
					( Origin gPackager )
				)
				( objectStatus "J4B1.115" )
			)
			( pin "@baseboard_fab2_lib.baseboard_fab2(sch_1):page49_i111:dq(43)"
				( attribute "PN" "260"
					( Origin gPackager )
				)
				( objectStatus "J4B1.260" )
			)
			( pin "@baseboard_fab2_lib.baseboard_fab2(sch_1):page49_i111:dq(44)"
				( attribute "PN" "106"
					( Origin gPackager )
				)
				( objectStatus "J4B1.106" )
			)
			( pin "@baseboard_fab2_lib.baseboard_fab2(sch_1):page49_i111:dq(45)"
				( attribute "PN" "251"
					( Origin gPackager )
				)
				( objectStatus "J4B1.251" )
			)
			( pin "@baseboard_fab2_lib.baseboard_fab2(sch_1):page49_i111:dq(46)"
				( attribute "PN" "113"
					( Origin gPackager )
				)
				( objectStatus "J4B1.113" )
			)
			( pin "@baseboard_fab2_lib.baseboard_fab2(sch_1):page49_i111:dq(47)"
				( attribute "PN" "258"
					( Origin gPackager )
				)
				( objectStatus "J4B1.258" )
			)
			( pin "@baseboard_fab2_lib.baseboard_fab2(sch_1):page49_i111:dq(48)"
				( attribute "PN" "119"
					( Origin gPackager )
				)
				( objectStatus "J4B1.119" )
			)
			( pin "@baseboard_fab2_lib.baseboard_fab2(sch_1):page49_i111:dq(49)"
				( attribute "PN" "264"
					( Origin gPackager )
				)
				( objectStatus "J4B1.264" )
			)
			( pin "@baseboard_fab2_lib.baseboard_fab2(sch_1):page49_i111:dq(50)"
				( attribute "PN" "126"
					( Origin gPackager )
				)
				( objectStatus "J4B1.126" )
			)
			( pin "@baseboard_fab2_lib.baseboard_fab2(sch_1):page49_i111:dq(51)"
				( attribute "PN" "271"
					( Origin gPackager )
				)
				( objectStatus "J4B1.271" )
			)
			( pin "@baseboard_fab2_lib.baseboard_fab2(sch_1):page49_i111:dq(52)"
				( attribute "PN" "117"
					( Origin gPackager )
				)
				( objectStatus "J4B1.117" )
			)
			( pin "@baseboard_fab2_lib.baseboard_fab2(sch_1):page49_i111:dq(53)"
				( attribute "PN" "262"
					( Origin gPackager )
				)
				( objectStatus "J4B1.262" )
			)
			( pin "@baseboard_fab2_lib.baseboard_fab2(sch_1):page49_i111:dq(54)"
				( attribute "PN" "124"
					( Origin gPackager )
				)
				( objectStatus "J4B1.124" )
			)
			( pin "@baseboard_fab2_lib.baseboard_fab2(sch_1):page49_i111:dq(55)"
				( attribute "PN" "269"
					( Origin gPackager )
				)
				( objectStatus "J4B1.269" )
			)
			( pin "@baseboard_fab2_lib.baseboard_fab2(sch_1):page49_i111:dq(56)"
				( attribute "PN" "130"
					( Origin gPackager )
				)
				( objectStatus "J4B1.130" )
			)
			( pin "@baseboard_fab2_lib.baseboard_fab2(sch_1):page49_i111:dq(57)"
				( attribute "PN" "275"
					( Origin gPackager )
				)
				( objectStatus "J4B1.275" )
			)
			( pin "@baseboard_fab2_lib.baseboard_fab2(sch_1):page49_i111:dq(58)"
				( attribute "PN" "137"
					( Origin gPackager )
				)
				( objectStatus "J4B1.137" )
			)
			( pin "@baseboard_fab2_lib.baseboard_fab2(sch_1):page49_i111:dq(59)"
				( attribute "PN" "282"
					( Origin gPackager )
				)
				( objectStatus "J4B1.282" )
			)
			( pin "@baseboard_fab2_lib.baseboard_fab2(sch_1):page49_i111:dq(60)"
				( attribute "PN" "128"
					( Origin gPackager )
				)
				( objectStatus "J4B1.128" )
			)
			( pin "@baseboard_fab2_lib.baseboard_fab2(sch_1):page49_i111:dq(61)"
				( attribute "PN" "273"
					( Origin gPackager )
				)
				( objectStatus "J4B1.273" )
			)
			( pin "@baseboard_fab2_lib.baseboard_fab2(sch_1):page49_i111:dq(62)"
				( attribute "PN" "135"
					( Origin gPackager )
				)
				( objectStatus "J4B1.135" )
			)
			( pin "@baseboard_fab2_lib.baseboard_fab2(sch_1):page49_i111:dq(63)"
				( attribute "PN" "280"
					( Origin gPackager )
				)
				( objectStatus "J4B1.280" )
			)
			( pin "@baseboard_fab2_lib.baseboard_fab2(sch_1):page49_i111:event_n"
				( attribute "PN" "78"
					( Origin gPackager )
				)
				( objectStatus "J4B1.78" )
			)
			( pin "@baseboard_fab2_lib.baseboard_fab2(sch_1):page49_i111:odt(0)"
				( attribute "PN" "87"
					( Origin gPackager )
				)
				( objectStatus "J4B1.87" )
			)
			( pin "@baseboard_fab2_lib.baseboard_fab2(sch_1):page49_i111:odt(1)"
				( attribute "PN" "91"
					( Origin gPackager )
				)
				( objectStatus "J4B1.91" )
			)
			( pin "@baseboard_fab2_lib.baseboard_fab2(sch_1):page49_i111:par"
				( attribute "PN" "222"
					( Origin gPackager )
				)
				( objectStatus "J4B1.222" )
			)
			( pin "@baseboard_fab2_lib.baseboard_fab2(sch_1):page49_i111:reset_n"
				( attribute "PN" "58"
					( Origin gPackager )
				)
				( objectStatus "J4B1.58" )
			)
			( pin "@baseboard_fab2_lib.baseboard_fab2(sch_1):page49_i111:rfu(0)"
				( attribute "PN" "205"
					( Origin gPackager )
				)
				( objectStatus "J4B1.205" )
			)
			( pin "@baseboard_fab2_lib.baseboard_fab2(sch_1):page49_i111:rfu(1)"
				( attribute "PN" "227"
					( Origin gPackager )
				)
				( objectStatus "J4B1.227" )
			)
			( pin "@baseboard_fab2_lib.baseboard_fab2(sch_1):page49_i111:rfu(2)"
				( attribute "PN" "144"
					( Origin gPackager )
				)
				( objectStatus "J4B1.144" )
			)
			( pin "@baseboard_fab2_lib.baseboard_fab2(sch_1):page49_i111:s0_n"
				( attribute "PN" "84"
					( Origin gPackager )
				)
				( objectStatus "J4B1.84" )
			)
			( pin "@baseboard_fab2_lib.baseboard_fab2(sch_1):page49_i111:s1_n"
				( attribute "PN" "89"
					( Origin gPackager )
				)
				( objectStatus "J4B1.89" )
			)
			( pin "@baseboard_fab2_lib.baseboard_fab2(sch_1):page49_i111:s2_n_c(0)"
				( attribute "PN" "93"
					( Origin gPackager )
				)
				( objectStatus "J4B1.93" )
			)
			( pin "@baseboard_fab2_lib.baseboard_fab2(sch_1):page49_i111:s3_n_c(1)"
				( attribute "PN" "237"
					( Origin gPackager )
				)
				( objectStatus "J4B1.237" )
			)
			( pin "@baseboard_fab2_lib.baseboard_fab2(sch_1):page49_i111:sa(0)"
				( attribute "PN" "139"
					( Origin gPackager )
				)
				( objectStatus "J4B1.139" )
			)
			( pin "@baseboard_fab2_lib.baseboard_fab2(sch_1):page49_i111:sa(1)"
				( attribute "PN" "140"
					( Origin gPackager )
				)
				( objectStatus "J4B1.140" )
			)
			( pin "@baseboard_fab2_lib.baseboard_fab2(sch_1):page49_i111:sa(2)"
				( attribute "PN" "238"
					( Origin gPackager )
				)
				( objectStatus "J4B1.238" )
			)
			( pin "@baseboard_fab2_lib.baseboard_fab2(sch_1):page49_i111:save_n_nc"
				( attribute "PN" "230"
					( Origin gPackager )
				)
				( objectStatus "J4B1.230" )
			)
			( pin "@baseboard_fab2_lib.baseboard_fab2(sch_1):page49_i111:scl"
				( attribute "PN" "141"
					( Origin gPackager )
				)
				( objectStatus "J4B1.141" )
			)
			( pin "@baseboard_fab2_lib.baseboard_fab2(sch_1):page49_i111:sda"
				( attribute "PN" "285"
					( Origin gPackager )
				)
				( objectStatus "J4B1.285" )
			)
			( pin "@baseboard_fab2_lib.baseboard_fab2(sch_1):page49_i111:vddspd"
				( attribute "PN" "284"
					( Origin gPackager )
				)
				( objectStatus "J4B1.284" )
			)
			( pin "@baseboard_fab2_lib.baseboard_fab2(sch_1):page49_i111:vrefca"
				( attribute "PN" "146"
					( Origin gPackager )
				)
				( objectStatus "J4B1.146" )
			)
			( pin "@baseboard_fab2_lib.baseboard_fab2(sch_1):page49_i169:\12v\(0)"
				( attribute "PN" "145"
					( Origin gPackager )
				)
				( objectStatus "J4B1.145" )
			)
			( pin "@baseboard_fab2_lib.baseboard_fab2(sch_1):page49_i169:\12v\(1)"
				( attribute "PN" "1"
					( Origin gPackager )
				)
				( objectStatus "J4B1.1" )
			)
			( pin "@baseboard_fab2_lib.baseboard_fab2(sch_1):page49_i169:vdd(0)"
				( attribute "PN" "236"
					( Origin gPackager )
				)
				( objectStatus "J4B1.236" )
			)
			( pin "@baseboard_fab2_lib.baseboard_fab2(sch_1):page49_i169:vdd(1)"
				( attribute "PN" "233"
					( Origin gPackager )
				)
				( objectStatus "J4B1.233" )
			)
			( pin "@baseboard_fab2_lib.baseboard_fab2(sch_1):page49_i169:vdd(2)"
				( attribute "PN" "231"
					( Origin gPackager )
				)
				( objectStatus "J4B1.231" )
			)
			( pin "@baseboard_fab2_lib.baseboard_fab2(sch_1):page49_i169:vdd(3)"
				( attribute "PN" "229"
					( Origin gPackager )
				)
				( objectStatus "J4B1.229" )
			)
			( pin "@baseboard_fab2_lib.baseboard_fab2(sch_1):page49_i169:vdd(4)"
				( attribute "PN" "226"
					( Origin gPackager )
				)
				( objectStatus "J4B1.226" )
			)
			( pin "@baseboard_fab2_lib.baseboard_fab2(sch_1):page49_i169:vdd(5)"
				( attribute "PN" "223"
					( Origin gPackager )
				)
				( objectStatus "J4B1.223" )
			)
			( pin "@baseboard_fab2_lib.baseboard_fab2(sch_1):page49_i169:vdd(6)"
				( attribute "PN" "220"
					( Origin gPackager )
				)
				( objectStatus "J4B1.220" )
			)
			( pin "@baseboard_fab2_lib.baseboard_fab2(sch_1):page49_i169:vdd(7)"
				( attribute "PN" "217"
					( Origin gPackager )
				)
				( objectStatus "J4B1.217" )
			)
			( pin "@baseboard_fab2_lib.baseboard_fab2(sch_1):page49_i169:vdd(8)"
				( attribute "PN" "215"
					( Origin gPackager )
				)
				( objectStatus "J4B1.215" )
			)
			( pin "@baseboard_fab2_lib.baseboard_fab2(sch_1):page49_i169:vdd(9)"
				( attribute "PN" "212"
					( Origin gPackager )
				)
				( objectStatus "J4B1.212" )
			)
			( pin "@baseboard_fab2_lib.baseboard_fab2(sch_1):page49_i169:vdd(10)"
				( attribute "PN" "209"
					( Origin gPackager )
				)
				( objectStatus "J4B1.209" )
			)
			( pin "@baseboard_fab2_lib.baseboard_fab2(sch_1):page49_i169:vdd(11)"
				( attribute "PN" "206"
					( Origin gPackager )
				)
				( objectStatus "J4B1.206" )
			)
			( pin "@baseboard_fab2_lib.baseboard_fab2(sch_1):page49_i169:vdd(12)"
				( attribute "PN" "204"
					( Origin gPackager )
				)
				( objectStatus "J4B1.204" )
			)
			( pin "@baseboard_fab2_lib.baseboard_fab2(sch_1):page49_i169:vdd(13)"
				( attribute "PN" "92"
					( Origin gPackager )
				)
				( objectStatus "J4B1.92" )
			)
			( pin "@baseboard_fab2_lib.baseboard_fab2(sch_1):page49_i169:vdd(14)"
				( attribute "PN" "90"
					( Origin gPackager )
				)
				( objectStatus "J4B1.90" )
			)
			( pin "@baseboard_fab2_lib.baseboard_fab2(sch_1):page49_i169:vdd(15)"
				( attribute "PN" "88"
					( Origin gPackager )
				)
				( objectStatus "J4B1.88" )
			)
			( pin "@baseboard_fab2_lib.baseboard_fab2(sch_1):page49_i169:vdd(16)"
				( attribute "PN" "85"
					( Origin gPackager )
				)
				( objectStatus "J4B1.85" )
			)
			( pin "@baseboard_fab2_lib.baseboard_fab2(sch_1):page49_i169:vdd(17)"
				( attribute "PN" "83"
					( Origin gPackager )
				)
				( objectStatus "J4B1.83" )
			)
			( pin "@baseboard_fab2_lib.baseboard_fab2(sch_1):page49_i169:vdd(18)"
				( attribute "PN" "80"
					( Origin gPackager )
				)
				( objectStatus "J4B1.80" )
			)
			( pin "@baseboard_fab2_lib.baseboard_fab2(sch_1):page49_i169:vdd(19)"
				( attribute "PN" "76"
					( Origin gPackager )
				)
				( objectStatus "J4B1.76" )
			)
			( pin "@baseboard_fab2_lib.baseboard_fab2(sch_1):page49_i169:vdd(20)"
				( attribute "PN" "73"
					( Origin gPackager )
				)
				( objectStatus "J4B1.73" )
			)
			( pin "@baseboard_fab2_lib.baseboard_fab2(sch_1):page49_i169:vdd(21)"
				( attribute "PN" "70"
					( Origin gPackager )
				)
				( objectStatus "J4B1.70" )
			)
			( pin "@baseboard_fab2_lib.baseboard_fab2(sch_1):page49_i169:vdd(22)"
				( attribute "PN" "67"
					( Origin gPackager )
				)
				( objectStatus "J4B1.67" )
			)
			( pin "@baseboard_fab2_lib.baseboard_fab2(sch_1):page49_i169:vdd(23)"
				( attribute "PN" "64"
					( Origin gPackager )
				)
				( objectStatus "J4B1.64" )
			)
			( pin "@baseboard_fab2_lib.baseboard_fab2(sch_1):page49_i169:vdd(24)"
				( attribute "PN" "61"
					( Origin gPackager )
				)
				( objectStatus "J4B1.61" )
			)
			( pin "@baseboard_fab2_lib.baseboard_fab2(sch_1):page49_i169:vdd(25)"
				( attribute "PN" "59"
					( Origin gPackager )
				)
				( objectStatus "J4B1.59" )
			)
			( pin "@baseboard_fab2_lib.baseboard_fab2(sch_1):page49_i169:vpp(0)"
				( attribute "PN" "287"
					( Origin gPackager )
				)
				( objectStatus "J4B1.287" )
			)
			( pin "@baseboard_fab2_lib.baseboard_fab2(sch_1):page49_i169:vpp(1)"
				( attribute "PN" "286"
					( Origin gPackager )
				)
				( objectStatus "J4B1.286" )
			)
			( pin "@baseboard_fab2_lib.baseboard_fab2(sch_1):page49_i169:vpp(2)"
				( attribute "PN" "288"
					( Origin gPackager )
				)
				( objectStatus "J4B1.288" )
			)
			( pin "@baseboard_fab2_lib.baseboard_fab2(sch_1):page49_i169:vpp(3)"
				( attribute "PN" "143"
					( Origin gPackager )
				)
				( objectStatus "J4B1.143" )
			)
			( pin "@baseboard_fab2_lib.baseboard_fab2(sch_1):page49_i169:vpp(4)"
				( attribute "PN" "142"
					( Origin gPackager )
				)
				( objectStatus "J4B1.142" )
			)
			( pin "@baseboard_fab2_lib.baseboard_fab2(sch_1):page49_i169:vtt(0)"
				( attribute "PN" "221"
					( Origin gPackager )
				)
				( objectStatus "J4B1.221" )
			)
			( pin "@baseboard_fab2_lib.baseboard_fab2(sch_1):page49_i169:vtt(1)"
				( attribute "PN" "77"
					( Origin gPackager )
				)
				( objectStatus "J4B1.77" )
			)
			( pin "@baseboard_fab2_lib.baseboard_fab2(sch_1):page49_i179:a"
				( attribute "PN" "1"
					( Origin gPackager )
				)
				( objectStatus "C4B12.1" )
			)
			( pin "@baseboard_fab2_lib.baseboard_fab2(sch_1):page49_i179:b"
				( attribute "PN" "2"
					( Origin gPackager )
				)
				( objectStatus "C4B12.2" )
			)
			( pin "@baseboard_fab2_lib.baseboard_fab2(sch_1):page50_i44:vss(0)"
				( attribute "PN" "283"
					( Origin gPackager )
				)
				( objectStatus "J6M1.283" )
			)
			( pin "@baseboard_fab2_lib.baseboard_fab2(sch_1):page50_i44:vss(1)"
				( attribute "PN" "281"
					( Origin gPackager )
				)
				( objectStatus "J6M1.281" )
			)
			( pin "@baseboard_fab2_lib.baseboard_fab2(sch_1):page50_i44:vss(2)"
				( attribute "PN" "279"
					( Origin gPackager )
				)
				( objectStatus "J6M1.279" )
			)
			( pin "@baseboard_fab2_lib.baseboard_fab2(sch_1):page50_i44:vss(3)"
				( attribute "PN" "276"
					( Origin gPackager )
				)
				( objectStatus "J6M1.276" )
			)
			( pin "@baseboard_fab2_lib.baseboard_fab2(sch_1):page50_i44:vss(4)"
				( attribute "PN" "274"
					( Origin gPackager )
				)
				( objectStatus "J6M1.274" )
			)
			( pin "@baseboard_fab2_lib.baseboard_fab2(sch_1):page50_i44:vss(5)"
				( attribute "PN" "272"
					( Origin gPackager )
				)
				( objectStatus "J6M1.272" )
			)
			( pin "@baseboard_fab2_lib.baseboard_fab2(sch_1):page50_i44:vss(6)"
				( attribute "PN" "270"
					( Origin gPackager )
				)
				( objectStatus "J6M1.270" )
			)
			( pin "@baseboard_fab2_lib.baseboard_fab2(sch_1):page50_i44:vss(7)"
				( attribute "PN" "268"
					( Origin gPackager )
				)
				( objectStatus "J6M1.268" )
			)
			( pin "@baseboard_fab2_lib.baseboard_fab2(sch_1):page50_i44:vss(8)"
				( attribute "PN" "265"
					( Origin gPackager )
				)
				( objectStatus "J6M1.265" )
			)
			( pin "@baseboard_fab2_lib.baseboard_fab2(sch_1):page50_i44:vss(9)"
				( attribute "PN" "263"
					( Origin gPackager )
				)
				( objectStatus "J6M1.263" )
			)
			( pin "@baseboard_fab2_lib.baseboard_fab2(sch_1):page50_i44:vss(10)"
				( attribute "PN" "261"
					( Origin gPackager )
				)
				( objectStatus "J6M1.261" )
			)
			( pin "@baseboard_fab2_lib.baseboard_fab2(sch_1):page50_i44:vss(11)"
				( attribute "PN" "259"
					( Origin gPackager )
				)
				( objectStatus "J6M1.259" )
			)
			( pin "@baseboard_fab2_lib.baseboard_fab2(sch_1):page50_i44:vss(12)"
				( attribute "PN" "257"
					( Origin gPackager )
				)
				( objectStatus "J6M1.257" )
			)
			( pin "@baseboard_fab2_lib.baseboard_fab2(sch_1):page50_i44:vss(13)"
				( attribute "PN" "254"
					( Origin gPackager )
				)
				( objectStatus "J6M1.254" )
			)
			( pin "@baseboard_fab2_lib.baseboard_fab2(sch_1):page50_i44:vss(14)"
				( attribute "PN" "252"
					( Origin gPackager )
				)
				( objectStatus "J6M1.252" )
			)
			( pin "@baseboard_fab2_lib.baseboard_fab2(sch_1):page50_i44:vss(15)"
				( attribute "PN" "250"
					( Origin gPackager )
				)
				( objectStatus "J6M1.250" )
			)
			( pin "@baseboard_fab2_lib.baseboard_fab2(sch_1):page50_i44:vss(16)"
				( attribute "PN" "248"
					( Origin gPackager )
				)
				( objectStatus "J6M1.248" )
			)
			( pin "@baseboard_fab2_lib.baseboard_fab2(sch_1):page50_i44:vss(17)"
				( attribute "PN" "246"
					( Origin gPackager )
				)
				( objectStatus "J6M1.246" )
			)
			( pin "@baseboard_fab2_lib.baseboard_fab2(sch_1):page50_i44:vss(18)"
				( attribute "PN" "243"
					( Origin gPackager )
				)
				( objectStatus "J6M1.243" )
			)
			( pin "@baseboard_fab2_lib.baseboard_fab2(sch_1):page50_i44:vss(19)"
				( attribute "PN" "241"
					( Origin gPackager )
				)
				( objectStatus "J6M1.241" )
			)
			( pin "@baseboard_fab2_lib.baseboard_fab2(sch_1):page50_i44:vss(20)"
				( attribute "PN" "239"
					( Origin gPackager )
				)
				( objectStatus "J6M1.239" )
			)
			( pin "@baseboard_fab2_lib.baseboard_fab2(sch_1):page50_i44:vss(21)"
				( attribute "PN" "202"
					( Origin gPackager )
				)
				( objectStatus "J6M1.202" )
			)
			( pin "@baseboard_fab2_lib.baseboard_fab2(sch_1):page50_i44:vss(22)"
				( attribute "PN" "200"
					( Origin gPackager )
				)
				( objectStatus "J6M1.200" )
			)
			( pin "@baseboard_fab2_lib.baseboard_fab2(sch_1):page50_i44:vss(23)"
				( attribute "PN" "198"
					( Origin gPackager )
				)
				( objectStatus "J6M1.198" )
			)
			( pin "@baseboard_fab2_lib.baseboard_fab2(sch_1):page50_i44:vss(24)"
				( attribute "PN" "195"
					( Origin gPackager )
				)
				( objectStatus "J6M1.195" )
			)
			( pin "@baseboard_fab2_lib.baseboard_fab2(sch_1):page50_i44:vss(25)"
				( attribute "PN" "193"
					( Origin gPackager )
				)
				( objectStatus "J6M1.193" )
			)
			( pin "@baseboard_fab2_lib.baseboard_fab2(sch_1):page50_i44:vss(26)"
				( attribute "PN" "191"
					( Origin gPackager )
				)
				( objectStatus "J6M1.191" )
			)
			( pin "@baseboard_fab2_lib.baseboard_fab2(sch_1):page50_i44:vss(27)"
				( attribute "PN" "189"
					( Origin gPackager )
				)
				( objectStatus "J6M1.189" )
			)
			( pin "@baseboard_fab2_lib.baseboard_fab2(sch_1):page50_i44:vss(28)"
				( attribute "PN" "187"
					( Origin gPackager )
				)
				( objectStatus "J6M1.187" )
			)
			( pin "@baseboard_fab2_lib.baseboard_fab2(sch_1):page50_i44:vss(29)"
				( attribute "PN" "184"
					( Origin gPackager )
				)
				( objectStatus "J6M1.184" )
			)
			( pin "@baseboard_fab2_lib.baseboard_fab2(sch_1):page50_i44:vss(30)"
				( attribute "PN" "182"
					( Origin gPackager )
				)
				( objectStatus "J6M1.182" )
			)
			( pin "@baseboard_fab2_lib.baseboard_fab2(sch_1):page50_i44:vss(31)"
				( attribute "PN" "180"
					( Origin gPackager )
				)
				( objectStatus "J6M1.180" )
			)
			( pin "@baseboard_fab2_lib.baseboard_fab2(sch_1):page50_i44:vss(32)"
				( attribute "PN" "178"
					( Origin gPackager )
				)
				( objectStatus "J6M1.178" )
			)
			( pin "@baseboard_fab2_lib.baseboard_fab2(sch_1):page50_i44:vss(33)"
				( attribute "PN" "176"
					( Origin gPackager )
				)
				( objectStatus "J6M1.176" )
			)
			( pin "@baseboard_fab2_lib.baseboard_fab2(sch_1):page50_i44:vss(34)"
				( attribute "PN" "173"
					( Origin gPackager )
				)
				( objectStatus "J6M1.173" )
			)
			( pin "@baseboard_fab2_lib.baseboard_fab2(sch_1):page50_i44:vss(35)"
				( attribute "PN" "171"
					( Origin gPackager )
				)
				( objectStatus "J6M1.171" )
			)
			( pin "@baseboard_fab2_lib.baseboard_fab2(sch_1):page50_i44:vss(36)"
				( attribute "PN" "169"
					( Origin gPackager )
				)
				( objectStatus "J6M1.169" )
			)
			( pin "@baseboard_fab2_lib.baseboard_fab2(sch_1):page50_i44:vss(37)"
				( attribute "PN" "167"
					( Origin gPackager )
				)
				( objectStatus "J6M1.167" )
			)
			( pin "@baseboard_fab2_lib.baseboard_fab2(sch_1):page50_i44:vss(38)"
				( attribute "PN" "165"
					( Origin gPackager )
				)
				( objectStatus "J6M1.165" )
			)
			( pin "@baseboard_fab2_lib.baseboard_fab2(sch_1):page50_i44:vss(39)"
				( attribute "PN" "162"
					( Origin gPackager )
				)
				( objectStatus "J6M1.162" )
			)
			( pin "@baseboard_fab2_lib.baseboard_fab2(sch_1):page50_i44:vss(40)"
				( attribute "PN" "160"
					( Origin gPackager )
				)
				( objectStatus "J6M1.160" )
			)
			( pin "@baseboard_fab2_lib.baseboard_fab2(sch_1):page50_i44:vss(41)"
				( attribute "PN" "158"
					( Origin gPackager )
				)
				( objectStatus "J6M1.158" )
			)
			( pin "@baseboard_fab2_lib.baseboard_fab2(sch_1):page50_i44:vss(42)"
				( attribute "PN" "156"
					( Origin gPackager )
				)
				( objectStatus "J6M1.156" )
			)
			( pin "@baseboard_fab2_lib.baseboard_fab2(sch_1):page50_i44:vss(43)"
				( attribute "PN" "154"
					( Origin gPackager )
				)
				( objectStatus "J6M1.154" )
			)
			( pin "@baseboard_fab2_lib.baseboard_fab2(sch_1):page50_i44:vss(44)"
				( attribute "PN" "151"
					( Origin gPackager )
				)
				( objectStatus "J6M1.151" )
			)
			( pin "@baseboard_fab2_lib.baseboard_fab2(sch_1):page50_i44:vss(45)"
				( attribute "PN" "149"
					( Origin gPackager )
				)
				( objectStatus "J6M1.149" )
			)
			( pin "@baseboard_fab2_lib.baseboard_fab2(sch_1):page50_i44:vss(46)"
				( attribute "PN" "147"
					( Origin gPackager )
				)
				( objectStatus "J6M1.147" )
			)
			( pin "@baseboard_fab2_lib.baseboard_fab2(sch_1):page50_i44:vss(47)"
				( attribute "PN" "138"
					( Origin gPackager )
				)
				( objectStatus "J6M1.138" )
			)
			( pin "@baseboard_fab2_lib.baseboard_fab2(sch_1):page50_i44:vss(48)"
				( attribute "PN" "136"
					( Origin gPackager )
				)
				( objectStatus "J6M1.136" )
			)
			( pin "@baseboard_fab2_lib.baseboard_fab2(sch_1):page50_i44:vss(49)"
				( attribute "PN" "134"
					( Origin gPackager )
				)
				( objectStatus "J6M1.134" )
			)
			( pin "@baseboard_fab2_lib.baseboard_fab2(sch_1):page50_i44:vss(50)"
				( attribute "PN" "131"
					( Origin gPackager )
				)
				( objectStatus "J6M1.131" )
			)
			( pin "@baseboard_fab2_lib.baseboard_fab2(sch_1):page50_i44:vss(51)"
				( attribute "PN" "129"
					( Origin gPackager )
				)
				( objectStatus "J6M1.129" )
			)
			( pin "@baseboard_fab2_lib.baseboard_fab2(sch_1):page50_i44:vss(52)"
				( attribute "PN" "127"
					( Origin gPackager )
				)
				( objectStatus "J6M1.127" )
			)
			( pin "@baseboard_fab2_lib.baseboard_fab2(sch_1):page50_i44:vss(53)"
				( attribute "PN" "125"
					( Origin gPackager )
				)
				( objectStatus "J6M1.125" )
			)
			( pin "@baseboard_fab2_lib.baseboard_fab2(sch_1):page50_i44:vss(54)"
				( attribute "PN" "123"
					( Origin gPackager )
				)
				( objectStatus "J6M1.123" )
			)
			( pin "@baseboard_fab2_lib.baseboard_fab2(sch_1):page50_i44:vss(55)"
				( attribute "PN" "120"
					( Origin gPackager )
				)
				( objectStatus "J6M1.120" )
			)
			( pin "@baseboard_fab2_lib.baseboard_fab2(sch_1):page50_i44:vss(56)"
				( attribute "PN" "118"
					( Origin gPackager )
				)
				( objectStatus "J6M1.118" )
			)
			( pin "@baseboard_fab2_lib.baseboard_fab2(sch_1):page50_i44:vss(57)"
				( attribute "PN" "116"
					( Origin gPackager )
				)
				( objectStatus "J6M1.116" )
			)
			( pin "@baseboard_fab2_lib.baseboard_fab2(sch_1):page50_i44:vss(58)"
				( attribute "PN" "114"
					( Origin gPackager )
				)
				( objectStatus "J6M1.114" )
			)
			( pin "@baseboard_fab2_lib.baseboard_fab2(sch_1):page50_i44:vss(59)"
				( attribute "PN" "112"
					( Origin gPackager )
				)
				( objectStatus "J6M1.112" )
			)
			( pin "@baseboard_fab2_lib.baseboard_fab2(sch_1):page50_i44:vss(60)"
				( attribute "PN" "109"
					( Origin gPackager )
				)
				( objectStatus "J6M1.109" )
			)
			( pin "@baseboard_fab2_lib.baseboard_fab2(sch_1):page50_i44:vss(61)"
				( attribute "PN" "107"
					( Origin gPackager )
				)
				( objectStatus "J6M1.107" )
			)
			( pin "@baseboard_fab2_lib.baseboard_fab2(sch_1):page50_i44:vss(62)"
				( attribute "PN" "105"
					( Origin gPackager )
				)
				( objectStatus "J6M1.105" )
			)
			( pin "@baseboard_fab2_lib.baseboard_fab2(sch_1):page50_i44:vss(63)"
				( attribute "PN" "103"
					( Origin gPackager )
				)
				( objectStatus "J6M1.103" )
			)
			( pin "@baseboard_fab2_lib.baseboard_fab2(sch_1):page50_i44:vss(64)"
				( attribute "PN" "101"
					( Origin gPackager )
				)
				( objectStatus "J6M1.101" )
			)
			( pin "@baseboard_fab2_lib.baseboard_fab2(sch_1):page50_i44:vss(65)"
				( attribute "PN" "98"
					( Origin gPackager )
				)
				( objectStatus "J6M1.98" )
			)
			( pin "@baseboard_fab2_lib.baseboard_fab2(sch_1):page50_i44:vss(66)"
				( attribute "PN" "96"
					( Origin gPackager )
				)
				( objectStatus "J6M1.96" )
			)
			( pin "@baseboard_fab2_lib.baseboard_fab2(sch_1):page50_i44:vss(67)"
				( attribute "PN" "94"
					( Origin gPackager )
				)
				( objectStatus "J6M1.94" )
			)
			( pin "@baseboard_fab2_lib.baseboard_fab2(sch_1):page50_i44:vss(68)"
				( attribute "PN" "57"
					( Origin gPackager )
				)
				( objectStatus "J6M1.57" )
			)
			( pin "@baseboard_fab2_lib.baseboard_fab2(sch_1):page50_i44:vss(69)"
				( attribute "PN" "55"
					( Origin gPackager )
				)
				( objectStatus "J6M1.55" )
			)
			( pin "@baseboard_fab2_lib.baseboard_fab2(sch_1):page50_i44:vss(70)"
				( attribute "PN" "53"
					( Origin gPackager )
				)
				( objectStatus "J6M1.53" )
			)
			( pin "@baseboard_fab2_lib.baseboard_fab2(sch_1):page50_i44:vss(71)"
				( attribute "PN" "50"
					( Origin gPackager )
				)
				( objectStatus "J6M1.50" )
			)
			( pin "@baseboard_fab2_lib.baseboard_fab2(sch_1):page50_i44:vss(72)"
				( attribute "PN" "48"
					( Origin gPackager )
				)
				( objectStatus "J6M1.48" )
			)
			( pin "@baseboard_fab2_lib.baseboard_fab2(sch_1):page50_i44:vss(73)"
				( attribute "PN" "46"
					( Origin gPackager )
				)
				( objectStatus "J6M1.46" )
			)
			( pin "@baseboard_fab2_lib.baseboard_fab2(sch_1):page50_i44:vss(74)"
				( attribute "PN" "44"
					( Origin gPackager )
				)
				( objectStatus "J6M1.44" )
			)
			( pin "@baseboard_fab2_lib.baseboard_fab2(sch_1):page50_i44:vss(75)"
				( attribute "PN" "42"
					( Origin gPackager )
				)
				( objectStatus "J6M1.42" )
			)
			( pin "@baseboard_fab2_lib.baseboard_fab2(sch_1):page50_i44:vss(76)"
				( attribute "PN" "39"
					( Origin gPackager )
				)
				( objectStatus "J6M1.39" )
			)
			( pin "@baseboard_fab2_lib.baseboard_fab2(sch_1):page50_i44:vss(77)"
				( attribute "PN" "37"
					( Origin gPackager )
				)
				( objectStatus "J6M1.37" )
			)
			( pin "@baseboard_fab2_lib.baseboard_fab2(sch_1):page50_i44:vss(78)"
				( attribute "PN" "35"
					( Origin gPackager )
				)
				( objectStatus "J6M1.35" )
			)
			( pin "@baseboard_fab2_lib.baseboard_fab2(sch_1):page50_i44:vss(79)"
				( attribute "PN" "33"
					( Origin gPackager )
				)
				( objectStatus "J6M1.33" )
			)
			( pin "@baseboard_fab2_lib.baseboard_fab2(sch_1):page50_i44:vss(80)"
				( attribute "PN" "31"
					( Origin gPackager )
				)
				( objectStatus "J6M1.31" )
			)
			( pin "@baseboard_fab2_lib.baseboard_fab2(sch_1):page50_i44:vss(81)"
				( attribute "PN" "28"
					( Origin gPackager )
				)
				( objectStatus "J6M1.28" )
			)
			( pin "@baseboard_fab2_lib.baseboard_fab2(sch_1):page50_i44:vss(82)"
				( attribute "PN" "26"
					( Origin gPackager )
				)
				( objectStatus "J6M1.26" )
			)
			( pin "@baseboard_fab2_lib.baseboard_fab2(sch_1):page50_i44:vss(83)"
				( attribute "PN" "24"
					( Origin gPackager )
				)
				( objectStatus "J6M1.24" )
			)
			( pin "@baseboard_fab2_lib.baseboard_fab2(sch_1):page50_i44:vss(84)"
				( attribute "PN" "22"
					( Origin gPackager )
				)
				( objectStatus "J6M1.22" )
			)
			( pin "@baseboard_fab2_lib.baseboard_fab2(sch_1):page50_i44:vss(85)"
				( attribute "PN" "20"
					( Origin gPackager )
				)
				( objectStatus "J6M1.20" )
			)
			( pin "@baseboard_fab2_lib.baseboard_fab2(sch_1):page50_i44:vss(86)"
				( attribute "PN" "17"
					( Origin gPackager )
				)
				( objectStatus "J6M1.17" )
			)
			( pin "@baseboard_fab2_lib.baseboard_fab2(sch_1):page50_i44:vss(87)"
				( attribute "PN" "15"
					( Origin gPackager )
				)
				( objectStatus "J6M1.15" )
			)
			( pin "@baseboard_fab2_lib.baseboard_fab2(sch_1):page50_i44:vss(88)"
				( attribute "PN" "13"
					( Origin gPackager )
				)
				( objectStatus "J6M1.13" )
			)
			( pin "@baseboard_fab2_lib.baseboard_fab2(sch_1):page50_i44:vss(89)"
				( attribute "PN" "11"
					( Origin gPackager )
				)
				( objectStatus "J6M1.11" )
			)
			( pin "@baseboard_fab2_lib.baseboard_fab2(sch_1):page50_i44:vss(90)"
				( attribute "PN" "9"
					( Origin gPackager )
				)
				( objectStatus "J6M1.9" )
			)
			( pin "@baseboard_fab2_lib.baseboard_fab2(sch_1):page50_i44:vss(91)"
				( attribute "PN" "6"
					( Origin gPackager )
				)
				( objectStatus "J6M1.6" )
			)
			( pin "@baseboard_fab2_lib.baseboard_fab2(sch_1):page50_i44:vss(92)"
				( attribute "PN" "4"
					( Origin gPackager )
				)
				( objectStatus "J6M1.4" )
			)
			( pin "@baseboard_fab2_lib.baseboard_fab2(sch_1):page50_i44:vss(93)"
				( attribute "PN" "2"
					( Origin gPackager )
				)
				( objectStatus "J6M1.2" )
			)
			( pin "@baseboard_fab2_lib.baseboard_fab2(sch_1):page50_i46:dqs0n"
				( attribute "PN" "152"
					( Origin gPackager )
				)
				( objectStatus "J6M1.152" )
			)
			( pin "@baseboard_fab2_lib.baseboard_fab2(sch_1):page50_i46:dqs0p"
				( attribute "PN" "153"
					( Origin gPackager )
				)
				( objectStatus "J6M1.153" )
			)
			( pin "@baseboard_fab2_lib.baseboard_fab2(sch_1):page50_i46:dqs1n"
				( attribute "PN" "163"
					( Origin gPackager )
				)
				( objectStatus "J6M1.163" )
			)
			( pin "@baseboard_fab2_lib.baseboard_fab2(sch_1):page50_i46:dqs1p"
				( attribute "PN" "164"
					( Origin gPackager )
				)
				( objectStatus "J6M1.164" )
			)
			( pin "@baseboard_fab2_lib.baseboard_fab2(sch_1):page50_i46:dqs2n"
				( attribute "PN" "174"
					( Origin gPackager )
				)
				( objectStatus "J6M1.174" )
			)
			( pin "@baseboard_fab2_lib.baseboard_fab2(sch_1):page50_i46:dqs2p"
				( attribute "PN" "175"
					( Origin gPackager )
				)
				( objectStatus "J6M1.175" )
			)
			( pin "@baseboard_fab2_lib.baseboard_fab2(sch_1):page50_i46:dqs3n"
				( attribute "PN" "185"
					( Origin gPackager )
				)
				( objectStatus "J6M1.185" )
			)
			( pin "@baseboard_fab2_lib.baseboard_fab2(sch_1):page50_i46:dqs3p"
				( attribute "PN" "186"
					( Origin gPackager )
				)
				( objectStatus "J6M1.186" )
			)
			( pin "@baseboard_fab2_lib.baseboard_fab2(sch_1):page50_i46:dqs4n"
				( attribute "PN" "244"
					( Origin gPackager )
				)
				( objectStatus "J6M1.244" )
			)
			( pin "@baseboard_fab2_lib.baseboard_fab2(sch_1):page50_i46:dqs4p"
				( attribute "PN" "245"
					( Origin gPackager )
				)
				( objectStatus "J6M1.245" )
			)
			( pin "@baseboard_fab2_lib.baseboard_fab2(sch_1):page50_i46:dqs5n"
				( attribute "PN" "255"
					( Origin gPackager )
				)
				( objectStatus "J6M1.255" )
			)
			( pin "@baseboard_fab2_lib.baseboard_fab2(sch_1):page50_i46:dqs5p"
				( attribute "PN" "256"
					( Origin gPackager )
				)
				( objectStatus "J6M1.256" )
			)
			( pin "@baseboard_fab2_lib.baseboard_fab2(sch_1):page50_i46:dqs6n"
				( attribute "PN" "266"
					( Origin gPackager )
				)
				( objectStatus "J6M1.266" )
			)
			( pin "@baseboard_fab2_lib.baseboard_fab2(sch_1):page50_i46:dqs6p"
				( attribute "PN" "267"
					( Origin gPackager )
				)
				( objectStatus "J6M1.267" )
			)
			( pin "@baseboard_fab2_lib.baseboard_fab2(sch_1):page50_i46:dqs7n"
				( attribute "PN" "277"
					( Origin gPackager )
				)
				( objectStatus "J6M1.277" )
			)
			( pin "@baseboard_fab2_lib.baseboard_fab2(sch_1):page50_i46:dqs7p"
				( attribute "PN" "278"
					( Origin gPackager )
				)
				( objectStatus "J6M1.278" )
			)
			( pin "@baseboard_fab2_lib.baseboard_fab2(sch_1):page50_i46:dqs8n"
				( attribute "PN" "196"
					( Origin gPackager )
				)
				( objectStatus "J6M1.196" )
			)
			( pin "@baseboard_fab2_lib.baseboard_fab2(sch_1):page50_i46:dqs8p"
				( attribute "PN" "197"
					( Origin gPackager )
				)
				( objectStatus "J6M1.197" )
			)
			( pin "@baseboard_fab2_lib.baseboard_fab2(sch_1):page50_i46:dqs9n"
				( attribute "PN" "8"
					( Origin gPackager )
				)
				( objectStatus "J6M1.8" )
			)
			( pin "@baseboard_fab2_lib.baseboard_fab2(sch_1):page50_i46:dqs9p"
				( attribute "PN" "7"
					( Origin gPackager )
				)
				( objectStatus "J6M1.7" )
			)
			( pin "@baseboard_fab2_lib.baseboard_fab2(sch_1):page50_i46:dqs10n"
				( attribute "PN" "19"
					( Origin gPackager )
				)
				( objectStatus "J6M1.19" )
			)
			( pin "@baseboard_fab2_lib.baseboard_fab2(sch_1):page50_i46:dqs10p"
				( attribute "PN" "18"
					( Origin gPackager )
				)
				( objectStatus "J6M1.18" )
			)
			( pin "@baseboard_fab2_lib.baseboard_fab2(sch_1):page50_i46:dqs11n"
				( attribute "PN" "30"
					( Origin gPackager )
				)
				( objectStatus "J6M1.30" )
			)
			( pin "@baseboard_fab2_lib.baseboard_fab2(sch_1):page50_i46:dqs11p"
				( attribute "PN" "29"
					( Origin gPackager )
				)
				( objectStatus "J6M1.29" )
			)
			( pin "@baseboard_fab2_lib.baseboard_fab2(sch_1):page50_i46:dqs12n"
				( attribute "PN" "41"
					( Origin gPackager )
				)
				( objectStatus "J6M1.41" )
			)
			( pin "@baseboard_fab2_lib.baseboard_fab2(sch_1):page50_i46:dqs12p"
				( attribute "PN" "40"
					( Origin gPackager )
				)
				( objectStatus "J6M1.40" )
			)
			( pin "@baseboard_fab2_lib.baseboard_fab2(sch_1):page50_i46:dqs13n"
				( attribute "PN" "100"
					( Origin gPackager )
				)
				( objectStatus "J6M1.100" )
			)
			( pin "@baseboard_fab2_lib.baseboard_fab2(sch_1):page50_i46:dqs13p"
				( attribute "PN" "99"
					( Origin gPackager )
				)
				( objectStatus "J6M1.99" )
			)
			( pin "@baseboard_fab2_lib.baseboard_fab2(sch_1):page50_i46:dqs14n"
				( attribute "PN" "111"
					( Origin gPackager )
				)
				( objectStatus "J6M1.111" )
			)
			( pin "@baseboard_fab2_lib.baseboard_fab2(sch_1):page50_i46:dqs14p"
				( attribute "PN" "110"
					( Origin gPackager )
				)
				( objectStatus "J6M1.110" )
			)
			( pin "@baseboard_fab2_lib.baseboard_fab2(sch_1):page50_i46:dqs15n"
				( attribute "PN" "122"
					( Origin gPackager )
				)
				( objectStatus "J6M1.122" )
			)
			( pin "@baseboard_fab2_lib.baseboard_fab2(sch_1):page50_i46:dqs15p"
				( attribute "PN" "121"
					( Origin gPackager )
				)
				( objectStatus "J6M1.121" )
			)
			( pin "@baseboard_fab2_lib.baseboard_fab2(sch_1):page50_i46:dqs16n"
				( attribute "PN" "133"
					( Origin gPackager )
				)
				( objectStatus "J6M1.133" )
			)
			( pin "@baseboard_fab2_lib.baseboard_fab2(sch_1):page50_i46:dqs16p"
				( attribute "PN" "132"
					( Origin gPackager )
				)
				( objectStatus "J6M1.132" )
			)
			( pin "@baseboard_fab2_lib.baseboard_fab2(sch_1):page50_i46:dqs17n"
				( attribute "PN" "52"
					( Origin gPackager )
				)
				( objectStatus "J6M1.52" )
			)
			( pin "@baseboard_fab2_lib.baseboard_fab2(sch_1):page50_i46:dqs17p"
				( attribute "PN" "51"
					( Origin gPackager )
				)
				( objectStatus "J6M1.51" )
			)
			( pin "@baseboard_fab2_lib.baseboard_fab2(sch_1):page50_i50:\12v\(0)"
				( attribute "PN" "145"
					( Origin gPackager )
				)
				( objectStatus "J6M1.145" )
			)
			( pin "@baseboard_fab2_lib.baseboard_fab2(sch_1):page50_i50:\12v\(1)"
				( attribute "PN" "1"
					( Origin gPackager )
				)
				( objectStatus "J6M1.1" )
			)
			( pin "@baseboard_fab2_lib.baseboard_fab2(sch_1):page50_i50:vdd(0)"
				( attribute "PN" "236"
					( Origin gPackager )
				)
				( objectStatus "J6M1.236" )
			)
			( pin "@baseboard_fab2_lib.baseboard_fab2(sch_1):page50_i50:vdd(1)"
				( attribute "PN" "233"
					( Origin gPackager )
				)
				( objectStatus "J6M1.233" )
			)
			( pin "@baseboard_fab2_lib.baseboard_fab2(sch_1):page50_i50:vdd(2)"
				( attribute "PN" "231"
					( Origin gPackager )
				)
				( objectStatus "J6M1.231" )
			)
			( pin "@baseboard_fab2_lib.baseboard_fab2(sch_1):page50_i50:vdd(3)"
				( attribute "PN" "229"
					( Origin gPackager )
				)
				( objectStatus "J6M1.229" )
			)
			( pin "@baseboard_fab2_lib.baseboard_fab2(sch_1):page50_i50:vdd(4)"
				( attribute "PN" "226"
					( Origin gPackager )
				)
				( objectStatus "J6M1.226" )
			)
			( pin "@baseboard_fab2_lib.baseboard_fab2(sch_1):page50_i50:vdd(5)"
				( attribute "PN" "223"
					( Origin gPackager )
				)
				( objectStatus "J6M1.223" )
			)
			( pin "@baseboard_fab2_lib.baseboard_fab2(sch_1):page50_i50:vdd(6)"
				( attribute "PN" "220"
					( Origin gPackager )
				)
				( objectStatus "J6M1.220" )
			)
			( pin "@baseboard_fab2_lib.baseboard_fab2(sch_1):page50_i50:vdd(7)"
				( attribute "PN" "217"
					( Origin gPackager )
				)
				( objectStatus "J6M1.217" )
			)
			( pin "@baseboard_fab2_lib.baseboard_fab2(sch_1):page50_i50:vdd(8)"
				( attribute "PN" "215"
					( Origin gPackager )
				)
				( objectStatus "J6M1.215" )
			)
			( pin "@baseboard_fab2_lib.baseboard_fab2(sch_1):page50_i50:vdd(9)"
				( attribute "PN" "212"
					( Origin gPackager )
				)
				( objectStatus "J6M1.212" )
			)
			( pin "@baseboard_fab2_lib.baseboard_fab2(sch_1):page50_i50:vdd(10)"
				( attribute "PN" "209"
					( Origin gPackager )
				)
				( objectStatus "J6M1.209" )
			)
			( pin "@baseboard_fab2_lib.baseboard_fab2(sch_1):page50_i50:vdd(11)"
				( attribute "PN" "206"
					( Origin gPackager )
				)
				( objectStatus "J6M1.206" )
			)
			( pin "@baseboard_fab2_lib.baseboard_fab2(sch_1):page50_i50:vdd(12)"
				( attribute "PN" "204"
					( Origin gPackager )
				)
				( objectStatus "J6M1.204" )
			)
			( pin "@baseboard_fab2_lib.baseboard_fab2(sch_1):page50_i50:vdd(13)"
				( attribute "PN" "92"
					( Origin gPackager )
				)
				( objectStatus "J6M1.92" )
			)
			( pin "@baseboard_fab2_lib.baseboard_fab2(sch_1):page50_i50:vdd(14)"
				( attribute "PN" "90"
					( Origin gPackager )
				)
				( objectStatus "J6M1.90" )
			)
			( pin "@baseboard_fab2_lib.baseboard_fab2(sch_1):page50_i50:vdd(15)"
				( attribute "PN" "88"
					( Origin gPackager )
				)
				( objectStatus "J6M1.88" )
			)
			( pin "@baseboard_fab2_lib.baseboard_fab2(sch_1):page50_i50:vdd(16)"
				( attribute "PN" "85"
					( Origin gPackager )
				)
				( objectStatus "J6M1.85" )
			)
			( pin "@baseboard_fab2_lib.baseboard_fab2(sch_1):page50_i50:vdd(17)"
				( attribute "PN" "83"
					( Origin gPackager )
				)
				( objectStatus "J6M1.83" )
			)
			( pin "@baseboard_fab2_lib.baseboard_fab2(sch_1):page50_i50:vdd(18)"
				( attribute "PN" "80"
					( Origin gPackager )
				)
				( objectStatus "J6M1.80" )
			)
			( pin "@baseboard_fab2_lib.baseboard_fab2(sch_1):page50_i50:vdd(19)"
				( attribute "PN" "76"
					( Origin gPackager )
				)
				( objectStatus "J6M1.76" )
			)
			( pin "@baseboard_fab2_lib.baseboard_fab2(sch_1):page50_i50:vdd(20)"
				( attribute "PN" "73"
					( Origin gPackager )
				)
				( objectStatus "J6M1.73" )
			)
			( pin "@baseboard_fab2_lib.baseboard_fab2(sch_1):page50_i50:vdd(21)"
				( attribute "PN" "70"
					( Origin gPackager )
				)
				( objectStatus "J6M1.70" )
			)
			( pin "@baseboard_fab2_lib.baseboard_fab2(sch_1):page50_i50:vdd(22)"
				( attribute "PN" "67"
					( Origin gPackager )
				)
				( objectStatus "J6M1.67" )
			)
			( pin "@baseboard_fab2_lib.baseboard_fab2(sch_1):page50_i50:vdd(23)"
				( attribute "PN" "64"
					( Origin gPackager )
				)
				( objectStatus "J6M1.64" )
			)
			( pin "@baseboard_fab2_lib.baseboard_fab2(sch_1):page50_i50:vdd(24)"
				( attribute "PN" "61"
					( Origin gPackager )
				)
				( objectStatus "J6M1.61" )
			)
			( pin "@baseboard_fab2_lib.baseboard_fab2(sch_1):page50_i50:vdd(25)"
				( attribute "PN" "59"
					( Origin gPackager )
				)
				( objectStatus "J6M1.59" )
			)
			( pin "@baseboard_fab2_lib.baseboard_fab2(sch_1):page50_i50:vpp(0)"
				( attribute "PN" "287"
					( Origin gPackager )
				)
				( objectStatus "J6M1.287" )
			)
			( pin "@baseboard_fab2_lib.baseboard_fab2(sch_1):page50_i50:vpp(1)"
				( attribute "PN" "286"
					( Origin gPackager )
				)
				( objectStatus "J6M1.286" )
			)
			( pin "@baseboard_fab2_lib.baseboard_fab2(sch_1):page50_i50:vpp(2)"
				( attribute "PN" "288"
					( Origin gPackager )
				)
				( objectStatus "J6M1.288" )
			)
			( pin "@baseboard_fab2_lib.baseboard_fab2(sch_1):page50_i50:vpp(3)"
				( attribute "PN" "143"
					( Origin gPackager )
				)
				( objectStatus "J6M1.143" )
			)
			( pin "@baseboard_fab2_lib.baseboard_fab2(sch_1):page50_i50:vpp(4)"
				( attribute "PN" "142"
					( Origin gPackager )
				)
				( objectStatus "J6M1.142" )
			)
			( pin "@baseboard_fab2_lib.baseboard_fab2(sch_1):page50_i50:vtt(0)"
				( attribute "PN" "221"
					( Origin gPackager )
				)
				( objectStatus "J6M1.221" )
			)
			( pin "@baseboard_fab2_lib.baseboard_fab2(sch_1):page50_i50:vtt(1)"
				( attribute "PN" "77"
					( Origin gPackager )
				)
				( objectStatus "J6M1.77" )
			)
			( pin "@baseboard_fab2_lib.baseboard_fab2(sch_1):page50_i158:a0"
				( attribute "PN" "79"
					( Origin gPackager )
				)
				( objectStatus "J6M1.79" )
			)
			( pin "@baseboard_fab2_lib.baseboard_fab2(sch_1):page50_i158:a1"
				( attribute "PN" "72"
					( Origin gPackager )
				)
				( objectStatus "J6M1.72" )
			)
			( pin "@baseboard_fab2_lib.baseboard_fab2(sch_1):page50_i158:a2"
				( attribute "PN" "216"
					( Origin gPackager )
				)
				( objectStatus "J6M1.216" )
			)
			( pin "@baseboard_fab2_lib.baseboard_fab2(sch_1):page50_i158:a3"
				( attribute "PN" "71"
					( Origin gPackager )
				)
				( objectStatus "J6M1.71" )
			)
			( pin "@baseboard_fab2_lib.baseboard_fab2(sch_1):page50_i158:a4"
				( attribute "PN" "214"
					( Origin gPackager )
				)
				( objectStatus "J6M1.214" )
			)
			( pin "@baseboard_fab2_lib.baseboard_fab2(sch_1):page50_i158:a5"
				( attribute "PN" "213"
					( Origin gPackager )
				)
				( objectStatus "J6M1.213" )
			)
			( pin "@baseboard_fab2_lib.baseboard_fab2(sch_1):page50_i158:a6"
				( attribute "PN" "69"
					( Origin gPackager )
				)
				( objectStatus "J6M1.69" )
			)
			( pin "@baseboard_fab2_lib.baseboard_fab2(sch_1):page50_i158:a7"
				( attribute "PN" "211"
					( Origin gPackager )
				)
				( objectStatus "J6M1.211" )
			)
			( pin "@baseboard_fab2_lib.baseboard_fab2(sch_1):page50_i158:a8"
				( attribute "PN" "68"
					( Origin gPackager )
				)
				( objectStatus "J6M1.68" )
			)
			( pin "@baseboard_fab2_lib.baseboard_fab2(sch_1):page50_i158:a9"
				( attribute "PN" "66"
					( Origin gPackager )
				)
				( objectStatus "J6M1.66" )
			)
			( pin "@baseboard_fab2_lib.baseboard_fab2(sch_1):page50_i158:a10"
				( attribute "PN" "225"
					( Origin gPackager )
				)
				( objectStatus "J6M1.225" )
			)
			( pin "@baseboard_fab2_lib.baseboard_fab2(sch_1):page50_i158:a11"
				( attribute "PN" "210"
					( Origin gPackager )
				)
				( objectStatus "J6M1.210" )
			)
			( pin "@baseboard_fab2_lib.baseboard_fab2(sch_1):page50_i158:a12"
				( attribute "PN" "65"
					( Origin gPackager )
				)
				( objectStatus "J6M1.65" )
			)
			( pin "@baseboard_fab2_lib.baseboard_fab2(sch_1):page50_i158:a13"
				( attribute "PN" "232"
					( Origin gPackager )
				)
				( objectStatus "J6M1.232" )
			)
			( pin "@baseboard_fab2_lib.baseboard_fab2(sch_1):page50_i158:a14_we_n"
				( attribute "PN" "228"
					( Origin gPackager )
				)
				( objectStatus "J6M1.228" )
			)
			( pin "@baseboard_fab2_lib.baseboard_fab2(sch_1):page50_i158:a15_cas_n"
				( attribute "PN" "86"
					( Origin gPackager )
				)
				( objectStatus "J6M1.86" )
			)
			( pin "@baseboard_fab2_lib.baseboard_fab2(sch_1):page50_i158:a16_ras_n"
				( attribute "PN" "82"
					( Origin gPackager )
				)
				( objectStatus "J6M1.82" )
			)
			( pin "@baseboard_fab2_lib.baseboard_fab2(sch_1):page50_i158:a17"
				( attribute "PN" "234"
					( Origin gPackager )
				)
				( objectStatus "J6M1.234" )
			)
			( pin "@baseboard_fab2_lib.baseboard_fab2(sch_1):page50_i158:act_n"
				( attribute "PN" "62"
					( Origin gPackager )
				)
				( objectStatus "J6M1.62" )
			)
			( pin "@baseboard_fab2_lib.baseboard_fab2(sch_1):page50_i158:alert_n"
				( attribute "PN" "208"
					( Origin gPackager )
				)
				( objectStatus "J6M1.208" )
			)
			( pin "@baseboard_fab2_lib.baseboard_fab2(sch_1):page50_i158:ba(0)"
				( attribute "PN" "81"
					( Origin gPackager )
				)
				( objectStatus "J6M1.81" )
			)
			( pin "@baseboard_fab2_lib.baseboard_fab2(sch_1):page50_i158:ba(1)"
				( attribute "PN" "224"
					( Origin gPackager )
				)
				( objectStatus "J6M1.224" )
			)
			( pin "@baseboard_fab2_lib.baseboard_fab2(sch_1):page50_i158:bg(0)"
				( attribute "PN" "63"
					( Origin gPackager )
				)
				( objectStatus "J6M1.63" )
			)
			( pin "@baseboard_fab2_lib.baseboard_fab2(sch_1):page50_i158:bg(1)"
				( attribute "PN" "207"
					( Origin gPackager )
				)
				( objectStatus "J6M1.207" )
			)
			( pin "@baseboard_fab2_lib.baseboard_fab2(sch_1):page50_i158:c(2)"
				( attribute "PN" "235"
					( Origin gPackager )
				)
				( objectStatus "J6M1.235" )
			)
			( pin "@baseboard_fab2_lib.baseboard_fab2(sch_1):page50_i158:cb(0)"
				( attribute "PN" "49"
					( Origin gPackager )
				)
				( objectStatus "J6M1.49" )
			)
			( pin "@baseboard_fab2_lib.baseboard_fab2(sch_1):page50_i158:cb(1)"
				( attribute "PN" "194"
					( Origin gPackager )
				)
				( objectStatus "J6M1.194" )
			)
			( pin "@baseboard_fab2_lib.baseboard_fab2(sch_1):page50_i158:cb(2)"
				( attribute "PN" "56"
					( Origin gPackager )
				)
				( objectStatus "J6M1.56" )
			)
			( pin "@baseboard_fab2_lib.baseboard_fab2(sch_1):page50_i158:cb(3)"
				( attribute "PN" "201"
					( Origin gPackager )
				)
				( objectStatus "J6M1.201" )
			)
			( pin "@baseboard_fab2_lib.baseboard_fab2(sch_1):page50_i158:cb(4)"
				( attribute "PN" "47"
					( Origin gPackager )
				)
				( objectStatus "J6M1.47" )
			)
			( pin "@baseboard_fab2_lib.baseboard_fab2(sch_1):page50_i158:cb(5)"
				( attribute "PN" "192"
					( Origin gPackager )
				)
				( objectStatus "J6M1.192" )
			)
			( pin "@baseboard_fab2_lib.baseboard_fab2(sch_1):page50_i158:cb(6)"
				( attribute "PN" "54"
					( Origin gPackager )
				)
				( objectStatus "J6M1.54" )
			)
			( pin "@baseboard_fab2_lib.baseboard_fab2(sch_1):page50_i158:cb(7)"
				( attribute "PN" "199"
					( Origin gPackager )
				)
				( objectStatus "J6M1.199" )
			)
			( pin "@baseboard_fab2_lib.baseboard_fab2(sch_1):page50_i158:ck0n"
				( attribute "PN" "75"
					( Origin gPackager )
				)
				( objectStatus "J6M1.75" )
			)
			( pin "@baseboard_fab2_lib.baseboard_fab2(sch_1):page50_i158:ck0p"
				( attribute "PN" "74"
					( Origin gPackager )
				)
				( objectStatus "J6M1.74" )
			)
			( pin "@baseboard_fab2_lib.baseboard_fab2(sch_1):page50_i158:ck1n"
				( attribute "PN" "219"
					( Origin gPackager )
				)
				( objectStatus "J6M1.219" )
			)
			( pin "@baseboard_fab2_lib.baseboard_fab2(sch_1):page50_i158:ck1p"
				( attribute "PN" "218"
					( Origin gPackager )
				)
				( objectStatus "J6M1.218" )
			)
			( pin "@baseboard_fab2_lib.baseboard_fab2(sch_1):page50_i158:cke(0)"
				( attribute "PN" "60"
					( Origin gPackager )
				)
				( objectStatus "J6M1.60" )
			)
			( pin "@baseboard_fab2_lib.baseboard_fab2(sch_1):page50_i158:cke(1)"
				( attribute "PN" "203"
					( Origin gPackager )
				)
				( objectStatus "J6M1.203" )
			)
			( pin "@baseboard_fab2_lib.baseboard_fab2(sch_1):page50_i158:dq(0)"
				( attribute "PN" "5"
					( Origin gPackager )
				)
				( objectStatus "J6M1.5" )
			)
			( pin "@baseboard_fab2_lib.baseboard_fab2(sch_1):page50_i158:dq(1)"
				( attribute "PN" "150"
					( Origin gPackager )
				)
				( objectStatus "J6M1.150" )
			)
			( pin "@baseboard_fab2_lib.baseboard_fab2(sch_1):page50_i158:dq(2)"
				( attribute "PN" "12"
					( Origin gPackager )
				)
				( objectStatus "J6M1.12" )
			)
			( pin "@baseboard_fab2_lib.baseboard_fab2(sch_1):page50_i158:dq(3)"
				( attribute "PN" "157"
					( Origin gPackager )
				)
				( objectStatus "J6M1.157" )
			)
			( pin "@baseboard_fab2_lib.baseboard_fab2(sch_1):page50_i158:dq(4)"
				( attribute "PN" "3"
					( Origin gPackager )
				)
				( objectStatus "J6M1.3" )
			)
			( pin "@baseboard_fab2_lib.baseboard_fab2(sch_1):page50_i158:dq(5)"
				( attribute "PN" "148"
					( Origin gPackager )
				)
				( objectStatus "J6M1.148" )
			)
			( pin "@baseboard_fab2_lib.baseboard_fab2(sch_1):page50_i158:dq(6)"
				( attribute "PN" "10"
					( Origin gPackager )
				)
				( objectStatus "J6M1.10" )
			)
			( pin "@baseboard_fab2_lib.baseboard_fab2(sch_1):page50_i158:dq(7)"
				( attribute "PN" "155"
					( Origin gPackager )
				)
				( objectStatus "J6M1.155" )
			)
			( pin "@baseboard_fab2_lib.baseboard_fab2(sch_1):page50_i158:dq(8)"
				( attribute "PN" "16"
					( Origin gPackager )
				)
				( objectStatus "J6M1.16" )
			)
			( pin "@baseboard_fab2_lib.baseboard_fab2(sch_1):page50_i158:dq(9)"
				( attribute "PN" "161"
					( Origin gPackager )
				)
				( objectStatus "J6M1.161" )
			)
			( pin "@baseboard_fab2_lib.baseboard_fab2(sch_1):page50_i158:dq(10)"
				( attribute "PN" "23"
					( Origin gPackager )
				)
				( objectStatus "J6M1.23" )
			)
			( pin "@baseboard_fab2_lib.baseboard_fab2(sch_1):page50_i158:dq(11)"
				( attribute "PN" "168"
					( Origin gPackager )
				)
				( objectStatus "J6M1.168" )
			)
			( pin "@baseboard_fab2_lib.baseboard_fab2(sch_1):page50_i158:dq(12)"
				( attribute "PN" "14"
					( Origin gPackager )
				)
				( objectStatus "J6M1.14" )
			)
			( pin "@baseboard_fab2_lib.baseboard_fab2(sch_1):page50_i158:dq(13)"
				( attribute "PN" "159"
					( Origin gPackager )
				)
				( objectStatus "J6M1.159" )
			)
			( pin "@baseboard_fab2_lib.baseboard_fab2(sch_1):page50_i158:dq(14)"
				( attribute "PN" "21"
					( Origin gPackager )
				)
				( objectStatus "J6M1.21" )
			)
			( pin "@baseboard_fab2_lib.baseboard_fab2(sch_1):page50_i158:dq(15)"
				( attribute "PN" "166"
					( Origin gPackager )
				)
				( objectStatus "J6M1.166" )
			)
			( pin "@baseboard_fab2_lib.baseboard_fab2(sch_1):page50_i158:dq(16)"
				( attribute "PN" "27"
					( Origin gPackager )
				)
				( objectStatus "J6M1.27" )
			)
			( pin "@baseboard_fab2_lib.baseboard_fab2(sch_1):page50_i158:dq(17)"
				( attribute "PN" "172"
					( Origin gPackager )
				)
				( objectStatus "J6M1.172" )
			)
			( pin "@baseboard_fab2_lib.baseboard_fab2(sch_1):page50_i158:dq(18)"
				( attribute "PN" "34"
					( Origin gPackager )
				)
				( objectStatus "J6M1.34" )
			)
			( pin "@baseboard_fab2_lib.baseboard_fab2(sch_1):page50_i158:dq(19)"
				( attribute "PN" "179"
					( Origin gPackager )
				)
				( objectStatus "J6M1.179" )
			)
			( pin "@baseboard_fab2_lib.baseboard_fab2(sch_1):page50_i158:dq(20)"
				( attribute "PN" "25"
					( Origin gPackager )
				)
				( objectStatus "J6M1.25" )
			)
			( pin "@baseboard_fab2_lib.baseboard_fab2(sch_1):page50_i158:dq(21)"
				( attribute "PN" "170"
					( Origin gPackager )
				)
				( objectStatus "J6M1.170" )
			)
			( pin "@baseboard_fab2_lib.baseboard_fab2(sch_1):page50_i158:dq(22)"
				( attribute "PN" "32"
					( Origin gPackager )
				)
				( objectStatus "J6M1.32" )
			)
			( pin "@baseboard_fab2_lib.baseboard_fab2(sch_1):page50_i158:dq(23)"
				( attribute "PN" "177"
					( Origin gPackager )
				)
				( objectStatus "J6M1.177" )
			)
			( pin "@baseboard_fab2_lib.baseboard_fab2(sch_1):page50_i158:dq(24)"
				( attribute "PN" "38"
					( Origin gPackager )
				)
				( objectStatus "J6M1.38" )
			)
			( pin "@baseboard_fab2_lib.baseboard_fab2(sch_1):page50_i158:dq(25)"
				( attribute "PN" "183"
					( Origin gPackager )
				)
				( objectStatus "J6M1.183" )
			)
			( pin "@baseboard_fab2_lib.baseboard_fab2(sch_1):page50_i158:dq(26)"
				( attribute "PN" "45"
					( Origin gPackager )
				)
				( objectStatus "J6M1.45" )
			)
			( pin "@baseboard_fab2_lib.baseboard_fab2(sch_1):page50_i158:dq(27)"
				( attribute "PN" "190"
					( Origin gPackager )
				)
				( objectStatus "J6M1.190" )
			)
			( pin "@baseboard_fab2_lib.baseboard_fab2(sch_1):page50_i158:dq(28)"
				( attribute "PN" "36"
					( Origin gPackager )
				)
				( objectStatus "J6M1.36" )
			)
			( pin "@baseboard_fab2_lib.baseboard_fab2(sch_1):page50_i158:dq(29)"
				( attribute "PN" "181"
					( Origin gPackager )
				)
				( objectStatus "J6M1.181" )
			)
			( pin "@baseboard_fab2_lib.baseboard_fab2(sch_1):page50_i158:dq(30)"
				( attribute "PN" "43"
					( Origin gPackager )
				)
				( objectStatus "J6M1.43" )
			)
			( pin "@baseboard_fab2_lib.baseboard_fab2(sch_1):page50_i158:dq(31)"
				( attribute "PN" "188"
					( Origin gPackager )
				)
				( objectStatus "J6M1.188" )
			)
			( pin "@baseboard_fab2_lib.baseboard_fab2(sch_1):page50_i158:dq(32)"
				( attribute "PN" "97"
					( Origin gPackager )
				)
				( objectStatus "J6M1.97" )
			)
			( pin "@baseboard_fab2_lib.baseboard_fab2(sch_1):page50_i158:dq(33)"
				( attribute "PN" "242"
					( Origin gPackager )
				)
				( objectStatus "J6M1.242" )
			)
			( pin "@baseboard_fab2_lib.baseboard_fab2(sch_1):page50_i158:dq(34)"
				( attribute "PN" "104"
					( Origin gPackager )
				)
				( objectStatus "J6M1.104" )
			)
			( pin "@baseboard_fab2_lib.baseboard_fab2(sch_1):page50_i158:dq(35)"
				( attribute "PN" "249"
					( Origin gPackager )
				)
				( objectStatus "J6M1.249" )
			)
			( pin "@baseboard_fab2_lib.baseboard_fab2(sch_1):page50_i158:dq(36)"
				( attribute "PN" "95"
					( Origin gPackager )
				)
				( objectStatus "J6M1.95" )
			)
			( pin "@baseboard_fab2_lib.baseboard_fab2(sch_1):page50_i158:dq(37)"
				( attribute "PN" "240"
					( Origin gPackager )
				)
				( objectStatus "J6M1.240" )
			)
			( pin "@baseboard_fab2_lib.baseboard_fab2(sch_1):page50_i158:dq(38)"
				( attribute "PN" "102"
					( Origin gPackager )
				)
				( objectStatus "J6M1.102" )
			)
			( pin "@baseboard_fab2_lib.baseboard_fab2(sch_1):page50_i158:dq(39)"
				( attribute "PN" "247"
					( Origin gPackager )
				)
				( objectStatus "J6M1.247" )
			)
			( pin "@baseboard_fab2_lib.baseboard_fab2(sch_1):page50_i158:dq(40)"
				( attribute "PN" "108"
					( Origin gPackager )
				)
				( objectStatus "J6M1.108" )
			)
			( pin "@baseboard_fab2_lib.baseboard_fab2(sch_1):page50_i158:dq(41)"
				( attribute "PN" "253"
					( Origin gPackager )
				)
				( objectStatus "J6M1.253" )
			)
			( pin "@baseboard_fab2_lib.baseboard_fab2(sch_1):page50_i158:dq(42)"
				( attribute "PN" "115"
					( Origin gPackager )
				)
				( objectStatus "J6M1.115" )
			)
			( pin "@baseboard_fab2_lib.baseboard_fab2(sch_1):page50_i158:dq(43)"
				( attribute "PN" "260"
					( Origin gPackager )
				)
				( objectStatus "J6M1.260" )
			)
			( pin "@baseboard_fab2_lib.baseboard_fab2(sch_1):page50_i158:dq(44)"
				( attribute "PN" "106"
					( Origin gPackager )
				)
				( objectStatus "J6M1.106" )
			)
			( pin "@baseboard_fab2_lib.baseboard_fab2(sch_1):page50_i158:dq(45)"
				( attribute "PN" "251"
					( Origin gPackager )
				)
				( objectStatus "J6M1.251" )
			)
			( pin "@baseboard_fab2_lib.baseboard_fab2(sch_1):page50_i158:dq(46)"
				( attribute "PN" "113"
					( Origin gPackager )
				)
				( objectStatus "J6M1.113" )
			)
			( pin "@baseboard_fab2_lib.baseboard_fab2(sch_1):page50_i158:dq(47)"
				( attribute "PN" "258"
					( Origin gPackager )
				)
				( objectStatus "J6M1.258" )
			)
			( pin "@baseboard_fab2_lib.baseboard_fab2(sch_1):page50_i158:dq(48)"
				( attribute "PN" "119"
					( Origin gPackager )
				)
				( objectStatus "J6M1.119" )
			)
			( pin "@baseboard_fab2_lib.baseboard_fab2(sch_1):page50_i158:dq(49)"
				( attribute "PN" "264"
					( Origin gPackager )
				)
				( objectStatus "J6M1.264" )
			)
			( pin "@baseboard_fab2_lib.baseboard_fab2(sch_1):page50_i158:dq(50)"
				( attribute "PN" "126"
					( Origin gPackager )
				)
				( objectStatus "J6M1.126" )
			)
			( pin "@baseboard_fab2_lib.baseboard_fab2(sch_1):page50_i158:dq(51)"
				( attribute "PN" "271"
					( Origin gPackager )
				)
				( objectStatus "J6M1.271" )
			)
			( pin "@baseboard_fab2_lib.baseboard_fab2(sch_1):page50_i158:dq(52)"
				( attribute "PN" "117"
					( Origin gPackager )
				)
				( objectStatus "J6M1.117" )
			)
			( pin "@baseboard_fab2_lib.baseboard_fab2(sch_1):page50_i158:dq(53)"
				( attribute "PN" "262"
					( Origin gPackager )
				)
				( objectStatus "J6M1.262" )
			)
			( pin "@baseboard_fab2_lib.baseboard_fab2(sch_1):page50_i158:dq(54)"
				( attribute "PN" "124"
					( Origin gPackager )
				)
				( objectStatus "J6M1.124" )
			)
			( pin "@baseboard_fab2_lib.baseboard_fab2(sch_1):page50_i158:dq(55)"
				( attribute "PN" "269"
					( Origin gPackager )
				)
				( objectStatus "J6M1.269" )
			)
			( pin "@baseboard_fab2_lib.baseboard_fab2(sch_1):page50_i158:dq(56)"
				( attribute "PN" "130"
					( Origin gPackager )
				)
				( objectStatus "J6M1.130" )
			)
			( pin "@baseboard_fab2_lib.baseboard_fab2(sch_1):page50_i158:dq(57)"
				( attribute "PN" "275"
					( Origin gPackager )
				)
				( objectStatus "J6M1.275" )
			)
			( pin "@baseboard_fab2_lib.baseboard_fab2(sch_1):page50_i158:dq(58)"
				( attribute "PN" "137"
					( Origin gPackager )
				)
				( objectStatus "J6M1.137" )
			)
			( pin "@baseboard_fab2_lib.baseboard_fab2(sch_1):page50_i158:dq(59)"
				( attribute "PN" "282"
					( Origin gPackager )
				)
				( objectStatus "J6M1.282" )
			)
			( pin "@baseboard_fab2_lib.baseboard_fab2(sch_1):page50_i158:dq(60)"
				( attribute "PN" "128"
					( Origin gPackager )
				)
				( objectStatus "J6M1.128" )
			)
			( pin "@baseboard_fab2_lib.baseboard_fab2(sch_1):page50_i158:dq(61)"
				( attribute "PN" "273"
					( Origin gPackager )
				)
				( objectStatus "J6M1.273" )
			)
			( pin "@baseboard_fab2_lib.baseboard_fab2(sch_1):page50_i158:dq(62)"
				( attribute "PN" "135"
					( Origin gPackager )
				)
				( objectStatus "J6M1.135" )
			)
			( pin "@baseboard_fab2_lib.baseboard_fab2(sch_1):page50_i158:dq(63)"
				( attribute "PN" "280"
					( Origin gPackager )
				)
				( objectStatus "J6M1.280" )
			)
			( pin "@baseboard_fab2_lib.baseboard_fab2(sch_1):page50_i158:event_n"
				( attribute "PN" "78"
					( Origin gPackager )
				)
				( objectStatus "J6M1.78" )
			)
			( pin "@baseboard_fab2_lib.baseboard_fab2(sch_1):page50_i158:odt(0)"
				( attribute "PN" "87"
					( Origin gPackager )
				)
				( objectStatus "J6M1.87" )
			)
			( pin "@baseboard_fab2_lib.baseboard_fab2(sch_1):page50_i158:odt(1)"
				( attribute "PN" "91"
					( Origin gPackager )
				)
				( objectStatus "J6M1.91" )
			)
			( pin "@baseboard_fab2_lib.baseboard_fab2(sch_1):page50_i158:par"
				( attribute "PN" "222"
					( Origin gPackager )
				)
				( objectStatus "J6M1.222" )
			)
			( pin "@baseboard_fab2_lib.baseboard_fab2(sch_1):page50_i158:reset_n"
				( attribute "PN" "58"
					( Origin gPackager )
				)
				( objectStatus "J6M1.58" )
			)
			( pin "@baseboard_fab2_lib.baseboard_fab2(sch_1):page50_i158:rfu(0)"
				( attribute "PN" "205"
					( Origin gPackager )
				)
				( objectStatus "J6M1.205" )
			)
			( pin "@baseboard_fab2_lib.baseboard_fab2(sch_1):page50_i158:rfu(1)"
				( attribute "PN" "227"
					( Origin gPackager )
				)
				( objectStatus "J6M1.227" )
			)
			( pin "@baseboard_fab2_lib.baseboard_fab2(sch_1):page50_i158:rfu(2)"
				( attribute "PN" "144"
					( Origin gPackager )
				)
				( objectStatus "J6M1.144" )
			)
			( pin "@baseboard_fab2_lib.baseboard_fab2(sch_1):page50_i158:s0_n"
				( attribute "PN" "84"
					( Origin gPackager )
				)
				( objectStatus "J6M1.84" )
			)
			( pin "@baseboard_fab2_lib.baseboard_fab2(sch_1):page50_i158:s1_n"
				( attribute "PN" "89"
					( Origin gPackager )
				)
				( objectStatus "J6M1.89" )
			)
			( pin "@baseboard_fab2_lib.baseboard_fab2(sch_1):page50_i158:s2_n_c(0)"
				( attribute "PN" "93"
					( Origin gPackager )
				)
				( objectStatus "J6M1.93" )
			)
			( pin "@baseboard_fab2_lib.baseboard_fab2(sch_1):page50_i158:s3_n_c(1)"
				( attribute "PN" "237"
					( Origin gPackager )
				)
				( objectStatus "J6M1.237" )
			)
			( pin "@baseboard_fab2_lib.baseboard_fab2(sch_1):page50_i158:sa(0)"
				( attribute "PN" "139"
					( Origin gPackager )
				)
				( objectStatus "J6M1.139" )
			)
			( pin "@baseboard_fab2_lib.baseboard_fab2(sch_1):page50_i158:sa(1)"
				( attribute "PN" "140"
					( Origin gPackager )
				)
				( objectStatus "J6M1.140" )
			)
			( pin "@baseboard_fab2_lib.baseboard_fab2(sch_1):page50_i158:sa(2)"
				( attribute "PN" "238"
					( Origin gPackager )
				)
				( objectStatus "J6M1.238" )
			)
			( pin "@baseboard_fab2_lib.baseboard_fab2(sch_1):page50_i158:save_n_nc"
				( attribute "PN" "230"
					( Origin gPackager )
				)
				( objectStatus "J6M1.230" )
			)
			( pin "@baseboard_fab2_lib.baseboard_fab2(sch_1):page50_i158:scl"
				( attribute "PN" "141"
					( Origin gPackager )
				)
				( objectStatus "J6M1.141" )
			)
			( pin "@baseboard_fab2_lib.baseboard_fab2(sch_1):page50_i158:sda"
				( attribute "PN" "285"
					( Origin gPackager )
				)
				( objectStatus "J6M1.285" )
			)
			( pin "@baseboard_fab2_lib.baseboard_fab2(sch_1):page50_i158:vddspd"
				( attribute "PN" "284"
					( Origin gPackager )
				)
				( objectStatus "J6M1.284" )
			)
			( pin "@baseboard_fab2_lib.baseboard_fab2(sch_1):page50_i158:vrefca"
				( attribute "PN" "146"
					( Origin gPackager )
				)
				( objectStatus "J6M1.146" )
			)
			( pin "@baseboard_fab2_lib.baseboard_fab2(sch_1):page50_i177:a"
				( attribute "PN" "1"
					( Origin gPackager )
				)
				( objectStatus "C6M1.1" )
			)
			( pin "@baseboard_fab2_lib.baseboard_fab2(sch_1):page50_i177:b"
				( attribute "PN" "2"
					( Origin gPackager )
				)
				( objectStatus "C6M1.2" )
			)
			( pin "@baseboard_fab2_lib.baseboard_fab2(sch_1):page51_i43:vss(0)"
				( attribute "PN" "283"
					( Origin gPackager )
				)
				( objectStatus "J4A2.283" )
			)
			( pin "@baseboard_fab2_lib.baseboard_fab2(sch_1):page51_i43:vss(1)"
				( attribute "PN" "281"
					( Origin gPackager )
				)
				( objectStatus "J4A2.281" )
			)
			( pin "@baseboard_fab2_lib.baseboard_fab2(sch_1):page51_i43:vss(2)"
				( attribute "PN" "279"
					( Origin gPackager )
				)
				( objectStatus "J4A2.279" )
			)
			( pin "@baseboard_fab2_lib.baseboard_fab2(sch_1):page51_i43:vss(3)"
				( attribute "PN" "276"
					( Origin gPackager )
				)
				( objectStatus "J4A2.276" )
			)
			( pin "@baseboard_fab2_lib.baseboard_fab2(sch_1):page51_i43:vss(4)"
				( attribute "PN" "274"
					( Origin gPackager )
				)
				( objectStatus "J4A2.274" )
			)
			( pin "@baseboard_fab2_lib.baseboard_fab2(sch_1):page51_i43:vss(5)"
				( attribute "PN" "272"
					( Origin gPackager )
				)
				( objectStatus "J4A2.272" )
			)
			( pin "@baseboard_fab2_lib.baseboard_fab2(sch_1):page51_i43:vss(6)"
				( attribute "PN" "270"
					( Origin gPackager )
				)
				( objectStatus "J4A2.270" )
			)
			( pin "@baseboard_fab2_lib.baseboard_fab2(sch_1):page51_i43:vss(7)"
				( attribute "PN" "268"
					( Origin gPackager )
				)
				( objectStatus "J4A2.268" )
			)
			( pin "@baseboard_fab2_lib.baseboard_fab2(sch_1):page51_i43:vss(8)"
				( attribute "PN" "265"
					( Origin gPackager )
				)
				( objectStatus "J4A2.265" )
			)
			( pin "@baseboard_fab2_lib.baseboard_fab2(sch_1):page51_i43:vss(9)"
				( attribute "PN" "263"
					( Origin gPackager )
				)
				( objectStatus "J4A2.263" )
			)
			( pin "@baseboard_fab2_lib.baseboard_fab2(sch_1):page51_i43:vss(10)"
				( attribute "PN" "261"
					( Origin gPackager )
				)
				( objectStatus "J4A2.261" )
			)
			( pin "@baseboard_fab2_lib.baseboard_fab2(sch_1):page51_i43:vss(11)"
				( attribute "PN" "259"
					( Origin gPackager )
				)
				( objectStatus "J4A2.259" )
			)
			( pin "@baseboard_fab2_lib.baseboard_fab2(sch_1):page51_i43:vss(12)"
				( attribute "PN" "257"
					( Origin gPackager )
				)
				( objectStatus "J4A2.257" )
			)
			( pin "@baseboard_fab2_lib.baseboard_fab2(sch_1):page51_i43:vss(13)"
				( attribute "PN" "254"
					( Origin gPackager )
				)
				( objectStatus "J4A2.254" )
			)
			( pin "@baseboard_fab2_lib.baseboard_fab2(sch_1):page51_i43:vss(14)"
				( attribute "PN" "252"
					( Origin gPackager )
				)
				( objectStatus "J4A2.252" )
			)
			( pin "@baseboard_fab2_lib.baseboard_fab2(sch_1):page51_i43:vss(15)"
				( attribute "PN" "250"
					( Origin gPackager )
				)
				( objectStatus "J4A2.250" )
			)
			( pin "@baseboard_fab2_lib.baseboard_fab2(sch_1):page51_i43:vss(16)"
				( attribute "PN" "248"
					( Origin gPackager )
				)
				( objectStatus "J4A2.248" )
			)
			( pin "@baseboard_fab2_lib.baseboard_fab2(sch_1):page51_i43:vss(17)"
				( attribute "PN" "246"
					( Origin gPackager )
				)
				( objectStatus "J4A2.246" )
			)
			( pin "@baseboard_fab2_lib.baseboard_fab2(sch_1):page51_i43:vss(18)"
				( attribute "PN" "243"
					( Origin gPackager )
				)
				( objectStatus "J4A2.243" )
			)
			( pin "@baseboard_fab2_lib.baseboard_fab2(sch_1):page51_i43:vss(19)"
				( attribute "PN" "241"
					( Origin gPackager )
				)
				( objectStatus "J4A2.241" )
			)
			( pin "@baseboard_fab2_lib.baseboard_fab2(sch_1):page51_i43:vss(20)"
				( attribute "PN" "239"
					( Origin gPackager )
				)
				( objectStatus "J4A2.239" )
			)
			( pin "@baseboard_fab2_lib.baseboard_fab2(sch_1):page51_i43:vss(21)"
				( attribute "PN" "202"
					( Origin gPackager )
				)
				( objectStatus "J4A2.202" )
			)
			( pin "@baseboard_fab2_lib.baseboard_fab2(sch_1):page51_i43:vss(22)"
				( attribute "PN" "200"
					( Origin gPackager )
				)
				( objectStatus "J4A2.200" )
			)
			( pin "@baseboard_fab2_lib.baseboard_fab2(sch_1):page51_i43:vss(23)"
				( attribute "PN" "198"
					( Origin gPackager )
				)
				( objectStatus "J4A2.198" )
			)
			( pin "@baseboard_fab2_lib.baseboard_fab2(sch_1):page51_i43:vss(24)"
				( attribute "PN" "195"
					( Origin gPackager )
				)
				( objectStatus "J4A2.195" )
			)
			( pin "@baseboard_fab2_lib.baseboard_fab2(sch_1):page51_i43:vss(25)"
				( attribute "PN" "193"
					( Origin gPackager )
				)
				( objectStatus "J4A2.193" )
			)
			( pin "@baseboard_fab2_lib.baseboard_fab2(sch_1):page51_i43:vss(26)"
				( attribute "PN" "191"
					( Origin gPackager )
				)
				( objectStatus "J4A2.191" )
			)
			( pin "@baseboard_fab2_lib.baseboard_fab2(sch_1):page51_i43:vss(27)"
				( attribute "PN" "189"
					( Origin gPackager )
				)
				( objectStatus "J4A2.189" )
			)
			( pin "@baseboard_fab2_lib.baseboard_fab2(sch_1):page51_i43:vss(28)"
				( attribute "PN" "187"
					( Origin gPackager )
				)
				( objectStatus "J4A2.187" )
			)
			( pin "@baseboard_fab2_lib.baseboard_fab2(sch_1):page51_i43:vss(29)"
				( attribute "PN" "184"
					( Origin gPackager )
				)
				( objectStatus "J4A2.184" )
			)
			( pin "@baseboard_fab2_lib.baseboard_fab2(sch_1):page51_i43:vss(30)"
				( attribute "PN" "182"
					( Origin gPackager )
				)
				( objectStatus "J4A2.182" )
			)
			( pin "@baseboard_fab2_lib.baseboard_fab2(sch_1):page51_i43:vss(31)"
				( attribute "PN" "180"
					( Origin gPackager )
				)
				( objectStatus "J4A2.180" )
			)
			( pin "@baseboard_fab2_lib.baseboard_fab2(sch_1):page51_i43:vss(32)"
				( attribute "PN" "178"
					( Origin gPackager )
				)
				( objectStatus "J4A2.178" )
			)
			( pin "@baseboard_fab2_lib.baseboard_fab2(sch_1):page51_i43:vss(33)"
				( attribute "PN" "176"
					( Origin gPackager )
				)
				( objectStatus "J4A2.176" )
			)
			( pin "@baseboard_fab2_lib.baseboard_fab2(sch_1):page51_i43:vss(34)"
				( attribute "PN" "173"
					( Origin gPackager )
				)
				( objectStatus "J4A2.173" )
			)
			( pin "@baseboard_fab2_lib.baseboard_fab2(sch_1):page51_i43:vss(35)"
				( attribute "PN" "171"
					( Origin gPackager )
				)
				( objectStatus "J4A2.171" )
			)
			( pin "@baseboard_fab2_lib.baseboard_fab2(sch_1):page51_i43:vss(36)"
				( attribute "PN" "169"
					( Origin gPackager )
				)
				( objectStatus "J4A2.169" )
			)
			( pin "@baseboard_fab2_lib.baseboard_fab2(sch_1):page51_i43:vss(37)"
				( attribute "PN" "167"
					( Origin gPackager )
				)
				( objectStatus "J4A2.167" )
			)
			( pin "@baseboard_fab2_lib.baseboard_fab2(sch_1):page51_i43:vss(38)"
				( attribute "PN" "165"
					( Origin gPackager )
				)
				( objectStatus "J4A2.165" )
			)
			( pin "@baseboard_fab2_lib.baseboard_fab2(sch_1):page51_i43:vss(39)"
				( attribute "PN" "162"
					( Origin gPackager )
				)
				( objectStatus "J4A2.162" )
			)
			( pin "@baseboard_fab2_lib.baseboard_fab2(sch_1):page51_i43:vss(40)"
				( attribute "PN" "160"
					( Origin gPackager )
				)
				( objectStatus "J4A2.160" )
			)
			( pin "@baseboard_fab2_lib.baseboard_fab2(sch_1):page51_i43:vss(41)"
				( attribute "PN" "158"
					( Origin gPackager )
				)
				( objectStatus "J4A2.158" )
			)
			( pin "@baseboard_fab2_lib.baseboard_fab2(sch_1):page51_i43:vss(42)"
				( attribute "PN" "156"
					( Origin gPackager )
				)
				( objectStatus "J4A2.156" )
			)
			( pin "@baseboard_fab2_lib.baseboard_fab2(sch_1):page51_i43:vss(43)"
				( attribute "PN" "154"
					( Origin gPackager )
				)
				( objectStatus "J4A2.154" )
			)
			( pin "@baseboard_fab2_lib.baseboard_fab2(sch_1):page51_i43:vss(44)"
				( attribute "PN" "151"
					( Origin gPackager )
				)
				( objectStatus "J4A2.151" )
			)
			( pin "@baseboard_fab2_lib.baseboard_fab2(sch_1):page51_i43:vss(45)"
				( attribute "PN" "149"
					( Origin gPackager )
				)
				( objectStatus "J4A2.149" )
			)
			( pin "@baseboard_fab2_lib.baseboard_fab2(sch_1):page51_i43:vss(46)"
				( attribute "PN" "147"
					( Origin gPackager )
				)
				( objectStatus "J4A2.147" )
			)
			( pin "@baseboard_fab2_lib.baseboard_fab2(sch_1):page51_i43:vss(47)"
				( attribute "PN" "138"
					( Origin gPackager )
				)
				( objectStatus "J4A2.138" )
			)
			( pin "@baseboard_fab2_lib.baseboard_fab2(sch_1):page51_i43:vss(48)"
				( attribute "PN" "136"
					( Origin gPackager )
				)
				( objectStatus "J4A2.136" )
			)
			( pin "@baseboard_fab2_lib.baseboard_fab2(sch_1):page51_i43:vss(49)"
				( attribute "PN" "134"
					( Origin gPackager )
				)
				( objectStatus "J4A2.134" )
			)
			( pin "@baseboard_fab2_lib.baseboard_fab2(sch_1):page51_i43:vss(50)"
				( attribute "PN" "131"
					( Origin gPackager )
				)
				( objectStatus "J4A2.131" )
			)
			( pin "@baseboard_fab2_lib.baseboard_fab2(sch_1):page51_i43:vss(51)"
				( attribute "PN" "129"
					( Origin gPackager )
				)
				( objectStatus "J4A2.129" )
			)
			( pin "@baseboard_fab2_lib.baseboard_fab2(sch_1):page51_i43:vss(52)"
				( attribute "PN" "127"
					( Origin gPackager )
				)
				( objectStatus "J4A2.127" )
			)
			( pin "@baseboard_fab2_lib.baseboard_fab2(sch_1):page51_i43:vss(53)"
				( attribute "PN" "125"
					( Origin gPackager )
				)
				( objectStatus "J4A2.125" )
			)
			( pin "@baseboard_fab2_lib.baseboard_fab2(sch_1):page51_i43:vss(54)"
				( attribute "PN" "123"
					( Origin gPackager )
				)
				( objectStatus "J4A2.123" )
			)
			( pin "@baseboard_fab2_lib.baseboard_fab2(sch_1):page51_i43:vss(55)"
				( attribute "PN" "120"
					( Origin gPackager )
				)
				( objectStatus "J4A2.120" )
			)
			( pin "@baseboard_fab2_lib.baseboard_fab2(sch_1):page51_i43:vss(56)"
				( attribute "PN" "118"
					( Origin gPackager )
				)
				( objectStatus "J4A2.118" )
			)
			( pin "@baseboard_fab2_lib.baseboard_fab2(sch_1):page51_i43:vss(57)"
				( attribute "PN" "116"
					( Origin gPackager )
				)
				( objectStatus "J4A2.116" )
			)
			( pin "@baseboard_fab2_lib.baseboard_fab2(sch_1):page51_i43:vss(58)"
				( attribute "PN" "114"
					( Origin gPackager )
				)
				( objectStatus "J4A2.114" )
			)
			( pin "@baseboard_fab2_lib.baseboard_fab2(sch_1):page51_i43:vss(59)"
				( attribute "PN" "112"
					( Origin gPackager )
				)
				( objectStatus "J4A2.112" )
			)
			( pin "@baseboard_fab2_lib.baseboard_fab2(sch_1):page51_i43:vss(60)"
				( attribute "PN" "109"
					( Origin gPackager )
				)
				( objectStatus "J4A2.109" )
			)
			( pin "@baseboard_fab2_lib.baseboard_fab2(sch_1):page51_i43:vss(61)"
				( attribute "PN" "107"
					( Origin gPackager )
				)
				( objectStatus "J4A2.107" )
			)
			( pin "@baseboard_fab2_lib.baseboard_fab2(sch_1):page51_i43:vss(62)"
				( attribute "PN" "105"
					( Origin gPackager )
				)
				( objectStatus "J4A2.105" )
			)
			( pin "@baseboard_fab2_lib.baseboard_fab2(sch_1):page51_i43:vss(63)"
				( attribute "PN" "103"
					( Origin gPackager )
				)
				( objectStatus "J4A2.103" )
			)
			( pin "@baseboard_fab2_lib.baseboard_fab2(sch_1):page51_i43:vss(64)"
				( attribute "PN" "101"
					( Origin gPackager )
				)
				( objectStatus "J4A2.101" )
			)
			( pin "@baseboard_fab2_lib.baseboard_fab2(sch_1):page51_i43:vss(65)"
				( attribute "PN" "98"
					( Origin gPackager )
				)
				( objectStatus "J4A2.98" )
			)
			( pin "@baseboard_fab2_lib.baseboard_fab2(sch_1):page51_i43:vss(66)"
				( attribute "PN" "96"
					( Origin gPackager )
				)
				( objectStatus "J4A2.96" )
			)
			( pin "@baseboard_fab2_lib.baseboard_fab2(sch_1):page51_i43:vss(67)"
				( attribute "PN" "94"
					( Origin gPackager )
				)
				( objectStatus "J4A2.94" )
			)
			( pin "@baseboard_fab2_lib.baseboard_fab2(sch_1):page51_i43:vss(68)"
				( attribute "PN" "57"
					( Origin gPackager )
				)
				( objectStatus "J4A2.57" )
			)
			( pin "@baseboard_fab2_lib.baseboard_fab2(sch_1):page51_i43:vss(69)"
				( attribute "PN" "55"
					( Origin gPackager )
				)
				( objectStatus "J4A2.55" )
			)
			( pin "@baseboard_fab2_lib.baseboard_fab2(sch_1):page51_i43:vss(70)"
				( attribute "PN" "53"
					( Origin gPackager )
				)
				( objectStatus "J4A2.53" )
			)
			( pin "@baseboard_fab2_lib.baseboard_fab2(sch_1):page51_i43:vss(71)"
				( attribute "PN" "50"
					( Origin gPackager )
				)
				( objectStatus "J4A2.50" )
			)
			( pin "@baseboard_fab2_lib.baseboard_fab2(sch_1):page51_i43:vss(72)"
				( attribute "PN" "48"
					( Origin gPackager )
				)
				( objectStatus "J4A2.48" )
			)
			( pin "@baseboard_fab2_lib.baseboard_fab2(sch_1):page51_i43:vss(73)"
				( attribute "PN" "46"
					( Origin gPackager )
				)
				( objectStatus "J4A2.46" )
			)
			( pin "@baseboard_fab2_lib.baseboard_fab2(sch_1):page51_i43:vss(74)"
				( attribute "PN" "44"
					( Origin gPackager )
				)
				( objectStatus "J4A2.44" )
			)
			( pin "@baseboard_fab2_lib.baseboard_fab2(sch_1):page51_i43:vss(75)"
				( attribute "PN" "42"
					( Origin gPackager )
				)
				( objectStatus "J4A2.42" )
			)
			( pin "@baseboard_fab2_lib.baseboard_fab2(sch_1):page51_i43:vss(76)"
				( attribute "PN" "39"
					( Origin gPackager )
				)
				( objectStatus "J4A2.39" )
			)
			( pin "@baseboard_fab2_lib.baseboard_fab2(sch_1):page51_i43:vss(77)"
				( attribute "PN" "37"
					( Origin gPackager )
				)
				( objectStatus "J4A2.37" )
			)
			( pin "@baseboard_fab2_lib.baseboard_fab2(sch_1):page51_i43:vss(78)"
				( attribute "PN" "35"
					( Origin gPackager )
				)
				( objectStatus "J4A2.35" )
			)
			( pin "@baseboard_fab2_lib.baseboard_fab2(sch_1):page51_i43:vss(79)"
				( attribute "PN" "33"
					( Origin gPackager )
				)
				( objectStatus "J4A2.33" )
			)
			( pin "@baseboard_fab2_lib.baseboard_fab2(sch_1):page51_i43:vss(80)"
				( attribute "PN" "31"
					( Origin gPackager )
				)
				( objectStatus "J4A2.31" )
			)
			( pin "@baseboard_fab2_lib.baseboard_fab2(sch_1):page51_i43:vss(81)"
				( attribute "PN" "28"
					( Origin gPackager )
				)
				( objectStatus "J4A2.28" )
			)
			( pin "@baseboard_fab2_lib.baseboard_fab2(sch_1):page51_i43:vss(82)"
				( attribute "PN" "26"
					( Origin gPackager )
				)
				( objectStatus "J4A2.26" )
			)
			( pin "@baseboard_fab2_lib.baseboard_fab2(sch_1):page51_i43:vss(83)"
				( attribute "PN" "24"
					( Origin gPackager )
				)
				( objectStatus "J4A2.24" )
			)
			( pin "@baseboard_fab2_lib.baseboard_fab2(sch_1):page51_i43:vss(84)"
				( attribute "PN" "22"
					( Origin gPackager )
				)
				( objectStatus "J4A2.22" )
			)
			( pin "@baseboard_fab2_lib.baseboard_fab2(sch_1):page51_i43:vss(85)"
				( attribute "PN" "20"
					( Origin gPackager )
				)
				( objectStatus "J4A2.20" )
			)
			( pin "@baseboard_fab2_lib.baseboard_fab2(sch_1):page51_i43:vss(86)"
				( attribute "PN" "17"
					( Origin gPackager )
				)
				( objectStatus "J4A2.17" )
			)
			( pin "@baseboard_fab2_lib.baseboard_fab2(sch_1):page51_i43:vss(87)"
				( attribute "PN" "15"
					( Origin gPackager )
				)
				( objectStatus "J4A2.15" )
			)
			( pin "@baseboard_fab2_lib.baseboard_fab2(sch_1):page51_i43:vss(88)"
				( attribute "PN" "13"
					( Origin gPackager )
				)
				( objectStatus "J4A2.13" )
			)
			( pin "@baseboard_fab2_lib.baseboard_fab2(sch_1):page51_i43:vss(89)"
				( attribute "PN" "11"
					( Origin gPackager )
				)
				( objectStatus "J4A2.11" )
			)
			( pin "@baseboard_fab2_lib.baseboard_fab2(sch_1):page51_i43:vss(90)"
				( attribute "PN" "9"
					( Origin gPackager )
				)
				( objectStatus "J4A2.9" )
			)
			( pin "@baseboard_fab2_lib.baseboard_fab2(sch_1):page51_i43:vss(91)"
				( attribute "PN" "6"
					( Origin gPackager )
				)
				( objectStatus "J4A2.6" )
			)
			( pin "@baseboard_fab2_lib.baseboard_fab2(sch_1):page51_i43:vss(92)"
				( attribute "PN" "4"
					( Origin gPackager )
				)
				( objectStatus "J4A2.4" )
			)
			( pin "@baseboard_fab2_lib.baseboard_fab2(sch_1):page51_i43:vss(93)"
				( attribute "PN" "2"
					( Origin gPackager )
				)
				( objectStatus "J4A2.2" )
			)
			( pin "@baseboard_fab2_lib.baseboard_fab2(sch_1):page51_i66:dqs0n"
				( attribute "PN" "152"
					( Origin gPackager )
				)
				( objectStatus "J4A2.152" )
			)
			( pin "@baseboard_fab2_lib.baseboard_fab2(sch_1):page51_i66:dqs0p"
				( attribute "PN" "153"
					( Origin gPackager )
				)
				( objectStatus "J4A2.153" )
			)
			( pin "@baseboard_fab2_lib.baseboard_fab2(sch_1):page51_i66:dqs1n"
				( attribute "PN" "163"
					( Origin gPackager )
				)
				( objectStatus "J4A2.163" )
			)
			( pin "@baseboard_fab2_lib.baseboard_fab2(sch_1):page51_i66:dqs1p"
				( attribute "PN" "164"
					( Origin gPackager )
				)
				( objectStatus "J4A2.164" )
			)
			( pin "@baseboard_fab2_lib.baseboard_fab2(sch_1):page51_i66:dqs2n"
				( attribute "PN" "174"
					( Origin gPackager )
				)
				( objectStatus "J4A2.174" )
			)
			( pin "@baseboard_fab2_lib.baseboard_fab2(sch_1):page51_i66:dqs2p"
				( attribute "PN" "175"
					( Origin gPackager )
				)
				( objectStatus "J4A2.175" )
			)
			( pin "@baseboard_fab2_lib.baseboard_fab2(sch_1):page51_i66:dqs3n"
				( attribute "PN" "185"
					( Origin gPackager )
				)
				( objectStatus "J4A2.185" )
			)
			( pin "@baseboard_fab2_lib.baseboard_fab2(sch_1):page51_i66:dqs3p"
				( attribute "PN" "186"
					( Origin gPackager )
				)
				( objectStatus "J4A2.186" )
			)
			( pin "@baseboard_fab2_lib.baseboard_fab2(sch_1):page51_i66:dqs4n"
				( attribute "PN" "244"
					( Origin gPackager )
				)
				( objectStatus "J4A2.244" )
			)
			( pin "@baseboard_fab2_lib.baseboard_fab2(sch_1):page51_i66:dqs4p"
				( attribute "PN" "245"
					( Origin gPackager )
				)
				( objectStatus "J4A2.245" )
			)
			( pin "@baseboard_fab2_lib.baseboard_fab2(sch_1):page51_i66:dqs5n"
				( attribute "PN" "255"
					( Origin gPackager )
				)
				( objectStatus "J4A2.255" )
			)
			( pin "@baseboard_fab2_lib.baseboard_fab2(sch_1):page51_i66:dqs5p"
				( attribute "PN" "256"
					( Origin gPackager )
				)
				( objectStatus "J4A2.256" )
			)
			( pin "@baseboard_fab2_lib.baseboard_fab2(sch_1):page51_i66:dqs6n"
				( attribute "PN" "266"
					( Origin gPackager )
				)
				( objectStatus "J4A2.266" )
			)
			( pin "@baseboard_fab2_lib.baseboard_fab2(sch_1):page51_i66:dqs6p"
				( attribute "PN" "267"
					( Origin gPackager )
				)
				( objectStatus "J4A2.267" )
			)
			( pin "@baseboard_fab2_lib.baseboard_fab2(sch_1):page51_i66:dqs7n"
				( attribute "PN" "277"
					( Origin gPackager )
				)
				( objectStatus "J4A2.277" )
			)
			( pin "@baseboard_fab2_lib.baseboard_fab2(sch_1):page51_i66:dqs7p"
				( attribute "PN" "278"
					( Origin gPackager )
				)
				( objectStatus "J4A2.278" )
			)
			( pin "@baseboard_fab2_lib.baseboard_fab2(sch_1):page51_i66:dqs8n"
				( attribute "PN" "196"
					( Origin gPackager )
				)
				( objectStatus "J4A2.196" )
			)
			( pin "@baseboard_fab2_lib.baseboard_fab2(sch_1):page51_i66:dqs8p"
				( attribute "PN" "197"
					( Origin gPackager )
				)
				( objectStatus "J4A2.197" )
			)
			( pin "@baseboard_fab2_lib.baseboard_fab2(sch_1):page51_i66:dqs9n"
				( attribute "PN" "8"
					( Origin gPackager )
				)
				( objectStatus "J4A2.8" )
			)
			( pin "@baseboard_fab2_lib.baseboard_fab2(sch_1):page51_i66:dqs9p"
				( attribute "PN" "7"
					( Origin gPackager )
				)
				( objectStatus "J4A2.7" )
			)
			( pin "@baseboard_fab2_lib.baseboard_fab2(sch_1):page51_i66:dqs10n"
				( attribute "PN" "19"
					( Origin gPackager )
				)
				( objectStatus "J4A2.19" )
			)
			( pin "@baseboard_fab2_lib.baseboard_fab2(sch_1):page51_i66:dqs10p"
				( attribute "PN" "18"
					( Origin gPackager )
				)
				( objectStatus "J4A2.18" )
			)
			( pin "@baseboard_fab2_lib.baseboard_fab2(sch_1):page51_i66:dqs11n"
				( attribute "PN" "30"
					( Origin gPackager )
				)
				( objectStatus "J4A2.30" )
			)
			( pin "@baseboard_fab2_lib.baseboard_fab2(sch_1):page51_i66:dqs11p"
				( attribute "PN" "29"
					( Origin gPackager )
				)
				( objectStatus "J4A2.29" )
			)
			( pin "@baseboard_fab2_lib.baseboard_fab2(sch_1):page51_i66:dqs12n"
				( attribute "PN" "41"
					( Origin gPackager )
				)
				( objectStatus "J4A2.41" )
			)
			( pin "@baseboard_fab2_lib.baseboard_fab2(sch_1):page51_i66:dqs12p"
				( attribute "PN" "40"
					( Origin gPackager )
				)
				( objectStatus "J4A2.40" )
			)
			( pin "@baseboard_fab2_lib.baseboard_fab2(sch_1):page51_i66:dqs13n"
				( attribute "PN" "100"
					( Origin gPackager )
				)
				( objectStatus "J4A2.100" )
			)
			( pin "@baseboard_fab2_lib.baseboard_fab2(sch_1):page51_i66:dqs13p"
				( attribute "PN" "99"
					( Origin gPackager )
				)
				( objectStatus "J4A2.99" )
			)
			( pin "@baseboard_fab2_lib.baseboard_fab2(sch_1):page51_i66:dqs14n"
				( attribute "PN" "111"
					( Origin gPackager )
				)
				( objectStatus "J4A2.111" )
			)
			( pin "@baseboard_fab2_lib.baseboard_fab2(sch_1):page51_i66:dqs14p"
				( attribute "PN" "110"
					( Origin gPackager )
				)
				( objectStatus "J4A2.110" )
			)
			( pin "@baseboard_fab2_lib.baseboard_fab2(sch_1):page51_i66:dqs15n"
				( attribute "PN" "122"
					( Origin gPackager )
				)
				( objectStatus "J4A2.122" )
			)
			( pin "@baseboard_fab2_lib.baseboard_fab2(sch_1):page51_i66:dqs15p"
				( attribute "PN" "121"
					( Origin gPackager )
				)
				( objectStatus "J4A2.121" )
			)
			( pin "@baseboard_fab2_lib.baseboard_fab2(sch_1):page51_i66:dqs16n"
				( attribute "PN" "133"
					( Origin gPackager )
				)
				( objectStatus "J4A2.133" )
			)
			( pin "@baseboard_fab2_lib.baseboard_fab2(sch_1):page51_i66:dqs16p"
				( attribute "PN" "132"
					( Origin gPackager )
				)
				( objectStatus "J4A2.132" )
			)
			( pin "@baseboard_fab2_lib.baseboard_fab2(sch_1):page51_i66:dqs17n"
				( attribute "PN" "52"
					( Origin gPackager )
				)
				( objectStatus "J4A2.52" )
			)
			( pin "@baseboard_fab2_lib.baseboard_fab2(sch_1):page51_i66:dqs17p"
				( attribute "PN" "51"
					( Origin gPackager )
				)
				( objectStatus "J4A2.51" )
			)
			( pin "@baseboard_fab2_lib.baseboard_fab2(sch_1):page51_i111:a0"
				( attribute "PN" "79"
					( Origin gPackager )
				)
				( objectStatus "J4A2.79" )
			)
			( pin "@baseboard_fab2_lib.baseboard_fab2(sch_1):page51_i111:a1"
				( attribute "PN" "72"
					( Origin gPackager )
				)
				( objectStatus "J4A2.72" )
			)
			( pin "@baseboard_fab2_lib.baseboard_fab2(sch_1):page51_i111:a2"
				( attribute "PN" "216"
					( Origin gPackager )
				)
				( objectStatus "J4A2.216" )
			)
			( pin "@baseboard_fab2_lib.baseboard_fab2(sch_1):page51_i111:a3"
				( attribute "PN" "71"
					( Origin gPackager )
				)
				( objectStatus "J4A2.71" )
			)
			( pin "@baseboard_fab2_lib.baseboard_fab2(sch_1):page51_i111:a4"
				( attribute "PN" "214"
					( Origin gPackager )
				)
				( objectStatus "J4A2.214" )
			)
			( pin "@baseboard_fab2_lib.baseboard_fab2(sch_1):page51_i111:a5"
				( attribute "PN" "213"
					( Origin gPackager )
				)
				( objectStatus "J4A2.213" )
			)
			( pin "@baseboard_fab2_lib.baseboard_fab2(sch_1):page51_i111:a6"
				( attribute "PN" "69"
					( Origin gPackager )
				)
				( objectStatus "J4A2.69" )
			)
			( pin "@baseboard_fab2_lib.baseboard_fab2(sch_1):page51_i111:a7"
				( attribute "PN" "211"
					( Origin gPackager )
				)
				( objectStatus "J4A2.211" )
			)
			( pin "@baseboard_fab2_lib.baseboard_fab2(sch_1):page51_i111:a8"
				( attribute "PN" "68"
					( Origin gPackager )
				)
				( objectStatus "J4A2.68" )
			)
			( pin "@baseboard_fab2_lib.baseboard_fab2(sch_1):page51_i111:a9"
				( attribute "PN" "66"
					( Origin gPackager )
				)
				( objectStatus "J4A2.66" )
			)
			( pin "@baseboard_fab2_lib.baseboard_fab2(sch_1):page51_i111:a10"
				( attribute "PN" "225"
					( Origin gPackager )
				)
				( objectStatus "J4A2.225" )
			)
			( pin "@baseboard_fab2_lib.baseboard_fab2(sch_1):page51_i111:a11"
				( attribute "PN" "210"
					( Origin gPackager )
				)
				( objectStatus "J4A2.210" )
			)
			( pin "@baseboard_fab2_lib.baseboard_fab2(sch_1):page51_i111:a12"
				( attribute "PN" "65"
					( Origin gPackager )
				)
				( objectStatus "J4A2.65" )
			)
			( pin "@baseboard_fab2_lib.baseboard_fab2(sch_1):page51_i111:a13"
				( attribute "PN" "232"
					( Origin gPackager )
				)
				( objectStatus "J4A2.232" )
			)
			( pin "@baseboard_fab2_lib.baseboard_fab2(sch_1):page51_i111:a14_we_n"
				( attribute "PN" "228"
					( Origin gPackager )
				)
				( objectStatus "J4A2.228" )
			)
			( pin "@baseboard_fab2_lib.baseboard_fab2(sch_1):page51_i111:a15_cas_n"
				( attribute "PN" "86"
					( Origin gPackager )
				)
				( objectStatus "J4A2.86" )
			)
			( pin "@baseboard_fab2_lib.baseboard_fab2(sch_1):page51_i111:a16_ras_n"
				( attribute "PN" "82"
					( Origin gPackager )
				)
				( objectStatus "J4A2.82" )
			)
			( pin "@baseboard_fab2_lib.baseboard_fab2(sch_1):page51_i111:a17"
				( attribute "PN" "234"
					( Origin gPackager )
				)
				( objectStatus "J4A2.234" )
			)
			( pin "@baseboard_fab2_lib.baseboard_fab2(sch_1):page51_i111:act_n"
				( attribute "PN" "62"
					( Origin gPackager )
				)
				( objectStatus "J4A2.62" )
			)
			( pin "@baseboard_fab2_lib.baseboard_fab2(sch_1):page51_i111:alert_n"
				( attribute "PN" "208"
					( Origin gPackager )
				)
				( objectStatus "J4A2.208" )
			)
			( pin "@baseboard_fab2_lib.baseboard_fab2(sch_1):page51_i111:ba(0)"
				( attribute "PN" "81"
					( Origin gPackager )
				)
				( objectStatus "J4A2.81" )
			)
			( pin "@baseboard_fab2_lib.baseboard_fab2(sch_1):page51_i111:ba(1)"
				( attribute "PN" "224"
					( Origin gPackager )
				)
				( objectStatus "J4A2.224" )
			)
			( pin "@baseboard_fab2_lib.baseboard_fab2(sch_1):page51_i111:bg(0)"
				( attribute "PN" "63"
					( Origin gPackager )
				)
				( objectStatus "J4A2.63" )
			)
			( pin "@baseboard_fab2_lib.baseboard_fab2(sch_1):page51_i111:bg(1)"
				( attribute "PN" "207"
					( Origin gPackager )
				)
				( objectStatus "J4A2.207" )
			)
			( pin "@baseboard_fab2_lib.baseboard_fab2(sch_1):page51_i111:c(2)"
				( attribute "PN" "235"
					( Origin gPackager )
				)
				( objectStatus "J4A2.235" )
			)
			( pin "@baseboard_fab2_lib.baseboard_fab2(sch_1):page51_i111:cb(0)"
				( attribute "PN" "49"
					( Origin gPackager )
				)
				( objectStatus "J4A2.49" )
			)
			( pin "@baseboard_fab2_lib.baseboard_fab2(sch_1):page51_i111:cb(1)"
				( attribute "PN" "194"
					( Origin gPackager )
				)
				( objectStatus "J4A2.194" )
			)
			( pin "@baseboard_fab2_lib.baseboard_fab2(sch_1):page51_i111:cb(2)"
				( attribute "PN" "56"
					( Origin gPackager )
				)
				( objectStatus "J4A2.56" )
			)
			( pin "@baseboard_fab2_lib.baseboard_fab2(sch_1):page51_i111:cb(3)"
				( attribute "PN" "201"
					( Origin gPackager )
				)
				( objectStatus "J4A2.201" )
			)
			( pin "@baseboard_fab2_lib.baseboard_fab2(sch_1):page51_i111:cb(4)"
				( attribute "PN" "47"
					( Origin gPackager )
				)
				( objectStatus "J4A2.47" )
			)
			( pin "@baseboard_fab2_lib.baseboard_fab2(sch_1):page51_i111:cb(5)"
				( attribute "PN" "192"
					( Origin gPackager )
				)
				( objectStatus "J4A2.192" )
			)
			( pin "@baseboard_fab2_lib.baseboard_fab2(sch_1):page51_i111:cb(6)"
				( attribute "PN" "54"
					( Origin gPackager )
				)
				( objectStatus "J4A2.54" )
			)
			( pin "@baseboard_fab2_lib.baseboard_fab2(sch_1):page51_i111:cb(7)"
				( attribute "PN" "199"
					( Origin gPackager )
				)
				( objectStatus "J4A2.199" )
			)
			( pin "@baseboard_fab2_lib.baseboard_fab2(sch_1):page51_i111:ck0n"
				( attribute "PN" "75"
					( Origin gPackager )
				)
				( objectStatus "J4A2.75" )
			)
			( pin "@baseboard_fab2_lib.baseboard_fab2(sch_1):page51_i111:ck0p"
				( attribute "PN" "74"
					( Origin gPackager )
				)
				( objectStatus "J4A2.74" )
			)
			( pin "@baseboard_fab2_lib.baseboard_fab2(sch_1):page51_i111:ck1n"
				( attribute "PN" "219"
					( Origin gPackager )
				)
				( objectStatus "J4A2.219" )
			)
			( pin "@baseboard_fab2_lib.baseboard_fab2(sch_1):page51_i111:ck1p"
				( attribute "PN" "218"
					( Origin gPackager )
				)
				( objectStatus "J4A2.218" )
			)
			( pin "@baseboard_fab2_lib.baseboard_fab2(sch_1):page51_i111:cke(0)"
				( attribute "PN" "60"
					( Origin gPackager )
				)
				( objectStatus "J4A2.60" )
			)
			( pin "@baseboard_fab2_lib.baseboard_fab2(sch_1):page51_i111:cke(1)"
				( attribute "PN" "203"
					( Origin gPackager )
				)
				( objectStatus "J4A2.203" )
			)
			( pin "@baseboard_fab2_lib.baseboard_fab2(sch_1):page51_i111:dq(0)"
				( attribute "PN" "5"
					( Origin gPackager )
				)
				( objectStatus "J4A2.5" )
			)
			( pin "@baseboard_fab2_lib.baseboard_fab2(sch_1):page51_i111:dq(1)"
				( attribute "PN" "150"
					( Origin gPackager )
				)
				( objectStatus "J4A2.150" )
			)
			( pin "@baseboard_fab2_lib.baseboard_fab2(sch_1):page51_i111:dq(2)"
				( attribute "PN" "12"
					( Origin gPackager )
				)
				( objectStatus "J4A2.12" )
			)
			( pin "@baseboard_fab2_lib.baseboard_fab2(sch_1):page51_i111:dq(3)"
				( attribute "PN" "157"
					( Origin gPackager )
				)
				( objectStatus "J4A2.157" )
			)
			( pin "@baseboard_fab2_lib.baseboard_fab2(sch_1):page51_i111:dq(4)"
				( attribute "PN" "3"
					( Origin gPackager )
				)
				( objectStatus "J4A2.3" )
			)
			( pin "@baseboard_fab2_lib.baseboard_fab2(sch_1):page51_i111:dq(5)"
				( attribute "PN" "148"
					( Origin gPackager )
				)
				( objectStatus "J4A2.148" )
			)
			( pin "@baseboard_fab2_lib.baseboard_fab2(sch_1):page51_i111:dq(6)"
				( attribute "PN" "10"
					( Origin gPackager )
				)
				( objectStatus "J4A2.10" )
			)
			( pin "@baseboard_fab2_lib.baseboard_fab2(sch_1):page51_i111:dq(7)"
				( attribute "PN" "155"
					( Origin gPackager )
				)
				( objectStatus "J4A2.155" )
			)
			( pin "@baseboard_fab2_lib.baseboard_fab2(sch_1):page51_i111:dq(8)"
				( attribute "PN" "16"
					( Origin gPackager )
				)
				( objectStatus "J4A2.16" )
			)
			( pin "@baseboard_fab2_lib.baseboard_fab2(sch_1):page51_i111:dq(9)"
				( attribute "PN" "161"
					( Origin gPackager )
				)
				( objectStatus "J4A2.161" )
			)
			( pin "@baseboard_fab2_lib.baseboard_fab2(sch_1):page51_i111:dq(10)"
				( attribute "PN" "23"
					( Origin gPackager )
				)
				( objectStatus "J4A2.23" )
			)
			( pin "@baseboard_fab2_lib.baseboard_fab2(sch_1):page51_i111:dq(11)"
				( attribute "PN" "168"
					( Origin gPackager )
				)
				( objectStatus "J4A2.168" )
			)
			( pin "@baseboard_fab2_lib.baseboard_fab2(sch_1):page51_i111:dq(12)"
				( attribute "PN" "14"
					( Origin gPackager )
				)
				( objectStatus "J4A2.14" )
			)
			( pin "@baseboard_fab2_lib.baseboard_fab2(sch_1):page51_i111:dq(13)"
				( attribute "PN" "159"
					( Origin gPackager )
				)
				( objectStatus "J4A2.159" )
			)
			( pin "@baseboard_fab2_lib.baseboard_fab2(sch_1):page51_i111:dq(14)"
				( attribute "PN" "21"
					( Origin gPackager )
				)
				( objectStatus "J4A2.21" )
			)
			( pin "@baseboard_fab2_lib.baseboard_fab2(sch_1):page51_i111:dq(15)"
				( attribute "PN" "166"
					( Origin gPackager )
				)
				( objectStatus "J4A2.166" )
			)
			( pin "@baseboard_fab2_lib.baseboard_fab2(sch_1):page51_i111:dq(16)"
				( attribute "PN" "27"
					( Origin gPackager )
				)
				( objectStatus "J4A2.27" )
			)
			( pin "@baseboard_fab2_lib.baseboard_fab2(sch_1):page51_i111:dq(17)"
				( attribute "PN" "172"
					( Origin gPackager )
				)
				( objectStatus "J4A2.172" )
			)
			( pin "@baseboard_fab2_lib.baseboard_fab2(sch_1):page51_i111:dq(18)"
				( attribute "PN" "34"
					( Origin gPackager )
				)
				( objectStatus "J4A2.34" )
			)
			( pin "@baseboard_fab2_lib.baseboard_fab2(sch_1):page51_i111:dq(19)"
				( attribute "PN" "179"
					( Origin gPackager )
				)
				( objectStatus "J4A2.179" )
			)
			( pin "@baseboard_fab2_lib.baseboard_fab2(sch_1):page51_i111:dq(20)"
				( attribute "PN" "25"
					( Origin gPackager )
				)
				( objectStatus "J4A2.25" )
			)
			( pin "@baseboard_fab2_lib.baseboard_fab2(sch_1):page51_i111:dq(21)"
				( attribute "PN" "170"
					( Origin gPackager )
				)
				( objectStatus "J4A2.170" )
			)
			( pin "@baseboard_fab2_lib.baseboard_fab2(sch_1):page51_i111:dq(22)"
				( attribute "PN" "32"
					( Origin gPackager )
				)
				( objectStatus "J4A2.32" )
			)
			( pin "@baseboard_fab2_lib.baseboard_fab2(sch_1):page51_i111:dq(23)"
				( attribute "PN" "177"
					( Origin gPackager )
				)
				( objectStatus "J4A2.177" )
			)
			( pin "@baseboard_fab2_lib.baseboard_fab2(sch_1):page51_i111:dq(24)"
				( attribute "PN" "38"
					( Origin gPackager )
				)
				( objectStatus "J4A2.38" )
			)
			( pin "@baseboard_fab2_lib.baseboard_fab2(sch_1):page51_i111:dq(25)"
				( attribute "PN" "183"
					( Origin gPackager )
				)
				( objectStatus "J4A2.183" )
			)
			( pin "@baseboard_fab2_lib.baseboard_fab2(sch_1):page51_i111:dq(26)"
				( attribute "PN" "45"
					( Origin gPackager )
				)
				( objectStatus "J4A2.45" )
			)
			( pin "@baseboard_fab2_lib.baseboard_fab2(sch_1):page51_i111:dq(27)"
				( attribute "PN" "190"
					( Origin gPackager )
				)
				( objectStatus "J4A2.190" )
			)
			( pin "@baseboard_fab2_lib.baseboard_fab2(sch_1):page51_i111:dq(28)"
				( attribute "PN" "36"
					( Origin gPackager )
				)
				( objectStatus "J4A2.36" )
			)
			( pin "@baseboard_fab2_lib.baseboard_fab2(sch_1):page51_i111:dq(29)"
				( attribute "PN" "181"
					( Origin gPackager )
				)
				( objectStatus "J4A2.181" )
			)
			( pin "@baseboard_fab2_lib.baseboard_fab2(sch_1):page51_i111:dq(30)"
				( attribute "PN" "43"
					( Origin gPackager )
				)
				( objectStatus "J4A2.43" )
			)
			( pin "@baseboard_fab2_lib.baseboard_fab2(sch_1):page51_i111:dq(31)"
				( attribute "PN" "188"
					( Origin gPackager )
				)
				( objectStatus "J4A2.188" )
			)
			( pin "@baseboard_fab2_lib.baseboard_fab2(sch_1):page51_i111:dq(32)"
				( attribute "PN" "97"
					( Origin gPackager )
				)
				( objectStatus "J4A2.97" )
			)
			( pin "@baseboard_fab2_lib.baseboard_fab2(sch_1):page51_i111:dq(33)"
				( attribute "PN" "242"
					( Origin gPackager )
				)
				( objectStatus "J4A2.242" )
			)
			( pin "@baseboard_fab2_lib.baseboard_fab2(sch_1):page51_i111:dq(34)"
				( attribute "PN" "104"
					( Origin gPackager )
				)
				( objectStatus "J4A2.104" )
			)
			( pin "@baseboard_fab2_lib.baseboard_fab2(sch_1):page51_i111:dq(35)"
				( attribute "PN" "249"
					( Origin gPackager )
				)
				( objectStatus "J4A2.249" )
			)
			( pin "@baseboard_fab2_lib.baseboard_fab2(sch_1):page51_i111:dq(36)"
				( attribute "PN" "95"
					( Origin gPackager )
				)
				( objectStatus "J4A2.95" )
			)
			( pin "@baseboard_fab2_lib.baseboard_fab2(sch_1):page51_i111:dq(37)"
				( attribute "PN" "240"
					( Origin gPackager )
				)
				( objectStatus "J4A2.240" )
			)
			( pin "@baseboard_fab2_lib.baseboard_fab2(sch_1):page51_i111:dq(38)"
				( attribute "PN" "102"
					( Origin gPackager )
				)
				( objectStatus "J4A2.102" )
			)
			( pin "@baseboard_fab2_lib.baseboard_fab2(sch_1):page51_i111:dq(39)"
				( attribute "PN" "247"
					( Origin gPackager )
				)
				( objectStatus "J4A2.247" )
			)
			( pin "@baseboard_fab2_lib.baseboard_fab2(sch_1):page51_i111:dq(40)"
				( attribute "PN" "108"
					( Origin gPackager )
				)
				( objectStatus "J4A2.108" )
			)
			( pin "@baseboard_fab2_lib.baseboard_fab2(sch_1):page51_i111:dq(41)"
				( attribute "PN" "253"
					( Origin gPackager )
				)
				( objectStatus "J4A2.253" )
			)
			( pin "@baseboard_fab2_lib.baseboard_fab2(sch_1):page51_i111:dq(42)"
				( attribute "PN" "115"
					( Origin gPackager )
				)
				( objectStatus "J4A2.115" )
			)
			( pin "@baseboard_fab2_lib.baseboard_fab2(sch_1):page51_i111:dq(43)"
				( attribute "PN" "260"
					( Origin gPackager )
				)
				( objectStatus "J4A2.260" )
			)
			( pin "@baseboard_fab2_lib.baseboard_fab2(sch_1):page51_i111:dq(44)"
				( attribute "PN" "106"
					( Origin gPackager )
				)
				( objectStatus "J4A2.106" )
			)
			( pin "@baseboard_fab2_lib.baseboard_fab2(sch_1):page51_i111:dq(45)"
				( attribute "PN" "251"
					( Origin gPackager )
				)
				( objectStatus "J4A2.251" )
			)
			( pin "@baseboard_fab2_lib.baseboard_fab2(sch_1):page51_i111:dq(46)"
				( attribute "PN" "113"
					( Origin gPackager )
				)
				( objectStatus "J4A2.113" )
			)
			( pin "@baseboard_fab2_lib.baseboard_fab2(sch_1):page51_i111:dq(47)"
				( attribute "PN" "258"
					( Origin gPackager )
				)
				( objectStatus "J4A2.258" )
			)
			( pin "@baseboard_fab2_lib.baseboard_fab2(sch_1):page51_i111:dq(48)"
				( attribute "PN" "119"
					( Origin gPackager )
				)
				( objectStatus "J4A2.119" )
			)
			( pin "@baseboard_fab2_lib.baseboard_fab2(sch_1):page51_i111:dq(49)"
				( attribute "PN" "264"
					( Origin gPackager )
				)
				( objectStatus "J4A2.264" )
			)
			( pin "@baseboard_fab2_lib.baseboard_fab2(sch_1):page51_i111:dq(50)"
				( attribute "PN" "126"
					( Origin gPackager )
				)
				( objectStatus "J4A2.126" )
			)
			( pin "@baseboard_fab2_lib.baseboard_fab2(sch_1):page51_i111:dq(51)"
				( attribute "PN" "271"
					( Origin gPackager )
				)
				( objectStatus "J4A2.271" )
			)
			( pin "@baseboard_fab2_lib.baseboard_fab2(sch_1):page51_i111:dq(52)"
				( attribute "PN" "117"
					( Origin gPackager )
				)
				( objectStatus "J4A2.117" )
			)
			( pin "@baseboard_fab2_lib.baseboard_fab2(sch_1):page51_i111:dq(53)"
				( attribute "PN" "262"
					( Origin gPackager )
				)
				( objectStatus "J4A2.262" )
			)
			( pin "@baseboard_fab2_lib.baseboard_fab2(sch_1):page51_i111:dq(54)"
				( attribute "PN" "124"
					( Origin gPackager )
				)
				( objectStatus "J4A2.124" )
			)
			( pin "@baseboard_fab2_lib.baseboard_fab2(sch_1):page51_i111:dq(55)"
				( attribute "PN" "269"
					( Origin gPackager )
				)
				( objectStatus "J4A2.269" )
			)
			( pin "@baseboard_fab2_lib.baseboard_fab2(sch_1):page51_i111:dq(56)"
				( attribute "PN" "130"
					( Origin gPackager )
				)
				( objectStatus "J4A2.130" )
			)
			( pin "@baseboard_fab2_lib.baseboard_fab2(sch_1):page51_i111:dq(57)"
				( attribute "PN" "275"
					( Origin gPackager )
				)
				( objectStatus "J4A2.275" )
			)
			( pin "@baseboard_fab2_lib.baseboard_fab2(sch_1):page51_i111:dq(58)"
				( attribute "PN" "137"
					( Origin gPackager )
				)
				( objectStatus "J4A2.137" )
			)
			( pin "@baseboard_fab2_lib.baseboard_fab2(sch_1):page51_i111:dq(59)"
				( attribute "PN" "282"
					( Origin gPackager )
				)
				( objectStatus "J4A2.282" )
			)
			( pin "@baseboard_fab2_lib.baseboard_fab2(sch_1):page51_i111:dq(60)"
				( attribute "PN" "128"
					( Origin gPackager )
				)
				( objectStatus "J4A2.128" )
			)
			( pin "@baseboard_fab2_lib.baseboard_fab2(sch_1):page51_i111:dq(61)"
				( attribute "PN" "273"
					( Origin gPackager )
				)
				( objectStatus "J4A2.273" )
			)
			( pin "@baseboard_fab2_lib.baseboard_fab2(sch_1):page51_i111:dq(62)"
				( attribute "PN" "135"
					( Origin gPackager )
				)
				( objectStatus "J4A2.135" )
			)
			( pin "@baseboard_fab2_lib.baseboard_fab2(sch_1):page51_i111:dq(63)"
				( attribute "PN" "280"
					( Origin gPackager )
				)
				( objectStatus "J4A2.280" )
			)
			( pin "@baseboard_fab2_lib.baseboard_fab2(sch_1):page51_i111:event_n"
				( attribute "PN" "78"
					( Origin gPackager )
				)
				( objectStatus "J4A2.78" )
			)
			( pin "@baseboard_fab2_lib.baseboard_fab2(sch_1):page51_i111:odt(0)"
				( attribute "PN" "87"
					( Origin gPackager )
				)
				( objectStatus "J4A2.87" )
			)
			( pin "@baseboard_fab2_lib.baseboard_fab2(sch_1):page51_i111:odt(1)"
				( attribute "PN" "91"
					( Origin gPackager )
				)
				( objectStatus "J4A2.91" )
			)
			( pin "@baseboard_fab2_lib.baseboard_fab2(sch_1):page51_i111:par"
				( attribute "PN" "222"
					( Origin gPackager )
				)
				( objectStatus "J4A2.222" )
			)
			( pin "@baseboard_fab2_lib.baseboard_fab2(sch_1):page51_i111:reset_n"
				( attribute "PN" "58"
					( Origin gPackager )
				)
				( objectStatus "J4A2.58" )
			)
			( pin "@baseboard_fab2_lib.baseboard_fab2(sch_1):page51_i111:rfu(0)"
				( attribute "PN" "205"
					( Origin gPackager )
				)
				( objectStatus "J4A2.205" )
			)
			( pin "@baseboard_fab2_lib.baseboard_fab2(sch_1):page51_i111:rfu(1)"
				( attribute "PN" "227"
					( Origin gPackager )
				)
				( objectStatus "J4A2.227" )
			)
			( pin "@baseboard_fab2_lib.baseboard_fab2(sch_1):page51_i111:rfu(2)"
				( attribute "PN" "144"
					( Origin gPackager )
				)
				( objectStatus "J4A2.144" )
			)
			( pin "@baseboard_fab2_lib.baseboard_fab2(sch_1):page51_i111:s0_n"
				( attribute "PN" "84"
					( Origin gPackager )
				)
				( objectStatus "J4A2.84" )
			)
			( pin "@baseboard_fab2_lib.baseboard_fab2(sch_1):page51_i111:s1_n"
				( attribute "PN" "89"
					( Origin gPackager )
				)
				( objectStatus "J4A2.89" )
			)
			( pin "@baseboard_fab2_lib.baseboard_fab2(sch_1):page51_i111:s2_n_c(0)"
				( attribute "PN" "93"
					( Origin gPackager )
				)
				( objectStatus "J4A2.93" )
			)
			( pin "@baseboard_fab2_lib.baseboard_fab2(sch_1):page51_i111:s3_n_c(1)"
				( attribute "PN" "237"
					( Origin gPackager )
				)
				( objectStatus "J4A2.237" )
			)
			( pin "@baseboard_fab2_lib.baseboard_fab2(sch_1):page51_i111:sa(0)"
				( attribute "PN" "139"
					( Origin gPackager )
				)
				( objectStatus "J4A2.139" )
			)
			( pin "@baseboard_fab2_lib.baseboard_fab2(sch_1):page51_i111:sa(1)"
				( attribute "PN" "140"
					( Origin gPackager )
				)
				( objectStatus "J4A2.140" )
			)
			( pin "@baseboard_fab2_lib.baseboard_fab2(sch_1):page51_i111:sa(2)"
				( attribute "PN" "238"
					( Origin gPackager )
				)
				( objectStatus "J4A2.238" )
			)
			( pin "@baseboard_fab2_lib.baseboard_fab2(sch_1):page51_i111:save_n_nc"
				( attribute "PN" "230"
					( Origin gPackager )
				)
				( objectStatus "J4A2.230" )
			)
			( pin "@baseboard_fab2_lib.baseboard_fab2(sch_1):page51_i111:scl"
				( attribute "PN" "141"
					( Origin gPackager )
				)
				( objectStatus "J4A2.141" )
			)
			( pin "@baseboard_fab2_lib.baseboard_fab2(sch_1):page51_i111:sda"
				( attribute "PN" "285"
					( Origin gPackager )
				)
				( objectStatus "J4A2.285" )
			)
			( pin "@baseboard_fab2_lib.baseboard_fab2(sch_1):page51_i111:vddspd"
				( attribute "PN" "284"
					( Origin gPackager )
				)
				( objectStatus "J4A2.284" )
			)
			( pin "@baseboard_fab2_lib.baseboard_fab2(sch_1):page51_i111:vrefca"
				( attribute "PN" "146"
					( Origin gPackager )
				)
				( objectStatus "J4A2.146" )
			)
			( pin "@baseboard_fab2_lib.baseboard_fab2(sch_1):page51_i167:\12v\(0)"
				( attribute "PN" "145"
					( Origin gPackager )
				)
				( objectStatus "J4A2.145" )
			)
			( pin "@baseboard_fab2_lib.baseboard_fab2(sch_1):page51_i167:\12v\(1)"
				( attribute "PN" "1"
					( Origin gPackager )
				)
				( objectStatus "J4A2.1" )
			)
			( pin "@baseboard_fab2_lib.baseboard_fab2(sch_1):page51_i167:vdd(0)"
				( attribute "PN" "236"
					( Origin gPackager )
				)
				( objectStatus "J4A2.236" )
			)
			( pin "@baseboard_fab2_lib.baseboard_fab2(sch_1):page51_i167:vdd(1)"
				( attribute "PN" "233"
					( Origin gPackager )
				)
				( objectStatus "J4A2.233" )
			)
			( pin "@baseboard_fab2_lib.baseboard_fab2(sch_1):page51_i167:vdd(2)"
				( attribute "PN" "231"
					( Origin gPackager )
				)
				( objectStatus "J4A2.231" )
			)
			( pin "@baseboard_fab2_lib.baseboard_fab2(sch_1):page51_i167:vdd(3)"
				( attribute "PN" "229"
					( Origin gPackager )
				)
				( objectStatus "J4A2.229" )
			)
			( pin "@baseboard_fab2_lib.baseboard_fab2(sch_1):page51_i167:vdd(4)"
				( attribute "PN" "226"
					( Origin gPackager )
				)
				( objectStatus "J4A2.226" )
			)
			( pin "@baseboard_fab2_lib.baseboard_fab2(sch_1):page51_i167:vdd(5)"
				( attribute "PN" "223"
					( Origin gPackager )
				)
				( objectStatus "J4A2.223" )
			)
			( pin "@baseboard_fab2_lib.baseboard_fab2(sch_1):page51_i167:vdd(6)"
				( attribute "PN" "220"
					( Origin gPackager )
				)
				( objectStatus "J4A2.220" )
			)
			( pin "@baseboard_fab2_lib.baseboard_fab2(sch_1):page51_i167:vdd(7)"
				( attribute "PN" "217"
					( Origin gPackager )
				)
				( objectStatus "J4A2.217" )
			)
			( pin "@baseboard_fab2_lib.baseboard_fab2(sch_1):page51_i167:vdd(8)"
				( attribute "PN" "215"
					( Origin gPackager )
				)
				( objectStatus "J4A2.215" )
			)
			( pin "@baseboard_fab2_lib.baseboard_fab2(sch_1):page51_i167:vdd(9)"
				( attribute "PN" "212"
					( Origin gPackager )
				)
				( objectStatus "J4A2.212" )
			)
			( pin "@baseboard_fab2_lib.baseboard_fab2(sch_1):page51_i167:vdd(10)"
				( attribute "PN" "209"
					( Origin gPackager )
				)
				( objectStatus "J4A2.209" )
			)
			( pin "@baseboard_fab2_lib.baseboard_fab2(sch_1):page51_i167:vdd(11)"
				( attribute "PN" "206"
					( Origin gPackager )
				)
				( objectStatus "J4A2.206" )
			)
			( pin "@baseboard_fab2_lib.baseboard_fab2(sch_1):page51_i167:vdd(12)"
				( attribute "PN" "204"
					( Origin gPackager )
				)
				( objectStatus "J4A2.204" )
			)
			( pin "@baseboard_fab2_lib.baseboard_fab2(sch_1):page51_i167:vdd(13)"
				( attribute "PN" "92"
					( Origin gPackager )
				)
				( objectStatus "J4A2.92" )
			)
			( pin "@baseboard_fab2_lib.baseboard_fab2(sch_1):page51_i167:vdd(14)"
				( attribute "PN" "90"
					( Origin gPackager )
				)
				( objectStatus "J4A2.90" )
			)
			( pin "@baseboard_fab2_lib.baseboard_fab2(sch_1):page51_i167:vdd(15)"
				( attribute "PN" "88"
					( Origin gPackager )
				)
				( objectStatus "J4A2.88" )
			)
			( pin "@baseboard_fab2_lib.baseboard_fab2(sch_1):page51_i167:vdd(16)"
				( attribute "PN" "85"
					( Origin gPackager )
				)
				( objectStatus "J4A2.85" )
			)
			( pin "@baseboard_fab2_lib.baseboard_fab2(sch_1):page51_i167:vdd(17)"
				( attribute "PN" "83"
					( Origin gPackager )
				)
				( objectStatus "J4A2.83" )
			)
			( pin "@baseboard_fab2_lib.baseboard_fab2(sch_1):page51_i167:vdd(18)"
				( attribute "PN" "80"
					( Origin gPackager )
				)
				( objectStatus "J4A2.80" )
			)
			( pin "@baseboard_fab2_lib.baseboard_fab2(sch_1):page51_i167:vdd(19)"
				( attribute "PN" "76"
					( Origin gPackager )
				)
				( objectStatus "J4A2.76" )
			)
			( pin "@baseboard_fab2_lib.baseboard_fab2(sch_1):page51_i167:vdd(20)"
				( attribute "PN" "73"
					( Origin gPackager )
				)
				( objectStatus "J4A2.73" )
			)
			( pin "@baseboard_fab2_lib.baseboard_fab2(sch_1):page51_i167:vdd(21)"
				( attribute "PN" "70"
					( Origin gPackager )
				)
				( objectStatus "J4A2.70" )
			)
			( pin "@baseboard_fab2_lib.baseboard_fab2(sch_1):page51_i167:vdd(22)"
				( attribute "PN" "67"
					( Origin gPackager )
				)
				( objectStatus "J4A2.67" )
			)
			( pin "@baseboard_fab2_lib.baseboard_fab2(sch_1):page51_i167:vdd(23)"
				( attribute "PN" "64"
					( Origin gPackager )
				)
				( objectStatus "J4A2.64" )
			)
			( pin "@baseboard_fab2_lib.baseboard_fab2(sch_1):page51_i167:vdd(24)"
				( attribute "PN" "61"
					( Origin gPackager )
				)
				( objectStatus "J4A2.61" )
			)
			( pin "@baseboard_fab2_lib.baseboard_fab2(sch_1):page51_i167:vdd(25)"
				( attribute "PN" "59"
					( Origin gPackager )
				)
				( objectStatus "J4A2.59" )
			)
			( pin "@baseboard_fab2_lib.baseboard_fab2(sch_1):page51_i167:vpp(0)"
				( attribute "PN" "287"
					( Origin gPackager )
				)
				( objectStatus "J4A2.287" )
			)
			( pin "@baseboard_fab2_lib.baseboard_fab2(sch_1):page51_i167:vpp(1)"
				( attribute "PN" "286"
					( Origin gPackager )
				)
				( objectStatus "J4A2.286" )
			)
			( pin "@baseboard_fab2_lib.baseboard_fab2(sch_1):page51_i167:vpp(2)"
				( attribute "PN" "288"
					( Origin gPackager )
				)
				( objectStatus "J4A2.288" )
			)
			( pin "@baseboard_fab2_lib.baseboard_fab2(sch_1):page51_i167:vpp(3)"
				( attribute "PN" "143"
					( Origin gPackager )
				)
				( objectStatus "J4A2.143" )
			)
			( pin "@baseboard_fab2_lib.baseboard_fab2(sch_1):page51_i167:vpp(4)"
				( attribute "PN" "142"
					( Origin gPackager )
				)
				( objectStatus "J4A2.142" )
			)
			( pin "@baseboard_fab2_lib.baseboard_fab2(sch_1):page51_i167:vtt(0)"
				( attribute "PN" "221"
					( Origin gPackager )
				)
				( objectStatus "J4A2.221" )
			)
			( pin "@baseboard_fab2_lib.baseboard_fab2(sch_1):page51_i167:vtt(1)"
				( attribute "PN" "77"
					( Origin gPackager )
				)
				( objectStatus "J4A2.77" )
			)
			( pin "@baseboard_fab2_lib.baseboard_fab2(sch_1):page51_i175:a"
				( attribute "PN" "1"
					( Origin gPackager )
				)
				( objectStatus "C6L6.1" )
			)
			( pin "@baseboard_fab2_lib.baseboard_fab2(sch_1):page51_i175:b"
				( attribute "PN" "2"
					( Origin gPackager )
				)
				( objectStatus "C6L6.2" )
			)
			( pin "@baseboard_fab2_lib.baseboard_fab2(sch_1):page52_i3:a"
				( attribute "PN" "1"
					( Origin gPackager )
				)
				( objectStatus "C4A18.1" )
			)
			( pin "@baseboard_fab2_lib.baseboard_fab2(sch_1):page52_i3:b"
				( attribute "PN" "2"
					( Origin gPackager )
				)
				( objectStatus "C4A18.2" )
			)
			( pin "@baseboard_fab2_lib.baseboard_fab2(sch_1):page52_i12:a0"
				( attribute "PN" "79"
					( Origin gPackager )
				)
				( objectStatus "J6L2.79" )
			)
			( pin "@baseboard_fab2_lib.baseboard_fab2(sch_1):page52_i12:a1"
				( attribute "PN" "72"
					( Origin gPackager )
				)
				( objectStatus "J6L2.72" )
			)
			( pin "@baseboard_fab2_lib.baseboard_fab2(sch_1):page52_i12:a2"
				( attribute "PN" "216"
					( Origin gPackager )
				)
				( objectStatus "J6L2.216" )
			)
			( pin "@baseboard_fab2_lib.baseboard_fab2(sch_1):page52_i12:a3"
				( attribute "PN" "71"
					( Origin gPackager )
				)
				( objectStatus "J6L2.71" )
			)
			( pin "@baseboard_fab2_lib.baseboard_fab2(sch_1):page52_i12:a4"
				( attribute "PN" "214"
					( Origin gPackager )
				)
				( objectStatus "J6L2.214" )
			)
			( pin "@baseboard_fab2_lib.baseboard_fab2(sch_1):page52_i12:a5"
				( attribute "PN" "213"
					( Origin gPackager )
				)
				( objectStatus "J6L2.213" )
			)
			( pin "@baseboard_fab2_lib.baseboard_fab2(sch_1):page52_i12:a6"
				( attribute "PN" "69"
					( Origin gPackager )
				)
				( objectStatus "J6L2.69" )
			)
			( pin "@baseboard_fab2_lib.baseboard_fab2(sch_1):page52_i12:a7"
				( attribute "PN" "211"
					( Origin gPackager )
				)
				( objectStatus "J6L2.211" )
			)
			( pin "@baseboard_fab2_lib.baseboard_fab2(sch_1):page52_i12:a8"
				( attribute "PN" "68"
					( Origin gPackager )
				)
				( objectStatus "J6L2.68" )
			)
			( pin "@baseboard_fab2_lib.baseboard_fab2(sch_1):page52_i12:a9"
				( attribute "PN" "66"
					( Origin gPackager )
				)
				( objectStatus "J6L2.66" )
			)
			( pin "@baseboard_fab2_lib.baseboard_fab2(sch_1):page52_i12:a10"
				( attribute "PN" "225"
					( Origin gPackager )
				)
				( objectStatus "J6L2.225" )
			)
			( pin "@baseboard_fab2_lib.baseboard_fab2(sch_1):page52_i12:a11"
				( attribute "PN" "210"
					( Origin gPackager )
				)
				( objectStatus "J6L2.210" )
			)
			( pin "@baseboard_fab2_lib.baseboard_fab2(sch_1):page52_i12:a12"
				( attribute "PN" "65"
					( Origin gPackager )
				)
				( objectStatus "J6L2.65" )
			)
			( pin "@baseboard_fab2_lib.baseboard_fab2(sch_1):page52_i12:a13"
				( attribute "PN" "232"
					( Origin gPackager )
				)
				( objectStatus "J6L2.232" )
			)
			( pin "@baseboard_fab2_lib.baseboard_fab2(sch_1):page52_i12:a14_we_n"
				( attribute "PN" "228"
					( Origin gPackager )
				)
				( objectStatus "J6L2.228" )
			)
			( pin "@baseboard_fab2_lib.baseboard_fab2(sch_1):page52_i12:a15_cas_n"
				( attribute "PN" "86"
					( Origin gPackager )
				)
				( objectStatus "J6L2.86" )
			)
			( pin "@baseboard_fab2_lib.baseboard_fab2(sch_1):page52_i12:a16_ras_n"
				( attribute "PN" "82"
					( Origin gPackager )
				)
				( objectStatus "J6L2.82" )
			)
			( pin "@baseboard_fab2_lib.baseboard_fab2(sch_1):page52_i12:a17"
				( attribute "PN" "234"
					( Origin gPackager )
				)
				( objectStatus "J6L2.234" )
			)
			( pin "@baseboard_fab2_lib.baseboard_fab2(sch_1):page52_i12:act_n"
				( attribute "PN" "62"
					( Origin gPackager )
				)
				( objectStatus "J6L2.62" )
			)
			( pin "@baseboard_fab2_lib.baseboard_fab2(sch_1):page52_i12:alert_n"
				( attribute "PN" "208"
					( Origin gPackager )
				)
				( objectStatus "J6L2.208" )
			)
			( pin "@baseboard_fab2_lib.baseboard_fab2(sch_1):page52_i12:ba(0)"
				( attribute "PN" "81"
					( Origin gPackager )
				)
				( objectStatus "J6L2.81" )
			)
			( pin "@baseboard_fab2_lib.baseboard_fab2(sch_1):page52_i12:ba(1)"
				( attribute "PN" "224"
					( Origin gPackager )
				)
				( objectStatus "J6L2.224" )
			)
			( pin "@baseboard_fab2_lib.baseboard_fab2(sch_1):page52_i12:bg(0)"
				( attribute "PN" "63"
					( Origin gPackager )
				)
				( objectStatus "J6L2.63" )
			)
			( pin "@baseboard_fab2_lib.baseboard_fab2(sch_1):page52_i12:bg(1)"
				( attribute "PN" "207"
					( Origin gPackager )
				)
				( objectStatus "J6L2.207" )
			)
			( pin "@baseboard_fab2_lib.baseboard_fab2(sch_1):page52_i12:c(2)"
				( attribute "PN" "235"
					( Origin gPackager )
				)
				( objectStatus "J6L2.235" )
			)
			( pin "@baseboard_fab2_lib.baseboard_fab2(sch_1):page52_i12:cb(0)"
				( attribute "PN" "49"
					( Origin gPackager )
				)
				( objectStatus "J6L2.49" )
			)
			( pin "@baseboard_fab2_lib.baseboard_fab2(sch_1):page52_i12:cb(1)"
				( attribute "PN" "194"
					( Origin gPackager )
				)
				( objectStatus "J6L2.194" )
			)
			( pin "@baseboard_fab2_lib.baseboard_fab2(sch_1):page52_i12:cb(2)"
				( attribute "PN" "56"
					( Origin gPackager )
				)
				( objectStatus "J6L2.56" )
			)
			( pin "@baseboard_fab2_lib.baseboard_fab2(sch_1):page52_i12:cb(3)"
				( attribute "PN" "201"
					( Origin gPackager )
				)
				( objectStatus "J6L2.201" )
			)
			( pin "@baseboard_fab2_lib.baseboard_fab2(sch_1):page52_i12:cb(4)"
				( attribute "PN" "47"
					( Origin gPackager )
				)
				( objectStatus "J6L2.47" )
			)
			( pin "@baseboard_fab2_lib.baseboard_fab2(sch_1):page52_i12:cb(5)"
				( attribute "PN" "192"
					( Origin gPackager )
				)
				( objectStatus "J6L2.192" )
			)
			( pin "@baseboard_fab2_lib.baseboard_fab2(sch_1):page52_i12:cb(6)"
				( attribute "PN" "54"
					( Origin gPackager )
				)
				( objectStatus "J6L2.54" )
			)
			( pin "@baseboard_fab2_lib.baseboard_fab2(sch_1):page52_i12:cb(7)"
				( attribute "PN" "199"
					( Origin gPackager )
				)
				( objectStatus "J6L2.199" )
			)
			( pin "@baseboard_fab2_lib.baseboard_fab2(sch_1):page52_i12:ck0n"
				( attribute "PN" "75"
					( Origin gPackager )
				)
				( objectStatus "J6L2.75" )
			)
			( pin "@baseboard_fab2_lib.baseboard_fab2(sch_1):page52_i12:ck0p"
				( attribute "PN" "74"
					( Origin gPackager )
				)
				( objectStatus "J6L2.74" )
			)
			( pin "@baseboard_fab2_lib.baseboard_fab2(sch_1):page52_i12:ck1n"
				( attribute "PN" "219"
					( Origin gPackager )
				)
				( objectStatus "J6L2.219" )
			)
			( pin "@baseboard_fab2_lib.baseboard_fab2(sch_1):page52_i12:ck1p"
				( attribute "PN" "218"
					( Origin gPackager )
				)
				( objectStatus "J6L2.218" )
			)
			( pin "@baseboard_fab2_lib.baseboard_fab2(sch_1):page52_i12:cke(0)"
				( attribute "PN" "60"
					( Origin gPackager )
				)
				( objectStatus "J6L2.60" )
			)
			( pin "@baseboard_fab2_lib.baseboard_fab2(sch_1):page52_i12:cke(1)"
				( attribute "PN" "203"
					( Origin gPackager )
				)
				( objectStatus "J6L2.203" )
			)
			( pin "@baseboard_fab2_lib.baseboard_fab2(sch_1):page52_i12:dq(0)"
				( attribute "PN" "5"
					( Origin gPackager )
				)
				( objectStatus "J6L2.5" )
			)
			( pin "@baseboard_fab2_lib.baseboard_fab2(sch_1):page52_i12:dq(1)"
				( attribute "PN" "150"
					( Origin gPackager )
				)
				( objectStatus "J6L2.150" )
			)
			( pin "@baseboard_fab2_lib.baseboard_fab2(sch_1):page52_i12:dq(2)"
				( attribute "PN" "12"
					( Origin gPackager )
				)
				( objectStatus "J6L2.12" )
			)
			( pin "@baseboard_fab2_lib.baseboard_fab2(sch_1):page52_i12:dq(3)"
				( attribute "PN" "157"
					( Origin gPackager )
				)
				( objectStatus "J6L2.157" )
			)
			( pin "@baseboard_fab2_lib.baseboard_fab2(sch_1):page52_i12:dq(4)"
				( attribute "PN" "3"
					( Origin gPackager )
				)
				( objectStatus "J6L2.3" )
			)
			( pin "@baseboard_fab2_lib.baseboard_fab2(sch_1):page52_i12:dq(5)"
				( attribute "PN" "148"
					( Origin gPackager )
				)
				( objectStatus "J6L2.148" )
			)
			( pin "@baseboard_fab2_lib.baseboard_fab2(sch_1):page52_i12:dq(6)"
				( attribute "PN" "10"
					( Origin gPackager )
				)
				( objectStatus "J6L2.10" )
			)
			( pin "@baseboard_fab2_lib.baseboard_fab2(sch_1):page52_i12:dq(7)"
				( attribute "PN" "155"
					( Origin gPackager )
				)
				( objectStatus "J6L2.155" )
			)
			( pin "@baseboard_fab2_lib.baseboard_fab2(sch_1):page52_i12:dq(8)"
				( attribute "PN" "16"
					( Origin gPackager )
				)
				( objectStatus "J6L2.16" )
			)
			( pin "@baseboard_fab2_lib.baseboard_fab2(sch_1):page52_i12:dq(9)"
				( attribute "PN" "161"
					( Origin gPackager )
				)
				( objectStatus "J6L2.161" )
			)
			( pin "@baseboard_fab2_lib.baseboard_fab2(sch_1):page52_i12:dq(10)"
				( attribute "PN" "23"
					( Origin gPackager )
				)
				( objectStatus "J6L2.23" )
			)
			( pin "@baseboard_fab2_lib.baseboard_fab2(sch_1):page52_i12:dq(11)"
				( attribute "PN" "168"
					( Origin gPackager )
				)
				( objectStatus "J6L2.168" )
			)
			( pin "@baseboard_fab2_lib.baseboard_fab2(sch_1):page52_i12:dq(12)"
				( attribute "PN" "14"
					( Origin gPackager )
				)
				( objectStatus "J6L2.14" )
			)
			( pin "@baseboard_fab2_lib.baseboard_fab2(sch_1):page52_i12:dq(13)"
				( attribute "PN" "159"
					( Origin gPackager )
				)
				( objectStatus "J6L2.159" )
			)
			( pin "@baseboard_fab2_lib.baseboard_fab2(sch_1):page52_i12:dq(14)"
				( attribute "PN" "21"
					( Origin gPackager )
				)
				( objectStatus "J6L2.21" )
			)
			( pin "@baseboard_fab2_lib.baseboard_fab2(sch_1):page52_i12:dq(15)"
				( attribute "PN" "166"
					( Origin gPackager )
				)
				( objectStatus "J6L2.166" )
			)
			( pin "@baseboard_fab2_lib.baseboard_fab2(sch_1):page52_i12:dq(16)"
				( attribute "PN" "27"
					( Origin gPackager )
				)
				( objectStatus "J6L2.27" )
			)
			( pin "@baseboard_fab2_lib.baseboard_fab2(sch_1):page52_i12:dq(17)"
				( attribute "PN" "172"
					( Origin gPackager )
				)
				( objectStatus "J6L2.172" )
			)
			( pin "@baseboard_fab2_lib.baseboard_fab2(sch_1):page52_i12:dq(18)"
				( attribute "PN" "34"
					( Origin gPackager )
				)
				( objectStatus "J6L2.34" )
			)
			( pin "@baseboard_fab2_lib.baseboard_fab2(sch_1):page52_i12:dq(19)"
				( attribute "PN" "179"
					( Origin gPackager )
				)
				( objectStatus "J6L2.179" )
			)
			( pin "@baseboard_fab2_lib.baseboard_fab2(sch_1):page52_i12:dq(20)"
				( attribute "PN" "25"
					( Origin gPackager )
				)
				( objectStatus "J6L2.25" )
			)
			( pin "@baseboard_fab2_lib.baseboard_fab2(sch_1):page52_i12:dq(21)"
				( attribute "PN" "170"
					( Origin gPackager )
				)
				( objectStatus "J6L2.170" )
			)
			( pin "@baseboard_fab2_lib.baseboard_fab2(sch_1):page52_i12:dq(22)"
				( attribute "PN" "32"
					( Origin gPackager )
				)
				( objectStatus "J6L2.32" )
			)
			( pin "@baseboard_fab2_lib.baseboard_fab2(sch_1):page52_i12:dq(23)"
				( attribute "PN" "177"
					( Origin gPackager )
				)
				( objectStatus "J6L2.177" )
			)
			( pin "@baseboard_fab2_lib.baseboard_fab2(sch_1):page52_i12:dq(24)"
				( attribute "PN" "38"
					( Origin gPackager )
				)
				( objectStatus "J6L2.38" )
			)
			( pin "@baseboard_fab2_lib.baseboard_fab2(sch_1):page52_i12:dq(25)"
				( attribute "PN" "183"
					( Origin gPackager )
				)
				( objectStatus "J6L2.183" )
			)
			( pin "@baseboard_fab2_lib.baseboard_fab2(sch_1):page52_i12:dq(26)"
				( attribute "PN" "45"
					( Origin gPackager )
				)
				( objectStatus "J6L2.45" )
			)
			( pin "@baseboard_fab2_lib.baseboard_fab2(sch_1):page52_i12:dq(27)"
				( attribute "PN" "190"
					( Origin gPackager )
				)
				( objectStatus "J6L2.190" )
			)
			( pin "@baseboard_fab2_lib.baseboard_fab2(sch_1):page52_i12:dq(28)"
				( attribute "PN" "36"
					( Origin gPackager )
				)
				( objectStatus "J6L2.36" )
			)
			( pin "@baseboard_fab2_lib.baseboard_fab2(sch_1):page52_i12:dq(29)"
				( attribute "PN" "181"
					( Origin gPackager )
				)
				( objectStatus "J6L2.181" )
			)
			( pin "@baseboard_fab2_lib.baseboard_fab2(sch_1):page52_i12:dq(30)"
				( attribute "PN" "43"
					( Origin gPackager )
				)
				( objectStatus "J6L2.43" )
			)
			( pin "@baseboard_fab2_lib.baseboard_fab2(sch_1):page52_i12:dq(31)"
				( attribute "PN" "188"
					( Origin gPackager )
				)
				( objectStatus "J6L2.188" )
			)
			( pin "@baseboard_fab2_lib.baseboard_fab2(sch_1):page52_i12:dq(32)"
				( attribute "PN" "97"
					( Origin gPackager )
				)
				( objectStatus "J6L2.97" )
			)
			( pin "@baseboard_fab2_lib.baseboard_fab2(sch_1):page52_i12:dq(33)"
				( attribute "PN" "242"
					( Origin gPackager )
				)
				( objectStatus "J6L2.242" )
			)
			( pin "@baseboard_fab2_lib.baseboard_fab2(sch_1):page52_i12:dq(34)"
				( attribute "PN" "104"
					( Origin gPackager )
				)
				( objectStatus "J6L2.104" )
			)
			( pin "@baseboard_fab2_lib.baseboard_fab2(sch_1):page52_i12:dq(35)"
				( attribute "PN" "249"
					( Origin gPackager )
				)
				( objectStatus "J6L2.249" )
			)
			( pin "@baseboard_fab2_lib.baseboard_fab2(sch_1):page52_i12:dq(36)"
				( attribute "PN" "95"
					( Origin gPackager )
				)
				( objectStatus "J6L2.95" )
			)
			( pin "@baseboard_fab2_lib.baseboard_fab2(sch_1):page52_i12:dq(37)"
				( attribute "PN" "240"
					( Origin gPackager )
				)
				( objectStatus "J6L2.240" )
			)
			( pin "@baseboard_fab2_lib.baseboard_fab2(sch_1):page52_i12:dq(38)"
				( attribute "PN" "102"
					( Origin gPackager )
				)
				( objectStatus "J6L2.102" )
			)
			( pin "@baseboard_fab2_lib.baseboard_fab2(sch_1):page52_i12:dq(39)"
				( attribute "PN" "247"
					( Origin gPackager )
				)
				( objectStatus "J6L2.247" )
			)
			( pin "@baseboard_fab2_lib.baseboard_fab2(sch_1):page52_i12:dq(40)"
				( attribute "PN" "108"
					( Origin gPackager )
				)
				( objectStatus "J6L2.108" )
			)
			( pin "@baseboard_fab2_lib.baseboard_fab2(sch_1):page52_i12:dq(41)"
				( attribute "PN" "253"
					( Origin gPackager )
				)
				( objectStatus "J6L2.253" )
			)
			( pin "@baseboard_fab2_lib.baseboard_fab2(sch_1):page52_i12:dq(42)"
				( attribute "PN" "115"
					( Origin gPackager )
				)
				( objectStatus "J6L2.115" )
			)
			( pin "@baseboard_fab2_lib.baseboard_fab2(sch_1):page52_i12:dq(43)"
				( attribute "PN" "260"
					( Origin gPackager )
				)
				( objectStatus "J6L2.260" )
			)
			( pin "@baseboard_fab2_lib.baseboard_fab2(sch_1):page52_i12:dq(44)"
				( attribute "PN" "106"
					( Origin gPackager )
				)
				( objectStatus "J6L2.106" )
			)
			( pin "@baseboard_fab2_lib.baseboard_fab2(sch_1):page52_i12:dq(45)"
				( attribute "PN" "251"
					( Origin gPackager )
				)
				( objectStatus "J6L2.251" )
			)
			( pin "@baseboard_fab2_lib.baseboard_fab2(sch_1):page52_i12:dq(46)"
				( attribute "PN" "113"
					( Origin gPackager )
				)
				( objectStatus "J6L2.113" )
			)
			( pin "@baseboard_fab2_lib.baseboard_fab2(sch_1):page52_i12:dq(47)"
				( attribute "PN" "258"
					( Origin gPackager )
				)
				( objectStatus "J6L2.258" )
			)
			( pin "@baseboard_fab2_lib.baseboard_fab2(sch_1):page52_i12:dq(48)"
				( attribute "PN" "119"
					( Origin gPackager )
				)
				( objectStatus "J6L2.119" )
			)
			( pin "@baseboard_fab2_lib.baseboard_fab2(sch_1):page52_i12:dq(49)"
				( attribute "PN" "264"
					( Origin gPackager )
				)
				( objectStatus "J6L2.264" )
			)
			( pin "@baseboard_fab2_lib.baseboard_fab2(sch_1):page52_i12:dq(50)"
				( attribute "PN" "126"
					( Origin gPackager )
				)
				( objectStatus "J6L2.126" )
			)
			( pin "@baseboard_fab2_lib.baseboard_fab2(sch_1):page52_i12:dq(51)"
				( attribute "PN" "271"
					( Origin gPackager )
				)
				( objectStatus "J6L2.271" )
			)
			( pin "@baseboard_fab2_lib.baseboard_fab2(sch_1):page52_i12:dq(52)"
				( attribute "PN" "117"
					( Origin gPackager )
				)
				( objectStatus "J6L2.117" )
			)
			( pin "@baseboard_fab2_lib.baseboard_fab2(sch_1):page52_i12:dq(53)"
				( attribute "PN" "262"
					( Origin gPackager )
				)
				( objectStatus "J6L2.262" )
			)
			( pin "@baseboard_fab2_lib.baseboard_fab2(sch_1):page52_i12:dq(54)"
				( attribute "PN" "124"
					( Origin gPackager )
				)
				( objectStatus "J6L2.124" )
			)
			( pin "@baseboard_fab2_lib.baseboard_fab2(sch_1):page52_i12:dq(55)"
				( attribute "PN" "269"
					( Origin gPackager )
				)
				( objectStatus "J6L2.269" )
			)
			( pin "@baseboard_fab2_lib.baseboard_fab2(sch_1):page52_i12:dq(56)"
				( attribute "PN" "130"
					( Origin gPackager )
				)
				( objectStatus "J6L2.130" )
			)
			( pin "@baseboard_fab2_lib.baseboard_fab2(sch_1):page52_i12:dq(57)"
				( attribute "PN" "275"
					( Origin gPackager )
				)
				( objectStatus "J6L2.275" )
			)
			( pin "@baseboard_fab2_lib.baseboard_fab2(sch_1):page52_i12:dq(58)"
				( attribute "PN" "137"
					( Origin gPackager )
				)
				( objectStatus "J6L2.137" )
			)
			( pin "@baseboard_fab2_lib.baseboard_fab2(sch_1):page52_i12:dq(59)"
				( attribute "PN" "282"
					( Origin gPackager )
				)
				( objectStatus "J6L2.282" )
			)
			( pin "@baseboard_fab2_lib.baseboard_fab2(sch_1):page52_i12:dq(60)"
				( attribute "PN" "128"
					( Origin gPackager )
				)
				( objectStatus "J6L2.128" )
			)
			( pin "@baseboard_fab2_lib.baseboard_fab2(sch_1):page52_i12:dq(61)"
				( attribute "PN" "273"
					( Origin gPackager )
				)
				( objectStatus "J6L2.273" )
			)
			( pin "@baseboard_fab2_lib.baseboard_fab2(sch_1):page52_i12:dq(62)"
				( attribute "PN" "135"
					( Origin gPackager )
				)
				( objectStatus "J6L2.135" )
			)
			( pin "@baseboard_fab2_lib.baseboard_fab2(sch_1):page52_i12:dq(63)"
				( attribute "PN" "280"
					( Origin gPackager )
				)
				( objectStatus "J6L2.280" )
			)
			( pin "@baseboard_fab2_lib.baseboard_fab2(sch_1):page52_i12:event_n"
				( attribute "PN" "78"
					( Origin gPackager )
				)
				( objectStatus "J6L2.78" )
			)
			( pin "@baseboard_fab2_lib.baseboard_fab2(sch_1):page52_i12:odt(0)"
				( attribute "PN" "87"
					( Origin gPackager )
				)
				( objectStatus "J6L2.87" )
			)
			( pin "@baseboard_fab2_lib.baseboard_fab2(sch_1):page52_i12:odt(1)"
				( attribute "PN" "91"
					( Origin gPackager )
				)
				( objectStatus "J6L2.91" )
			)
			( pin "@baseboard_fab2_lib.baseboard_fab2(sch_1):page52_i12:par"
				( attribute "PN" "222"
					( Origin gPackager )
				)
				( objectStatus "J6L2.222" )
			)
			( pin "@baseboard_fab2_lib.baseboard_fab2(sch_1):page52_i12:reset_n"
				( attribute "PN" "58"
					( Origin gPackager )
				)
				( objectStatus "J6L2.58" )
			)
			( pin "@baseboard_fab2_lib.baseboard_fab2(sch_1):page52_i12:rfu(0)"
				( attribute "PN" "205"
					( Origin gPackager )
				)
				( objectStatus "J6L2.205" )
			)
			( pin "@baseboard_fab2_lib.baseboard_fab2(sch_1):page52_i12:rfu(1)"
				( attribute "PN" "227"
					( Origin gPackager )
				)
				( objectStatus "J6L2.227" )
			)
			( pin "@baseboard_fab2_lib.baseboard_fab2(sch_1):page52_i12:rfu(2)"
				( attribute "PN" "144"
					( Origin gPackager )
				)
				( objectStatus "J6L2.144" )
			)
			( pin "@baseboard_fab2_lib.baseboard_fab2(sch_1):page52_i12:s0_n"
				( attribute "PN" "84"
					( Origin gPackager )
				)
				( objectStatus "J6L2.84" )
			)
			( pin "@baseboard_fab2_lib.baseboard_fab2(sch_1):page52_i12:s1_n"
				( attribute "PN" "89"
					( Origin gPackager )
				)
				( objectStatus "J6L2.89" )
			)
			( pin "@baseboard_fab2_lib.baseboard_fab2(sch_1):page52_i12:s2_n_c(0)"
				( attribute "PN" "93"
					( Origin gPackager )
				)
				( objectStatus "J6L2.93" )
			)
			( pin "@baseboard_fab2_lib.baseboard_fab2(sch_1):page52_i12:s3_n_c(1)"
				( attribute "PN" "237"
					( Origin gPackager )
				)
				( objectStatus "J6L2.237" )
			)
			( pin "@baseboard_fab2_lib.baseboard_fab2(sch_1):page52_i12:sa(0)"
				( attribute "PN" "139"
					( Origin gPackager )
				)
				( objectStatus "J6L2.139" )
			)
			( pin "@baseboard_fab2_lib.baseboard_fab2(sch_1):page52_i12:sa(1)"
				( attribute "PN" "140"
					( Origin gPackager )
				)
				( objectStatus "J6L2.140" )
			)
			( pin "@baseboard_fab2_lib.baseboard_fab2(sch_1):page52_i12:sa(2)"
				( attribute "PN" "238"
					( Origin gPackager )
				)
				( objectStatus "J6L2.238" )
			)
			( pin "@baseboard_fab2_lib.baseboard_fab2(sch_1):page52_i12:save_n_nc"
				( attribute "PN" "230"
					( Origin gPackager )
				)
				( objectStatus "J6L2.230" )
			)
			( pin "@baseboard_fab2_lib.baseboard_fab2(sch_1):page52_i12:scl"
				( attribute "PN" "141"
					( Origin gPackager )
				)
				( objectStatus "J6L2.141" )
			)
			( pin "@baseboard_fab2_lib.baseboard_fab2(sch_1):page52_i12:sda"
				( attribute "PN" "285"
					( Origin gPackager )
				)
				( objectStatus "J6L2.285" )
			)
			( pin "@baseboard_fab2_lib.baseboard_fab2(sch_1):page52_i12:vddspd"
				( attribute "PN" "284"
					( Origin gPackager )
				)
				( objectStatus "J6L2.284" )
			)
			( pin "@baseboard_fab2_lib.baseboard_fab2(sch_1):page52_i12:vrefca"
				( attribute "PN" "146"
					( Origin gPackager )
				)
				( objectStatus "J6L2.146" )
			)
			( pin "@baseboard_fab2_lib.baseboard_fab2(sch_1):page52_i55:\12v\(0)"
				( attribute "PN" "145"
					( Origin gPackager )
				)
				( objectStatus "J6L2.145" )
			)
			( pin "@baseboard_fab2_lib.baseboard_fab2(sch_1):page52_i55:\12v\(1)"
				( attribute "PN" "1"
					( Origin gPackager )
				)
				( objectStatus "J6L2.1" )
			)
			( pin "@baseboard_fab2_lib.baseboard_fab2(sch_1):page52_i55:vdd(0)"
				( attribute "PN" "236"
					( Origin gPackager )
				)
				( objectStatus "J6L2.236" )
			)
			( pin "@baseboard_fab2_lib.baseboard_fab2(sch_1):page52_i55:vdd(1)"
				( attribute "PN" "233"
					( Origin gPackager )
				)
				( objectStatus "J6L2.233" )
			)
			( pin "@baseboard_fab2_lib.baseboard_fab2(sch_1):page52_i55:vdd(2)"
				( attribute "PN" "231"
					( Origin gPackager )
				)
				( objectStatus "J6L2.231" )
			)
			( pin "@baseboard_fab2_lib.baseboard_fab2(sch_1):page52_i55:vdd(3)"
				( attribute "PN" "229"
					( Origin gPackager )
				)
				( objectStatus "J6L2.229" )
			)
			( pin "@baseboard_fab2_lib.baseboard_fab2(sch_1):page52_i55:vdd(4)"
				( attribute "PN" "226"
					( Origin gPackager )
				)
				( objectStatus "J6L2.226" )
			)
			( pin "@baseboard_fab2_lib.baseboard_fab2(sch_1):page52_i55:vdd(5)"
				( attribute "PN" "223"
					( Origin gPackager )
				)
				( objectStatus "J6L2.223" )
			)
			( pin "@baseboard_fab2_lib.baseboard_fab2(sch_1):page52_i55:vdd(6)"
				( attribute "PN" "220"
					( Origin gPackager )
				)
				( objectStatus "J6L2.220" )
			)
			( pin "@baseboard_fab2_lib.baseboard_fab2(sch_1):page52_i55:vdd(7)"
				( attribute "PN" "217"
					( Origin gPackager )
				)
				( objectStatus "J6L2.217" )
			)
			( pin "@baseboard_fab2_lib.baseboard_fab2(sch_1):page52_i55:vdd(8)"
				( attribute "PN" "215"
					( Origin gPackager )
				)
				( objectStatus "J6L2.215" )
			)
			( pin "@baseboard_fab2_lib.baseboard_fab2(sch_1):page52_i55:vdd(9)"
				( attribute "PN" "212"
					( Origin gPackager )
				)
				( objectStatus "J6L2.212" )
			)
			( pin "@baseboard_fab2_lib.baseboard_fab2(sch_1):page52_i55:vdd(10)"
				( attribute "PN" "209"
					( Origin gPackager )
				)
				( objectStatus "J6L2.209" )
			)
			( pin "@baseboard_fab2_lib.baseboard_fab2(sch_1):page52_i55:vdd(11)"
				( attribute "PN" "206"
					( Origin gPackager )
				)
				( objectStatus "J6L2.206" )
			)
			( pin "@baseboard_fab2_lib.baseboard_fab2(sch_1):page52_i55:vdd(12)"
				( attribute "PN" "204"
					( Origin gPackager )
				)
				( objectStatus "J6L2.204" )
			)
			( pin "@baseboard_fab2_lib.baseboard_fab2(sch_1):page52_i55:vdd(13)"
				( attribute "PN" "92"
					( Origin gPackager )
				)
				( objectStatus "J6L2.92" )
			)
			( pin "@baseboard_fab2_lib.baseboard_fab2(sch_1):page52_i55:vdd(14)"
				( attribute "PN" "90"
					( Origin gPackager )
				)
				( objectStatus "J6L2.90" )
			)
			( pin "@baseboard_fab2_lib.baseboard_fab2(sch_1):page52_i55:vdd(15)"
				( attribute "PN" "88"
					( Origin gPackager )
				)
				( objectStatus "J6L2.88" )
			)
			( pin "@baseboard_fab2_lib.baseboard_fab2(sch_1):page52_i55:vdd(16)"
				( attribute "PN" "85"
					( Origin gPackager )
				)
				( objectStatus "J6L2.85" )
			)
			( pin "@baseboard_fab2_lib.baseboard_fab2(sch_1):page52_i55:vdd(17)"
				( attribute "PN" "83"
					( Origin gPackager )
				)
				( objectStatus "J6L2.83" )
			)
			( pin "@baseboard_fab2_lib.baseboard_fab2(sch_1):page52_i55:vdd(18)"
				( attribute "PN" "80"
					( Origin gPackager )
				)
				( objectStatus "J6L2.80" )
			)
			( pin "@baseboard_fab2_lib.baseboard_fab2(sch_1):page52_i55:vdd(19)"
				( attribute "PN" "76"
					( Origin gPackager )
				)
				( objectStatus "J6L2.76" )
			)
			( pin "@baseboard_fab2_lib.baseboard_fab2(sch_1):page52_i55:vdd(20)"
				( attribute "PN" "73"
					( Origin gPackager )
				)
				( objectStatus "J6L2.73" )
			)
			( pin "@baseboard_fab2_lib.baseboard_fab2(sch_1):page52_i55:vdd(21)"
				( attribute "PN" "70"
					( Origin gPackager )
				)
				( objectStatus "J6L2.70" )
			)
			( pin "@baseboard_fab2_lib.baseboard_fab2(sch_1):page52_i55:vdd(22)"
				( attribute "PN" "67"
					( Origin gPackager )
				)
				( objectStatus "J6L2.67" )
			)
			( pin "@baseboard_fab2_lib.baseboard_fab2(sch_1):page52_i55:vdd(23)"
				( attribute "PN" "64"
					( Origin gPackager )
				)
				( objectStatus "J6L2.64" )
			)
			( pin "@baseboard_fab2_lib.baseboard_fab2(sch_1):page52_i55:vdd(24)"
				( attribute "PN" "61"
					( Origin gPackager )
				)
				( objectStatus "J6L2.61" )
			)
			( pin "@baseboard_fab2_lib.baseboard_fab2(sch_1):page52_i55:vdd(25)"
				( attribute "PN" "59"
					( Origin gPackager )
				)
				( objectStatus "J6L2.59" )
			)
			( pin "@baseboard_fab2_lib.baseboard_fab2(sch_1):page52_i55:vpp(0)"
				( attribute "PN" "287"
					( Origin gPackager )
				)
				( objectStatus "J6L2.287" )
			)
			( pin "@baseboard_fab2_lib.baseboard_fab2(sch_1):page52_i55:vpp(1)"
				( attribute "PN" "286"
					( Origin gPackager )
				)
				( objectStatus "J6L2.286" )
			)
			( pin "@baseboard_fab2_lib.baseboard_fab2(sch_1):page52_i55:vpp(2)"
				( attribute "PN" "288"
					( Origin gPackager )
				)
				( objectStatus "J6L2.288" )
			)
			( pin "@baseboard_fab2_lib.baseboard_fab2(sch_1):page52_i55:vpp(3)"
				( attribute "PN" "143"
					( Origin gPackager )
				)
				( objectStatus "J6L2.143" )
			)
			( pin "@baseboard_fab2_lib.baseboard_fab2(sch_1):page52_i55:vpp(4)"
				( attribute "PN" "142"
					( Origin gPackager )
				)
				( objectStatus "J6L2.142" )
			)
			( pin "@baseboard_fab2_lib.baseboard_fab2(sch_1):page52_i55:vtt(0)"
				( attribute "PN" "221"
					( Origin gPackager )
				)
				( objectStatus "J6L2.221" )
			)
			( pin "@baseboard_fab2_lib.baseboard_fab2(sch_1):page52_i55:vtt(1)"
				( attribute "PN" "77"
					( Origin gPackager )
				)
				( objectStatus "J6L2.77" )
			)
			( pin "@baseboard_fab2_lib.baseboard_fab2(sch_1):page52_i100:dqs0n"
				( attribute "PN" "152"
					( Origin gPackager )
				)
				( objectStatus "J6L2.152" )
			)
			( pin "@baseboard_fab2_lib.baseboard_fab2(sch_1):page52_i100:dqs0p"
				( attribute "PN" "153"
					( Origin gPackager )
				)
				( objectStatus "J6L2.153" )
			)
			( pin "@baseboard_fab2_lib.baseboard_fab2(sch_1):page52_i100:dqs1n"
				( attribute "PN" "163"
					( Origin gPackager )
				)
				( objectStatus "J6L2.163" )
			)
			( pin "@baseboard_fab2_lib.baseboard_fab2(sch_1):page52_i100:dqs1p"
				( attribute "PN" "164"
					( Origin gPackager )
				)
				( objectStatus "J6L2.164" )
			)
			( pin "@baseboard_fab2_lib.baseboard_fab2(sch_1):page52_i100:dqs2n"
				( attribute "PN" "174"
					( Origin gPackager )
				)
				( objectStatus "J6L2.174" )
			)
			( pin "@baseboard_fab2_lib.baseboard_fab2(sch_1):page52_i100:dqs2p"
				( attribute "PN" "175"
					( Origin gPackager )
				)
				( objectStatus "J6L2.175" )
			)
			( pin "@baseboard_fab2_lib.baseboard_fab2(sch_1):page52_i100:dqs3n"
				( attribute "PN" "185"
					( Origin gPackager )
				)
				( objectStatus "J6L2.185" )
			)
			( pin "@baseboard_fab2_lib.baseboard_fab2(sch_1):page52_i100:dqs3p"
				( attribute "PN" "186"
					( Origin gPackager )
				)
				( objectStatus "J6L2.186" )
			)
			( pin "@baseboard_fab2_lib.baseboard_fab2(sch_1):page52_i100:dqs4n"
				( attribute "PN" "244"
					( Origin gPackager )
				)
				( objectStatus "J6L2.244" )
			)
			( pin "@baseboard_fab2_lib.baseboard_fab2(sch_1):page52_i100:dqs4p"
				( attribute "PN" "245"
					( Origin gPackager )
				)
				( objectStatus "J6L2.245" )
			)
			( pin "@baseboard_fab2_lib.baseboard_fab2(sch_1):page52_i100:dqs5n"
				( attribute "PN" "255"
					( Origin gPackager )
				)
				( objectStatus "J6L2.255" )
			)
			( pin "@baseboard_fab2_lib.baseboard_fab2(sch_1):page52_i100:dqs5p"
				( attribute "PN" "256"
					( Origin gPackager )
				)
				( objectStatus "J6L2.256" )
			)
			( pin "@baseboard_fab2_lib.baseboard_fab2(sch_1):page52_i100:dqs6n"
				( attribute "PN" "266"
					( Origin gPackager )
				)
				( objectStatus "J6L2.266" )
			)
			( pin "@baseboard_fab2_lib.baseboard_fab2(sch_1):page52_i100:dqs6p"
				( attribute "PN" "267"
					( Origin gPackager )
				)
				( objectStatus "J6L2.267" )
			)
			( pin "@baseboard_fab2_lib.baseboard_fab2(sch_1):page52_i100:dqs7n"
				( attribute "PN" "277"
					( Origin gPackager )
				)
				( objectStatus "J6L2.277" )
			)
			( pin "@baseboard_fab2_lib.baseboard_fab2(sch_1):page52_i100:dqs7p"
				( attribute "PN" "278"
					( Origin gPackager )
				)
				( objectStatus "J6L2.278" )
			)
			( pin "@baseboard_fab2_lib.baseboard_fab2(sch_1):page52_i100:dqs8n"
				( attribute "PN" "196"
					( Origin gPackager )
				)
				( objectStatus "J6L2.196" )
			)
			( pin "@baseboard_fab2_lib.baseboard_fab2(sch_1):page52_i100:dqs8p"
				( attribute "PN" "197"
					( Origin gPackager )
				)
				( objectStatus "J6L2.197" )
			)
			( pin "@baseboard_fab2_lib.baseboard_fab2(sch_1):page52_i100:dqs9n"
				( attribute "PN" "8"
					( Origin gPackager )
				)
				( objectStatus "J6L2.8" )
			)
			( pin "@baseboard_fab2_lib.baseboard_fab2(sch_1):page52_i100:dqs9p"
				( attribute "PN" "7"
					( Origin gPackager )
				)
				( objectStatus "J6L2.7" )
			)
			( pin "@baseboard_fab2_lib.baseboard_fab2(sch_1):page52_i100:dqs10n"
				( attribute "PN" "19"
					( Origin gPackager )
				)
				( objectStatus "J6L2.19" )
			)
			( pin "@baseboard_fab2_lib.baseboard_fab2(sch_1):page52_i100:dqs10p"
				( attribute "PN" "18"
					( Origin gPackager )
				)
				( objectStatus "J6L2.18" )
			)
			( pin "@baseboard_fab2_lib.baseboard_fab2(sch_1):page52_i100:dqs11n"
				( attribute "PN" "30"
					( Origin gPackager )
				)
				( objectStatus "J6L2.30" )
			)
			( pin "@baseboard_fab2_lib.baseboard_fab2(sch_1):page52_i100:dqs11p"
				( attribute "PN" "29"
					( Origin gPackager )
				)
				( objectStatus "J6L2.29" )
			)
			( pin "@baseboard_fab2_lib.baseboard_fab2(sch_1):page52_i100:dqs12n"
				( attribute "PN" "41"
					( Origin gPackager )
				)
				( objectStatus "J6L2.41" )
			)
			( pin "@baseboard_fab2_lib.baseboard_fab2(sch_1):page52_i100:dqs12p"
				( attribute "PN" "40"
					( Origin gPackager )
				)
				( objectStatus "J6L2.40" )
			)
			( pin "@baseboard_fab2_lib.baseboard_fab2(sch_1):page52_i100:dqs13n"
				( attribute "PN" "100"
					( Origin gPackager )
				)
				( objectStatus "J6L2.100" )
			)
			( pin "@baseboard_fab2_lib.baseboard_fab2(sch_1):page52_i100:dqs13p"
				( attribute "PN" "99"
					( Origin gPackager )
				)
				( objectStatus "J6L2.99" )
			)
			( pin "@baseboard_fab2_lib.baseboard_fab2(sch_1):page52_i100:dqs14n"
				( attribute "PN" "111"
					( Origin gPackager )
				)
				( objectStatus "J6L2.111" )
			)
			( pin "@baseboard_fab2_lib.baseboard_fab2(sch_1):page52_i100:dqs14p"
				( attribute "PN" "110"
					( Origin gPackager )
				)
				( objectStatus "J6L2.110" )
			)
			( pin "@baseboard_fab2_lib.baseboard_fab2(sch_1):page52_i100:dqs15n"
				( attribute "PN" "122"
					( Origin gPackager )
				)
				( objectStatus "J6L2.122" )
			)
			( pin "@baseboard_fab2_lib.baseboard_fab2(sch_1):page52_i100:dqs15p"
				( attribute "PN" "121"
					( Origin gPackager )
				)
				( objectStatus "J6L2.121" )
			)
			( pin "@baseboard_fab2_lib.baseboard_fab2(sch_1):page52_i100:dqs16n"
				( attribute "PN" "133"
					( Origin gPackager )
				)
				( objectStatus "J6L2.133" )
			)
			( pin "@baseboard_fab2_lib.baseboard_fab2(sch_1):page52_i100:dqs16p"
				( attribute "PN" "132"
					( Origin gPackager )
				)
				( objectStatus "J6L2.132" )
			)
			( pin "@baseboard_fab2_lib.baseboard_fab2(sch_1):page52_i100:dqs17n"
				( attribute "PN" "52"
					( Origin gPackager )
				)
				( objectStatus "J6L2.52" )
			)
			( pin "@baseboard_fab2_lib.baseboard_fab2(sch_1):page52_i100:dqs17p"
				( attribute "PN" "51"
					( Origin gPackager )
				)
				( objectStatus "J6L2.51" )
			)
			( pin "@baseboard_fab2_lib.baseboard_fab2(sch_1):page52_i138:vss(0)"
				( attribute "PN" "283"
					( Origin gPackager )
				)
				( objectStatus "J6L2.283" )
			)
			( pin "@baseboard_fab2_lib.baseboard_fab2(sch_1):page52_i138:vss(1)"
				( attribute "PN" "281"
					( Origin gPackager )
				)
				( objectStatus "J6L2.281" )
			)
			( pin "@baseboard_fab2_lib.baseboard_fab2(sch_1):page52_i138:vss(2)"
				( attribute "PN" "279"
					( Origin gPackager )
				)
				( objectStatus "J6L2.279" )
			)
			( pin "@baseboard_fab2_lib.baseboard_fab2(sch_1):page52_i138:vss(3)"
				( attribute "PN" "276"
					( Origin gPackager )
				)
				( objectStatus "J6L2.276" )
			)
			( pin "@baseboard_fab2_lib.baseboard_fab2(sch_1):page52_i138:vss(4)"
				( attribute "PN" "274"
					( Origin gPackager )
				)
				( objectStatus "J6L2.274" )
			)
			( pin "@baseboard_fab2_lib.baseboard_fab2(sch_1):page52_i138:vss(5)"
				( attribute "PN" "272"
					( Origin gPackager )
				)
				( objectStatus "J6L2.272" )
			)
			( pin "@baseboard_fab2_lib.baseboard_fab2(sch_1):page52_i138:vss(6)"
				( attribute "PN" "270"
					( Origin gPackager )
				)
				( objectStatus "J6L2.270" )
			)
			( pin "@baseboard_fab2_lib.baseboard_fab2(sch_1):page52_i138:vss(7)"
				( attribute "PN" "268"
					( Origin gPackager )
				)
				( objectStatus "J6L2.268" )
			)
			( pin "@baseboard_fab2_lib.baseboard_fab2(sch_1):page52_i138:vss(8)"
				( attribute "PN" "265"
					( Origin gPackager )
				)
				( objectStatus "J6L2.265" )
			)
			( pin "@baseboard_fab2_lib.baseboard_fab2(sch_1):page52_i138:vss(9)"
				( attribute "PN" "263"
					( Origin gPackager )
				)
				( objectStatus "J6L2.263" )
			)
			( pin "@baseboard_fab2_lib.baseboard_fab2(sch_1):page52_i138:vss(10)"
				( attribute "PN" "261"
					( Origin gPackager )
				)
				( objectStatus "J6L2.261" )
			)
			( pin "@baseboard_fab2_lib.baseboard_fab2(sch_1):page52_i138:vss(11)"
				( attribute "PN" "259"
					( Origin gPackager )
				)
				( objectStatus "J6L2.259" )
			)
			( pin "@baseboard_fab2_lib.baseboard_fab2(sch_1):page52_i138:vss(12)"
				( attribute "PN" "257"
					( Origin gPackager )
				)
				( objectStatus "J6L2.257" )
			)
			( pin "@baseboard_fab2_lib.baseboard_fab2(sch_1):page52_i138:vss(13)"
				( attribute "PN" "254"
					( Origin gPackager )
				)
				( objectStatus "J6L2.254" )
			)
			( pin "@baseboard_fab2_lib.baseboard_fab2(sch_1):page52_i138:vss(14)"
				( attribute "PN" "252"
					( Origin gPackager )
				)
				( objectStatus "J6L2.252" )
			)
			( pin "@baseboard_fab2_lib.baseboard_fab2(sch_1):page52_i138:vss(15)"
				( attribute "PN" "250"
					( Origin gPackager )
				)
				( objectStatus "J6L2.250" )
			)
			( pin "@baseboard_fab2_lib.baseboard_fab2(sch_1):page52_i138:vss(16)"
				( attribute "PN" "248"
					( Origin gPackager )
				)
				( objectStatus "J6L2.248" )
			)
			( pin "@baseboard_fab2_lib.baseboard_fab2(sch_1):page52_i138:vss(17)"
				( attribute "PN" "246"
					( Origin gPackager )
				)
				( objectStatus "J6L2.246" )
			)
			( pin "@baseboard_fab2_lib.baseboard_fab2(sch_1):page52_i138:vss(18)"
				( attribute "PN" "243"
					( Origin gPackager )
				)
				( objectStatus "J6L2.243" )
			)
			( pin "@baseboard_fab2_lib.baseboard_fab2(sch_1):page52_i138:vss(19)"
				( attribute "PN" "241"
					( Origin gPackager )
				)
				( objectStatus "J6L2.241" )
			)
			( pin "@baseboard_fab2_lib.baseboard_fab2(sch_1):page52_i138:vss(20)"
				( attribute "PN" "239"
					( Origin gPackager )
				)
				( objectStatus "J6L2.239" )
			)
			( pin "@baseboard_fab2_lib.baseboard_fab2(sch_1):page52_i138:vss(21)"
				( attribute "PN" "202"
					( Origin gPackager )
				)
				( objectStatus "J6L2.202" )
			)
			( pin "@baseboard_fab2_lib.baseboard_fab2(sch_1):page52_i138:vss(22)"
				( attribute "PN" "200"
					( Origin gPackager )
				)
				( objectStatus "J6L2.200" )
			)
			( pin "@baseboard_fab2_lib.baseboard_fab2(sch_1):page52_i138:vss(23)"
				( attribute "PN" "198"
					( Origin gPackager )
				)
				( objectStatus "J6L2.198" )
			)
			( pin "@baseboard_fab2_lib.baseboard_fab2(sch_1):page52_i138:vss(24)"
				( attribute "PN" "195"
					( Origin gPackager )
				)
				( objectStatus "J6L2.195" )
			)
			( pin "@baseboard_fab2_lib.baseboard_fab2(sch_1):page52_i138:vss(25)"
				( attribute "PN" "193"
					( Origin gPackager )
				)
				( objectStatus "J6L2.193" )
			)
			( pin "@baseboard_fab2_lib.baseboard_fab2(sch_1):page52_i138:vss(26)"
				( attribute "PN" "191"
					( Origin gPackager )
				)
				( objectStatus "J6L2.191" )
			)
			( pin "@baseboard_fab2_lib.baseboard_fab2(sch_1):page52_i138:vss(27)"
				( attribute "PN" "189"
					( Origin gPackager )
				)
				( objectStatus "J6L2.189" )
			)
			( pin "@baseboard_fab2_lib.baseboard_fab2(sch_1):page52_i138:vss(28)"
				( attribute "PN" "187"
					( Origin gPackager )
				)
				( objectStatus "J6L2.187" )
			)
			( pin "@baseboard_fab2_lib.baseboard_fab2(sch_1):page52_i138:vss(29)"
				( attribute "PN" "184"
					( Origin gPackager )
				)
				( objectStatus "J6L2.184" )
			)
			( pin "@baseboard_fab2_lib.baseboard_fab2(sch_1):page52_i138:vss(30)"
				( attribute "PN" "182"
					( Origin gPackager )
				)
				( objectStatus "J6L2.182" )
			)
			( pin "@baseboard_fab2_lib.baseboard_fab2(sch_1):page52_i138:vss(31)"
				( attribute "PN" "180"
					( Origin gPackager )
				)
				( objectStatus "J6L2.180" )
			)
			( pin "@baseboard_fab2_lib.baseboard_fab2(sch_1):page52_i138:vss(32)"
				( attribute "PN" "178"
					( Origin gPackager )
				)
				( objectStatus "J6L2.178" )
			)
			( pin "@baseboard_fab2_lib.baseboard_fab2(sch_1):page52_i138:vss(33)"
				( attribute "PN" "176"
					( Origin gPackager )
				)
				( objectStatus "J6L2.176" )
			)
			( pin "@baseboard_fab2_lib.baseboard_fab2(sch_1):page52_i138:vss(34)"
				( attribute "PN" "173"
					( Origin gPackager )
				)
				( objectStatus "J6L2.173" )
			)
			( pin "@baseboard_fab2_lib.baseboard_fab2(sch_1):page52_i138:vss(35)"
				( attribute "PN" "171"
					( Origin gPackager )
				)
				( objectStatus "J6L2.171" )
			)
			( pin "@baseboard_fab2_lib.baseboard_fab2(sch_1):page52_i138:vss(36)"
				( attribute "PN" "169"
					( Origin gPackager )
				)
				( objectStatus "J6L2.169" )
			)
			( pin "@baseboard_fab2_lib.baseboard_fab2(sch_1):page52_i138:vss(37)"
				( attribute "PN" "167"
					( Origin gPackager )
				)
				( objectStatus "J6L2.167" )
			)
			( pin "@baseboard_fab2_lib.baseboard_fab2(sch_1):page52_i138:vss(38)"
				( attribute "PN" "165"
					( Origin gPackager )
				)
				( objectStatus "J6L2.165" )
			)
			( pin "@baseboard_fab2_lib.baseboard_fab2(sch_1):page52_i138:vss(39)"
				( attribute "PN" "162"
					( Origin gPackager )
				)
				( objectStatus "J6L2.162" )
			)
			( pin "@baseboard_fab2_lib.baseboard_fab2(sch_1):page52_i138:vss(40)"
				( attribute "PN" "160"
					( Origin gPackager )
				)
				( objectStatus "J6L2.160" )
			)
			( pin "@baseboard_fab2_lib.baseboard_fab2(sch_1):page52_i138:vss(41)"
				( attribute "PN" "158"
					( Origin gPackager )
				)
				( objectStatus "J6L2.158" )
			)
			( pin "@baseboard_fab2_lib.baseboard_fab2(sch_1):page52_i138:vss(42)"
				( attribute "PN" "156"
					( Origin gPackager )
				)
				( objectStatus "J6L2.156" )
			)
			( pin "@baseboard_fab2_lib.baseboard_fab2(sch_1):page52_i138:vss(43)"
				( attribute "PN" "154"
					( Origin gPackager )
				)
				( objectStatus "J6L2.154" )
			)
			( pin "@baseboard_fab2_lib.baseboard_fab2(sch_1):page52_i138:vss(44)"
				( attribute "PN" "151"
					( Origin gPackager )
				)
				( objectStatus "J6L2.151" )
			)
			( pin "@baseboard_fab2_lib.baseboard_fab2(sch_1):page52_i138:vss(45)"
				( attribute "PN" "149"
					( Origin gPackager )
				)
				( objectStatus "J6L2.149" )
			)
			( pin "@baseboard_fab2_lib.baseboard_fab2(sch_1):page52_i138:vss(46)"
				( attribute "PN" "147"
					( Origin gPackager )
				)
				( objectStatus "J6L2.147" )
			)
			( pin "@baseboard_fab2_lib.baseboard_fab2(sch_1):page52_i138:vss(47)"
				( attribute "PN" "138"
					( Origin gPackager )
				)
				( objectStatus "J6L2.138" )
			)
			( pin "@baseboard_fab2_lib.baseboard_fab2(sch_1):page52_i138:vss(48)"
				( attribute "PN" "136"
					( Origin gPackager )
				)
				( objectStatus "J6L2.136" )
			)
			( pin "@baseboard_fab2_lib.baseboard_fab2(sch_1):page52_i138:vss(49)"
				( attribute "PN" "134"
					( Origin gPackager )
				)
				( objectStatus "J6L2.134" )
			)
			( pin "@baseboard_fab2_lib.baseboard_fab2(sch_1):page52_i138:vss(50)"
				( attribute "PN" "131"
					( Origin gPackager )
				)
				( objectStatus "J6L2.131" )
			)
			( pin "@baseboard_fab2_lib.baseboard_fab2(sch_1):page52_i138:vss(51)"
				( attribute "PN" "129"
					( Origin gPackager )
				)
				( objectStatus "J6L2.129" )
			)
			( pin "@baseboard_fab2_lib.baseboard_fab2(sch_1):page52_i138:vss(52)"
				( attribute "PN" "127"
					( Origin gPackager )
				)
				( objectStatus "J6L2.127" )
			)
			( pin "@baseboard_fab2_lib.baseboard_fab2(sch_1):page52_i138:vss(53)"
				( attribute "PN" "125"
					( Origin gPackager )
				)
				( objectStatus "J6L2.125" )
			)
			( pin "@baseboard_fab2_lib.baseboard_fab2(sch_1):page52_i138:vss(54)"
				( attribute "PN" "123"
					( Origin gPackager )
				)
				( objectStatus "J6L2.123" )
			)
			( pin "@baseboard_fab2_lib.baseboard_fab2(sch_1):page52_i138:vss(55)"
				( attribute "PN" "120"
					( Origin gPackager )
				)
				( objectStatus "J6L2.120" )
			)
			( pin "@baseboard_fab2_lib.baseboard_fab2(sch_1):page52_i138:vss(56)"
				( attribute "PN" "118"
					( Origin gPackager )
				)
				( objectStatus "J6L2.118" )
			)
			( pin "@baseboard_fab2_lib.baseboard_fab2(sch_1):page52_i138:vss(57)"
				( attribute "PN" "116"
					( Origin gPackager )
				)
				( objectStatus "J6L2.116" )
			)
			( pin "@baseboard_fab2_lib.baseboard_fab2(sch_1):page52_i138:vss(58)"
				( attribute "PN" "114"
					( Origin gPackager )
				)
				( objectStatus "J6L2.114" )
			)
			( pin "@baseboard_fab2_lib.baseboard_fab2(sch_1):page52_i138:vss(59)"
				( attribute "PN" "112"
					( Origin gPackager )
				)
				( objectStatus "J6L2.112" )
			)
			( pin "@baseboard_fab2_lib.baseboard_fab2(sch_1):page52_i138:vss(60)"
				( attribute "PN" "109"
					( Origin gPackager )
				)
				( objectStatus "J6L2.109" )
			)
			( pin "@baseboard_fab2_lib.baseboard_fab2(sch_1):page52_i138:vss(61)"
				( attribute "PN" "107"
					( Origin gPackager )
				)
				( objectStatus "J6L2.107" )
			)
			( pin "@baseboard_fab2_lib.baseboard_fab2(sch_1):page52_i138:vss(62)"
				( attribute "PN" "105"
					( Origin gPackager )
				)
				( objectStatus "J6L2.105" )
			)
			( pin "@baseboard_fab2_lib.baseboard_fab2(sch_1):page52_i138:vss(63)"
				( attribute "PN" "103"
					( Origin gPackager )
				)
				( objectStatus "J6L2.103" )
			)
			( pin "@baseboard_fab2_lib.baseboard_fab2(sch_1):page52_i138:vss(64)"
				( attribute "PN" "101"
					( Origin gPackager )
				)
				( objectStatus "J6L2.101" )
			)
			( pin "@baseboard_fab2_lib.baseboard_fab2(sch_1):page52_i138:vss(65)"
				( attribute "PN" "98"
					( Origin gPackager )
				)
				( objectStatus "J6L2.98" )
			)
			( pin "@baseboard_fab2_lib.baseboard_fab2(sch_1):page52_i138:vss(66)"
				( attribute "PN" "96"
					( Origin gPackager )
				)
				( objectStatus "J6L2.96" )
			)
			( pin "@baseboard_fab2_lib.baseboard_fab2(sch_1):page52_i138:vss(67)"
				( attribute "PN" "94"
					( Origin gPackager )
				)
				( objectStatus "J6L2.94" )
			)
			( pin "@baseboard_fab2_lib.baseboard_fab2(sch_1):page52_i138:vss(68)"
				( attribute "PN" "57"
					( Origin gPackager )
				)
				( objectStatus "J6L2.57" )
			)
			( pin "@baseboard_fab2_lib.baseboard_fab2(sch_1):page52_i138:vss(69)"
				( attribute "PN" "55"
					( Origin gPackager )
				)
				( objectStatus "J6L2.55" )
			)
			( pin "@baseboard_fab2_lib.baseboard_fab2(sch_1):page52_i138:vss(70)"
				( attribute "PN" "53"
					( Origin gPackager )
				)
				( objectStatus "J6L2.53" )
			)
			( pin "@baseboard_fab2_lib.baseboard_fab2(sch_1):page52_i138:vss(71)"
				( attribute "PN" "50"
					( Origin gPackager )
				)
				( objectStatus "J6L2.50" )
			)
			( pin "@baseboard_fab2_lib.baseboard_fab2(sch_1):page52_i138:vss(72)"
				( attribute "PN" "48"
					( Origin gPackager )
				)
				( objectStatus "J6L2.48" )
			)
			( pin "@baseboard_fab2_lib.baseboard_fab2(sch_1):page52_i138:vss(73)"
				( attribute "PN" "46"
					( Origin gPackager )
				)
				( objectStatus "J6L2.46" )
			)
			( pin "@baseboard_fab2_lib.baseboard_fab2(sch_1):page52_i138:vss(74)"
				( attribute "PN" "44"
					( Origin gPackager )
				)
				( objectStatus "J6L2.44" )
			)
			( pin "@baseboard_fab2_lib.baseboard_fab2(sch_1):page52_i138:vss(75)"
				( attribute "PN" "42"
					( Origin gPackager )
				)
				( objectStatus "J6L2.42" )
			)
			( pin "@baseboard_fab2_lib.baseboard_fab2(sch_1):page52_i138:vss(76)"
				( attribute "PN" "39"
					( Origin gPackager )
				)
				( objectStatus "J6L2.39" )
			)
			( pin "@baseboard_fab2_lib.baseboard_fab2(sch_1):page52_i138:vss(77)"
				( attribute "PN" "37"
					( Origin gPackager )
				)
				( objectStatus "J6L2.37" )
			)
			( pin "@baseboard_fab2_lib.baseboard_fab2(sch_1):page52_i138:vss(78)"
				( attribute "PN" "35"
					( Origin gPackager )
				)
				( objectStatus "J6L2.35" )
			)
			( pin "@baseboard_fab2_lib.baseboard_fab2(sch_1):page52_i138:vss(79)"
				( attribute "PN" "33"
					( Origin gPackager )
				)
				( objectStatus "J6L2.33" )
			)
			( pin "@baseboard_fab2_lib.baseboard_fab2(sch_1):page52_i138:vss(80)"
				( attribute "PN" "31"
					( Origin gPackager )
				)
				( objectStatus "J6L2.31" )
			)
			( pin "@baseboard_fab2_lib.baseboard_fab2(sch_1):page52_i138:vss(81)"
				( attribute "PN" "28"
					( Origin gPackager )
				)
				( objectStatus "J6L2.28" )
			)
			( pin "@baseboard_fab2_lib.baseboard_fab2(sch_1):page52_i138:vss(82)"
				( attribute "PN" "26"
					( Origin gPackager )
				)
				( objectStatus "J6L2.26" )
			)
			( pin "@baseboard_fab2_lib.baseboard_fab2(sch_1):page52_i138:vss(83)"
				( attribute "PN" "24"
					( Origin gPackager )
				)
				( objectStatus "J6L2.24" )
			)
			( pin "@baseboard_fab2_lib.baseboard_fab2(sch_1):page52_i138:vss(84)"
				( attribute "PN" "22"
					( Origin gPackager )
				)
				( objectStatus "J6L2.22" )
			)
			( pin "@baseboard_fab2_lib.baseboard_fab2(sch_1):page52_i138:vss(85)"
				( attribute "PN" "20"
					( Origin gPackager )
				)
				( objectStatus "J6L2.20" )
			)
			( pin "@baseboard_fab2_lib.baseboard_fab2(sch_1):page52_i138:vss(86)"
				( attribute "PN" "17"
					( Origin gPackager )
				)
				( objectStatus "J6L2.17" )
			)
			( pin "@baseboard_fab2_lib.baseboard_fab2(sch_1):page52_i138:vss(87)"
				( attribute "PN" "15"
					( Origin gPackager )
				)
				( objectStatus "J6L2.15" )
			)
			( pin "@baseboard_fab2_lib.baseboard_fab2(sch_1):page52_i138:vss(88)"
				( attribute "PN" "13"
					( Origin gPackager )
				)
				( objectStatus "J6L2.13" )
			)
			( pin "@baseboard_fab2_lib.baseboard_fab2(sch_1):page52_i138:vss(89)"
				( attribute "PN" "11"
					( Origin gPackager )
				)
				( objectStatus "J6L2.11" )
			)
			( pin "@baseboard_fab2_lib.baseboard_fab2(sch_1):page52_i138:vss(90)"
				( attribute "PN" "9"
					( Origin gPackager )
				)
				( objectStatus "J6L2.9" )
			)
			( pin "@baseboard_fab2_lib.baseboard_fab2(sch_1):page52_i138:vss(91)"
				( attribute "PN" "6"
					( Origin gPackager )
				)
				( objectStatus "J6L2.6" )
			)
			( pin "@baseboard_fab2_lib.baseboard_fab2(sch_1):page52_i138:vss(92)"
				( attribute "PN" "4"
					( Origin gPackager )
				)
				( objectStatus "J6L2.4" )
			)
			( pin "@baseboard_fab2_lib.baseboard_fab2(sch_1):page52_i138:vss(93)"
				( attribute "PN" "2"
					( Origin gPackager )
				)
				( objectStatus "J6L2.2" )
			)
			( pin "@baseboard_fab2_lib.baseboard_fab2(sch_1):page53_i43:vss(0)"
				( attribute "PN" "283"
					( Origin gPackager )
				)
				( objectStatus "J4A1.283" )
			)
			( pin "@baseboard_fab2_lib.baseboard_fab2(sch_1):page53_i43:vss(1)"
				( attribute "PN" "281"
					( Origin gPackager )
				)
				( objectStatus "J4A1.281" )
			)
			( pin "@baseboard_fab2_lib.baseboard_fab2(sch_1):page53_i43:vss(2)"
				( attribute "PN" "279"
					( Origin gPackager )
				)
				( objectStatus "J4A1.279" )
			)
			( pin "@baseboard_fab2_lib.baseboard_fab2(sch_1):page53_i43:vss(3)"
				( attribute "PN" "276"
					( Origin gPackager )
				)
				( objectStatus "J4A1.276" )
			)
			( pin "@baseboard_fab2_lib.baseboard_fab2(sch_1):page53_i43:vss(4)"
				( attribute "PN" "274"
					( Origin gPackager )
				)
				( objectStatus "J4A1.274" )
			)
			( pin "@baseboard_fab2_lib.baseboard_fab2(sch_1):page53_i43:vss(5)"
				( attribute "PN" "272"
					( Origin gPackager )
				)
				( objectStatus "J4A1.272" )
			)
			( pin "@baseboard_fab2_lib.baseboard_fab2(sch_1):page53_i43:vss(6)"
				( attribute "PN" "270"
					( Origin gPackager )
				)
				( objectStatus "J4A1.270" )
			)
			( pin "@baseboard_fab2_lib.baseboard_fab2(sch_1):page53_i43:vss(7)"
				( attribute "PN" "268"
					( Origin gPackager )
				)
				( objectStatus "J4A1.268" )
			)
			( pin "@baseboard_fab2_lib.baseboard_fab2(sch_1):page53_i43:vss(8)"
				( attribute "PN" "265"
					( Origin gPackager )
				)
				( objectStatus "J4A1.265" )
			)
			( pin "@baseboard_fab2_lib.baseboard_fab2(sch_1):page53_i43:vss(9)"
				( attribute "PN" "263"
					( Origin gPackager )
				)
				( objectStatus "J4A1.263" )
			)
			( pin "@baseboard_fab2_lib.baseboard_fab2(sch_1):page53_i43:vss(10)"
				( attribute "PN" "261"
					( Origin gPackager )
				)
				( objectStatus "J4A1.261" )
			)
			( pin "@baseboard_fab2_lib.baseboard_fab2(sch_1):page53_i43:vss(11)"
				( attribute "PN" "259"
					( Origin gPackager )
				)
				( objectStatus "J4A1.259" )
			)
			( pin "@baseboard_fab2_lib.baseboard_fab2(sch_1):page53_i43:vss(12)"
				( attribute "PN" "257"
					( Origin gPackager )
				)
				( objectStatus "J4A1.257" )
			)
			( pin "@baseboard_fab2_lib.baseboard_fab2(sch_1):page53_i43:vss(13)"
				( attribute "PN" "254"
					( Origin gPackager )
				)
				( objectStatus "J4A1.254" )
			)
			( pin "@baseboard_fab2_lib.baseboard_fab2(sch_1):page53_i43:vss(14)"
				( attribute "PN" "252"
					( Origin gPackager )
				)
				( objectStatus "J4A1.252" )
			)
			( pin "@baseboard_fab2_lib.baseboard_fab2(sch_1):page53_i43:vss(15)"
				( attribute "PN" "250"
					( Origin gPackager )
				)
				( objectStatus "J4A1.250" )
			)
			( pin "@baseboard_fab2_lib.baseboard_fab2(sch_1):page53_i43:vss(16)"
				( attribute "PN" "248"
					( Origin gPackager )
				)
				( objectStatus "J4A1.248" )
			)
			( pin "@baseboard_fab2_lib.baseboard_fab2(sch_1):page53_i43:vss(17)"
				( attribute "PN" "246"
					( Origin gPackager )
				)
				( objectStatus "J4A1.246" )
			)
			( pin "@baseboard_fab2_lib.baseboard_fab2(sch_1):page53_i43:vss(18)"
				( attribute "PN" "243"
					( Origin gPackager )
				)
				( objectStatus "J4A1.243" )
			)
			( pin "@baseboard_fab2_lib.baseboard_fab2(sch_1):page53_i43:vss(19)"
				( attribute "PN" "241"
					( Origin gPackager )
				)
				( objectStatus "J4A1.241" )
			)
			( pin "@baseboard_fab2_lib.baseboard_fab2(sch_1):page53_i43:vss(20)"
				( attribute "PN" "239"
					( Origin gPackager )
				)
				( objectStatus "J4A1.239" )
			)
			( pin "@baseboard_fab2_lib.baseboard_fab2(sch_1):page53_i43:vss(21)"
				( attribute "PN" "202"
					( Origin gPackager )
				)
				( objectStatus "J4A1.202" )
			)
			( pin "@baseboard_fab2_lib.baseboard_fab2(sch_1):page53_i43:vss(22)"
				( attribute "PN" "200"
					( Origin gPackager )
				)
				( objectStatus "J4A1.200" )
			)
			( pin "@baseboard_fab2_lib.baseboard_fab2(sch_1):page53_i43:vss(23)"
				( attribute "PN" "198"
					( Origin gPackager )
				)
				( objectStatus "J4A1.198" )
			)
			( pin "@baseboard_fab2_lib.baseboard_fab2(sch_1):page53_i43:vss(24)"
				( attribute "PN" "195"
					( Origin gPackager )
				)
				( objectStatus "J4A1.195" )
			)
			( pin "@baseboard_fab2_lib.baseboard_fab2(sch_1):page53_i43:vss(25)"
				( attribute "PN" "193"
					( Origin gPackager )
				)
				( objectStatus "J4A1.193" )
			)
			( pin "@baseboard_fab2_lib.baseboard_fab2(sch_1):page53_i43:vss(26)"
				( attribute "PN" "191"
					( Origin gPackager )
				)
				( objectStatus "J4A1.191" )
			)
			( pin "@baseboard_fab2_lib.baseboard_fab2(sch_1):page53_i43:vss(27)"
				( attribute "PN" "189"
					( Origin gPackager )
				)
				( objectStatus "J4A1.189" )
			)
			( pin "@baseboard_fab2_lib.baseboard_fab2(sch_1):page53_i43:vss(28)"
				( attribute "PN" "187"
					( Origin gPackager )
				)
				( objectStatus "J4A1.187" )
			)
			( pin "@baseboard_fab2_lib.baseboard_fab2(sch_1):page53_i43:vss(29)"
				( attribute "PN" "184"
					( Origin gPackager )
				)
				( objectStatus "J4A1.184" )
			)
			( pin "@baseboard_fab2_lib.baseboard_fab2(sch_1):page53_i43:vss(30)"
				( attribute "PN" "182"
					( Origin gPackager )
				)
				( objectStatus "J4A1.182" )
			)
			( pin "@baseboard_fab2_lib.baseboard_fab2(sch_1):page53_i43:vss(31)"
				( attribute "PN" "180"
					( Origin gPackager )
				)
				( objectStatus "J4A1.180" )
			)
			( pin "@baseboard_fab2_lib.baseboard_fab2(sch_1):page53_i43:vss(32)"
				( attribute "PN" "178"
					( Origin gPackager )
				)
				( objectStatus "J4A1.178" )
			)
			( pin "@baseboard_fab2_lib.baseboard_fab2(sch_1):page53_i43:vss(33)"
				( attribute "PN" "176"
					( Origin gPackager )
				)
				( objectStatus "J4A1.176" )
			)
			( pin "@baseboard_fab2_lib.baseboard_fab2(sch_1):page53_i43:vss(34)"
				( attribute "PN" "173"
					( Origin gPackager )
				)
				( objectStatus "J4A1.173" )
			)
			( pin "@baseboard_fab2_lib.baseboard_fab2(sch_1):page53_i43:vss(35)"
				( attribute "PN" "171"
					( Origin gPackager )
				)
				( objectStatus "J4A1.171" )
			)
			( pin "@baseboard_fab2_lib.baseboard_fab2(sch_1):page53_i43:vss(36)"
				( attribute "PN" "169"
					( Origin gPackager )
				)
				( objectStatus "J4A1.169" )
			)
			( pin "@baseboard_fab2_lib.baseboard_fab2(sch_1):page53_i43:vss(37)"
				( attribute "PN" "167"
					( Origin gPackager )
				)
				( objectStatus "J4A1.167" )
			)
			( pin "@baseboard_fab2_lib.baseboard_fab2(sch_1):page53_i43:vss(38)"
				( attribute "PN" "165"
					( Origin gPackager )
				)
				( objectStatus "J4A1.165" )
			)
			( pin "@baseboard_fab2_lib.baseboard_fab2(sch_1):page53_i43:vss(39)"
				( attribute "PN" "162"
					( Origin gPackager )
				)
				( objectStatus "J4A1.162" )
			)
			( pin "@baseboard_fab2_lib.baseboard_fab2(sch_1):page53_i43:vss(40)"
				( attribute "PN" "160"
					( Origin gPackager )
				)
				( objectStatus "J4A1.160" )
			)
			( pin "@baseboard_fab2_lib.baseboard_fab2(sch_1):page53_i43:vss(41)"
				( attribute "PN" "158"
					( Origin gPackager )
				)
				( objectStatus "J4A1.158" )
			)
			( pin "@baseboard_fab2_lib.baseboard_fab2(sch_1):page53_i43:vss(42)"
				( attribute "PN" "156"
					( Origin gPackager )
				)
				( objectStatus "J4A1.156" )
			)
			( pin "@baseboard_fab2_lib.baseboard_fab2(sch_1):page53_i43:vss(43)"
				( attribute "PN" "154"
					( Origin gPackager )
				)
				( objectStatus "J4A1.154" )
			)
			( pin "@baseboard_fab2_lib.baseboard_fab2(sch_1):page53_i43:vss(44)"
				( attribute "PN" "151"
					( Origin gPackager )
				)
				( objectStatus "J4A1.151" )
			)
			( pin "@baseboard_fab2_lib.baseboard_fab2(sch_1):page53_i43:vss(45)"
				( attribute "PN" "149"
					( Origin gPackager )
				)
				( objectStatus "J4A1.149" )
			)
			( pin "@baseboard_fab2_lib.baseboard_fab2(sch_1):page53_i43:vss(46)"
				( attribute "PN" "147"
					( Origin gPackager )
				)
				( objectStatus "J4A1.147" )
			)
			( pin "@baseboard_fab2_lib.baseboard_fab2(sch_1):page53_i43:vss(47)"
				( attribute "PN" "138"
					( Origin gPackager )
				)
				( objectStatus "J4A1.138" )
			)
			( pin "@baseboard_fab2_lib.baseboard_fab2(sch_1):page53_i43:vss(48)"
				( attribute "PN" "136"
					( Origin gPackager )
				)
				( objectStatus "J4A1.136" )
			)
			( pin "@baseboard_fab2_lib.baseboard_fab2(sch_1):page53_i43:vss(49)"
				( attribute "PN" "134"
					( Origin gPackager )
				)
				( objectStatus "J4A1.134" )
			)
			( pin "@baseboard_fab2_lib.baseboard_fab2(sch_1):page53_i43:vss(50)"
				( attribute "PN" "131"
					( Origin gPackager )
				)
				( objectStatus "J4A1.131" )
			)
			( pin "@baseboard_fab2_lib.baseboard_fab2(sch_1):page53_i43:vss(51)"
				( attribute "PN" "129"
					( Origin gPackager )
				)
				( objectStatus "J4A1.129" )
			)
			( pin "@baseboard_fab2_lib.baseboard_fab2(sch_1):page53_i43:vss(52)"
				( attribute "PN" "127"
					( Origin gPackager )
				)
				( objectStatus "J4A1.127" )
			)
			( pin "@baseboard_fab2_lib.baseboard_fab2(sch_1):page53_i43:vss(53)"
				( attribute "PN" "125"
					( Origin gPackager )
				)
				( objectStatus "J4A1.125" )
			)
			( pin "@baseboard_fab2_lib.baseboard_fab2(sch_1):page53_i43:vss(54)"
				( attribute "PN" "123"
					( Origin gPackager )
				)
				( objectStatus "J4A1.123" )
			)
			( pin "@baseboard_fab2_lib.baseboard_fab2(sch_1):page53_i43:vss(55)"
				( attribute "PN" "120"
					( Origin gPackager )
				)
				( objectStatus "J4A1.120" )
			)
			( pin "@baseboard_fab2_lib.baseboard_fab2(sch_1):page53_i43:vss(56)"
				( attribute "PN" "118"
					( Origin gPackager )
				)
				( objectStatus "J4A1.118" )
			)
			( pin "@baseboard_fab2_lib.baseboard_fab2(sch_1):page53_i43:vss(57)"
				( attribute "PN" "116"
					( Origin gPackager )
				)
				( objectStatus "J4A1.116" )
			)
			( pin "@baseboard_fab2_lib.baseboard_fab2(sch_1):page53_i43:vss(58)"
				( attribute "PN" "114"
					( Origin gPackager )
				)
				( objectStatus "J4A1.114" )
			)
			( pin "@baseboard_fab2_lib.baseboard_fab2(sch_1):page53_i43:vss(59)"
				( attribute "PN" "112"
					( Origin gPackager )
				)
				( objectStatus "J4A1.112" )
			)
			( pin "@baseboard_fab2_lib.baseboard_fab2(sch_1):page53_i43:vss(60)"
				( attribute "PN" "109"
					( Origin gPackager )
				)
				( objectStatus "J4A1.109" )
			)
			( pin "@baseboard_fab2_lib.baseboard_fab2(sch_1):page53_i43:vss(61)"
				( attribute "PN" "107"
					( Origin gPackager )
				)
				( objectStatus "J4A1.107" )
			)
			( pin "@baseboard_fab2_lib.baseboard_fab2(sch_1):page53_i43:vss(62)"
				( attribute "PN" "105"
					( Origin gPackager )
				)
				( objectStatus "J4A1.105" )
			)
			( pin "@baseboard_fab2_lib.baseboard_fab2(sch_1):page53_i43:vss(63)"
				( attribute "PN" "103"
					( Origin gPackager )
				)
				( objectStatus "J4A1.103" )
			)
			( pin "@baseboard_fab2_lib.baseboard_fab2(sch_1):page53_i43:vss(64)"
				( attribute "PN" "101"
					( Origin gPackager )
				)
				( objectStatus "J4A1.101" )
			)
			( pin "@baseboard_fab2_lib.baseboard_fab2(sch_1):page53_i43:vss(65)"
				( attribute "PN" "98"
					( Origin gPackager )
				)
				( objectStatus "J4A1.98" )
			)
			( pin "@baseboard_fab2_lib.baseboard_fab2(sch_1):page53_i43:vss(66)"
				( attribute "PN" "96"
					( Origin gPackager )
				)
				( objectStatus "J4A1.96" )
			)
			( pin "@baseboard_fab2_lib.baseboard_fab2(sch_1):page53_i43:vss(67)"
				( attribute "PN" "94"
					( Origin gPackager )
				)
				( objectStatus "J4A1.94" )
			)
			( pin "@baseboard_fab2_lib.baseboard_fab2(sch_1):page53_i43:vss(68)"
				( attribute "PN" "57"
					( Origin gPackager )
				)
				( objectStatus "J4A1.57" )
			)
			( pin "@baseboard_fab2_lib.baseboard_fab2(sch_1):page53_i43:vss(69)"
				( attribute "PN" "55"
					( Origin gPackager )
				)
				( objectStatus "J4A1.55" )
			)
			( pin "@baseboard_fab2_lib.baseboard_fab2(sch_1):page53_i43:vss(70)"
				( attribute "PN" "53"
					( Origin gPackager )
				)
				( objectStatus "J4A1.53" )
			)
			( pin "@baseboard_fab2_lib.baseboard_fab2(sch_1):page53_i43:vss(71)"
				( attribute "PN" "50"
					( Origin gPackager )
				)
				( objectStatus "J4A1.50" )
			)
			( pin "@baseboard_fab2_lib.baseboard_fab2(sch_1):page53_i43:vss(72)"
				( attribute "PN" "48"
					( Origin gPackager )
				)
				( objectStatus "J4A1.48" )
			)
			( pin "@baseboard_fab2_lib.baseboard_fab2(sch_1):page53_i43:vss(73)"
				( attribute "PN" "46"
					( Origin gPackager )
				)
				( objectStatus "J4A1.46" )
			)
			( pin "@baseboard_fab2_lib.baseboard_fab2(sch_1):page53_i43:vss(74)"
				( attribute "PN" "44"
					( Origin gPackager )
				)
				( objectStatus "J4A1.44" )
			)
			( pin "@baseboard_fab2_lib.baseboard_fab2(sch_1):page53_i43:vss(75)"
				( attribute "PN" "42"
					( Origin gPackager )
				)
				( objectStatus "J4A1.42" )
			)
			( pin "@baseboard_fab2_lib.baseboard_fab2(sch_1):page53_i43:vss(76)"
				( attribute "PN" "39"
					( Origin gPackager )
				)
				( objectStatus "J4A1.39" )
			)
			( pin "@baseboard_fab2_lib.baseboard_fab2(sch_1):page53_i43:vss(77)"
				( attribute "PN" "37"
					( Origin gPackager )
				)
				( objectStatus "J4A1.37" )
			)
			( pin "@baseboard_fab2_lib.baseboard_fab2(sch_1):page53_i43:vss(78)"
				( attribute "PN" "35"
					( Origin gPackager )
				)
				( objectStatus "J4A1.35" )
			)
			( pin "@baseboard_fab2_lib.baseboard_fab2(sch_1):page53_i43:vss(79)"
				( attribute "PN" "33"
					( Origin gPackager )
				)
				( objectStatus "J4A1.33" )
			)
			( pin "@baseboard_fab2_lib.baseboard_fab2(sch_1):page53_i43:vss(80)"
				( attribute "PN" "31"
					( Origin gPackager )
				)
				( objectStatus "J4A1.31" )
			)
			( pin "@baseboard_fab2_lib.baseboard_fab2(sch_1):page53_i43:vss(81)"
				( attribute "PN" "28"
					( Origin gPackager )
				)
				( objectStatus "J4A1.28" )
			)
			( pin "@baseboard_fab2_lib.baseboard_fab2(sch_1):page53_i43:vss(82)"
				( attribute "PN" "26"
					( Origin gPackager )
				)
				( objectStatus "J4A1.26" )
			)
			( pin "@baseboard_fab2_lib.baseboard_fab2(sch_1):page53_i43:vss(83)"
				( attribute "PN" "24"
					( Origin gPackager )
				)
				( objectStatus "J4A1.24" )
			)
			( pin "@baseboard_fab2_lib.baseboard_fab2(sch_1):page53_i43:vss(84)"
				( attribute "PN" "22"
					( Origin gPackager )
				)
				( objectStatus "J4A1.22" )
			)
			( pin "@baseboard_fab2_lib.baseboard_fab2(sch_1):page53_i43:vss(85)"
				( attribute "PN" "20"
					( Origin gPackager )
				)
				( objectStatus "J4A1.20" )
			)
			( pin "@baseboard_fab2_lib.baseboard_fab2(sch_1):page53_i43:vss(86)"
				( attribute "PN" "17"
					( Origin gPackager )
				)
				( objectStatus "J4A1.17" )
			)
			( pin "@baseboard_fab2_lib.baseboard_fab2(sch_1):page53_i43:vss(87)"
				( attribute "PN" "15"
					( Origin gPackager )
				)
				( objectStatus "J4A1.15" )
			)
			( pin "@baseboard_fab2_lib.baseboard_fab2(sch_1):page53_i43:vss(88)"
				( attribute "PN" "13"
					( Origin gPackager )
				)
				( objectStatus "J4A1.13" )
			)
			( pin "@baseboard_fab2_lib.baseboard_fab2(sch_1):page53_i43:vss(89)"
				( attribute "PN" "11"
					( Origin gPackager )
				)
				( objectStatus "J4A1.11" )
			)
			( pin "@baseboard_fab2_lib.baseboard_fab2(sch_1):page53_i43:vss(90)"
				( attribute "PN" "9"
					( Origin gPackager )
				)
				( objectStatus "J4A1.9" )
			)
			( pin "@baseboard_fab2_lib.baseboard_fab2(sch_1):page53_i43:vss(91)"
				( attribute "PN" "6"
					( Origin gPackager )
				)
				( objectStatus "J4A1.6" )
			)
			( pin "@baseboard_fab2_lib.baseboard_fab2(sch_1):page53_i43:vss(92)"
				( attribute "PN" "4"
					( Origin gPackager )
				)
				( objectStatus "J4A1.4" )
			)
			( pin "@baseboard_fab2_lib.baseboard_fab2(sch_1):page53_i43:vss(93)"
				( attribute "PN" "2"
					( Origin gPackager )
				)
				( objectStatus "J4A1.2" )
			)
			( pin "@baseboard_fab2_lib.baseboard_fab2(sch_1):page53_i66:dqs0n"
				( attribute "PN" "152"
					( Origin gPackager )
				)
				( objectStatus "J4A1.152" )
			)
			( pin "@baseboard_fab2_lib.baseboard_fab2(sch_1):page53_i66:dqs0p"
				( attribute "PN" "153"
					( Origin gPackager )
				)
				( objectStatus "J4A1.153" )
			)
			( pin "@baseboard_fab2_lib.baseboard_fab2(sch_1):page53_i66:dqs1n"
				( attribute "PN" "163"
					( Origin gPackager )
				)
				( objectStatus "J4A1.163" )
			)
			( pin "@baseboard_fab2_lib.baseboard_fab2(sch_1):page53_i66:dqs1p"
				( attribute "PN" "164"
					( Origin gPackager )
				)
				( objectStatus "J4A1.164" )
			)
			( pin "@baseboard_fab2_lib.baseboard_fab2(sch_1):page53_i66:dqs2n"
				( attribute "PN" "174"
					( Origin gPackager )
				)
				( objectStatus "J4A1.174" )
			)
			( pin "@baseboard_fab2_lib.baseboard_fab2(sch_1):page53_i66:dqs2p"
				( attribute "PN" "175"
					( Origin gPackager )
				)
				( objectStatus "J4A1.175" )
			)
			( pin "@baseboard_fab2_lib.baseboard_fab2(sch_1):page53_i66:dqs3n"
				( attribute "PN" "185"
					( Origin gPackager )
				)
				( objectStatus "J4A1.185" )
			)
			( pin "@baseboard_fab2_lib.baseboard_fab2(sch_1):page53_i66:dqs3p"
				( attribute "PN" "186"
					( Origin gPackager )
				)
				( objectStatus "J4A1.186" )
			)
			( pin "@baseboard_fab2_lib.baseboard_fab2(sch_1):page53_i66:dqs4n"
				( attribute "PN" "244"
					( Origin gPackager )
				)
				( objectStatus "J4A1.244" )
			)
			( pin "@baseboard_fab2_lib.baseboard_fab2(sch_1):page53_i66:dqs4p"
				( attribute "PN" "245"
					( Origin gPackager )
				)
				( objectStatus "J4A1.245" )
			)
			( pin "@baseboard_fab2_lib.baseboard_fab2(sch_1):page53_i66:dqs5n"
				( attribute "PN" "255"
					( Origin gPackager )
				)
				( objectStatus "J4A1.255" )
			)
			( pin "@baseboard_fab2_lib.baseboard_fab2(sch_1):page53_i66:dqs5p"
				( attribute "PN" "256"
					( Origin gPackager )
				)
				( objectStatus "J4A1.256" )
			)
			( pin "@baseboard_fab2_lib.baseboard_fab2(sch_1):page53_i66:dqs6n"
				( attribute "PN" "266"
					( Origin gPackager )
				)
				( objectStatus "J4A1.266" )
			)
			( pin "@baseboard_fab2_lib.baseboard_fab2(sch_1):page53_i66:dqs6p"
				( attribute "PN" "267"
					( Origin gPackager )
				)
				( objectStatus "J4A1.267" )
			)
			( pin "@baseboard_fab2_lib.baseboard_fab2(sch_1):page53_i66:dqs7n"
				( attribute "PN" "277"
					( Origin gPackager )
				)
				( objectStatus "J4A1.277" )
			)
			( pin "@baseboard_fab2_lib.baseboard_fab2(sch_1):page53_i66:dqs7p"
				( attribute "PN" "278"
					( Origin gPackager )
				)
				( objectStatus "J4A1.278" )
			)
			( pin "@baseboard_fab2_lib.baseboard_fab2(sch_1):page53_i66:dqs8n"
				( attribute "PN" "196"
					( Origin gPackager )
				)
				( objectStatus "J4A1.196" )
			)
			( pin "@baseboard_fab2_lib.baseboard_fab2(sch_1):page53_i66:dqs8p"
				( attribute "PN" "197"
					( Origin gPackager )
				)
				( objectStatus "J4A1.197" )
			)
			( pin "@baseboard_fab2_lib.baseboard_fab2(sch_1):page53_i66:dqs9n"
				( attribute "PN" "8"
					( Origin gPackager )
				)
				( objectStatus "J4A1.8" )
			)
			( pin "@baseboard_fab2_lib.baseboard_fab2(sch_1):page53_i66:dqs9p"
				( attribute "PN" "7"
					( Origin gPackager )
				)
				( objectStatus "J4A1.7" )
			)
			( pin "@baseboard_fab2_lib.baseboard_fab2(sch_1):page53_i66:dqs10n"
				( attribute "PN" "19"
					( Origin gPackager )
				)
				( objectStatus "J4A1.19" )
			)
			( pin "@baseboard_fab2_lib.baseboard_fab2(sch_1):page53_i66:dqs10p"
				( attribute "PN" "18"
					( Origin gPackager )
				)
				( objectStatus "J4A1.18" )
			)
			( pin "@baseboard_fab2_lib.baseboard_fab2(sch_1):page53_i66:dqs11n"
				( attribute "PN" "30"
					( Origin gPackager )
				)
				( objectStatus "J4A1.30" )
			)
			( pin "@baseboard_fab2_lib.baseboard_fab2(sch_1):page53_i66:dqs11p"
				( attribute "PN" "29"
					( Origin gPackager )
				)
				( objectStatus "J4A1.29" )
			)
			( pin "@baseboard_fab2_lib.baseboard_fab2(sch_1):page53_i66:dqs12n"
				( attribute "PN" "41"
					( Origin gPackager )
				)
				( objectStatus "J4A1.41" )
			)
			( pin "@baseboard_fab2_lib.baseboard_fab2(sch_1):page53_i66:dqs12p"
				( attribute "PN" "40"
					( Origin gPackager )
				)
				( objectStatus "J4A1.40" )
			)
			( pin "@baseboard_fab2_lib.baseboard_fab2(sch_1):page53_i66:dqs13n"
				( attribute "PN" "100"
					( Origin gPackager )
				)
				( objectStatus "J4A1.100" )
			)
			( pin "@baseboard_fab2_lib.baseboard_fab2(sch_1):page53_i66:dqs13p"
				( attribute "PN" "99"
					( Origin gPackager )
				)
				( objectStatus "J4A1.99" )
			)
			( pin "@baseboard_fab2_lib.baseboard_fab2(sch_1):page53_i66:dqs14n"
				( attribute "PN" "111"
					( Origin gPackager )
				)
				( objectStatus "J4A1.111" )
			)
			( pin "@baseboard_fab2_lib.baseboard_fab2(sch_1):page53_i66:dqs14p"
				( attribute "PN" "110"
					( Origin gPackager )
				)
				( objectStatus "J4A1.110" )
			)
			( pin "@baseboard_fab2_lib.baseboard_fab2(sch_1):page53_i66:dqs15n"
				( attribute "PN" "122"
					( Origin gPackager )
				)
				( objectStatus "J4A1.122" )
			)
			( pin "@baseboard_fab2_lib.baseboard_fab2(sch_1):page53_i66:dqs15p"
				( attribute "PN" "121"
					( Origin gPackager )
				)
				( objectStatus "J4A1.121" )
			)
			( pin "@baseboard_fab2_lib.baseboard_fab2(sch_1):page53_i66:dqs16n"
				( attribute "PN" "133"
					( Origin gPackager )
				)
				( objectStatus "J4A1.133" )
			)
			( pin "@baseboard_fab2_lib.baseboard_fab2(sch_1):page53_i66:dqs16p"
				( attribute "PN" "132"
					( Origin gPackager )
				)
				( objectStatus "J4A1.132" )
			)
			( pin "@baseboard_fab2_lib.baseboard_fab2(sch_1):page53_i66:dqs17n"
				( attribute "PN" "52"
					( Origin gPackager )
				)
				( objectStatus "J4A1.52" )
			)
			( pin "@baseboard_fab2_lib.baseboard_fab2(sch_1):page53_i66:dqs17p"
				( attribute "PN" "51"
					( Origin gPackager )
				)
				( objectStatus "J4A1.51" )
			)
			( pin "@baseboard_fab2_lib.baseboard_fab2(sch_1):page53_i111:a0"
				( attribute "PN" "79"
					( Origin gPackager )
				)
				( objectStatus "J4A1.79" )
			)
			( pin "@baseboard_fab2_lib.baseboard_fab2(sch_1):page53_i111:a1"
				( attribute "PN" "72"
					( Origin gPackager )
				)
				( objectStatus "J4A1.72" )
			)
			( pin "@baseboard_fab2_lib.baseboard_fab2(sch_1):page53_i111:a2"
				( attribute "PN" "216"
					( Origin gPackager )
				)
				( objectStatus "J4A1.216" )
			)
			( pin "@baseboard_fab2_lib.baseboard_fab2(sch_1):page53_i111:a3"
				( attribute "PN" "71"
					( Origin gPackager )
				)
				( objectStatus "J4A1.71" )
			)
			( pin "@baseboard_fab2_lib.baseboard_fab2(sch_1):page53_i111:a4"
				( attribute "PN" "214"
					( Origin gPackager )
				)
				( objectStatus "J4A1.214" )
			)
			( pin "@baseboard_fab2_lib.baseboard_fab2(sch_1):page53_i111:a5"
				( attribute "PN" "213"
					( Origin gPackager )
				)
				( objectStatus "J4A1.213" )
			)
			( pin "@baseboard_fab2_lib.baseboard_fab2(sch_1):page53_i111:a6"
				( attribute "PN" "69"
					( Origin gPackager )
				)
				( objectStatus "J4A1.69" )
			)
			( pin "@baseboard_fab2_lib.baseboard_fab2(sch_1):page53_i111:a7"
				( attribute "PN" "211"
					( Origin gPackager )
				)
				( objectStatus "J4A1.211" )
			)
			( pin "@baseboard_fab2_lib.baseboard_fab2(sch_1):page53_i111:a8"
				( attribute "PN" "68"
					( Origin gPackager )
				)
				( objectStatus "J4A1.68" )
			)
			( pin "@baseboard_fab2_lib.baseboard_fab2(sch_1):page53_i111:a9"
				( attribute "PN" "66"
					( Origin gPackager )
				)
				( objectStatus "J4A1.66" )
			)
			( pin "@baseboard_fab2_lib.baseboard_fab2(sch_1):page53_i111:a10"
				( attribute "PN" "225"
					( Origin gPackager )
				)
				( objectStatus "J4A1.225" )
			)
			( pin "@baseboard_fab2_lib.baseboard_fab2(sch_1):page53_i111:a11"
				( attribute "PN" "210"
					( Origin gPackager )
				)
				( objectStatus "J4A1.210" )
			)
			( pin "@baseboard_fab2_lib.baseboard_fab2(sch_1):page53_i111:a12"
				( attribute "PN" "65"
					( Origin gPackager )
				)
				( objectStatus "J4A1.65" )
			)
			( pin "@baseboard_fab2_lib.baseboard_fab2(sch_1):page53_i111:a13"
				( attribute "PN" "232"
					( Origin gPackager )
				)
				( objectStatus "J4A1.232" )
			)
			( pin "@baseboard_fab2_lib.baseboard_fab2(sch_1):page53_i111:a14_we_n"
				( attribute "PN" "228"
					( Origin gPackager )
				)
				( objectStatus "J4A1.228" )
			)
			( pin "@baseboard_fab2_lib.baseboard_fab2(sch_1):page53_i111:a15_cas_n"
				( attribute "PN" "86"
					( Origin gPackager )
				)
				( objectStatus "J4A1.86" )
			)
			( pin "@baseboard_fab2_lib.baseboard_fab2(sch_1):page53_i111:a16_ras_n"
				( attribute "PN" "82"
					( Origin gPackager )
				)
				( objectStatus "J4A1.82" )
			)
			( pin "@baseboard_fab2_lib.baseboard_fab2(sch_1):page53_i111:a17"
				( attribute "PN" "234"
					( Origin gPackager )
				)
				( objectStatus "J4A1.234" )
			)
			( pin "@baseboard_fab2_lib.baseboard_fab2(sch_1):page53_i111:act_n"
				( attribute "PN" "62"
					( Origin gPackager )
				)
				( objectStatus "J4A1.62" )
			)
			( pin "@baseboard_fab2_lib.baseboard_fab2(sch_1):page53_i111:alert_n"
				( attribute "PN" "208"
					( Origin gPackager )
				)
				( objectStatus "J4A1.208" )
			)
			( pin "@baseboard_fab2_lib.baseboard_fab2(sch_1):page53_i111:ba(0)"
				( attribute "PN" "81"
					( Origin gPackager )
				)
				( objectStatus "J4A1.81" )
			)
			( pin "@baseboard_fab2_lib.baseboard_fab2(sch_1):page53_i111:ba(1)"
				( attribute "PN" "224"
					( Origin gPackager )
				)
				( objectStatus "J4A1.224" )
			)
			( pin "@baseboard_fab2_lib.baseboard_fab2(sch_1):page53_i111:bg(0)"
				( attribute "PN" "63"
					( Origin gPackager )
				)
				( objectStatus "J4A1.63" )
			)
			( pin "@baseboard_fab2_lib.baseboard_fab2(sch_1):page53_i111:bg(1)"
				( attribute "PN" "207"
					( Origin gPackager )
				)
				( objectStatus "J4A1.207" )
			)
			( pin "@baseboard_fab2_lib.baseboard_fab2(sch_1):page53_i111:c(2)"
				( attribute "PN" "235"
					( Origin gPackager )
				)
				( objectStatus "J4A1.235" )
			)
			( pin "@baseboard_fab2_lib.baseboard_fab2(sch_1):page53_i111:cb(0)"
				( attribute "PN" "49"
					( Origin gPackager )
				)
				( objectStatus "J4A1.49" )
			)
			( pin "@baseboard_fab2_lib.baseboard_fab2(sch_1):page53_i111:cb(1)"
				( attribute "PN" "194"
					( Origin gPackager )
				)
				( objectStatus "J4A1.194" )
			)
			( pin "@baseboard_fab2_lib.baseboard_fab2(sch_1):page53_i111:cb(2)"
				( attribute "PN" "56"
					( Origin gPackager )
				)
				( objectStatus "J4A1.56" )
			)
			( pin "@baseboard_fab2_lib.baseboard_fab2(sch_1):page53_i111:cb(3)"
				( attribute "PN" "201"
					( Origin gPackager )
				)
				( objectStatus "J4A1.201" )
			)
			( pin "@baseboard_fab2_lib.baseboard_fab2(sch_1):page53_i111:cb(4)"
				( attribute "PN" "47"
					( Origin gPackager )
				)
				( objectStatus "J4A1.47" )
			)
			( pin "@baseboard_fab2_lib.baseboard_fab2(sch_1):page53_i111:cb(5)"
				( attribute "PN" "192"
					( Origin gPackager )
				)
				( objectStatus "J4A1.192" )
			)
			( pin "@baseboard_fab2_lib.baseboard_fab2(sch_1):page53_i111:cb(6)"
				( attribute "PN" "54"
					( Origin gPackager )
				)
				( objectStatus "J4A1.54" )
			)
			( pin "@baseboard_fab2_lib.baseboard_fab2(sch_1):page53_i111:cb(7)"
				( attribute "PN" "199"
					( Origin gPackager )
				)
				( objectStatus "J4A1.199" )
			)
			( pin "@baseboard_fab2_lib.baseboard_fab2(sch_1):page53_i111:ck0n"
				( attribute "PN" "75"
					( Origin gPackager )
				)
				( objectStatus "J4A1.75" )
			)
			( pin "@baseboard_fab2_lib.baseboard_fab2(sch_1):page53_i111:ck0p"
				( attribute "PN" "74"
					( Origin gPackager )
				)
				( objectStatus "J4A1.74" )
			)
			( pin "@baseboard_fab2_lib.baseboard_fab2(sch_1):page53_i111:ck1n"
				( attribute "PN" "219"
					( Origin gPackager )
				)
				( objectStatus "J4A1.219" )
			)
			( pin "@baseboard_fab2_lib.baseboard_fab2(sch_1):page53_i111:ck1p"
				( attribute "PN" "218"
					( Origin gPackager )
				)
				( objectStatus "J4A1.218" )
			)
			( pin "@baseboard_fab2_lib.baseboard_fab2(sch_1):page53_i111:cke(0)"
				( attribute "PN" "60"
					( Origin gPackager )
				)
				( objectStatus "J4A1.60" )
			)
			( pin "@baseboard_fab2_lib.baseboard_fab2(sch_1):page53_i111:cke(1)"
				( attribute "PN" "203"
					( Origin gPackager )
				)
				( objectStatus "J4A1.203" )
			)
			( pin "@baseboard_fab2_lib.baseboard_fab2(sch_1):page53_i111:dq(0)"
				( attribute "PN" "5"
					( Origin gPackager )
				)
				( objectStatus "J4A1.5" )
			)
			( pin "@baseboard_fab2_lib.baseboard_fab2(sch_1):page53_i111:dq(1)"
				( attribute "PN" "150"
					( Origin gPackager )
				)
				( objectStatus "J4A1.150" )
			)
			( pin "@baseboard_fab2_lib.baseboard_fab2(sch_1):page53_i111:dq(2)"
				( attribute "PN" "12"
					( Origin gPackager )
				)
				( objectStatus "J4A1.12" )
			)
			( pin "@baseboard_fab2_lib.baseboard_fab2(sch_1):page53_i111:dq(3)"
				( attribute "PN" "157"
					( Origin gPackager )
				)
				( objectStatus "J4A1.157" )
			)
			( pin "@baseboard_fab2_lib.baseboard_fab2(sch_1):page53_i111:dq(4)"
				( attribute "PN" "3"
					( Origin gPackager )
				)
				( objectStatus "J4A1.3" )
			)
			( pin "@baseboard_fab2_lib.baseboard_fab2(sch_1):page53_i111:dq(5)"
				( attribute "PN" "148"
					( Origin gPackager )
				)
				( objectStatus "J4A1.148" )
			)
			( pin "@baseboard_fab2_lib.baseboard_fab2(sch_1):page53_i111:dq(6)"
				( attribute "PN" "10"
					( Origin gPackager )
				)
				( objectStatus "J4A1.10" )
			)
			( pin "@baseboard_fab2_lib.baseboard_fab2(sch_1):page53_i111:dq(7)"
				( attribute "PN" "155"
					( Origin gPackager )
				)
				( objectStatus "J4A1.155" )
			)
			( pin "@baseboard_fab2_lib.baseboard_fab2(sch_1):page53_i111:dq(8)"
				( attribute "PN" "16"
					( Origin gPackager )
				)
				( objectStatus "J4A1.16" )
			)
			( pin "@baseboard_fab2_lib.baseboard_fab2(sch_1):page53_i111:dq(9)"
				( attribute "PN" "161"
					( Origin gPackager )
				)
				( objectStatus "J4A1.161" )
			)
			( pin "@baseboard_fab2_lib.baseboard_fab2(sch_1):page53_i111:dq(10)"
				( attribute "PN" "23"
					( Origin gPackager )
				)
				( objectStatus "J4A1.23" )
			)
			( pin "@baseboard_fab2_lib.baseboard_fab2(sch_1):page53_i111:dq(11)"
				( attribute "PN" "168"
					( Origin gPackager )
				)
				( objectStatus "J4A1.168" )
			)
			( pin "@baseboard_fab2_lib.baseboard_fab2(sch_1):page53_i111:dq(12)"
				( attribute "PN" "14"
					( Origin gPackager )
				)
				( objectStatus "J4A1.14" )
			)
			( pin "@baseboard_fab2_lib.baseboard_fab2(sch_1):page53_i111:dq(13)"
				( attribute "PN" "159"
					( Origin gPackager )
				)
				( objectStatus "J4A1.159" )
			)
			( pin "@baseboard_fab2_lib.baseboard_fab2(sch_1):page53_i111:dq(14)"
				( attribute "PN" "21"
					( Origin gPackager )
				)
				( objectStatus "J4A1.21" )
			)
			( pin "@baseboard_fab2_lib.baseboard_fab2(sch_1):page53_i111:dq(15)"
				( attribute "PN" "166"
					( Origin gPackager )
				)
				( objectStatus "J4A1.166" )
			)
			( pin "@baseboard_fab2_lib.baseboard_fab2(sch_1):page53_i111:dq(16)"
				( attribute "PN" "27"
					( Origin gPackager )
				)
				( objectStatus "J4A1.27" )
			)
			( pin "@baseboard_fab2_lib.baseboard_fab2(sch_1):page53_i111:dq(17)"
				( attribute "PN" "172"
					( Origin gPackager )
				)
				( objectStatus "J4A1.172" )
			)
			( pin "@baseboard_fab2_lib.baseboard_fab2(sch_1):page53_i111:dq(18)"
				( attribute "PN" "34"
					( Origin gPackager )
				)
				( objectStatus "J4A1.34" )
			)
			( pin "@baseboard_fab2_lib.baseboard_fab2(sch_1):page53_i111:dq(19)"
				( attribute "PN" "179"
					( Origin gPackager )
				)
				( objectStatus "J4A1.179" )
			)
			( pin "@baseboard_fab2_lib.baseboard_fab2(sch_1):page53_i111:dq(20)"
				( attribute "PN" "25"
					( Origin gPackager )
				)
				( objectStatus "J4A1.25" )
			)
			( pin "@baseboard_fab2_lib.baseboard_fab2(sch_1):page53_i111:dq(21)"
				( attribute "PN" "170"
					( Origin gPackager )
				)
				( objectStatus "J4A1.170" )
			)
			( pin "@baseboard_fab2_lib.baseboard_fab2(sch_1):page53_i111:dq(22)"
				( attribute "PN" "32"
					( Origin gPackager )
				)
				( objectStatus "J4A1.32" )
			)
			( pin "@baseboard_fab2_lib.baseboard_fab2(sch_1):page53_i111:dq(23)"
				( attribute "PN" "177"
					( Origin gPackager )
				)
				( objectStatus "J4A1.177" )
			)
			( pin "@baseboard_fab2_lib.baseboard_fab2(sch_1):page53_i111:dq(24)"
				( attribute "PN" "38"
					( Origin gPackager )
				)
				( objectStatus "J4A1.38" )
			)
			( pin "@baseboard_fab2_lib.baseboard_fab2(sch_1):page53_i111:dq(25)"
				( attribute "PN" "183"
					( Origin gPackager )
				)
				( objectStatus "J4A1.183" )
			)
			( pin "@baseboard_fab2_lib.baseboard_fab2(sch_1):page53_i111:dq(26)"
				( attribute "PN" "45"
					( Origin gPackager )
				)
				( objectStatus "J4A1.45" )
			)
			( pin "@baseboard_fab2_lib.baseboard_fab2(sch_1):page53_i111:dq(27)"
				( attribute "PN" "190"
					( Origin gPackager )
				)
				( objectStatus "J4A1.190" )
			)
			( pin "@baseboard_fab2_lib.baseboard_fab2(sch_1):page53_i111:dq(28)"
				( attribute "PN" "36"
					( Origin gPackager )
				)
				( objectStatus "J4A1.36" )
			)
			( pin "@baseboard_fab2_lib.baseboard_fab2(sch_1):page53_i111:dq(29)"
				( attribute "PN" "181"
					( Origin gPackager )
				)
				( objectStatus "J4A1.181" )
			)
			( pin "@baseboard_fab2_lib.baseboard_fab2(sch_1):page53_i111:dq(30)"
				( attribute "PN" "43"
					( Origin gPackager )
				)
				( objectStatus "J4A1.43" )
			)
			( pin "@baseboard_fab2_lib.baseboard_fab2(sch_1):page53_i111:dq(31)"
				( attribute "PN" "188"
					( Origin gPackager )
				)
				( objectStatus "J4A1.188" )
			)
			( pin "@baseboard_fab2_lib.baseboard_fab2(sch_1):page53_i111:dq(32)"
				( attribute "PN" "97"
					( Origin gPackager )
				)
				( objectStatus "J4A1.97" )
			)
			( pin "@baseboard_fab2_lib.baseboard_fab2(sch_1):page53_i111:dq(33)"
				( attribute "PN" "242"
					( Origin gPackager )
				)
				( objectStatus "J4A1.242" )
			)
			( pin "@baseboard_fab2_lib.baseboard_fab2(sch_1):page53_i111:dq(34)"
				( attribute "PN" "104"
					( Origin gPackager )
				)
				( objectStatus "J4A1.104" )
			)
			( pin "@baseboard_fab2_lib.baseboard_fab2(sch_1):page53_i111:dq(35)"
				( attribute "PN" "249"
					( Origin gPackager )
				)
				( objectStatus "J4A1.249" )
			)
			( pin "@baseboard_fab2_lib.baseboard_fab2(sch_1):page53_i111:dq(36)"
				( attribute "PN" "95"
					( Origin gPackager )
				)
				( objectStatus "J4A1.95" )
			)
			( pin "@baseboard_fab2_lib.baseboard_fab2(sch_1):page53_i111:dq(37)"
				( attribute "PN" "240"
					( Origin gPackager )
				)
				( objectStatus "J4A1.240" )
			)
			( pin "@baseboard_fab2_lib.baseboard_fab2(sch_1):page53_i111:dq(38)"
				( attribute "PN" "102"
					( Origin gPackager )
				)
				( objectStatus "J4A1.102" )
			)
			( pin "@baseboard_fab2_lib.baseboard_fab2(sch_1):page53_i111:dq(39)"
				( attribute "PN" "247"
					( Origin gPackager )
				)
				( objectStatus "J4A1.247" )
			)
			( pin "@baseboard_fab2_lib.baseboard_fab2(sch_1):page53_i111:dq(40)"
				( attribute "PN" "108"
					( Origin gPackager )
				)
				( objectStatus "J4A1.108" )
			)
			( pin "@baseboard_fab2_lib.baseboard_fab2(sch_1):page53_i111:dq(41)"
				( attribute "PN" "253"
					( Origin gPackager )
				)
				( objectStatus "J4A1.253" )
			)
			( pin "@baseboard_fab2_lib.baseboard_fab2(sch_1):page53_i111:dq(42)"
				( attribute "PN" "115"
					( Origin gPackager )
				)
				( objectStatus "J4A1.115" )
			)
			( pin "@baseboard_fab2_lib.baseboard_fab2(sch_1):page53_i111:dq(43)"
				( attribute "PN" "260"
					( Origin gPackager )
				)
				( objectStatus "J4A1.260" )
			)
			( pin "@baseboard_fab2_lib.baseboard_fab2(sch_1):page53_i111:dq(44)"
				( attribute "PN" "106"
					( Origin gPackager )
				)
				( objectStatus "J4A1.106" )
			)
			( pin "@baseboard_fab2_lib.baseboard_fab2(sch_1):page53_i111:dq(45)"
				( attribute "PN" "251"
					( Origin gPackager )
				)
				( objectStatus "J4A1.251" )
			)
			( pin "@baseboard_fab2_lib.baseboard_fab2(sch_1):page53_i111:dq(46)"
				( attribute "PN" "113"
					( Origin gPackager )
				)
				( objectStatus "J4A1.113" )
			)
			( pin "@baseboard_fab2_lib.baseboard_fab2(sch_1):page53_i111:dq(47)"
				( attribute "PN" "258"
					( Origin gPackager )
				)
				( objectStatus "J4A1.258" )
			)
			( pin "@baseboard_fab2_lib.baseboard_fab2(sch_1):page53_i111:dq(48)"
				( attribute "PN" "119"
					( Origin gPackager )
				)
				( objectStatus "J4A1.119" )
			)
			( pin "@baseboard_fab2_lib.baseboard_fab2(sch_1):page53_i111:dq(49)"
				( attribute "PN" "264"
					( Origin gPackager )
				)
				( objectStatus "J4A1.264" )
			)
			( pin "@baseboard_fab2_lib.baseboard_fab2(sch_1):page53_i111:dq(50)"
				( attribute "PN" "126"
					( Origin gPackager )
				)
				( objectStatus "J4A1.126" )
			)
			( pin "@baseboard_fab2_lib.baseboard_fab2(sch_1):page53_i111:dq(51)"
				( attribute "PN" "271"
					( Origin gPackager )
				)
				( objectStatus "J4A1.271" )
			)
			( pin "@baseboard_fab2_lib.baseboard_fab2(sch_1):page53_i111:dq(52)"
				( attribute "PN" "117"
					( Origin gPackager )
				)
				( objectStatus "J4A1.117" )
			)
			( pin "@baseboard_fab2_lib.baseboard_fab2(sch_1):page53_i111:dq(53)"
				( attribute "PN" "262"
					( Origin gPackager )
				)
				( objectStatus "J4A1.262" )
			)
			( pin "@baseboard_fab2_lib.baseboard_fab2(sch_1):page53_i111:dq(54)"
				( attribute "PN" "124"
					( Origin gPackager )
				)
				( objectStatus "J4A1.124" )
			)
			( pin "@baseboard_fab2_lib.baseboard_fab2(sch_1):page53_i111:dq(55)"
				( attribute "PN" "269"
					( Origin gPackager )
				)
				( objectStatus "J4A1.269" )
			)
			( pin "@baseboard_fab2_lib.baseboard_fab2(sch_1):page53_i111:dq(56)"
				( attribute "PN" "130"
					( Origin gPackager )
				)
				( objectStatus "J4A1.130" )
			)
			( pin "@baseboard_fab2_lib.baseboard_fab2(sch_1):page53_i111:dq(57)"
				( attribute "PN" "275"
					( Origin gPackager )
				)
				( objectStatus "J4A1.275" )
			)
			( pin "@baseboard_fab2_lib.baseboard_fab2(sch_1):page53_i111:dq(58)"
				( attribute "PN" "137"
					( Origin gPackager )
				)
				( objectStatus "J4A1.137" )
			)
			( pin "@baseboard_fab2_lib.baseboard_fab2(sch_1):page53_i111:dq(59)"
				( attribute "PN" "282"
					( Origin gPackager )
				)
				( objectStatus "J4A1.282" )
			)
			( pin "@baseboard_fab2_lib.baseboard_fab2(sch_1):page53_i111:dq(60)"
				( attribute "PN" "128"
					( Origin gPackager )
				)
				( objectStatus "J4A1.128" )
			)
			( pin "@baseboard_fab2_lib.baseboard_fab2(sch_1):page53_i111:dq(61)"
				( attribute "PN" "273"
					( Origin gPackager )
				)
				( objectStatus "J4A1.273" )
			)
			( pin "@baseboard_fab2_lib.baseboard_fab2(sch_1):page53_i111:dq(62)"
				( attribute "PN" "135"
					( Origin gPackager )
				)
				( objectStatus "J4A1.135" )
			)
			( pin "@baseboard_fab2_lib.baseboard_fab2(sch_1):page53_i111:dq(63)"
				( attribute "PN" "280"
					( Origin gPackager )
				)
				( objectStatus "J4A1.280" )
			)
			( pin "@baseboard_fab2_lib.baseboard_fab2(sch_1):page53_i111:event_n"
				( attribute "PN" "78"
					( Origin gPackager )
				)
				( objectStatus "J4A1.78" )
			)
			( pin "@baseboard_fab2_lib.baseboard_fab2(sch_1):page53_i111:odt(0)"
				( attribute "PN" "87"
					( Origin gPackager )
				)
				( objectStatus "J4A1.87" )
			)
			( pin "@baseboard_fab2_lib.baseboard_fab2(sch_1):page53_i111:odt(1)"
				( attribute "PN" "91"
					( Origin gPackager )
				)
				( objectStatus "J4A1.91" )
			)
			( pin "@baseboard_fab2_lib.baseboard_fab2(sch_1):page53_i111:par"
				( attribute "PN" "222"
					( Origin gPackager )
				)
				( objectStatus "J4A1.222" )
			)
			( pin "@baseboard_fab2_lib.baseboard_fab2(sch_1):page53_i111:reset_n"
				( attribute "PN" "58"
					( Origin gPackager )
				)
				( objectStatus "J4A1.58" )
			)
			( pin "@baseboard_fab2_lib.baseboard_fab2(sch_1):page53_i111:rfu(0)"
				( attribute "PN" "205"
					( Origin gPackager )
				)
				( objectStatus "J4A1.205" )
			)
			( pin "@baseboard_fab2_lib.baseboard_fab2(sch_1):page53_i111:rfu(1)"
				( attribute "PN" "227"
					( Origin gPackager )
				)
				( objectStatus "J4A1.227" )
			)
			( pin "@baseboard_fab2_lib.baseboard_fab2(sch_1):page53_i111:rfu(2)"
				( attribute "PN" "144"
					( Origin gPackager )
				)
				( objectStatus "J4A1.144" )
			)
			( pin "@baseboard_fab2_lib.baseboard_fab2(sch_1):page53_i111:s0_n"
				( attribute "PN" "84"
					( Origin gPackager )
				)
				( objectStatus "J4A1.84" )
			)
			( pin "@baseboard_fab2_lib.baseboard_fab2(sch_1):page53_i111:s1_n"
				( attribute "PN" "89"
					( Origin gPackager )
				)
				( objectStatus "J4A1.89" )
			)
			( pin "@baseboard_fab2_lib.baseboard_fab2(sch_1):page53_i111:s2_n_c(0)"
				( attribute "PN" "93"
					( Origin gPackager )
				)
				( objectStatus "J4A1.93" )
			)
			( pin "@baseboard_fab2_lib.baseboard_fab2(sch_1):page53_i111:s3_n_c(1)"
				( attribute "PN" "237"
					( Origin gPackager )
				)
				( objectStatus "J4A1.237" )
			)
			( pin "@baseboard_fab2_lib.baseboard_fab2(sch_1):page53_i111:sa(0)"
				( attribute "PN" "139"
					( Origin gPackager )
				)
				( objectStatus "J4A1.139" )
			)
			( pin "@baseboard_fab2_lib.baseboard_fab2(sch_1):page53_i111:sa(1)"
				( attribute "PN" "140"
					( Origin gPackager )
				)
				( objectStatus "J4A1.140" )
			)
			( pin "@baseboard_fab2_lib.baseboard_fab2(sch_1):page53_i111:sa(2)"
				( attribute "PN" "238"
					( Origin gPackager )
				)
				( objectStatus "J4A1.238" )
			)
			( pin "@baseboard_fab2_lib.baseboard_fab2(sch_1):page53_i111:save_n_nc"
				( attribute "PN" "230"
					( Origin gPackager )
				)
				( objectStatus "J4A1.230" )
			)
			( pin "@baseboard_fab2_lib.baseboard_fab2(sch_1):page53_i111:scl"
				( attribute "PN" "141"
					( Origin gPackager )
				)
				( objectStatus "J4A1.141" )
			)
			( pin "@baseboard_fab2_lib.baseboard_fab2(sch_1):page53_i111:sda"
				( attribute "PN" "285"
					( Origin gPackager )
				)
				( objectStatus "J4A1.285" )
			)
			( pin "@baseboard_fab2_lib.baseboard_fab2(sch_1):page53_i111:vddspd"
				( attribute "PN" "284"
					( Origin gPackager )
				)
				( objectStatus "J4A1.284" )
			)
			( pin "@baseboard_fab2_lib.baseboard_fab2(sch_1):page53_i111:vrefca"
				( attribute "PN" "146"
					( Origin gPackager )
				)
				( objectStatus "J4A1.146" )
			)
			( pin "@baseboard_fab2_lib.baseboard_fab2(sch_1):page53_i171:\12v\(0)"
				( attribute "PN" "145"
					( Origin gPackager )
				)
				( objectStatus "J4A1.145" )
			)
			( pin "@baseboard_fab2_lib.baseboard_fab2(sch_1):page53_i171:\12v\(1)"
				( attribute "PN" "1"
					( Origin gPackager )
				)
				( objectStatus "J4A1.1" )
			)
			( pin "@baseboard_fab2_lib.baseboard_fab2(sch_1):page53_i171:vdd(0)"
				( attribute "PN" "236"
					( Origin gPackager )
				)
				( objectStatus "J4A1.236" )
			)
			( pin "@baseboard_fab2_lib.baseboard_fab2(sch_1):page53_i171:vdd(1)"
				( attribute "PN" "233"
					( Origin gPackager )
				)
				( objectStatus "J4A1.233" )
			)
			( pin "@baseboard_fab2_lib.baseboard_fab2(sch_1):page53_i171:vdd(2)"
				( attribute "PN" "231"
					( Origin gPackager )
				)
				( objectStatus "J4A1.231" )
			)
			( pin "@baseboard_fab2_lib.baseboard_fab2(sch_1):page53_i171:vdd(3)"
				( attribute "PN" "229"
					( Origin gPackager )
				)
				( objectStatus "J4A1.229" )
			)
			( pin "@baseboard_fab2_lib.baseboard_fab2(sch_1):page53_i171:vdd(4)"
				( attribute "PN" "226"
					( Origin gPackager )
				)
				( objectStatus "J4A1.226" )
			)
			( pin "@baseboard_fab2_lib.baseboard_fab2(sch_1):page53_i171:vdd(5)"
				( attribute "PN" "223"
					( Origin gPackager )
				)
				( objectStatus "J4A1.223" )
			)
			( pin "@baseboard_fab2_lib.baseboard_fab2(sch_1):page53_i171:vdd(6)"
				( attribute "PN" "220"
					( Origin gPackager )
				)
				( objectStatus "J4A1.220" )
			)
			( pin "@baseboard_fab2_lib.baseboard_fab2(sch_1):page53_i171:vdd(7)"
				( attribute "PN" "217"
					( Origin gPackager )
				)
				( objectStatus "J4A1.217" )
			)
			( pin "@baseboard_fab2_lib.baseboard_fab2(sch_1):page53_i171:vdd(8)"
				( attribute "PN" "215"
					( Origin gPackager )
				)
				( objectStatus "J4A1.215" )
			)
			( pin "@baseboard_fab2_lib.baseboard_fab2(sch_1):page53_i171:vdd(9)"
				( attribute "PN" "212"
					( Origin gPackager )
				)
				( objectStatus "J4A1.212" )
			)
			( pin "@baseboard_fab2_lib.baseboard_fab2(sch_1):page53_i171:vdd(10)"
				( attribute "PN" "209"
					( Origin gPackager )
				)
				( objectStatus "J4A1.209" )
			)
			( pin "@baseboard_fab2_lib.baseboard_fab2(sch_1):page53_i171:vdd(11)"
				( attribute "PN" "206"
					( Origin gPackager )
				)
				( objectStatus "J4A1.206" )
			)
			( pin "@baseboard_fab2_lib.baseboard_fab2(sch_1):page53_i171:vdd(12)"
				( attribute "PN" "204"
					( Origin gPackager )
				)
				( objectStatus "J4A1.204" )
			)
			( pin "@baseboard_fab2_lib.baseboard_fab2(sch_1):page53_i171:vdd(13)"
				( attribute "PN" "92"
					( Origin gPackager )
				)
				( objectStatus "J4A1.92" )
			)
			( pin "@baseboard_fab2_lib.baseboard_fab2(sch_1):page53_i171:vdd(14)"
				( attribute "PN" "90"
					( Origin gPackager )
				)
				( objectStatus "J4A1.90" )
			)
			( pin "@baseboard_fab2_lib.baseboard_fab2(sch_1):page53_i171:vdd(15)"
				( attribute "PN" "88"
					( Origin gPackager )
				)
				( objectStatus "J4A1.88" )
			)
			( pin "@baseboard_fab2_lib.baseboard_fab2(sch_1):page53_i171:vdd(16)"
				( attribute "PN" "85"
					( Origin gPackager )
				)
				( objectStatus "J4A1.85" )
			)
			( pin "@baseboard_fab2_lib.baseboard_fab2(sch_1):page53_i171:vdd(17)"
				( attribute "PN" "83"
					( Origin gPackager )
				)
				( objectStatus "J4A1.83" )
			)
			( pin "@baseboard_fab2_lib.baseboard_fab2(sch_1):page53_i171:vdd(18)"
				( attribute "PN" "80"
					( Origin gPackager )
				)
				( objectStatus "J4A1.80" )
			)
			( pin "@baseboard_fab2_lib.baseboard_fab2(sch_1):page53_i171:vdd(19)"
				( attribute "PN" "76"
					( Origin gPackager )
				)
				( objectStatus "J4A1.76" )
			)
			( pin "@baseboard_fab2_lib.baseboard_fab2(sch_1):page53_i171:vdd(20)"
				( attribute "PN" "73"
					( Origin gPackager )
				)
				( objectStatus "J4A1.73" )
			)
			( pin "@baseboard_fab2_lib.baseboard_fab2(sch_1):page53_i171:vdd(21)"
				( attribute "PN" "70"
					( Origin gPackager )
				)
				( objectStatus "J4A1.70" )
			)
			( pin "@baseboard_fab2_lib.baseboard_fab2(sch_1):page53_i171:vdd(22)"
				( attribute "PN" "67"
					( Origin gPackager )
				)
				( objectStatus "J4A1.67" )
			)
			( pin "@baseboard_fab2_lib.baseboard_fab2(sch_1):page53_i171:vdd(23)"
				( attribute "PN" "64"
					( Origin gPackager )
				)
				( objectStatus "J4A1.64" )
			)
			( pin "@baseboard_fab2_lib.baseboard_fab2(sch_1):page53_i171:vdd(24)"
				( attribute "PN" "61"
					( Origin gPackager )
				)
				( objectStatus "J4A1.61" )
			)
			( pin "@baseboard_fab2_lib.baseboard_fab2(sch_1):page53_i171:vdd(25)"
				( attribute "PN" "59"
					( Origin gPackager )
				)
				( objectStatus "J4A1.59" )
			)
			( pin "@baseboard_fab2_lib.baseboard_fab2(sch_1):page53_i171:vpp(0)"
				( attribute "PN" "287"
					( Origin gPackager )
				)
				( objectStatus "J4A1.287" )
			)
			( pin "@baseboard_fab2_lib.baseboard_fab2(sch_1):page53_i171:vpp(1)"
				( attribute "PN" "286"
					( Origin gPackager )
				)
				( objectStatus "J4A1.286" )
			)
			( pin "@baseboard_fab2_lib.baseboard_fab2(sch_1):page53_i171:vpp(2)"
				( attribute "PN" "288"
					( Origin gPackager )
				)
				( objectStatus "J4A1.288" )
			)
			( pin "@baseboard_fab2_lib.baseboard_fab2(sch_1):page53_i171:vpp(3)"
				( attribute "PN" "143"
					( Origin gPackager )
				)
				( objectStatus "J4A1.143" )
			)
			( pin "@baseboard_fab2_lib.baseboard_fab2(sch_1):page53_i171:vpp(4)"
				( attribute "PN" "142"
					( Origin gPackager )
				)
				( objectStatus "J4A1.142" )
			)
			( pin "@baseboard_fab2_lib.baseboard_fab2(sch_1):page53_i171:vtt(0)"
				( attribute "PN" "221"
					( Origin gPackager )
				)
				( objectStatus "J4A1.221" )
			)
			( pin "@baseboard_fab2_lib.baseboard_fab2(sch_1):page53_i171:vtt(1)"
				( attribute "PN" "77"
					( Origin gPackager )
				)
				( objectStatus "J4A1.77" )
			)
			( pin "@baseboard_fab2_lib.baseboard_fab2(sch_1):page53_i178:a"
				( attribute "PN" "1"
					( Origin gPackager )
				)
				( objectStatus "C6L1.1" )
			)
			( pin "@baseboard_fab2_lib.baseboard_fab2(sch_1):page53_i178:b"
				( attribute "PN" "2"
					( Origin gPackager )
				)
				( objectStatus "C6L1.2" )
			)
			( pin "@baseboard_fab2_lib.baseboard_fab2(sch_1):page54_i43:vss(0)"
				( attribute "PN" "283"
					( Origin gPackager )
				)
				( objectStatus "J6L1.283" )
			)
			( pin "@baseboard_fab2_lib.baseboard_fab2(sch_1):page54_i43:vss(1)"
				( attribute "PN" "281"
					( Origin gPackager )
				)
				( objectStatus "J6L1.281" )
			)
			( pin "@baseboard_fab2_lib.baseboard_fab2(sch_1):page54_i43:vss(2)"
				( attribute "PN" "279"
					( Origin gPackager )
				)
				( objectStatus "J6L1.279" )
			)
			( pin "@baseboard_fab2_lib.baseboard_fab2(sch_1):page54_i43:vss(3)"
				( attribute "PN" "276"
					( Origin gPackager )
				)
				( objectStatus "J6L1.276" )
			)
			( pin "@baseboard_fab2_lib.baseboard_fab2(sch_1):page54_i43:vss(4)"
				( attribute "PN" "274"
					( Origin gPackager )
				)
				( objectStatus "J6L1.274" )
			)
			( pin "@baseboard_fab2_lib.baseboard_fab2(sch_1):page54_i43:vss(5)"
				( attribute "PN" "272"
					( Origin gPackager )
				)
				( objectStatus "J6L1.272" )
			)
			( pin "@baseboard_fab2_lib.baseboard_fab2(sch_1):page54_i43:vss(6)"
				( attribute "PN" "270"
					( Origin gPackager )
				)
				( objectStatus "J6L1.270" )
			)
			( pin "@baseboard_fab2_lib.baseboard_fab2(sch_1):page54_i43:vss(7)"
				( attribute "PN" "268"
					( Origin gPackager )
				)
				( objectStatus "J6L1.268" )
			)
			( pin "@baseboard_fab2_lib.baseboard_fab2(sch_1):page54_i43:vss(8)"
				( attribute "PN" "265"
					( Origin gPackager )
				)
				( objectStatus "J6L1.265" )
			)
			( pin "@baseboard_fab2_lib.baseboard_fab2(sch_1):page54_i43:vss(9)"
				( attribute "PN" "263"
					( Origin gPackager )
				)
				( objectStatus "J6L1.263" )
			)
			( pin "@baseboard_fab2_lib.baseboard_fab2(sch_1):page54_i43:vss(10)"
				( attribute "PN" "261"
					( Origin gPackager )
				)
				( objectStatus "J6L1.261" )
			)
			( pin "@baseboard_fab2_lib.baseboard_fab2(sch_1):page54_i43:vss(11)"
				( attribute "PN" "259"
					( Origin gPackager )
				)
				( objectStatus "J6L1.259" )
			)
			( pin "@baseboard_fab2_lib.baseboard_fab2(sch_1):page54_i43:vss(12)"
				( attribute "PN" "257"
					( Origin gPackager )
				)
				( objectStatus "J6L1.257" )
			)
			( pin "@baseboard_fab2_lib.baseboard_fab2(sch_1):page54_i43:vss(13)"
				( attribute "PN" "254"
					( Origin gPackager )
				)
				( objectStatus "J6L1.254" )
			)
			( pin "@baseboard_fab2_lib.baseboard_fab2(sch_1):page54_i43:vss(14)"
				( attribute "PN" "252"
					( Origin gPackager )
				)
				( objectStatus "J6L1.252" )
			)
			( pin "@baseboard_fab2_lib.baseboard_fab2(sch_1):page54_i43:vss(15)"
				( attribute "PN" "250"
					( Origin gPackager )
				)
				( objectStatus "J6L1.250" )
			)
			( pin "@baseboard_fab2_lib.baseboard_fab2(sch_1):page54_i43:vss(16)"
				( attribute "PN" "248"
					( Origin gPackager )
				)
				( objectStatus "J6L1.248" )
			)
			( pin "@baseboard_fab2_lib.baseboard_fab2(sch_1):page54_i43:vss(17)"
				( attribute "PN" "246"
					( Origin gPackager )
				)
				( objectStatus "J6L1.246" )
			)
			( pin "@baseboard_fab2_lib.baseboard_fab2(sch_1):page54_i43:vss(18)"
				( attribute "PN" "243"
					( Origin gPackager )
				)
				( objectStatus "J6L1.243" )
			)
			( pin "@baseboard_fab2_lib.baseboard_fab2(sch_1):page54_i43:vss(19)"
				( attribute "PN" "241"
					( Origin gPackager )
				)
				( objectStatus "J6L1.241" )
			)
			( pin "@baseboard_fab2_lib.baseboard_fab2(sch_1):page54_i43:vss(20)"
				( attribute "PN" "239"
					( Origin gPackager )
				)
				( objectStatus "J6L1.239" )
			)
			( pin "@baseboard_fab2_lib.baseboard_fab2(sch_1):page54_i43:vss(21)"
				( attribute "PN" "202"
					( Origin gPackager )
				)
				( objectStatus "J6L1.202" )
			)
			( pin "@baseboard_fab2_lib.baseboard_fab2(sch_1):page54_i43:vss(22)"
				( attribute "PN" "200"
					( Origin gPackager )
				)
				( objectStatus "J6L1.200" )
			)
			( pin "@baseboard_fab2_lib.baseboard_fab2(sch_1):page54_i43:vss(23)"
				( attribute "PN" "198"
					( Origin gPackager )
				)
				( objectStatus "J6L1.198" )
			)
			( pin "@baseboard_fab2_lib.baseboard_fab2(sch_1):page54_i43:vss(24)"
				( attribute "PN" "195"
					( Origin gPackager )
				)
				( objectStatus "J6L1.195" )
			)
			( pin "@baseboard_fab2_lib.baseboard_fab2(sch_1):page54_i43:vss(25)"
				( attribute "PN" "193"
					( Origin gPackager )
				)
				( objectStatus "J6L1.193" )
			)
			( pin "@baseboard_fab2_lib.baseboard_fab2(sch_1):page54_i43:vss(26)"
				( attribute "PN" "191"
					( Origin gPackager )
				)
				( objectStatus "J6L1.191" )
			)
			( pin "@baseboard_fab2_lib.baseboard_fab2(sch_1):page54_i43:vss(27)"
				( attribute "PN" "189"
					( Origin gPackager )
				)
				( objectStatus "J6L1.189" )
			)
			( pin "@baseboard_fab2_lib.baseboard_fab2(sch_1):page54_i43:vss(28)"
				( attribute "PN" "187"
					( Origin gPackager )
				)
				( objectStatus "J6L1.187" )
			)
			( pin "@baseboard_fab2_lib.baseboard_fab2(sch_1):page54_i43:vss(29)"
				( attribute "PN" "184"
					( Origin gPackager )
				)
				( objectStatus "J6L1.184" )
			)
			( pin "@baseboard_fab2_lib.baseboard_fab2(sch_1):page54_i43:vss(30)"
				( attribute "PN" "182"
					( Origin gPackager )
				)
				( objectStatus "J6L1.182" )
			)
			( pin "@baseboard_fab2_lib.baseboard_fab2(sch_1):page54_i43:vss(31)"
				( attribute "PN" "180"
					( Origin gPackager )
				)
				( objectStatus "J6L1.180" )
			)
			( pin "@baseboard_fab2_lib.baseboard_fab2(sch_1):page54_i43:vss(32)"
				( attribute "PN" "178"
					( Origin gPackager )
				)
				( objectStatus "J6L1.178" )
			)
			( pin "@baseboard_fab2_lib.baseboard_fab2(sch_1):page54_i43:vss(33)"
				( attribute "PN" "176"
					( Origin gPackager )
				)
				( objectStatus "J6L1.176" )
			)
			( pin "@baseboard_fab2_lib.baseboard_fab2(sch_1):page54_i43:vss(34)"
				( attribute "PN" "173"
					( Origin gPackager )
				)
				( objectStatus "J6L1.173" )
			)
			( pin "@baseboard_fab2_lib.baseboard_fab2(sch_1):page54_i43:vss(35)"
				( attribute "PN" "171"
					( Origin gPackager )
				)
				( objectStatus "J6L1.171" )
			)
			( pin "@baseboard_fab2_lib.baseboard_fab2(sch_1):page54_i43:vss(36)"
				( attribute "PN" "169"
					( Origin gPackager )
				)
				( objectStatus "J6L1.169" )
			)
			( pin "@baseboard_fab2_lib.baseboard_fab2(sch_1):page54_i43:vss(37)"
				( attribute "PN" "167"
					( Origin gPackager )
				)
				( objectStatus "J6L1.167" )
			)
			( pin "@baseboard_fab2_lib.baseboard_fab2(sch_1):page54_i43:vss(38)"
				( attribute "PN" "165"
					( Origin gPackager )
				)
				( objectStatus "J6L1.165" )
			)
			( pin "@baseboard_fab2_lib.baseboard_fab2(sch_1):page54_i43:vss(39)"
				( attribute "PN" "162"
					( Origin gPackager )
				)
				( objectStatus "J6L1.162" )
			)
			( pin "@baseboard_fab2_lib.baseboard_fab2(sch_1):page54_i43:vss(40)"
				( attribute "PN" "160"
					( Origin gPackager )
				)
				( objectStatus "J6L1.160" )
			)
			( pin "@baseboard_fab2_lib.baseboard_fab2(sch_1):page54_i43:vss(41)"
				( attribute "PN" "158"
					( Origin gPackager )
				)
				( objectStatus "J6L1.158" )
			)
			( pin "@baseboard_fab2_lib.baseboard_fab2(sch_1):page54_i43:vss(42)"
				( attribute "PN" "156"
					( Origin gPackager )
				)
				( objectStatus "J6L1.156" )
			)
			( pin "@baseboard_fab2_lib.baseboard_fab2(sch_1):page54_i43:vss(43)"
				( attribute "PN" "154"
					( Origin gPackager )
				)
				( objectStatus "J6L1.154" )
			)
			( pin "@baseboard_fab2_lib.baseboard_fab2(sch_1):page54_i43:vss(44)"
				( attribute "PN" "151"
					( Origin gPackager )
				)
				( objectStatus "J6L1.151" )
			)
			( pin "@baseboard_fab2_lib.baseboard_fab2(sch_1):page54_i43:vss(45)"
				( attribute "PN" "149"
					( Origin gPackager )
				)
				( objectStatus "J6L1.149" )
			)
			( pin "@baseboard_fab2_lib.baseboard_fab2(sch_1):page54_i43:vss(46)"
				( attribute "PN" "147"
					( Origin gPackager )
				)
				( objectStatus "J6L1.147" )
			)
			( pin "@baseboard_fab2_lib.baseboard_fab2(sch_1):page54_i43:vss(47)"
				( attribute "PN" "138"
					( Origin gPackager )
				)
				( objectStatus "J6L1.138" )
			)
			( pin "@baseboard_fab2_lib.baseboard_fab2(sch_1):page54_i43:vss(48)"
				( attribute "PN" "136"
					( Origin gPackager )
				)
				( objectStatus "J6L1.136" )
			)
			( pin "@baseboard_fab2_lib.baseboard_fab2(sch_1):page54_i43:vss(49)"
				( attribute "PN" "134"
					( Origin gPackager )
				)
				( objectStatus "J6L1.134" )
			)
			( pin "@baseboard_fab2_lib.baseboard_fab2(sch_1):page54_i43:vss(50)"
				( attribute "PN" "131"
					( Origin gPackager )
				)
				( objectStatus "J6L1.131" )
			)
			( pin "@baseboard_fab2_lib.baseboard_fab2(sch_1):page54_i43:vss(51)"
				( attribute "PN" "129"
					( Origin gPackager )
				)
				( objectStatus "J6L1.129" )
			)
			( pin "@baseboard_fab2_lib.baseboard_fab2(sch_1):page54_i43:vss(52)"
				( attribute "PN" "127"
					( Origin gPackager )
				)
				( objectStatus "J6L1.127" )
			)
			( pin "@baseboard_fab2_lib.baseboard_fab2(sch_1):page54_i43:vss(53)"
				( attribute "PN" "125"
					( Origin gPackager )
				)
				( objectStatus "J6L1.125" )
			)
			( pin "@baseboard_fab2_lib.baseboard_fab2(sch_1):page54_i43:vss(54)"
				( attribute "PN" "123"
					( Origin gPackager )
				)
				( objectStatus "J6L1.123" )
			)
			( pin "@baseboard_fab2_lib.baseboard_fab2(sch_1):page54_i43:vss(55)"
				( attribute "PN" "120"
					( Origin gPackager )
				)
				( objectStatus "J6L1.120" )
			)
			( pin "@baseboard_fab2_lib.baseboard_fab2(sch_1):page54_i43:vss(56)"
				( attribute "PN" "118"
					( Origin gPackager )
				)
				( objectStatus "J6L1.118" )
			)
			( pin "@baseboard_fab2_lib.baseboard_fab2(sch_1):page54_i43:vss(57)"
				( attribute "PN" "116"
					( Origin gPackager )
				)
				( objectStatus "J6L1.116" )
			)
			( pin "@baseboard_fab2_lib.baseboard_fab2(sch_1):page54_i43:vss(58)"
				( attribute "PN" "114"
					( Origin gPackager )
				)
				( objectStatus "J6L1.114" )
			)
			( pin "@baseboard_fab2_lib.baseboard_fab2(sch_1):page54_i43:vss(59)"
				( attribute "PN" "112"
					( Origin gPackager )
				)
				( objectStatus "J6L1.112" )
			)
			( pin "@baseboard_fab2_lib.baseboard_fab2(sch_1):page54_i43:vss(60)"
				( attribute "PN" "109"
					( Origin gPackager )
				)
				( objectStatus "J6L1.109" )
			)
			( pin "@baseboard_fab2_lib.baseboard_fab2(sch_1):page54_i43:vss(61)"
				( attribute "PN" "107"
					( Origin gPackager )
				)
				( objectStatus "J6L1.107" )
			)
			( pin "@baseboard_fab2_lib.baseboard_fab2(sch_1):page54_i43:vss(62)"
				( attribute "PN" "105"
					( Origin gPackager )
				)
				( objectStatus "J6L1.105" )
			)
			( pin "@baseboard_fab2_lib.baseboard_fab2(sch_1):page54_i43:vss(63)"
				( attribute "PN" "103"
					( Origin gPackager )
				)
				( objectStatus "J6L1.103" )
			)
			( pin "@baseboard_fab2_lib.baseboard_fab2(sch_1):page54_i43:vss(64)"
				( attribute "PN" "101"
					( Origin gPackager )
				)
				( objectStatus "J6L1.101" )
			)
			( pin "@baseboard_fab2_lib.baseboard_fab2(sch_1):page54_i43:vss(65)"
				( attribute "PN" "98"
					( Origin gPackager )
				)
				( objectStatus "J6L1.98" )
			)
			( pin "@baseboard_fab2_lib.baseboard_fab2(sch_1):page54_i43:vss(66)"
				( attribute "PN" "96"
					( Origin gPackager )
				)
				( objectStatus "J6L1.96" )
			)
			( pin "@baseboard_fab2_lib.baseboard_fab2(sch_1):page54_i43:vss(67)"
				( attribute "PN" "94"
					( Origin gPackager )
				)
				( objectStatus "J6L1.94" )
			)
			( pin "@baseboard_fab2_lib.baseboard_fab2(sch_1):page54_i43:vss(68)"
				( attribute "PN" "57"
					( Origin gPackager )
				)
				( objectStatus "J6L1.57" )
			)
			( pin "@baseboard_fab2_lib.baseboard_fab2(sch_1):page54_i43:vss(69)"
				( attribute "PN" "55"
					( Origin gPackager )
				)
				( objectStatus "J6L1.55" )
			)
			( pin "@baseboard_fab2_lib.baseboard_fab2(sch_1):page54_i43:vss(70)"
				( attribute "PN" "53"
					( Origin gPackager )
				)
				( objectStatus "J6L1.53" )
			)
			( pin "@baseboard_fab2_lib.baseboard_fab2(sch_1):page54_i43:vss(71)"
				( attribute "PN" "50"
					( Origin gPackager )
				)
				( objectStatus "J6L1.50" )
			)
			( pin "@baseboard_fab2_lib.baseboard_fab2(sch_1):page54_i43:vss(72)"
				( attribute "PN" "48"
					( Origin gPackager )
				)
				( objectStatus "J6L1.48" )
			)
			( pin "@baseboard_fab2_lib.baseboard_fab2(sch_1):page54_i43:vss(73)"
				( attribute "PN" "46"
					( Origin gPackager )
				)
				( objectStatus "J6L1.46" )
			)
			( pin "@baseboard_fab2_lib.baseboard_fab2(sch_1):page54_i43:vss(74)"
				( attribute "PN" "44"
					( Origin gPackager )
				)
				( objectStatus "J6L1.44" )
			)
			( pin "@baseboard_fab2_lib.baseboard_fab2(sch_1):page54_i43:vss(75)"
				( attribute "PN" "42"
					( Origin gPackager )
				)
				( objectStatus "J6L1.42" )
			)
			( pin "@baseboard_fab2_lib.baseboard_fab2(sch_1):page54_i43:vss(76)"
				( attribute "PN" "39"
					( Origin gPackager )
				)
				( objectStatus "J6L1.39" )
			)
			( pin "@baseboard_fab2_lib.baseboard_fab2(sch_1):page54_i43:vss(77)"
				( attribute "PN" "37"
					( Origin gPackager )
				)
				( objectStatus "J6L1.37" )
			)
			( pin "@baseboard_fab2_lib.baseboard_fab2(sch_1):page54_i43:vss(78)"
				( attribute "PN" "35"
					( Origin gPackager )
				)
				( objectStatus "J6L1.35" )
			)
			( pin "@baseboard_fab2_lib.baseboard_fab2(sch_1):page54_i43:vss(79)"
				( attribute "PN" "33"
					( Origin gPackager )
				)
				( objectStatus "J6L1.33" )
			)
			( pin "@baseboard_fab2_lib.baseboard_fab2(sch_1):page54_i43:vss(80)"
				( attribute "PN" "31"
					( Origin gPackager )
				)
				( objectStatus "J6L1.31" )
			)
			( pin "@baseboard_fab2_lib.baseboard_fab2(sch_1):page54_i43:vss(81)"
				( attribute "PN" "28"
					( Origin gPackager )
				)
				( objectStatus "J6L1.28" )
			)
			( pin "@baseboard_fab2_lib.baseboard_fab2(sch_1):page54_i43:vss(82)"
				( attribute "PN" "26"
					( Origin gPackager )
				)
				( objectStatus "J6L1.26" )
			)
			( pin "@baseboard_fab2_lib.baseboard_fab2(sch_1):page54_i43:vss(83)"
				( attribute "PN" "24"
					( Origin gPackager )
				)
				( objectStatus "J6L1.24" )
			)
			( pin "@baseboard_fab2_lib.baseboard_fab2(sch_1):page54_i43:vss(84)"
				( attribute "PN" "22"
					( Origin gPackager )
				)
				( objectStatus "J6L1.22" )
			)
			( pin "@baseboard_fab2_lib.baseboard_fab2(sch_1):page54_i43:vss(85)"
				( attribute "PN" "20"
					( Origin gPackager )
				)
				( objectStatus "J6L1.20" )
			)
			( pin "@baseboard_fab2_lib.baseboard_fab2(sch_1):page54_i43:vss(86)"
				( attribute "PN" "17"
					( Origin gPackager )
				)
				( objectStatus "J6L1.17" )
			)
			( pin "@baseboard_fab2_lib.baseboard_fab2(sch_1):page54_i43:vss(87)"
				( attribute "PN" "15"
					( Origin gPackager )
				)
				( objectStatus "J6L1.15" )
			)
			( pin "@baseboard_fab2_lib.baseboard_fab2(sch_1):page54_i43:vss(88)"
				( attribute "PN" "13"
					( Origin gPackager )
				)
				( objectStatus "J6L1.13" )
			)
			( pin "@baseboard_fab2_lib.baseboard_fab2(sch_1):page54_i43:vss(89)"
				( attribute "PN" "11"
					( Origin gPackager )
				)
				( objectStatus "J6L1.11" )
			)
			( pin "@baseboard_fab2_lib.baseboard_fab2(sch_1):page54_i43:vss(90)"
				( attribute "PN" "9"
					( Origin gPackager )
				)
				( objectStatus "J6L1.9" )
			)
			( pin "@baseboard_fab2_lib.baseboard_fab2(sch_1):page54_i43:vss(91)"
				( attribute "PN" "6"
					( Origin gPackager )
				)
				( objectStatus "J6L1.6" )
			)
			( pin "@baseboard_fab2_lib.baseboard_fab2(sch_1):page54_i43:vss(92)"
				( attribute "PN" "4"
					( Origin gPackager )
				)
				( objectStatus "J6L1.4" )
			)
			( pin "@baseboard_fab2_lib.baseboard_fab2(sch_1):page54_i43:vss(93)"
				( attribute "PN" "2"
					( Origin gPackager )
				)
				( objectStatus "J6L1.2" )
			)
			( pin "@baseboard_fab2_lib.baseboard_fab2(sch_1):page54_i66:dqs0n"
				( attribute "PN" "152"
					( Origin gPackager )
				)
				( objectStatus "J6L1.152" )
			)
			( pin "@baseboard_fab2_lib.baseboard_fab2(sch_1):page54_i66:dqs0p"
				( attribute "PN" "153"
					( Origin gPackager )
				)
				( objectStatus "J6L1.153" )
			)
			( pin "@baseboard_fab2_lib.baseboard_fab2(sch_1):page54_i66:dqs1n"
				( attribute "PN" "163"
					( Origin gPackager )
				)
				( objectStatus "J6L1.163" )
			)
			( pin "@baseboard_fab2_lib.baseboard_fab2(sch_1):page54_i66:dqs1p"
				( attribute "PN" "164"
					( Origin gPackager )
				)
				( objectStatus "J6L1.164" )
			)
			( pin "@baseboard_fab2_lib.baseboard_fab2(sch_1):page54_i66:dqs2n"
				( attribute "PN" "174"
					( Origin gPackager )
				)
				( objectStatus "J6L1.174" )
			)
			( pin "@baseboard_fab2_lib.baseboard_fab2(sch_1):page54_i66:dqs2p"
				( attribute "PN" "175"
					( Origin gPackager )
				)
				( objectStatus "J6L1.175" )
			)
			( pin "@baseboard_fab2_lib.baseboard_fab2(sch_1):page54_i66:dqs3n"
				( attribute "PN" "185"
					( Origin gPackager )
				)
				( objectStatus "J6L1.185" )
			)
			( pin "@baseboard_fab2_lib.baseboard_fab2(sch_1):page54_i66:dqs3p"
				( attribute "PN" "186"
					( Origin gPackager )
				)
				( objectStatus "J6L1.186" )
			)
			( pin "@baseboard_fab2_lib.baseboard_fab2(sch_1):page54_i66:dqs4n"
				( attribute "PN" "244"
					( Origin gPackager )
				)
				( objectStatus "J6L1.244" )
			)
			( pin "@baseboard_fab2_lib.baseboard_fab2(sch_1):page54_i66:dqs4p"
				( attribute "PN" "245"
					( Origin gPackager )
				)
				( objectStatus "J6L1.245" )
			)
			( pin "@baseboard_fab2_lib.baseboard_fab2(sch_1):page54_i66:dqs5n"
				( attribute "PN" "255"
					( Origin gPackager )
				)
				( objectStatus "J6L1.255" )
			)
			( pin "@baseboard_fab2_lib.baseboard_fab2(sch_1):page54_i66:dqs5p"
				( attribute "PN" "256"
					( Origin gPackager )
				)
				( objectStatus "J6L1.256" )
			)
			( pin "@baseboard_fab2_lib.baseboard_fab2(sch_1):page54_i66:dqs6n"
				( attribute "PN" "266"
					( Origin gPackager )
				)
				( objectStatus "J6L1.266" )
			)
			( pin "@baseboard_fab2_lib.baseboard_fab2(sch_1):page54_i66:dqs6p"
				( attribute "PN" "267"
					( Origin gPackager )
				)
				( objectStatus "J6L1.267" )
			)
			( pin "@baseboard_fab2_lib.baseboard_fab2(sch_1):page54_i66:dqs7n"
				( attribute "PN" "277"
					( Origin gPackager )
				)
				( objectStatus "J6L1.277" )
			)
			( pin "@baseboard_fab2_lib.baseboard_fab2(sch_1):page54_i66:dqs7p"
				( attribute "PN" "278"
					( Origin gPackager )
				)
				( objectStatus "J6L1.278" )
			)
			( pin "@baseboard_fab2_lib.baseboard_fab2(sch_1):page54_i66:dqs8n"
				( attribute "PN" "196"
					( Origin gPackager )
				)
				( objectStatus "J6L1.196" )
			)
			( pin "@baseboard_fab2_lib.baseboard_fab2(sch_1):page54_i66:dqs8p"
				( attribute "PN" "197"
					( Origin gPackager )
				)
				( objectStatus "J6L1.197" )
			)
			( pin "@baseboard_fab2_lib.baseboard_fab2(sch_1):page54_i66:dqs9n"
				( attribute "PN" "8"
					( Origin gPackager )
				)
				( objectStatus "J6L1.8" )
			)
			( pin "@baseboard_fab2_lib.baseboard_fab2(sch_1):page54_i66:dqs9p"
				( attribute "PN" "7"
					( Origin gPackager )
				)
				( objectStatus "J6L1.7" )
			)
			( pin "@baseboard_fab2_lib.baseboard_fab2(sch_1):page54_i66:dqs10n"
				( attribute "PN" "19"
					( Origin gPackager )
				)
				( objectStatus "J6L1.19" )
			)
			( pin "@baseboard_fab2_lib.baseboard_fab2(sch_1):page54_i66:dqs10p"
				( attribute "PN" "18"
					( Origin gPackager )
				)
				( objectStatus "J6L1.18" )
			)
			( pin "@baseboard_fab2_lib.baseboard_fab2(sch_1):page54_i66:dqs11n"
				( attribute "PN" "30"
					( Origin gPackager )
				)
				( objectStatus "J6L1.30" )
			)
			( pin "@baseboard_fab2_lib.baseboard_fab2(sch_1):page54_i66:dqs11p"
				( attribute "PN" "29"
					( Origin gPackager )
				)
				( objectStatus "J6L1.29" )
			)
			( pin "@baseboard_fab2_lib.baseboard_fab2(sch_1):page54_i66:dqs12n"
				( attribute "PN" "41"
					( Origin gPackager )
				)
				( objectStatus "J6L1.41" )
			)
			( pin "@baseboard_fab2_lib.baseboard_fab2(sch_1):page54_i66:dqs12p"
				( attribute "PN" "40"
					( Origin gPackager )
				)
				( objectStatus "J6L1.40" )
			)
			( pin "@baseboard_fab2_lib.baseboard_fab2(sch_1):page54_i66:dqs13n"
				( attribute "PN" "100"
					( Origin gPackager )
				)
				( objectStatus "J6L1.100" )
			)
			( pin "@baseboard_fab2_lib.baseboard_fab2(sch_1):page54_i66:dqs13p"
				( attribute "PN" "99"
					( Origin gPackager )
				)
				( objectStatus "J6L1.99" )
			)
			( pin "@baseboard_fab2_lib.baseboard_fab2(sch_1):page54_i66:dqs14n"
				( attribute "PN" "111"
					( Origin gPackager )
				)
				( objectStatus "J6L1.111" )
			)
			( pin "@baseboard_fab2_lib.baseboard_fab2(sch_1):page54_i66:dqs14p"
				( attribute "PN" "110"
					( Origin gPackager )
				)
				( objectStatus "J6L1.110" )
			)
			( pin "@baseboard_fab2_lib.baseboard_fab2(sch_1):page54_i66:dqs15n"
				( attribute "PN" "122"
					( Origin gPackager )
				)
				( objectStatus "J6L1.122" )
			)
			( pin "@baseboard_fab2_lib.baseboard_fab2(sch_1):page54_i66:dqs15p"
				( attribute "PN" "121"
					( Origin gPackager )
				)
				( objectStatus "J6L1.121" )
			)
			( pin "@baseboard_fab2_lib.baseboard_fab2(sch_1):page54_i66:dqs16n"
				( attribute "PN" "133"
					( Origin gPackager )
				)
				( objectStatus "J6L1.133" )
			)
			( pin "@baseboard_fab2_lib.baseboard_fab2(sch_1):page54_i66:dqs16p"
				( attribute "PN" "132"
					( Origin gPackager )
				)
				( objectStatus "J6L1.132" )
			)
			( pin "@baseboard_fab2_lib.baseboard_fab2(sch_1):page54_i66:dqs17n"
				( attribute "PN" "52"
					( Origin gPackager )
				)
				( objectStatus "J6L1.52" )
			)
			( pin "@baseboard_fab2_lib.baseboard_fab2(sch_1):page54_i66:dqs17p"
				( attribute "PN" "51"
					( Origin gPackager )
				)
				( objectStatus "J6L1.51" )
			)
			( pin "@baseboard_fab2_lib.baseboard_fab2(sch_1):page54_i111:a0"
				( attribute "PN" "79"
					( Origin gPackager )
				)
				( objectStatus "J6L1.79" )
			)
			( pin "@baseboard_fab2_lib.baseboard_fab2(sch_1):page54_i111:a1"
				( attribute "PN" "72"
					( Origin gPackager )
				)
				( objectStatus "J6L1.72" )
			)
			( pin "@baseboard_fab2_lib.baseboard_fab2(sch_1):page54_i111:a2"
				( attribute "PN" "216"
					( Origin gPackager )
				)
				( objectStatus "J6L1.216" )
			)
			( pin "@baseboard_fab2_lib.baseboard_fab2(sch_1):page54_i111:a3"
				( attribute "PN" "71"
					( Origin gPackager )
				)
				( objectStatus "J6L1.71" )
			)
			( pin "@baseboard_fab2_lib.baseboard_fab2(sch_1):page54_i111:a4"
				( attribute "PN" "214"
					( Origin gPackager )
				)
				( objectStatus "J6L1.214" )
			)
			( pin "@baseboard_fab2_lib.baseboard_fab2(sch_1):page54_i111:a5"
				( attribute "PN" "213"
					( Origin gPackager )
				)
				( objectStatus "J6L1.213" )
			)
			( pin "@baseboard_fab2_lib.baseboard_fab2(sch_1):page54_i111:a6"
				( attribute "PN" "69"
					( Origin gPackager )
				)
				( objectStatus "J6L1.69" )
			)
			( pin "@baseboard_fab2_lib.baseboard_fab2(sch_1):page54_i111:a7"
				( attribute "PN" "211"
					( Origin gPackager )
				)
				( objectStatus "J6L1.211" )
			)
			( pin "@baseboard_fab2_lib.baseboard_fab2(sch_1):page54_i111:a8"
				( attribute "PN" "68"
					( Origin gPackager )
				)
				( objectStatus "J6L1.68" )
			)
			( pin "@baseboard_fab2_lib.baseboard_fab2(sch_1):page54_i111:a9"
				( attribute "PN" "66"
					( Origin gPackager )
				)
				( objectStatus "J6L1.66" )
			)
			( pin "@baseboard_fab2_lib.baseboard_fab2(sch_1):page54_i111:a10"
				( attribute "PN" "225"
					( Origin gPackager )
				)
				( objectStatus "J6L1.225" )
			)
			( pin "@baseboard_fab2_lib.baseboard_fab2(sch_1):page54_i111:a11"
				( attribute "PN" "210"
					( Origin gPackager )
				)
				( objectStatus "J6L1.210" )
			)
			( pin "@baseboard_fab2_lib.baseboard_fab2(sch_1):page54_i111:a12"
				( attribute "PN" "65"
					( Origin gPackager )
				)
				( objectStatus "J6L1.65" )
			)
			( pin "@baseboard_fab2_lib.baseboard_fab2(sch_1):page54_i111:a13"
				( attribute "PN" "232"
					( Origin gPackager )
				)
				( objectStatus "J6L1.232" )
			)
			( pin "@baseboard_fab2_lib.baseboard_fab2(sch_1):page54_i111:a14_we_n"
				( attribute "PN" "228"
					( Origin gPackager )
				)
				( objectStatus "J6L1.228" )
			)
			( pin "@baseboard_fab2_lib.baseboard_fab2(sch_1):page54_i111:a15_cas_n"
				( attribute "PN" "86"
					( Origin gPackager )
				)
				( objectStatus "J6L1.86" )
			)
			( pin "@baseboard_fab2_lib.baseboard_fab2(sch_1):page54_i111:a16_ras_n"
				( attribute "PN" "82"
					( Origin gPackager )
				)
				( objectStatus "J6L1.82" )
			)
			( pin "@baseboard_fab2_lib.baseboard_fab2(sch_1):page54_i111:a17"
				( attribute "PN" "234"
					( Origin gPackager )
				)
				( objectStatus "J6L1.234" )
			)
			( pin "@baseboard_fab2_lib.baseboard_fab2(sch_1):page54_i111:act_n"
				( attribute "PN" "62"
					( Origin gPackager )
				)
				( objectStatus "J6L1.62" )
			)
			( pin "@baseboard_fab2_lib.baseboard_fab2(sch_1):page54_i111:alert_n"
				( attribute "PN" "208"
					( Origin gPackager )
				)
				( objectStatus "J6L1.208" )
			)
			( pin "@baseboard_fab2_lib.baseboard_fab2(sch_1):page54_i111:ba(0)"
				( attribute "PN" "81"
					( Origin gPackager )
				)
				( objectStatus "J6L1.81" )
			)
			( pin "@baseboard_fab2_lib.baseboard_fab2(sch_1):page54_i111:ba(1)"
				( attribute "PN" "224"
					( Origin gPackager )
				)
				( objectStatus "J6L1.224" )
			)
			( pin "@baseboard_fab2_lib.baseboard_fab2(sch_1):page54_i111:bg(0)"
				( attribute "PN" "63"
					( Origin gPackager )
				)
				( objectStatus "J6L1.63" )
			)
			( pin "@baseboard_fab2_lib.baseboard_fab2(sch_1):page54_i111:bg(1)"
				( attribute "PN" "207"
					( Origin gPackager )
				)
				( objectStatus "J6L1.207" )
			)
			( pin "@baseboard_fab2_lib.baseboard_fab2(sch_1):page54_i111:c(2)"
				( attribute "PN" "235"
					( Origin gPackager )
				)
				( objectStatus "J6L1.235" )
			)
			( pin "@baseboard_fab2_lib.baseboard_fab2(sch_1):page54_i111:cb(0)"
				( attribute "PN" "49"
					( Origin gPackager )
				)
				( objectStatus "J6L1.49" )
			)
			( pin "@baseboard_fab2_lib.baseboard_fab2(sch_1):page54_i111:cb(1)"
				( attribute "PN" "194"
					( Origin gPackager )
				)
				( objectStatus "J6L1.194" )
			)
			( pin "@baseboard_fab2_lib.baseboard_fab2(sch_1):page54_i111:cb(2)"
				( attribute "PN" "56"
					( Origin gPackager )
				)
				( objectStatus "J6L1.56" )
			)
			( pin "@baseboard_fab2_lib.baseboard_fab2(sch_1):page54_i111:cb(3)"
				( attribute "PN" "201"
					( Origin gPackager )
				)
				( objectStatus "J6L1.201" )
			)
			( pin "@baseboard_fab2_lib.baseboard_fab2(sch_1):page54_i111:cb(4)"
				( attribute "PN" "47"
					( Origin gPackager )
				)
				( objectStatus "J6L1.47" )
			)
			( pin "@baseboard_fab2_lib.baseboard_fab2(sch_1):page54_i111:cb(5)"
				( attribute "PN" "192"
					( Origin gPackager )
				)
				( objectStatus "J6L1.192" )
			)
			( pin "@baseboard_fab2_lib.baseboard_fab2(sch_1):page54_i111:cb(6)"
				( attribute "PN" "54"
					( Origin gPackager )
				)
				( objectStatus "J6L1.54" )
			)
			( pin "@baseboard_fab2_lib.baseboard_fab2(sch_1):page54_i111:cb(7)"
				( attribute "PN" "199"
					( Origin gPackager )
				)
				( objectStatus "J6L1.199" )
			)
			( pin "@baseboard_fab2_lib.baseboard_fab2(sch_1):page54_i111:ck0n"
				( attribute "PN" "75"
					( Origin gPackager )
				)
				( objectStatus "J6L1.75" )
			)
			( pin "@baseboard_fab2_lib.baseboard_fab2(sch_1):page54_i111:ck0p"
				( attribute "PN" "74"
					( Origin gPackager )
				)
				( objectStatus "J6L1.74" )
			)
			( pin "@baseboard_fab2_lib.baseboard_fab2(sch_1):page54_i111:ck1n"
				( attribute "PN" "219"
					( Origin gPackager )
				)
				( objectStatus "J6L1.219" )
			)
			( pin "@baseboard_fab2_lib.baseboard_fab2(sch_1):page54_i111:ck1p"
				( attribute "PN" "218"
					( Origin gPackager )
				)
				( objectStatus "J6L1.218" )
			)
			( pin "@baseboard_fab2_lib.baseboard_fab2(sch_1):page54_i111:cke(0)"
				( attribute "PN" "60"
					( Origin gPackager )
				)
				( objectStatus "J6L1.60" )
			)
			( pin "@baseboard_fab2_lib.baseboard_fab2(sch_1):page54_i111:cke(1)"
				( attribute "PN" "203"
					( Origin gPackager )
				)
				( objectStatus "J6L1.203" )
			)
			( pin "@baseboard_fab2_lib.baseboard_fab2(sch_1):page54_i111:dq(0)"
				( attribute "PN" "5"
					( Origin gPackager )
				)
				( objectStatus "J6L1.5" )
			)
			( pin "@baseboard_fab2_lib.baseboard_fab2(sch_1):page54_i111:dq(1)"
				( attribute "PN" "150"
					( Origin gPackager )
				)
				( objectStatus "J6L1.150" )
			)
			( pin "@baseboard_fab2_lib.baseboard_fab2(sch_1):page54_i111:dq(2)"
				( attribute "PN" "12"
					( Origin gPackager )
				)
				( objectStatus "J6L1.12" )
			)
			( pin "@baseboard_fab2_lib.baseboard_fab2(sch_1):page54_i111:dq(3)"
				( attribute "PN" "157"
					( Origin gPackager )
				)
				( objectStatus "J6L1.157" )
			)
			( pin "@baseboard_fab2_lib.baseboard_fab2(sch_1):page54_i111:dq(4)"
				( attribute "PN" "3"
					( Origin gPackager )
				)
				( objectStatus "J6L1.3" )
			)
			( pin "@baseboard_fab2_lib.baseboard_fab2(sch_1):page54_i111:dq(5)"
				( attribute "PN" "148"
					( Origin gPackager )
				)
				( objectStatus "J6L1.148" )
			)
			( pin "@baseboard_fab2_lib.baseboard_fab2(sch_1):page54_i111:dq(6)"
				( attribute "PN" "10"
					( Origin gPackager )
				)
				( objectStatus "J6L1.10" )
			)
			( pin "@baseboard_fab2_lib.baseboard_fab2(sch_1):page54_i111:dq(7)"
				( attribute "PN" "155"
					( Origin gPackager )
				)
				( objectStatus "J6L1.155" )
			)
			( pin "@baseboard_fab2_lib.baseboard_fab2(sch_1):page54_i111:dq(8)"
				( attribute "PN" "16"
					( Origin gPackager )
				)
				( objectStatus "J6L1.16" )
			)
			( pin "@baseboard_fab2_lib.baseboard_fab2(sch_1):page54_i111:dq(9)"
				( attribute "PN" "161"
					( Origin gPackager )
				)
				( objectStatus "J6L1.161" )
			)
			( pin "@baseboard_fab2_lib.baseboard_fab2(sch_1):page54_i111:dq(10)"
				( attribute "PN" "23"
					( Origin gPackager )
				)
				( objectStatus "J6L1.23" )
			)
			( pin "@baseboard_fab2_lib.baseboard_fab2(sch_1):page54_i111:dq(11)"
				( attribute "PN" "168"
					( Origin gPackager )
				)
				( objectStatus "J6L1.168" )
			)
			( pin "@baseboard_fab2_lib.baseboard_fab2(sch_1):page54_i111:dq(12)"
				( attribute "PN" "14"
					( Origin gPackager )
				)
				( objectStatus "J6L1.14" )
			)
			( pin "@baseboard_fab2_lib.baseboard_fab2(sch_1):page54_i111:dq(13)"
				( attribute "PN" "159"
					( Origin gPackager )
				)
				( objectStatus "J6L1.159" )
			)
			( pin "@baseboard_fab2_lib.baseboard_fab2(sch_1):page54_i111:dq(14)"
				( attribute "PN" "21"
					( Origin gPackager )
				)
				( objectStatus "J6L1.21" )
			)
			( pin "@baseboard_fab2_lib.baseboard_fab2(sch_1):page54_i111:dq(15)"
				( attribute "PN" "166"
					( Origin gPackager )
				)
				( objectStatus "J6L1.166" )
			)
			( pin "@baseboard_fab2_lib.baseboard_fab2(sch_1):page54_i111:dq(16)"
				( attribute "PN" "27"
					( Origin gPackager )
				)
				( objectStatus "J6L1.27" )
			)
			( pin "@baseboard_fab2_lib.baseboard_fab2(sch_1):page54_i111:dq(17)"
				( attribute "PN" "172"
					( Origin gPackager )
				)
				( objectStatus "J6L1.172" )
			)
			( pin "@baseboard_fab2_lib.baseboard_fab2(sch_1):page54_i111:dq(18)"
				( attribute "PN" "34"
					( Origin gPackager )
				)
				( objectStatus "J6L1.34" )
			)
			( pin "@baseboard_fab2_lib.baseboard_fab2(sch_1):page54_i111:dq(19)"
				( attribute "PN" "179"
					( Origin gPackager )
				)
				( objectStatus "J6L1.179" )
			)
			( pin "@baseboard_fab2_lib.baseboard_fab2(sch_1):page54_i111:dq(20)"
				( attribute "PN" "25"
					( Origin gPackager )
				)
				( objectStatus "J6L1.25" )
			)
			( pin "@baseboard_fab2_lib.baseboard_fab2(sch_1):page54_i111:dq(21)"
				( attribute "PN" "170"
					( Origin gPackager )
				)
				( objectStatus "J6L1.170" )
			)
			( pin "@baseboard_fab2_lib.baseboard_fab2(sch_1):page54_i111:dq(22)"
				( attribute "PN" "32"
					( Origin gPackager )
				)
				( objectStatus "J6L1.32" )
			)
			( pin "@baseboard_fab2_lib.baseboard_fab2(sch_1):page54_i111:dq(23)"
				( attribute "PN" "177"
					( Origin gPackager )
				)
				( objectStatus "J6L1.177" )
			)
			( pin "@baseboard_fab2_lib.baseboard_fab2(sch_1):page54_i111:dq(24)"
				( attribute "PN" "38"
					( Origin gPackager )
				)
				( objectStatus "J6L1.38" )
			)
			( pin "@baseboard_fab2_lib.baseboard_fab2(sch_1):page54_i111:dq(25)"
				( attribute "PN" "183"
					( Origin gPackager )
				)
				( objectStatus "J6L1.183" )
			)
			( pin "@baseboard_fab2_lib.baseboard_fab2(sch_1):page54_i111:dq(26)"
				( attribute "PN" "45"
					( Origin gPackager )
				)
				( objectStatus "J6L1.45" )
			)
			( pin "@baseboard_fab2_lib.baseboard_fab2(sch_1):page54_i111:dq(27)"
				( attribute "PN" "190"
					( Origin gPackager )
				)
				( objectStatus "J6L1.190" )
			)
			( pin "@baseboard_fab2_lib.baseboard_fab2(sch_1):page54_i111:dq(28)"
				( attribute "PN" "36"
					( Origin gPackager )
				)
				( objectStatus "J6L1.36" )
			)
			( pin "@baseboard_fab2_lib.baseboard_fab2(sch_1):page54_i111:dq(29)"
				( attribute "PN" "181"
					( Origin gPackager )
				)
				( objectStatus "J6L1.181" )
			)
			( pin "@baseboard_fab2_lib.baseboard_fab2(sch_1):page54_i111:dq(30)"
				( attribute "PN" "43"
					( Origin gPackager )
				)
				( objectStatus "J6L1.43" )
			)
			( pin "@baseboard_fab2_lib.baseboard_fab2(sch_1):page54_i111:dq(31)"
				( attribute "PN" "188"
					( Origin gPackager )
				)
				( objectStatus "J6L1.188" )
			)
			( pin "@baseboard_fab2_lib.baseboard_fab2(sch_1):page54_i111:dq(32)"
				( attribute "PN" "97"
					( Origin gPackager )
				)
				( objectStatus "J6L1.97" )
			)
			( pin "@baseboard_fab2_lib.baseboard_fab2(sch_1):page54_i111:dq(33)"
				( attribute "PN" "242"
					( Origin gPackager )
				)
				( objectStatus "J6L1.242" )
			)
			( pin "@baseboard_fab2_lib.baseboard_fab2(sch_1):page54_i111:dq(34)"
				( attribute "PN" "104"
					( Origin gPackager )
				)
				( objectStatus "J6L1.104" )
			)
			( pin "@baseboard_fab2_lib.baseboard_fab2(sch_1):page54_i111:dq(35)"
				( attribute "PN" "249"
					( Origin gPackager )
				)
				( objectStatus "J6L1.249" )
			)
			( pin "@baseboard_fab2_lib.baseboard_fab2(sch_1):page54_i111:dq(36)"
				( attribute "PN" "95"
					( Origin gPackager )
				)
				( objectStatus "J6L1.95" )
			)
			( pin "@baseboard_fab2_lib.baseboard_fab2(sch_1):page54_i111:dq(37)"
				( attribute "PN" "240"
					( Origin gPackager )
				)
				( objectStatus "J6L1.240" )
			)
			( pin "@baseboard_fab2_lib.baseboard_fab2(sch_1):page54_i111:dq(38)"
				( attribute "PN" "102"
					( Origin gPackager )
				)
				( objectStatus "J6L1.102" )
			)
			( pin "@baseboard_fab2_lib.baseboard_fab2(sch_1):page54_i111:dq(39)"
				( attribute "PN" "247"
					( Origin gPackager )
				)
				( objectStatus "J6L1.247" )
			)
			( pin "@baseboard_fab2_lib.baseboard_fab2(sch_1):page54_i111:dq(40)"
				( attribute "PN" "108"
					( Origin gPackager )
				)
				( objectStatus "J6L1.108" )
			)
			( pin "@baseboard_fab2_lib.baseboard_fab2(sch_1):page54_i111:dq(41)"
				( attribute "PN" "253"
					( Origin gPackager )
				)
				( objectStatus "J6L1.253" )
			)
			( pin "@baseboard_fab2_lib.baseboard_fab2(sch_1):page54_i111:dq(42)"
				( attribute "PN" "115"
					( Origin gPackager )
				)
				( objectStatus "J6L1.115" )
			)
			( pin "@baseboard_fab2_lib.baseboard_fab2(sch_1):page54_i111:dq(43)"
				( attribute "PN" "260"
					( Origin gPackager )
				)
				( objectStatus "J6L1.260" )
			)
			( pin "@baseboard_fab2_lib.baseboard_fab2(sch_1):page54_i111:dq(44)"
				( attribute "PN" "106"
					( Origin gPackager )
				)
				( objectStatus "J6L1.106" )
			)
			( pin "@baseboard_fab2_lib.baseboard_fab2(sch_1):page54_i111:dq(45)"
				( attribute "PN" "251"
					( Origin gPackager )
				)
				( objectStatus "J6L1.251" )
			)
			( pin "@baseboard_fab2_lib.baseboard_fab2(sch_1):page54_i111:dq(46)"
				( attribute "PN" "113"
					( Origin gPackager )
				)
				( objectStatus "J6L1.113" )
			)
			( pin "@baseboard_fab2_lib.baseboard_fab2(sch_1):page54_i111:dq(47)"
				( attribute "PN" "258"
					( Origin gPackager )
				)
				( objectStatus "J6L1.258" )
			)
			( pin "@baseboard_fab2_lib.baseboard_fab2(sch_1):page54_i111:dq(48)"
				( attribute "PN" "119"
					( Origin gPackager )
				)
				( objectStatus "J6L1.119" )
			)
			( pin "@baseboard_fab2_lib.baseboard_fab2(sch_1):page54_i111:dq(49)"
				( attribute "PN" "264"
					( Origin gPackager )
				)
				( objectStatus "J6L1.264" )
			)
			( pin "@baseboard_fab2_lib.baseboard_fab2(sch_1):page54_i111:dq(50)"
				( attribute "PN" "126"
					( Origin gPackager )
				)
				( objectStatus "J6L1.126" )
			)
			( pin "@baseboard_fab2_lib.baseboard_fab2(sch_1):page54_i111:dq(51)"
				( attribute "PN" "271"
					( Origin gPackager )
				)
				( objectStatus "J6L1.271" )
			)
			( pin "@baseboard_fab2_lib.baseboard_fab2(sch_1):page54_i111:dq(52)"
				( attribute "PN" "117"
					( Origin gPackager )
				)
				( objectStatus "J6L1.117" )
			)
			( pin "@baseboard_fab2_lib.baseboard_fab2(sch_1):page54_i111:dq(53)"
				( attribute "PN" "262"
					( Origin gPackager )
				)
				( objectStatus "J6L1.262" )
			)
			( pin "@baseboard_fab2_lib.baseboard_fab2(sch_1):page54_i111:dq(54)"
				( attribute "PN" "124"
					( Origin gPackager )
				)
				( objectStatus "J6L1.124" )
			)
			( pin "@baseboard_fab2_lib.baseboard_fab2(sch_1):page54_i111:dq(55)"
				( attribute "PN" "269"
					( Origin gPackager )
				)
				( objectStatus "J6L1.269" )
			)
			( pin "@baseboard_fab2_lib.baseboard_fab2(sch_1):page54_i111:dq(56)"
				( attribute "PN" "130"
					( Origin gPackager )
				)
				( objectStatus "J6L1.130" )
			)
			( pin "@baseboard_fab2_lib.baseboard_fab2(sch_1):page54_i111:dq(57)"
				( attribute "PN" "275"
					( Origin gPackager )
				)
				( objectStatus "J6L1.275" )
			)
			( pin "@baseboard_fab2_lib.baseboard_fab2(sch_1):page54_i111:dq(58)"
				( attribute "PN" "137"
					( Origin gPackager )
				)
				( objectStatus "J6L1.137" )
			)
			( pin "@baseboard_fab2_lib.baseboard_fab2(sch_1):page54_i111:dq(59)"
				( attribute "PN" "282"
					( Origin gPackager )
				)
				( objectStatus "J6L1.282" )
			)
			( pin "@baseboard_fab2_lib.baseboard_fab2(sch_1):page54_i111:dq(60)"
				( attribute "PN" "128"
					( Origin gPackager )
				)
				( objectStatus "J6L1.128" )
			)
			( pin "@baseboard_fab2_lib.baseboard_fab2(sch_1):page54_i111:dq(61)"
				( attribute "PN" "273"
					( Origin gPackager )
				)
				( objectStatus "J6L1.273" )
			)
			( pin "@baseboard_fab2_lib.baseboard_fab2(sch_1):page54_i111:dq(62)"
				( attribute "PN" "135"
					( Origin gPackager )
				)
				( objectStatus "J6L1.135" )
			)
			( pin "@baseboard_fab2_lib.baseboard_fab2(sch_1):page54_i111:dq(63)"
				( attribute "PN" "280"
					( Origin gPackager )
				)
				( objectStatus "J6L1.280" )
			)
			( pin "@baseboard_fab2_lib.baseboard_fab2(sch_1):page54_i111:event_n"
				( attribute "PN" "78"
					( Origin gPackager )
				)
				( objectStatus "J6L1.78" )
			)
			( pin "@baseboard_fab2_lib.baseboard_fab2(sch_1):page54_i111:odt(0)"
				( attribute "PN" "87"
					( Origin gPackager )
				)
				( objectStatus "J6L1.87" )
			)
			( pin "@baseboard_fab2_lib.baseboard_fab2(sch_1):page54_i111:odt(1)"
				( attribute "PN" "91"
					( Origin gPackager )
				)
				( objectStatus "J6L1.91" )
			)
			( pin "@baseboard_fab2_lib.baseboard_fab2(sch_1):page54_i111:par"
				( attribute "PN" "222"
					( Origin gPackager )
				)
				( objectStatus "J6L1.222" )
			)
			( pin "@baseboard_fab2_lib.baseboard_fab2(sch_1):page54_i111:reset_n"
				( attribute "PN" "58"
					( Origin gPackager )
				)
				( objectStatus "J6L1.58" )
			)
			( pin "@baseboard_fab2_lib.baseboard_fab2(sch_1):page54_i111:rfu(0)"
				( attribute "PN" "205"
					( Origin gPackager )
				)
				( objectStatus "J6L1.205" )
			)
			( pin "@baseboard_fab2_lib.baseboard_fab2(sch_1):page54_i111:rfu(1)"
				( attribute "PN" "227"
					( Origin gPackager )
				)
				( objectStatus "J6L1.227" )
			)
			( pin "@baseboard_fab2_lib.baseboard_fab2(sch_1):page54_i111:rfu(2)"
				( attribute "PN" "144"
					( Origin gPackager )
				)
				( objectStatus "J6L1.144" )
			)
			( pin "@baseboard_fab2_lib.baseboard_fab2(sch_1):page54_i111:s0_n"
				( attribute "PN" "84"
					( Origin gPackager )
				)
				( objectStatus "J6L1.84" )
			)
			( pin "@baseboard_fab2_lib.baseboard_fab2(sch_1):page54_i111:s1_n"
				( attribute "PN" "89"
					( Origin gPackager )
				)
				( objectStatus "J6L1.89" )
			)
			( pin "@baseboard_fab2_lib.baseboard_fab2(sch_1):page54_i111:s2_n_c(0)"
				( attribute "PN" "93"
					( Origin gPackager )
				)
				( objectStatus "J6L1.93" )
			)
			( pin "@baseboard_fab2_lib.baseboard_fab2(sch_1):page54_i111:s3_n_c(1)"
				( attribute "PN" "237"
					( Origin gPackager )
				)
				( objectStatus "J6L1.237" )
			)
			( pin "@baseboard_fab2_lib.baseboard_fab2(sch_1):page54_i111:sa(0)"
				( attribute "PN" "139"
					( Origin gPackager )
				)
				( objectStatus "J6L1.139" )
			)
			( pin "@baseboard_fab2_lib.baseboard_fab2(sch_1):page54_i111:sa(1)"
				( attribute "PN" "140"
					( Origin gPackager )
				)
				( objectStatus "J6L1.140" )
			)
			( pin "@baseboard_fab2_lib.baseboard_fab2(sch_1):page54_i111:sa(2)"
				( attribute "PN" "238"
					( Origin gPackager )
				)
				( objectStatus "J6L1.238" )
			)
			( pin "@baseboard_fab2_lib.baseboard_fab2(sch_1):page54_i111:save_n_nc"
				( attribute "PN" "230"
					( Origin gPackager )
				)
				( objectStatus "J6L1.230" )
			)
			( pin "@baseboard_fab2_lib.baseboard_fab2(sch_1):page54_i111:scl"
				( attribute "PN" "141"
					( Origin gPackager )
				)
				( objectStatus "J6L1.141" )
			)
			( pin "@baseboard_fab2_lib.baseboard_fab2(sch_1):page54_i111:sda"
				( attribute "PN" "285"
					( Origin gPackager )
				)
				( objectStatus "J6L1.285" )
			)
			( pin "@baseboard_fab2_lib.baseboard_fab2(sch_1):page54_i111:vddspd"
				( attribute "PN" "284"
					( Origin gPackager )
				)
				( objectStatus "J6L1.284" )
			)
			( pin "@baseboard_fab2_lib.baseboard_fab2(sch_1):page54_i111:vrefca"
				( attribute "PN" "146"
					( Origin gPackager )
				)
				( objectStatus "J6L1.146" )
			)
			( pin "@baseboard_fab2_lib.baseboard_fab2(sch_1):page54_i170:\12v\(0)"
				( attribute "PN" "145"
					( Origin gPackager )
				)
				( objectStatus "J6L1.145" )
			)
			( pin "@baseboard_fab2_lib.baseboard_fab2(sch_1):page54_i170:\12v\(1)"
				( attribute "PN" "1"
					( Origin gPackager )
				)
				( objectStatus "J6L1.1" )
			)
			( pin "@baseboard_fab2_lib.baseboard_fab2(sch_1):page54_i170:vdd(0)"
				( attribute "PN" "236"
					( Origin gPackager )
				)
				( objectStatus "J6L1.236" )
			)
			( pin "@baseboard_fab2_lib.baseboard_fab2(sch_1):page54_i170:vdd(1)"
				( attribute "PN" "233"
					( Origin gPackager )
				)
				( objectStatus "J6L1.233" )
			)
			( pin "@baseboard_fab2_lib.baseboard_fab2(sch_1):page54_i170:vdd(2)"
				( attribute "PN" "231"
					( Origin gPackager )
				)
				( objectStatus "J6L1.231" )
			)
			( pin "@baseboard_fab2_lib.baseboard_fab2(sch_1):page54_i170:vdd(3)"
				( attribute "PN" "229"
					( Origin gPackager )
				)
				( objectStatus "J6L1.229" )
			)
			( pin "@baseboard_fab2_lib.baseboard_fab2(sch_1):page54_i170:vdd(4)"
				( attribute "PN" "226"
					( Origin gPackager )
				)
				( objectStatus "J6L1.226" )
			)
			( pin "@baseboard_fab2_lib.baseboard_fab2(sch_1):page54_i170:vdd(5)"
				( attribute "PN" "223"
					( Origin gPackager )
				)
				( objectStatus "J6L1.223" )
			)
			( pin "@baseboard_fab2_lib.baseboard_fab2(sch_1):page54_i170:vdd(6)"
				( attribute "PN" "220"
					( Origin gPackager )
				)
				( objectStatus "J6L1.220" )
			)
			( pin "@baseboard_fab2_lib.baseboard_fab2(sch_1):page54_i170:vdd(7)"
				( attribute "PN" "217"
					( Origin gPackager )
				)
				( objectStatus "J6L1.217" )
			)
			( pin "@baseboard_fab2_lib.baseboard_fab2(sch_1):page54_i170:vdd(8)"
				( attribute "PN" "215"
					( Origin gPackager )
				)
				( objectStatus "J6L1.215" )
			)
			( pin "@baseboard_fab2_lib.baseboard_fab2(sch_1):page54_i170:vdd(9)"
				( attribute "PN" "212"
					( Origin gPackager )
				)
				( objectStatus "J6L1.212" )
			)
			( pin "@baseboard_fab2_lib.baseboard_fab2(sch_1):page54_i170:vdd(10)"
				( attribute "PN" "209"
					( Origin gPackager )
				)
				( objectStatus "J6L1.209" )
			)
			( pin "@baseboard_fab2_lib.baseboard_fab2(sch_1):page54_i170:vdd(11)"
				( attribute "PN" "206"
					( Origin gPackager )
				)
				( objectStatus "J6L1.206" )
			)
			( pin "@baseboard_fab2_lib.baseboard_fab2(sch_1):page54_i170:vdd(12)"
				( attribute "PN" "204"
					( Origin gPackager )
				)
				( objectStatus "J6L1.204" )
			)
			( pin "@baseboard_fab2_lib.baseboard_fab2(sch_1):page54_i170:vdd(13)"
				( attribute "PN" "92"
					( Origin gPackager )
				)
				( objectStatus "J6L1.92" )
			)
			( pin "@baseboard_fab2_lib.baseboard_fab2(sch_1):page54_i170:vdd(14)"
				( attribute "PN" "90"
					( Origin gPackager )
				)
				( objectStatus "J6L1.90" )
			)
			( pin "@baseboard_fab2_lib.baseboard_fab2(sch_1):page54_i170:vdd(15)"
				( attribute "PN" "88"
					( Origin gPackager )
				)
				( objectStatus "J6L1.88" )
			)
			( pin "@baseboard_fab2_lib.baseboard_fab2(sch_1):page54_i170:vdd(16)"
				( attribute "PN" "85"
					( Origin gPackager )
				)
				( objectStatus "J6L1.85" )
			)
			( pin "@baseboard_fab2_lib.baseboard_fab2(sch_1):page54_i170:vdd(17)"
				( attribute "PN" "83"
					( Origin gPackager )
				)
				( objectStatus "J6L1.83" )
			)
			( pin "@baseboard_fab2_lib.baseboard_fab2(sch_1):page54_i170:vdd(18)"
				( attribute "PN" "80"
					( Origin gPackager )
				)
				( objectStatus "J6L1.80" )
			)
			( pin "@baseboard_fab2_lib.baseboard_fab2(sch_1):page54_i170:vdd(19)"
				( attribute "PN" "76"
					( Origin gPackager )
				)
				( objectStatus "J6L1.76" )
			)
			( pin "@baseboard_fab2_lib.baseboard_fab2(sch_1):page54_i170:vdd(20)"
				( attribute "PN" "73"
					( Origin gPackager )
				)
				( objectStatus "J6L1.73" )
			)
			( pin "@baseboard_fab2_lib.baseboard_fab2(sch_1):page54_i170:vdd(21)"
				( attribute "PN" "70"
					( Origin gPackager )
				)
				( objectStatus "J6L1.70" )
			)
			( pin "@baseboard_fab2_lib.baseboard_fab2(sch_1):page54_i170:vdd(22)"
				( attribute "PN" "67"
					( Origin gPackager )
				)
				( objectStatus "J6L1.67" )
			)
			( pin "@baseboard_fab2_lib.baseboard_fab2(sch_1):page54_i170:vdd(23)"
				( attribute "PN" "64"
					( Origin gPackager )
				)
				( objectStatus "J6L1.64" )
			)
			( pin "@baseboard_fab2_lib.baseboard_fab2(sch_1):page54_i170:vdd(24)"
				( attribute "PN" "61"
					( Origin gPackager )
				)
				( objectStatus "J6L1.61" )
			)
			( pin "@baseboard_fab2_lib.baseboard_fab2(sch_1):page54_i170:vdd(25)"
				( attribute "PN" "59"
					( Origin gPackager )
				)
				( objectStatus "J6L1.59" )
			)
			( pin "@baseboard_fab2_lib.baseboard_fab2(sch_1):page54_i170:vpp(0)"
				( attribute "PN" "287"
					( Origin gPackager )
				)
				( objectStatus "J6L1.287" )
			)
			( pin "@baseboard_fab2_lib.baseboard_fab2(sch_1):page54_i170:vpp(1)"
				( attribute "PN" "286"
					( Origin gPackager )
				)
				( objectStatus "J6L1.286" )
			)
			( pin "@baseboard_fab2_lib.baseboard_fab2(sch_1):page54_i170:vpp(2)"
				( attribute "PN" "288"
					( Origin gPackager )
				)
				( objectStatus "J6L1.288" )
			)
			( pin "@baseboard_fab2_lib.baseboard_fab2(sch_1):page54_i170:vpp(3)"
				( attribute "PN" "143"
					( Origin gPackager )
				)
				( objectStatus "J6L1.143" )
			)
			( pin "@baseboard_fab2_lib.baseboard_fab2(sch_1):page54_i170:vpp(4)"
				( attribute "PN" "142"
					( Origin gPackager )
				)
				( objectStatus "J6L1.142" )
			)
			( pin "@baseboard_fab2_lib.baseboard_fab2(sch_1):page54_i170:vtt(0)"
				( attribute "PN" "221"
					( Origin gPackager )
				)
				( objectStatus "J6L1.221" )
			)
			( pin "@baseboard_fab2_lib.baseboard_fab2(sch_1):page54_i170:vtt(1)"
				( attribute "PN" "77"
					( Origin gPackager )
				)
				( objectStatus "J6L1.77" )
			)
			( pin "@baseboard_fab2_lib.baseboard_fab2(sch_1):page54_i179:a"
				( attribute "PN" "1"
					( Origin gPackager )
				)
				( objectStatus "C4A5.1" )
			)
			( pin "@baseboard_fab2_lib.baseboard_fab2(sch_1):page54_i179:b"
				( attribute "PN" "2"
					( Origin gPackager )
				)
				( objectStatus "C4A5.2" )
			)
			( pin "@baseboard_fab2_lib.baseboard_fab2(sch_1):page55_i4:a"
				( attribute "PN" "1"
					( Origin gPackager )
				)
				( objectStatus "R9N1.1" )
			)
			( pin "@baseboard_fab2_lib.baseboard_fab2(sch_1):page55_i4:b"
				( attribute "PN" "2"
					( Origin gPackager )
				)
				( objectStatus "R9N1.2" )
			)
			( pin "@baseboard_fab2_lib.baseboard_fab2(sch_1):page55_i7:a"
				( attribute "PN" "1"
					( Origin gPackager )
				)
				( objectStatus "R9N2.1" )
			)
			( pin "@baseboard_fab2_lib.baseboard_fab2(sch_1):page55_i7:b"
				( attribute "PN" "2"
					( Origin gPackager )
				)
				( objectStatus "R9N2.2" )
			)
			( pin "@baseboard_fab2_lib.baseboard_fab2(sch_1):page55_i19:a"
				( attribute "PN" "1"
					( Origin gPackager )
				)
				( objectStatus "R3B2.1" )
			)
			( pin "@baseboard_fab2_lib.baseboard_fab2(sch_1):page55_i19:b"
				( attribute "PN" "2"
					( Origin gPackager )
				)
				( objectStatus "R3B2.2" )
			)
			( pin "@baseboard_fab2_lib.baseboard_fab2(sch_1):page55_i21:a"
				( attribute "PN" "1"
					( Origin gPackager )
				)
				( objectStatus "R3B4.1" )
			)
			( pin "@baseboard_fab2_lib.baseboard_fab2(sch_1):page55_i21:b"
				( attribute "PN" "2"
					( Origin gPackager )
				)
				( objectStatus "R3B4.2" )
			)
			( pin "@baseboard_fab2_lib.baseboard_fab2(sch_1):page55_i24:a"
				( attribute "PN" "1"
					( Origin gPackager )
				)
				( objectStatus "R1C2.1" )
			)
			( pin "@baseboard_fab2_lib.baseboard_fab2(sch_1):page55_i24:b"
				( attribute "PN" "2"
					( Origin gPackager )
				)
				( objectStatus "R1C2.2" )
			)
			( pin "@baseboard_fab2_lib.baseboard_fab2(sch_1):page55_i25:a"
				( attribute "PN" "1"
					( Origin gPackager )
				)
				( objectStatus "R1C3.1" )
			)
			( pin "@baseboard_fab2_lib.baseboard_fab2(sch_1):page55_i25:b"
				( attribute "PN" "2"
					( Origin gPackager )
				)
				( objectStatus "R1C3.2" )
			)
			( pin "@baseboard_fab2_lib.baseboard_fab2(sch_1):page55_i26:a"
				( attribute "PN" "1"
					( Origin gPackager )
				)
				( objectStatus "R1C1.1" )
			)
			( pin "@baseboard_fab2_lib.baseboard_fab2(sch_1):page55_i26:b"
				( attribute "PN" "2"
					( Origin gPackager )
				)
				( objectStatus "R1C1.2" )
			)
			( pin "@baseboard_fab2_lib.baseboard_fab2(sch_1):page55_i27:a"
				( attribute "PN" "1"
					( Origin gPackager )
				)
				( objectStatus "R3B1.1" )
			)
			( pin "@baseboard_fab2_lib.baseboard_fab2(sch_1):page55_i27:b"
				( attribute "PN" "2"
					( Origin gPackager )
				)
				( objectStatus "R3B1.2" )
			)
			( pin "@baseboard_fab2_lib.baseboard_fab2(sch_1):page55_i28:a"
				( attribute "PN" "1"
					( Origin gPackager )
				)
				( objectStatus "R3B5.1" )
			)
			( pin "@baseboard_fab2_lib.baseboard_fab2(sch_1):page55_i28:b"
				( attribute "PN" "2"
					( Origin gPackager )
				)
				( objectStatus "R3B5.2" )
			)
			( pin "@baseboard_fab2_lib.baseboard_fab2(sch_1):page55_i29:a"
				( attribute "PN" "1"
					( Origin gPackager )
				)
				( objectStatus "R3B3.1" )
			)
			( pin "@baseboard_fab2_lib.baseboard_fab2(sch_1):page55_i29:b"
				( attribute "PN" "2"
					( Origin gPackager )
				)
				( objectStatus "R3B3.2" )
			)
			( pin "@baseboard_fab2_lib.baseboard_fab2(sch_1):page55_i115:a"
				( attribute "PN" "1"
					( Origin gPackager )
				)
				( objectStatus "R7P19.1" )
			)
			( pin "@baseboard_fab2_lib.baseboard_fab2(sch_1):page55_i115:b"
				( attribute "PN" "2"
					( Origin gPackager )
				)
				( objectStatus "R7P19.2" )
			)
			( pin "@baseboard_fab2_lib.baseboard_fab2(sch_1):page55_i116:a"
				( attribute "PN" "1"
					( Origin gPackager )
				)
				( objectStatus "R3D1.1" )
			)
			( pin "@baseboard_fab2_lib.baseboard_fab2(sch_1):page55_i116:b"
				( attribute "PN" "2"
					( Origin gPackager )
				)
				( objectStatus "R3D1.2" )
			)
			( pin "@baseboard_fab2_lib.baseboard_fab2(sch_1):page55_i117:a"
				( attribute "PN" "1"
					( Origin gPackager )
				)
				( objectStatus "R3D2.1" )
			)
			( pin "@baseboard_fab2_lib.baseboard_fab2(sch_1):page55_i117:b"
				( attribute "PN" "2"
					( Origin gPackager )
				)
				( objectStatus "R3D2.2" )
			)
			( pin "@baseboard_fab2_lib.baseboard_fab2(sch_1):page55_i118:a"
				( attribute "PN" "1"
					( Origin gPackager )
				)
				( objectStatus "R3D3.1" )
			)
			( pin "@baseboard_fab2_lib.baseboard_fab2(sch_1):page55_i118:b"
				( attribute "PN" "2"
					( Origin gPackager )
				)
				( objectStatus "R3D3.2" )
			)
			( pin "@baseboard_fab2_lib.baseboard_fab2(sch_1):page55_i119:a"
				( attribute "PN" "1"
					( Origin gPackager )
				)
				( objectStatus "R7P16.1" )
			)
			( pin "@baseboard_fab2_lib.baseboard_fab2(sch_1):page55_i119:b"
				( attribute "PN" "2"
					( Origin gPackager )
				)
				( objectStatus "R7P16.2" )
			)
			( pin "@baseboard_fab2_lib.baseboard_fab2(sch_1):page55_i123:a"
				( attribute "PN" "1"
					( Origin gPackager )
				)
				( objectStatus "R7P8.1" )
			)
			( pin "@baseboard_fab2_lib.baseboard_fab2(sch_1):page55_i123:b"
				( attribute "PN" "2"
					( Origin gPackager )
				)
				( objectStatus "R7P8.2" )
			)
			( pin "@baseboard_fab2_lib.baseboard_fab2(sch_1):page55_i124:a"
				( attribute "PN" "1"
					( Origin gPackager )
				)
				( objectStatus "R7P10.1" )
			)
			( pin "@baseboard_fab2_lib.baseboard_fab2(sch_1):page55_i124:b"
				( attribute "PN" "2"
					( Origin gPackager )
				)
				( objectStatus "R7P10.2" )
			)
			( pin "@baseboard_fab2_lib.baseboard_fab2(sch_1):page55_i125:a"
				( attribute "PN" "1"
					( Origin gPackager )
				)
				( objectStatus "R3D19.1" )
			)
			( pin "@baseboard_fab2_lib.baseboard_fab2(sch_1):page55_i125:b"
				( attribute "PN" "2"
					( Origin gPackager )
				)
				( objectStatus "R3D19.2" )
			)
			( pin "@baseboard_fab2_lib.baseboard_fab2(sch_1):page55_i126:a"
				( attribute "PN" "1"
					( Origin gPackager )
				)
				( objectStatus "R7P11.1" )
			)
			( pin "@baseboard_fab2_lib.baseboard_fab2(sch_1):page55_i126:b"
				( attribute "PN" "2"
					( Origin gPackager )
				)
				( objectStatus "R7P11.2" )
			)
			( pin "@baseboard_fab2_lib.baseboard_fab2(sch_1):page55_i140:a"
				( attribute "PN" "1"
					( Origin gPackager )
				)
				( objectStatus "R7P17.1" )
			)
			( pin "@baseboard_fab2_lib.baseboard_fab2(sch_1):page55_i140:b"
				( attribute "PN" "2"
					( Origin gPackager )
				)
				( objectStatus "R7P17.2" )
			)
			( pin "@baseboard_fab2_lib.baseboard_fab2(sch_1):page55_i155:a"
				( attribute "PN" "1"
					( Origin gPackager )
				)
				( objectStatus "R3D4.1" )
			)
			( pin "@baseboard_fab2_lib.baseboard_fab2(sch_1):page55_i155:b"
				( attribute "PN" "2"
					( Origin gPackager )
				)
				( objectStatus "R3D4.2" )
			)
			( pin "@baseboard_fab2_lib.baseboard_fab2(sch_1):page55_i156:a"
				( attribute "PN" "1"
					( Origin gPackager )
				)
				( objectStatus "R7P26.1" )
			)
			( pin "@baseboard_fab2_lib.baseboard_fab2(sch_1):page55_i156:b"
				( attribute "PN" "2"
					( Origin gPackager )
				)
				( objectStatus "R7P26.2" )
			)
			( pin "@baseboard_fab2_lib.baseboard_fab2(sch_1):page55_i157:a"
				( attribute "PN" "1"
					( Origin gPackager )
				)
				( objectStatus "R8N1.1" )
			)
			( pin "@baseboard_fab2_lib.baseboard_fab2(sch_1):page55_i157:b"
				( attribute "PN" "2"
					( Origin gPackager )
				)
				( objectStatus "R8N1.2" )
			)
			( pin "@baseboard_fab2_lib.baseboard_fab2(sch_1):page55_i158:a"
				( attribute "PN" "1"
					( Origin gPackager )
				)
				( objectStatus "R8N4.1" )
			)
			( pin "@baseboard_fab2_lib.baseboard_fab2(sch_1):page55_i158:b"
				( attribute "PN" "2"
					( Origin gPackager )
				)
				( objectStatus "R8N4.2" )
			)
			( pin "@baseboard_fab2_lib.baseboard_fab2(sch_1):page55_i159:a"
				( attribute "PN" "1"
					( Origin gPackager )
				)
				( objectStatus "R8N3.1" )
			)
			( pin "@baseboard_fab2_lib.baseboard_fab2(sch_1):page55_i159:b"
				( attribute "PN" "2"
					( Origin gPackager )
				)
				( objectStatus "R8N3.2" )
			)
			( pin "@baseboard_fab2_lib.baseboard_fab2(sch_1):page55_i160:a"
				( attribute "PN" "1"
					( Origin gPackager )
				)
				( objectStatus "R8N5.1" )
			)
			( pin "@baseboard_fab2_lib.baseboard_fab2(sch_1):page55_i160:b"
				( attribute "PN" "2"
					( Origin gPackager )
				)
				( objectStatus "R8N5.2" )
			)
			( pin "@baseboard_fab2_lib.baseboard_fab2(sch_1):page55_i161:a"
				( attribute "PN" "1"
					( Origin gPackager )
				)
				( objectStatus "R8N2.1" )
			)
			( pin "@baseboard_fab2_lib.baseboard_fab2(sch_1):page55_i161:b"
				( attribute "PN" "2"
					( Origin gPackager )
				)
				( objectStatus "R8N2.2" )
			)
			( pin "@baseboard_fab2_lib.baseboard_fab2(sch_1):page55_i170:a"
				( attribute "PN" "1"
					( Origin gPackager )
				)
				( objectStatus "R7P25.1" )
			)
			( pin "@baseboard_fab2_lib.baseboard_fab2(sch_1):page55_i170:b"
				( attribute "PN" "2"
					( Origin gPackager )
				)
				( objectStatus "R7P25.2" )
			)
			( pin "@baseboard_fab2_lib.baseboard_fab2(sch_1):page55_i172:bclk0_dn"
				( attribute "PN" "AU24"
					( Origin gPackager )
				)
				( objectStatus "U2D1.AU24" )
			)
			( pin "@baseboard_fab2_lib.baseboard_fab2(sch_1):page55_i172:bclk0_dp"
				( attribute "PN" "AW24"
					( Origin gPackager )
				)
				( objectStatus "U2D1.AW24" )
			)
			( pin "@baseboard_fab2_lib.baseboard_fab2(sch_1):page55_i172:bclk1_dn"
				( attribute "PN" "CR26"
					( Origin gPackager )
				)
				( objectStatus "U2D1.CR26" )
			)
			( pin "@baseboard_fab2_lib.baseboard_fab2(sch_1):page55_i172:bclk1_dp"
				( attribute "PN" "CP27"
					( Origin gPackager )
				)
				( objectStatus "U2D1.CP27" )
			)
			( pin "@baseboard_fab2_lib.baseboard_fab2(sch_1):page55_i172:bclk2_dn"
				( attribute "PN" "CT25"
					( Origin gPackager )
				)
				( objectStatus "U2D1.CT25" )
			)
			( pin "@baseboard_fab2_lib.baseboard_fab2(sch_1):page55_i172:bclk2_dp"
				( attribute "PN" "CU26"
					( Origin gPackager )
				)
				( objectStatus "U2D1.CU26" )
			)
			( pin "@baseboard_fab2_lib.baseboard_fab2(sch_1):page55_i172:bist_enable"
				( attribute "PN" "BA20"
					( Origin gPackager )
				)
				( objectStatus "U2D1.BA20" )
			)
			( pin "@baseboard_fab2_lib.baseboard_fab2(sch_1):page55_i172:bmcinit"
				( attribute "PN" "BD23"
					( Origin gPackager )
				)
				( objectStatus "U2D1.BD23" )
			)
			( pin "@baseboard_fab2_lib.baseboard_fab2(sch_1):page55_i172:bpm_n(0)"
				( attribute "PN" "AJ10"
					( Origin gPackager )
				)
				( objectStatus "U2D1.AJ10" )
			)
			( pin "@baseboard_fab2_lib.baseboard_fab2(sch_1):page55_i172:bpm_n(1)"
				( attribute "PN" "AH11"
					( Origin gPackager )
				)
				( objectStatus "U2D1.AH11" )
			)
			( pin "@baseboard_fab2_lib.baseboard_fab2(sch_1):page55_i172:bpm_n(2)"
				( attribute "PN" "AG10"
					( Origin gPackager )
				)
				( objectStatus "U2D1.AG10" )
			)
			( pin "@baseboard_fab2_lib.baseboard_fab2(sch_1):page55_i172:bpm_n(3)"
				( attribute "PN" "AF11"
					( Origin gPackager )
				)
				( objectStatus "U2D1.AF11" )
			)
			( pin "@baseboard_fab2_lib.baseboard_fab2(sch_1):page55_i172:bpm_n(4)"
				( attribute "PN" "AA12"
					( Origin gPackager )
				)
				( objectStatus "U2D1.AA12" )
			)
			( pin "@baseboard_fab2_lib.baseboard_fab2(sch_1):page55_i172:bpm_n(5)"
				( attribute "PN" "Y11"
					( Origin gPackager )
				)
				( objectStatus "U2D1.Y11" )
			)
			( pin "@baseboard_fab2_lib.baseboard_fab2(sch_1):page55_i172:bpm_n(6)"
				( attribute "PN" "AE12"
					( Origin gPackager )
				)
				( objectStatus "U2D1.AE12" )
			)
			( pin "@baseboard_fab2_lib.baseboard_fab2(sch_1):page55_i172:bpm_n(7)"
				( attribute "PN" "AC12"
					( Origin gPackager )
				)
				( objectStatus "U2D1.AC12" )
			)
			( pin "@baseboard_fab2_lib.baseboard_fab2(sch_1):page55_i172:caterr_n"
				( attribute "PN" "AL14"
					( Origin gPackager )
				)
				( objectStatus "U2D1.AL14" )
			)
			( pin "@baseboard_fab2_lib.baseboard_fab2(sch_1):page55_i172:ddr0_cavref"
				( attribute "PN" "AJ64"
					( Origin gPackager )
				)
				( objectStatus "U2D1.AJ64" )
			)
			( pin "@baseboard_fab2_lib.baseboard_fab2(sch_1):page55_i172:ddr1_cavref"
				( attribute "PN" "AK63"
					( Origin gPackager )
				)
				( objectStatus "U2D1.AK63" )
			)
			( pin "@baseboard_fab2_lib.baseboard_fab2(sch_1):page55_i172:ddr2_cavref"
				( attribute "PN" "AH63"
					( Origin gPackager )
				)
				( objectStatus "U2D1.AH63" )
			)
			( pin "@baseboard_fab2_lib.baseboard_fab2(sch_1):page55_i172:ddr3_cavref"
				( attribute "PN" "CP61"
					( Origin gPackager )
				)
				( objectStatus "U2D1.CP61" )
			)
			( pin "@baseboard_fab2_lib.baseboard_fab2(sch_1):page55_i172:ddr4_cavref"
				( attribute "PN" "CT61"
					( Origin gPackager )
				)
				( objectStatus "U2D1.CT61" )
			)
			( pin "@baseboard_fab2_lib.baseboard_fab2(sch_1):page55_i172:ddr5_cavref"
				( attribute "PN" "CV61"
					( Origin gPackager )
				)
				( objectStatus "U2D1.CV61" )
			)
			( pin "@baseboard_fab2_lib.baseboard_fab2(sch_1):page55_i172:ddr012_dram_pwr_ok"
				( attribute "PN" "AN30"
					( Origin gPackager )
				)
				( objectStatus "U2D1.AN30" )
			)
			( pin "@baseboard_fab2_lib.baseboard_fab2(sch_1):page55_i172:ddr012_rcomp(0)"
				( attribute "PN" "Y43"
					( Origin gPackager )
				)
				( objectStatus "U2D1.Y43" )
			)
			( pin "@baseboard_fab2_lib.baseboard_fab2(sch_1):page55_i172:ddr012_rcomp(1)"
				( attribute "PN" "AB43"
					( Origin gPackager )
				)
				( objectStatus "U2D1.AB43" )
			)
			( pin "@baseboard_fab2_lib.baseboard_fab2(sch_1):page55_i172:ddr012_rcomp(2)"
				( attribute "PN" "AC42"
					( Origin gPackager )
				)
				( objectStatus "U2D1.AC42" )
			)
			( pin "@baseboard_fab2_lib.baseboard_fab2(sch_1):page55_i172:ddr012_reset_n"
				( attribute "PN" "U64"
					( Origin gPackager )
				)
				( objectStatus "U2D1.U64" )
			)
			( pin "@baseboard_fab2_lib.baseboard_fab2(sch_1):page55_i172:ddr012_spdscl"
				( attribute "PN" "AJ18"
					( Origin gPackager )
				)
				( objectStatus "U2D1.AJ18" )
			)
			( pin "@baseboard_fab2_lib.baseboard_fab2(sch_1):page55_i172:ddr012_spdsda"
				( attribute "PN" "AF17"
					( Origin gPackager )
				)
				( objectStatus "U2D1.AF17" )
			)
			( pin "@baseboard_fab2_lib.baseboard_fab2(sch_1):page55_i172:ddr345_dram_pwr_ok"
				( attribute "PN" "CR28"
					( Origin gPackager )
				)
				( objectStatus "U2D1.CR28" )
			)
			( pin "@baseboard_fab2_lib.baseboard_fab2(sch_1):page55_i172:ddr345_rcomp(0)"
				( attribute "PN" "DC48"
					( Origin gPackager )
				)
				( objectStatus "U2D1.DC48" )
			)
			( pin "@baseboard_fab2_lib.baseboard_fab2(sch_1):page55_i172:ddr345_rcomp(1)"
				( attribute "PN" "DD47"
					( Origin gPackager )
				)
				( objectStatus "U2D1.DD47" )
			)
			( pin "@baseboard_fab2_lib.baseboard_fab2(sch_1):page55_i172:ddr345_rcomp(2)"
				( attribute "PN" "DD49"
					( Origin gPackager )
				)
				( objectStatus "U2D1.DD49" )
			)
			( pin "@baseboard_fab2_lib.baseboard_fab2(sch_1):page55_i172:ddr345_reset_n"
				( attribute "PN" "DV63"
					( Origin gPackager )
				)
				( objectStatus "U2D1.DV63" )
			)
			( pin "@baseboard_fab2_lib.baseboard_fab2(sch_1):page55_i172:ddr345_spdscl"
				( attribute "PN" "AE18"
					( Origin gPackager )
				)
				( objectStatus "U2D1.AE18" )
			)
			( pin "@baseboard_fab2_lib.baseboard_fab2(sch_1):page55_i172:ddr345_spdsda"
				( attribute "PN" "AD17"
					( Origin gPackager )
				)
				( objectStatus "U2D1.AD17" )
			)
			( pin "@baseboard_fab2_lib.baseboard_fab2(sch_1):page55_i172:ear_n"
				( attribute "PN" "AJ14"
					( Origin gPackager )
				)
				( objectStatus "U2D1.AJ14" )
			)
			( pin "@baseboard_fab2_lib.baseboard_fab2(sch_1):page55_i172:error_n(0)"
				( attribute "PN" "AJ12"
					( Origin gPackager )
				)
				( objectStatus "U2D1.AJ12" )
			)
			( pin "@baseboard_fab2_lib.baseboard_fab2(sch_1):page55_i172:error_n(1)"
				( attribute "PN" "AK11"
					( Origin gPackager )
				)
				( objectStatus "U2D1.AK11" )
			)
			( pin "@baseboard_fab2_lib.baseboard_fab2(sch_1):page55_i172:error_n(2)"
				( attribute "PN" "AL12"
					( Origin gPackager )
				)
				( objectStatus "U2D1.AL12" )
			)
			( pin "@baseboard_fab2_lib.baseboard_fab2(sch_1):page55_i172:frmagent"
				( attribute "PN" "AV17"
					( Origin gPackager )
				)
				( objectStatus "U2D1.AV17" )
			)
			( pin "@baseboard_fab2_lib.baseboard_fab2(sch_1):page55_i172:legacy_skt"
				( attribute "PN" "AE20"
					( Origin gPackager )
				)
				( objectStatus "U2D1.AE20" )
			)
			( pin "@baseboard_fab2_lib.baseboard_fab2(sch_1):page55_i172:mcp01_rbias(0)"
				( attribute "PN" "CU32"
					( Origin gPackager )
				)
				( objectStatus "U2D1.CU32" )
			)
			( pin "@baseboard_fab2_lib.baseboard_fab2(sch_1):page55_i172:mcp01_rbias(1)"
				( attribute "PN" "CT31"
					( Origin gPackager )
				)
				( objectStatus "U2D1.CT31" )
			)
			( pin "@baseboard_fab2_lib.baseboard_fab2(sch_1):page55_i172:mem_hot_c012_n"
				( attribute "PN" "AH13"
					( Origin gPackager )
				)
				( objectStatus "U2D1.AH13" )
			)
			( pin "@baseboard_fab2_lib.baseboard_fab2(sch_1):page55_i172:mem_hot_c345_n"
				( attribute "PN" "AF13"
					( Origin gPackager )
				)
				( objectStatus "U2D1.AF13" )
			)
			( pin "@baseboard_fab2_lib.baseboard_fab2(sch_1):page55_i172:msmi_n"
				( attribute "PN" "AN20"
					( Origin gPackager )
				)
				( objectStatus "U2D1.AN20" )
			)
			( pin "@baseboard_fab2_lib.baseboard_fab2(sch_1):page55_i172:nmi"
				( attribute "PN" "AP11"
					( Origin gPackager )
				)
				( objectStatus "U2D1.AP11" )
			)
			( pin "@baseboard_fab2_lib.baseboard_fab2(sch_1):page55_i172:pe3_rbias(0)"
				( attribute "PN" "CP29"
					( Origin gPackager )
				)
				( objectStatus "U2D1.CP29" )
			)
			( pin "@baseboard_fab2_lib.baseboard_fab2(sch_1):page55_i172:pe3_rbias(1)"
				( attribute "PN" "CR30"
					( Origin gPackager )
				)
				( objectStatus "U2D1.CR30" )
			)
			( pin "@baseboard_fab2_lib.baseboard_fab2(sch_1):page55_i172:pe012_rbias(0)"
				( attribute "PN" "CN30"
					( Origin gPackager )
				)
				( objectStatus "U2D1.CN30" )
			)
			( pin "@baseboard_fab2_lib.baseboard_fab2(sch_1):page55_i172:pe012_rbias(1)"
				( attribute "PN" "CL30"
					( Origin gPackager )
				)
				( objectStatus "U2D1.CL30" )
			)
			( pin "@baseboard_fab2_lib.baseboard_fab2(sch_1):page55_i172:pe_hp_scl"
				( attribute "PN" "AM19"
					( Origin gPackager )
				)
				( objectStatus "U2D1.AM19" )
			)
			( pin "@baseboard_fab2_lib.baseboard_fab2(sch_1):page55_i172:pe_hp_sda"
				( attribute "PN" "AL18"
					( Origin gPackager )
				)
				( objectStatus "U2D1.AL18" )
			)
			( pin "@baseboard_fab2_lib.baseboard_fab2(sch_1):page55_i172:peci"
				( attribute "PN" "AU12"
					( Origin gPackager )
				)
				( objectStatus "U2D1.AU12" )
			)
			( pin "@baseboard_fab2_lib.baseboard_fab2(sch_1):page55_i172:pirom_addr(0)"
				( attribute "PN" "CU58"
					( Origin gPackager )
				)
				( objectStatus "U2D1.CU58" )
			)
			( pin "@baseboard_fab2_lib.baseboard_fab2(sch_1):page55_i172:pirom_addr(1)"
				( attribute "PN" "CV57"
					( Origin gPackager )
				)
				( objectStatus "U2D1.CV57" )
			)
			( pin "@baseboard_fab2_lib.baseboard_fab2(sch_1):page55_i172:pirom_addr(2)"
				( attribute "PN" "CW56"
					( Origin gPackager )
				)
				( objectStatus "U2D1.CW56" )
			)
			( pin "@baseboard_fab2_lib.baseboard_fab2(sch_1):page55_i172:pkgid(0)"
				( attribute "PN" "DC72"
					( Origin gPackager )
				)
				( objectStatus "U2D1.DC72" )
			)
			( pin "@baseboard_fab2_lib.baseboard_fab2(sch_1):page55_i172:pkgid(1)"
				( attribute "PN" "CW72"
					( Origin gPackager )
				)
				( objectStatus "U2D1.CW72" )
			)
			( pin "@baseboard_fab2_lib.baseboard_fab2(sch_1):page55_i172:pkgid(2)"
				( attribute "PN" "DA72"
					( Origin gPackager )
				)
				( objectStatus "U2D1.DA72" )
			)
			( pin "@baseboard_fab2_lib.baseboard_fab2(sch_1):page55_i172:pm_fast_wake_n"
				( attribute "PN" "AF15"
					( Origin gPackager )
				)
				( objectStatus "U2D1.AF15" )
			)
			( pin "@baseboard_fab2_lib.baseboard_fab2(sch_1):page55_i172:pmsync"
				( attribute "PN" "AR14"
					( Origin gPackager )
				)
				( objectStatus "U2D1.AR14" )
			)
			( pin "@baseboard_fab2_lib.baseboard_fab2(sch_1):page55_i172:pmsync_clk"
				( attribute "PN" "AT19"
					( Origin gPackager )
				)
				( objectStatus "U2D1.AT19" )
			)
			( pin "@baseboard_fab2_lib.baseboard_fab2(sch_1):page55_i172:prdy_n"
				( attribute "PN" "AG16"
					( Origin gPackager )
				)
				( objectStatus "U2D1.AG16" )
			)
			( pin "@baseboard_fab2_lib.baseboard_fab2(sch_1):page55_i172:preq_n"
				( attribute "PN" "AR12"
					( Origin gPackager )
				)
				( objectStatus "U2D1.AR12" )
			)
			( pin "@baseboard_fab2_lib.baseboard_fab2(sch_1):page55_i172:proc_id(0)"
				( attribute "PN" "CY71"
					( Origin gPackager )
				)
				( objectStatus "U2D1.CY71" )
			)
			( pin "@baseboard_fab2_lib.baseboard_fab2(sch_1):page55_i172:proc_id(1)"
				( attribute "PN" "DB71"
					( Origin gPackager )
				)
				( objectStatus "U2D1.DB71" )
			)
			( pin "@baseboard_fab2_lib.baseboard_fab2(sch_1):page55_i172:procdis_n"
				( attribute "PN" "AB17"
					( Origin gPackager )
				)
				( objectStatus "U2D1.AB17" )
			)
			( pin "@baseboard_fab2_lib.baseboard_fab2(sch_1):page55_i172:prochot_n"
				( attribute "PN" "AC16"
					( Origin gPackager )
				)
				( objectStatus "U2D1.AC16" )
			)
			( pin "@baseboard_fab2_lib.baseboard_fab2(sch_1):page55_i172:pwrgood"
				( attribute "PN" "BC24"
					( Origin gPackager )
				)
				( objectStatus "U2D1.BC24" )
			)
			( pin "@baseboard_fab2_lib.baseboard_fab2(sch_1):page55_i172:reset_n"
				( attribute "PN" "AP21"
					( Origin gPackager )
				)
				( objectStatus "U2D1.AP21" )
			)
			( pin "@baseboard_fab2_lib.baseboard_fab2(sch_1):page55_i172:safe_mode_boot"
				( attribute "PN" "AR18"
					( Origin gPackager )
				)
				( objectStatus "U2D1.AR18" )
			)
			( pin "@baseboard_fab2_lib.baseboard_fab2(sch_1):page55_i172:sktocc_n"
				( attribute "PN" "AB13"
					( Origin gPackager )
				)
				( objectStatus "U2D1.AB13" )
			)
			( pin "@baseboard_fab2_lib.baseboard_fab2(sch_1):page55_i172:sm_wp"
				( attribute "PN" "CV59"
					( Origin gPackager )
				)
				( objectStatus "U2D1.CV59" )
			)
			( pin "@baseboard_fab2_lib.baseboard_fab2(sch_1):page55_i172:smbclk"
				( attribute "PN" "CT59"
					( Origin gPackager )
				)
				( objectStatus "U2D1.CT59" )
			)
			( pin "@baseboard_fab2_lib.baseboard_fab2(sch_1):page55_i172:smbdat"
				( attribute "PN" "CW58"
					( Origin gPackager )
				)
				( objectStatus "U2D1.CW58" )
			)
			( pin "@baseboard_fab2_lib.baseboard_fab2(sch_1):page55_i172:socket_id(0)"
				( attribute "PN" "AU22"
					( Origin gPackager )
				)
				( objectStatus "U2D1.AU22" )
			)
			( pin "@baseboard_fab2_lib.baseboard_fab2(sch_1):page55_i172:socket_id(1)"
				( attribute "PN" "AU16"
					( Origin gPackager )
				)
				( objectStatus "U2D1.AU16" )
			)
			( pin "@baseboard_fab2_lib.baseboard_fab2(sch_1):page55_i172:socket_id(2)"
				( attribute "PN" "AU20"
					( Origin gPackager )
				)
				( objectStatus "U2D1.AU20" )
			)
			( pin "@baseboard_fab2_lib.baseboard_fab2(sch_1):page55_i172:svidalert_n(0)"
				( attribute "PN" "DE44"
					( Origin gPackager )
				)
				( objectStatus "U2D1.DE44" )
			)
			( pin "@baseboard_fab2_lib.baseboard_fab2(sch_1):page55_i172:svidalert_n(1)"
				( attribute "PN" "DL44"
					( Origin gPackager )
				)
				( objectStatus "U2D1.DL44" )
			)
			( pin "@baseboard_fab2_lib.baseboard_fab2(sch_1):page55_i172:svidclk(0)"
				( attribute "PN" "DC44"
					( Origin gPackager )
				)
				( objectStatus "U2D1.DC44" )
			)
			( pin "@baseboard_fab2_lib.baseboard_fab2(sch_1):page55_i172:svidclk(1)"
				( attribute "PN" "DG44"
					( Origin gPackager )
				)
				( objectStatus "U2D1.DG44" )
			)
			( pin "@baseboard_fab2_lib.baseboard_fab2(sch_1):page55_i172:sviddata(0)"
				( attribute "PN" "DB45"
					( Origin gPackager )
				)
				( objectStatus "U2D1.DB45" )
			)
			( pin "@baseboard_fab2_lib.baseboard_fab2(sch_1):page55_i172:sviddata(1)"
				( attribute "PN" "DJ44"
					( Origin gPackager )
				)
				( objectStatus "U2D1.DJ44" )
			)
			( pin "@baseboard_fab2_lib.baseboard_fab2(sch_1):page55_i172:tck"
				( attribute "PN" "AA14"
					( Origin gPackager )
				)
				( objectStatus "U2D1.AA14" )
			)
			( pin "@baseboard_fab2_lib.baseboard_fab2(sch_1):page55_i172:tdi"
				( attribute "PN" "AC14"
					( Origin gPackager )
				)
				( objectStatus "U2D1.AC14" )
			)
			( pin "@baseboard_fab2_lib.baseboard_fab2(sch_1):page55_i172:tdo"
				( attribute "PN" "AE14"
					( Origin gPackager )
				)
				( objectStatus "U2D1.AE14" )
			)
			( pin "@baseboard_fab2_lib.baseboard_fab2(sch_1):page55_i172:test_12"
				( attribute "PN" "AY19"
					( Origin gPackager )
				)
				( objectStatus "U2D1.AY19" )
			)
			( pin "@baseboard_fab2_lib.baseboard_fab2(sch_1):page55_i172:test_13"
				( attribute "PN" "DB51"
					( Origin gPackager )
				)
				( objectStatus "U2D1.DB51" )
			)
			( pin "@baseboard_fab2_lib.baseboard_fab2(sch_1):page55_i172:test_14"
				( attribute "PN" "DC50"
					( Origin gPackager )
				)
				( objectStatus "U2D1.DC50" )
			)
			( pin "@baseboard_fab2_lib.baseboard_fab2(sch_1):page55_i172:test_15"
				( attribute "PN" "AW14"
					( Origin gPackager )
				)
				( objectStatus "U2D1.AW14" )
			)
			( pin "@baseboard_fab2_lib.baseboard_fab2(sch_1):page55_i172:thermtrip_n"
				( attribute "PN" "AB15"
					( Origin gPackager )
				)
				( objectStatus "U2D1.AB15" )
			)
			( pin "@baseboard_fab2_lib.baseboard_fab2(sch_1):page55_i172:tms"
				( attribute "PN" "W14"
					( Origin gPackager )
				)
				( objectStatus "U2D1.W14" )
			)
			( pin "@baseboard_fab2_lib.baseboard_fab2(sch_1):page55_i172:trst_n"
				( attribute "PN" "Y13"
					( Origin gPackager )
				)
				( objectStatus "U2D1.Y13" )
			)
			( pin "@baseboard_fab2_lib.baseboard_fab2(sch_1):page55_i172:tsc_sync"
				( attribute "PN" "AM11"
					( Origin gPackager )
				)
				( objectStatus "U2D1.AM11" )
			)
			( pin "@baseboard_fab2_lib.baseboard_fab2(sch_1):page55_i172:txt_agent"
				( attribute "PN" "AW18"
					( Origin gPackager )
				)
				( objectStatus "U2D1.AW18" )
			)
			( pin "@baseboard_fab2_lib.baseboard_fab2(sch_1):page55_i172:txt_plten"
				( attribute "PN" "AV15"
					( Origin gPackager )
				)
				( objectStatus "U2D1.AV15" )
			)
			( pin "@baseboard_fab2_lib.baseboard_fab2(sch_1):page55_i172:upi01_rbias(0)"
				( attribute "PN" "AT29"
					( Origin gPackager )
				)
				( objectStatus "U2D1.AT29" )
			)
			( pin "@baseboard_fab2_lib.baseboard_fab2(sch_1):page55_i172:upi01_rbias(1)"
				( attribute "PN" "AP29"
					( Origin gPackager )
				)
				( objectStatus "U2D1.AP29" )
			)
			( pin "@baseboard_fab2_lib.baseboard_fab2(sch_1):page55_i172:upi2_rbias(0)"
				( attribute "PN" "CL28"
					( Origin gPackager )
				)
				( objectStatus "U2D1.CL28" )
			)
			( pin "@baseboard_fab2_lib.baseboard_fab2(sch_1):page55_i172:upi2_rbias(1)"
				( attribute "PN" "CK29"
					( Origin gPackager )
				)
				( objectStatus "U2D1.CK29" )
			)
			( pin "@baseboard_fab2_lib.baseboard_fab2(sch_1):page55_i181:a"
				( attribute "PN" "1"
					( Origin gPackager )
				)
				( objectStatus "R6P39.1" )
			)
			( pin "@baseboard_fab2_lib.baseboard_fab2(sch_1):page55_i181:b"
				( attribute "PN" "2"
					( Origin gPackager )
				)
				( objectStatus "R6P39.2" )
			)
			( pin "@baseboard_fab2_lib.baseboard_fab2(sch_1):page56_i169:debug_en_n"
				( attribute "PN" "AV21"
					( Origin gPackager )
				)
				( objectStatus "U2D1.AV21" )
			)
			( pin "@baseboard_fab2_lib.baseboard_fab2(sch_1):page56_i169:dmimode_override"
				( attribute "PN" "AW12"
					( Origin gPackager )
				)
				( objectStatus "U2D1.AW12" )
			)
			( pin "@baseboard_fab2_lib.baseboard_fab2(sch_1):page56_i169:fivr_fault"
				( attribute "PN" "AU14"
					( Origin gPackager )
				)
				( objectStatus "U2D1.AU14" )
			)
			( pin "@baseboard_fab2_lib.baseboard_fab2(sch_1):page56_i169:pwr_debug_n"
				( attribute "PN" "AP17"
					( Origin gPackager )
				)
				( objectStatus "U2D1.AP17" )
			)
			( pin "@baseboard_fab2_lib.baseboard_fab2(sch_1):page56_i169:rsvd(194)"
				( attribute "PN" "AP61"
					( Origin gPackager )
				)
				( objectStatus "U2D1.AP61" )
			)
			( pin "@baseboard_fab2_lib.baseboard_fab2(sch_1):page56_i169:rsvd(195)"
				( attribute "PN" "AP27"
					( Origin gPackager )
				)
				( objectStatus "U2D1.AP27" )
			)
			( pin "@baseboard_fab2_lib.baseboard_fab2(sch_1):page56_i169:rsvd(196)"
				( attribute "PN" "AP25"
					( Origin gPackager )
				)
				( objectStatus "U2D1.AP25" )
			)
			( pin "@baseboard_fab2_lib.baseboard_fab2(sch_1):page56_i169:rsvd(197)"
				( attribute "PN" "AP23"
					( Origin gPackager )
				)
				( objectStatus "U2D1.AP23" )
			)
			( pin "@baseboard_fab2_lib.baseboard_fab2(sch_1):page56_i169:rsvd(198)"
				( attribute "PN" "AN62"
					( Origin gPackager )
				)
				( objectStatus "U2D1.AN62" )
			)
			( pin "@baseboard_fab2_lib.baseboard_fab2(sch_1):page56_i169:rsvd(199)"
				( attribute "PN" "AN60"
					( Origin gPackager )
				)
				( objectStatus "U2D1.AN60" )
			)
			( pin "@baseboard_fab2_lib.baseboard_fab2(sch_1):page56_i169:rsvd(200)"
				( attribute "PN" "AN26"
					( Origin gPackager )
				)
				( objectStatus "U2D1.AN26" )
			)
			( pin "@baseboard_fab2_lib.baseboard_fab2(sch_1):page56_i169:rsvd(201)"
				( attribute "PN" "AN24"
					( Origin gPackager )
				)
				( objectStatus "U2D1.AN24" )
			)
			( pin "@baseboard_fab2_lib.baseboard_fab2(sch_1):page56_i169:rsvd(202)"
				( attribute "PN" "AN22"
					( Origin gPackager )
				)
				( objectStatus "U2D1.AN22" )
			)
			( pin "@baseboard_fab2_lib.baseboard_fab2(sch_1):page56_i169:rsvd(203)"
				( attribute "PN" "AN18"
					( Origin gPackager )
				)
				( objectStatus "U2D1.AN18" )
			)
			( pin "@baseboard_fab2_lib.baseboard_fab2(sch_1):page56_i169:rsvd(204)"
				( attribute "PN" "AM61"
					( Origin gPackager )
				)
				( objectStatus "U2D1.AM61" )
			)
			( pin "@baseboard_fab2_lib.baseboard_fab2(sch_1):page56_i169:rsvd(205)"
				( attribute "PN" "AM59"
					( Origin gPackager )
				)
				( objectStatus "U2D1.AM59" )
			)
			( pin "@baseboard_fab2_lib.baseboard_fab2(sch_1):page56_i169:rsvd(206)"
				( attribute "PN" "AM27"
					( Origin gPackager )
				)
				( objectStatus "U2D1.AM27" )
			)
			( pin "@baseboard_fab2_lib.baseboard_fab2(sch_1):page56_i169:rsvd(207)"
				( attribute "PN" "AM25"
					( Origin gPackager )
				)
				( objectStatus "U2D1.AM25" )
			)
			( pin "@baseboard_fab2_lib.baseboard_fab2(sch_1):page56_i169:rsvd(208)"
				( attribute "PN" "AM23"
					( Origin gPackager )
				)
				( objectStatus "U2D1.AM23" )
			)
			( pin "@baseboard_fab2_lib.baseboard_fab2(sch_1):page56_i169:rsvd(209)"
				( attribute "PN" "AM21"
					( Origin gPackager )
				)
				( objectStatus "U2D1.AM21" )
			)
			( pin "@baseboard_fab2_lib.baseboard_fab2(sch_1):page56_i169:rsvd(210)"
				( attribute "PN" "AL62"
					( Origin gPackager )
				)
				( objectStatus "U2D1.AL62" )
			)
			( pin "@baseboard_fab2_lib.baseboard_fab2(sch_1):page56_i169:rsvd(211)"
				( attribute "PN" "AL60"
					( Origin gPackager )
				)
				( objectStatus "U2D1.AL60" )
			)
			( pin "@baseboard_fab2_lib.baseboard_fab2(sch_1):page56_i169:rsvd(212)"
				( attribute "PN" "AL58"
					( Origin gPackager )
				)
				( objectStatus "U2D1.AL58" )
			)
			( pin "@baseboard_fab2_lib.baseboard_fab2(sch_1):page56_i169:rsvd(213)"
				( attribute "PN" "AL26"
					( Origin gPackager )
				)
				( objectStatus "U2D1.AL26" )
			)
			( pin "@baseboard_fab2_lib.baseboard_fab2(sch_1):page56_i169:rsvd(214)"
				( attribute "PN" "AL22"
					( Origin gPackager )
				)
				( objectStatus "U2D1.AL22" )
			)
			( pin "@baseboard_fab2_lib.baseboard_fab2(sch_1):page56_i169:rsvd(215)"
				( attribute "PN" "AL20"
					( Origin gPackager )
				)
				( objectStatus "U2D1.AL20" )
			)
			( pin "@baseboard_fab2_lib.baseboard_fab2(sch_1):page56_i169:rsvd(216)"
				( attribute "PN" "AK69"
					( Origin gPackager )
				)
				( objectStatus "U2D1.AK69" )
			)
			( pin "@baseboard_fab2_lib.baseboard_fab2(sch_1):page56_i169:rsvd(217)"
				( attribute "PN" "AK61"
					( Origin gPackager )
				)
				( objectStatus "U2D1.AK61" )
			)
			( pin "@baseboard_fab2_lib.baseboard_fab2(sch_1):page56_i169:rsvd(218)"
				( attribute "PN" "AK59"
					( Origin gPackager )
				)
				( objectStatus "U2D1.AK59" )
			)
			( pin "@baseboard_fab2_lib.baseboard_fab2(sch_1):page56_i169:rsvd(219)"
				( attribute "PN" "AK57"
					( Origin gPackager )
				)
				( objectStatus "U2D1.AK57" )
			)
			( pin "@baseboard_fab2_lib.baseboard_fab2(sch_1):page56_i169:rsvd(220)"
				( attribute "PN" "AK27"
					( Origin gPackager )
				)
				( objectStatus "U2D1.AK27" )
			)
			( pin "@baseboard_fab2_lib.baseboard_fab2(sch_1):page56_i169:rsvd(221)"
				( attribute "PN" "AK21"
					( Origin gPackager )
				)
				( objectStatus "U2D1.AK21" )
			)
			( pin "@baseboard_fab2_lib.baseboard_fab2(sch_1):page56_i169:rsvd(222)"
				( attribute "PN" "AJ70"
					( Origin gPackager )
				)
				( objectStatus "U2D1.AJ70" )
			)
			( pin "@baseboard_fab2_lib.baseboard_fab2(sch_1):page56_i169:rsvd(223)"
				( attribute "PN" "AJ62"
					( Origin gPackager )
				)
				( objectStatus "U2D1.AJ62" )
			)
			( pin "@baseboard_fab2_lib.baseboard_fab2(sch_1):page56_i169:rsvd(224)"
				( attribute "PN" "AJ60"
					( Origin gPackager )
				)
				( objectStatus "U2D1.AJ60" )
			)
			( pin "@baseboard_fab2_lib.baseboard_fab2(sch_1):page56_i169:rsvd(225)"
				( attribute "PN" "AJ58"
					( Origin gPackager )
				)
				( objectStatus "U2D1.AJ58" )
			)
			( pin "@baseboard_fab2_lib.baseboard_fab2(sch_1):page56_i169:rsvd(226)"
				( attribute "PN" "AJ56"
					( Origin gPackager )
				)
				( objectStatus "U2D1.AJ56" )
			)
			( pin "@baseboard_fab2_lib.baseboard_fab2(sch_1):page56_i169:rsvd(227)"
				( attribute "PN" "AJ20"
					( Origin gPackager )
				)
				( objectStatus "U2D1.AJ20" )
			)
			( pin "@baseboard_fab2_lib.baseboard_fab2(sch_1):page56_i169:rsvd(228)"
				( attribute "PN" "AH73"
					( Origin gPackager )
				)
				( objectStatus "U2D1.AH73" )
			)
			( pin "@baseboard_fab2_lib.baseboard_fab2(sch_1):page56_i169:rsvd(229)"
				( attribute "PN" "AH71"
					( Origin gPackager )
				)
				( objectStatus "U2D1.AH71" )
			)
			( pin "@baseboard_fab2_lib.baseboard_fab2(sch_1):page56_i169:rsvd(230)"
				( attribute "PN" "AH57"
					( Origin gPackager )
				)
				( objectStatus "U2D1.AH57" )
			)
			( pin "@baseboard_fab2_lib.baseboard_fab2(sch_1):page56_i169:rsvd(231)"
				( attribute "PN" "AH55"
					( Origin gPackager )
				)
				( objectStatus "U2D1.AH55" )
			)
			( pin "@baseboard_fab2_lib.baseboard_fab2(sch_1):page56_i169:rsvd(232)"
				( attribute "PN" "AH19"
					( Origin gPackager )
				)
				( objectStatus "U2D1.AH19" )
			)
			( pin "@baseboard_fab2_lib.baseboard_fab2(sch_1):page56_i169:rsvd(233)"
				( attribute "PN" "AH15"
					( Origin gPackager )
				)
				( objectStatus "U2D1.AH15" )
			)
			( pin "@baseboard_fab2_lib.baseboard_fab2(sch_1):page56_i169:rsvd(234)"
				( attribute "PN" "AG72"
					( Origin gPackager )
				)
				( objectStatus "U2D1.AG72" )
			)
			( pin "@baseboard_fab2_lib.baseboard_fab2(sch_1):page56_i169:rsvd(235)"
				( attribute "PN" "AG56"
					( Origin gPackager )
				)
				( objectStatus "U2D1.AG56" )
			)
			( pin "@baseboard_fab2_lib.baseboard_fab2(sch_1):page56_i169:rsvd(236)"
				( attribute "PN" "AG54"
					( Origin gPackager )
				)
				( objectStatus "U2D1.AG54" )
			)
			( pin "@baseboard_fab2_lib.baseboard_fab2(sch_1):page56_i169:rsvd(237)"
				( attribute "PN" "AG52"
					( Origin gPackager )
				)
				( objectStatus "U2D1.AG52" )
			)
			( pin "@baseboard_fab2_lib.baseboard_fab2(sch_1):page56_i169:rsvd(238)"
				( attribute "PN" "AG50"
					( Origin gPackager )
				)
				( objectStatus "U2D1.AG50" )
			)
			( pin "@baseboard_fab2_lib.baseboard_fab2(sch_1):page56_i169:rsvd(239)"
				( attribute "PN" "AG48"
					( Origin gPackager )
				)
				( objectStatus "U2D1.AG48" )
			)
			( pin "@baseboard_fab2_lib.baseboard_fab2(sch_1):page56_i169:rsvd(240)"
				( attribute "PN" "AG20"
					( Origin gPackager )
				)
				( objectStatus "U2D1.AG20" )
			)
			( pin "@baseboard_fab2_lib.baseboard_fab2(sch_1):page56_i169:rsvd(241)"
				( attribute "PN" "AF71"
					( Origin gPackager )
				)
				( objectStatus "U2D1.AF71" )
			)
			( pin "@baseboard_fab2_lib.baseboard_fab2(sch_1):page56_i169:rsvd(242)"
				( attribute "PN" "AF53"
					( Origin gPackager )
				)
				( objectStatus "U2D1.AF53" )
			)
			( pin "@baseboard_fab2_lib.baseboard_fab2(sch_1):page56_i169:rsvd(243)"
				( attribute "PN" "AF51"
					( Origin gPackager )
				)
				( objectStatus "U2D1.AF51" )
			)
			( pin "@baseboard_fab2_lib.baseboard_fab2(sch_1):page56_i169:rsvd(244)"
				( attribute "PN" "AF49"
					( Origin gPackager )
				)
				( objectStatus "U2D1.AF49" )
			)
			( pin "@baseboard_fab2_lib.baseboard_fab2(sch_1):page56_i169:rsvd(245)"
				( attribute "PN" "AF47"
					( Origin gPackager )
				)
				( objectStatus "U2D1.AF47" )
			)
			( pin "@baseboard_fab2_lib.baseboard_fab2(sch_1):page56_i169:rsvd(246)"
				( attribute "PN" "AF19"
					( Origin gPackager )
				)
				( objectStatus "U2D1.AF19" )
			)
			( pin "@baseboard_fab2_lib.baseboard_fab2(sch_1):page56_i169:rsvd(247)"
				( attribute "PN" "AE72"
					( Origin gPackager )
				)
				( objectStatus "U2D1.AE72" )
			)
			( pin "@baseboard_fab2_lib.baseboard_fab2(sch_1):page56_i169:rsvd(248)"
				( attribute "PN" "AE52"
					( Origin gPackager )
				)
				( objectStatus "U2D1.AE52" )
			)
			( pin "@baseboard_fab2_lib.baseboard_fab2(sch_1):page56_i169:rsvd(249)"
				( attribute "PN" "AE50"
					( Origin gPackager )
				)
				( objectStatus "U2D1.AE50" )
			)
			( pin "@baseboard_fab2_lib.baseboard_fab2(sch_1):page56_i169:rsvd(250)"
				( attribute "PN" "AE48"
					( Origin gPackager )
				)
				( objectStatus "U2D1.AE48" )
			)
			( pin "@baseboard_fab2_lib.baseboard_fab2(sch_1):page56_i169:rsvd(251)"
				( attribute "PN" "AE46"
					( Origin gPackager )
				)
				( objectStatus "U2D1.AE46" )
			)
			( pin "@baseboard_fab2_lib.baseboard_fab2(sch_1):page56_i169:rsvd(252)"
				( attribute "PN" "AD51"
					( Origin gPackager )
				)
				( objectStatus "U2D1.AD51" )
			)
			( pin "@baseboard_fab2_lib.baseboard_fab2(sch_1):page56_i169:rsvd(253)"
				( attribute "PN" "AD49"
					( Origin gPackager )
				)
				( objectStatus "U2D1.AD49" )
			)
			( pin "@baseboard_fab2_lib.baseboard_fab2(sch_1):page56_i169:rsvd(254)"
				( attribute "PN" "AD47"
					( Origin gPackager )
				)
				( objectStatus "U2D1.AD47" )
			)
			( pin "@baseboard_fab2_lib.baseboard_fab2(sch_1):page56_i169:rsvd(255)"
				( attribute "CDS_NOT_ON_SYM" "TRUE"
					( Origin gFrontEnd )
				)
			)
			( pin "@baseboard_fab2_lib.baseboard_fab2(sch_1):page56_i169:rsvd(256)"
				( attribute "PN" "Y65"
					( Origin gPackager )
				)
				( objectStatus "U2D1.Y65" )
			)
			( pin "@baseboard_fab2_lib.baseboard_fab2(sch_1):page56_i169:rsvd(257)"
				( attribute "PN" "Y23"
					( Origin gPackager )
				)
				( objectStatus "U2D1.Y23" )
			)
			( pin "@baseboard_fab2_lib.baseboard_fab2(sch_1):page56_i169:rsvd(258)"
				( attribute "PN" "W66"
					( Origin gPackager )
				)
				( objectStatus "U2D1.W66" )
			)
			( pin "@baseboard_fab2_lib.baseboard_fab2(sch_1):page56_i169:rsvd(259)"
				( attribute "PN" "V67"
					( Origin gPackager )
				)
				( objectStatus "U2D1.V67" )
			)
			( pin "@baseboard_fab2_lib.baseboard_fab2(sch_1):page56_i169:rsvd(260)"
				( attribute "PN" "V65"
					( Origin gPackager )
				)
				( objectStatus "U2D1.V65" )
			)
			( pin "@baseboard_fab2_lib.baseboard_fab2(sch_1):page56_i169:rsvd(261)"
				( attribute "PN" "U66"
					( Origin gPackager )
				)
				( objectStatus "U2D1.U66" )
			)
			( pin "@baseboard_fab2_lib.baseboard_fab2(sch_1):page56_i169:rsvd(262)"
				( attribute "PN" "T67"
					( Origin gPackager )
				)
				( objectStatus "U2D1.T67" )
			)
			( pin "@baseboard_fab2_lib.baseboard_fab2(sch_1):page56_i169:rsvd(263)"
				( attribute "PN" "R66"
					( Origin gPackager )
				)
				( objectStatus "U2D1.R66" )
			)
			( pin "@baseboard_fab2_lib.baseboard_fab2(sch_1):page56_i169:rsvd(264)"
				( attribute "PN" "R62"
					( Origin gPackager )
				)
				( objectStatus "U2D1.R62" )
			)
			( pin "@baseboard_fab2_lib.baseboard_fab2(sch_1):page56_i169:rsvd(265)"
				( attribute "PN" "P65"
					( Origin gPackager )
				)
				( objectStatus "U2D1.P65" )
			)
			( pin "@baseboard_fab2_lib.baseboard_fab2(sch_1):page56_i169:rsvd(266)"
				( attribute "PN" "M63"
					( Origin gPackager )
				)
				( objectStatus "U2D1.M63" )
			)
			( pin "@baseboard_fab2_lib.baseboard_fab2(sch_1):page56_i169:rsvd(267)"
				( attribute "PN" "K61"
					( Origin gPackager )
				)
				( objectStatus "U2D1.K61" )
			)
			( pin "@baseboard_fab2_lib.baseboard_fab2(sch_1):page56_i169:rsvd(268)"
				( attribute "PN" "J62"
					( Origin gPackager )
				)
				( objectStatus "U2D1.J62" )
			)
			( pin "@baseboard_fab2_lib.baseboard_fab2(sch_1):page56_i169:rsvd(269)"
				( attribute "PN" "J46"
					( Origin gPackager )
				)
				( objectStatus "U2D1.J46" )
			)
			( pin "@baseboard_fab2_lib.baseboard_fab2(sch_1):page56_i169:rsvd(270)"
				( attribute "PN" "H85"
					( Origin gPackager )
				)
				( objectStatus "U2D1.H85" )
			)
			( pin "@baseboard_fab2_lib.baseboard_fab2(sch_1):page56_i169:rsvd(271)"
				( attribute "PN" "H83"
					( Origin gPackager )
				)
				( objectStatus "U2D1.H83" )
			)
			( pin "@baseboard_fab2_lib.baseboard_fab2(sch_1):page56_i169:rsvd(272)"
				( attribute "PN" "H1"
					( Origin gPackager )
				)
				( objectStatus "U2D1.H1" )
			)
			( pin "@baseboard_fab2_lib.baseboard_fab2(sch_1):page56_i169:rsvd(273)"
				( attribute "PN" "G84"
					( Origin gPackager )
				)
				( objectStatus "U2D1.G84" )
			)
			( pin "@baseboard_fab2_lib.baseboard_fab2(sch_1):page56_i169:rsvd(274)"
				( attribute "PN" "G64"
					( Origin gPackager )
				)
				( objectStatus "U2D1.G64" )
			)
			( pin "@baseboard_fab2_lib.baseboard_fab2(sch_1):page56_i169:rsvd(275)"
				( attribute "PN" "G2"
					( Origin gPackager )
				)
				( objectStatus "U2D1.G2" )
			)
			( pin "@baseboard_fab2_lib.baseboard_fab2(sch_1):page56_i169:rsvd(276)"
				( attribute "PN" "F83"
					( Origin gPackager )
				)
				( objectStatus "U2D1.F83" )
			)
			( pin "@baseboard_fab2_lib.baseboard_fab2(sch_1):page56_i169:rsvd(277)"
				( attribute "PN" "F65"
					( Origin gPackager )
				)
				( objectStatus "U2D1.F65" )
			)
			( pin "@baseboard_fab2_lib.baseboard_fab2(sch_1):page56_i169:rsvd(278)"
				( attribute "PN" "F23"
					( Origin gPackager )
				)
				( objectStatus "U2D1.F23" )
			)
			( pin "@baseboard_fab2_lib.baseboard_fab2(sch_1):page56_i169:rsvd(279)"
				( attribute "PN" "F3"
					( Origin gPackager )
				)
				( objectStatus "U2D1.F3" )
			)
			( pin "@baseboard_fab2_lib.baseboard_fab2(sch_1):page56_i169:rsvd(280)"
				( attribute "PN" "E84"
					( Origin gPackager )
				)
				( objectStatus "U2D1.E84" )
			)
			( pin "@baseboard_fab2_lib.baseboard_fab2(sch_1):page56_i169:rsvd(281)"
				( attribute "PN" "E24"
					( Origin gPackager )
				)
				( objectStatus "U2D1.E24" )
			)
			( pin "@baseboard_fab2_lib.baseboard_fab2(sch_1):page56_i169:rsvd(282)"
				( attribute "PN" "E4"
					( Origin gPackager )
				)
				( objectStatus "U2D1.E4" )
			)
			( pin "@baseboard_fab2_lib.baseboard_fab2(sch_1):page56_i169:rsvd(283)"
				( attribute "PN" "E2"
					( Origin gPackager )
				)
				( objectStatus "U2D1.E2" )
			)
			( pin "@baseboard_fab2_lib.baseboard_fab2(sch_1):page56_i169:rsvd(284)"
				( attribute "PN" "D83"
					( Origin gPackager )
				)
				( objectStatus "U2D1.D83" )
			)
			( pin "@baseboard_fab2_lib.baseboard_fab2(sch_1):page56_i169:rsvd(285)"
				( attribute "PN" "D65"
					( Origin gPackager )
				)
				( objectStatus "U2D1.D65" )
			)
			( pin "@baseboard_fab2_lib.baseboard_fab2(sch_1):page56_i169:rsvd(286)"
				( attribute "PN" "D17"
					( Origin gPackager )
				)
				( objectStatus "U2D1.D17" )
			)
			( pin "@baseboard_fab2_lib.baseboard_fab2(sch_1):page56_i169:rsvd(287)"
				( attribute "PN" "D5"
					( Origin gPackager )
				)
				( objectStatus "U2D1.D5" )
			)
			( pin "@baseboard_fab2_lib.baseboard_fab2(sch_1):page56_i169:rsvd(288)"
				( attribute "PN" "C82"
					( Origin gPackager )
				)
				( objectStatus "U2D1.C82" )
			)
			( pin "@baseboard_fab2_lib.baseboard_fab2(sch_1):page56_i169:rsvd(289)"
				( attribute "PN" "C24"
					( Origin gPackager )
				)
				( objectStatus "U2D1.C24" )
			)
			( pin "@baseboard_fab2_lib.baseboard_fab2(sch_1):page56_i169:rsvd(290)"
				( attribute "PN" "C18"
					( Origin gPackager )
				)
				( objectStatus "U2D1.C18" )
			)
			( pin "@baseboard_fab2_lib.baseboard_fab2(sch_1):page56_i169:rsvd(291)"
				( attribute "PN" "C6"
					( Origin gPackager )
				)
				( objectStatus "U2D1.C6" )
			)
			( pin "@baseboard_fab2_lib.baseboard_fab2(sch_1):page56_i169:rsvd(292)"
				( attribute "PN" "B81"
					( Origin gPackager )
				)
				( objectStatus "U2D1.B81" )
			)
			( pin "@baseboard_fab2_lib.baseboard_fab2(sch_1):page56_i169:rsvd(293)"
				( attribute "PN" "B77"
					( Origin gPackager )
				)
				( objectStatus "U2D1.B77" )
			)
			( pin "@baseboard_fab2_lib.baseboard_fab2(sch_1):page56_i169:rsvd(294)"
				( attribute "PN" "B17"
					( Origin gPackager )
				)
				( objectStatus "U2D1.B17" )
			)
			( pin "@baseboard_fab2_lib.baseboard_fab2(sch_1):page56_i169:rsvd(295)"
				( attribute "PN" "B15"
					( Origin gPackager )
				)
				( objectStatus "U2D1.B15" )
			)
			( pin "@baseboard_fab2_lib.baseboard_fab2(sch_1):page56_i169:rsvd(296)"
				( attribute "PN" "B13"
					( Origin gPackager )
				)
				( objectStatus "U2D1.B13" )
			)
			( pin "@baseboard_fab2_lib.baseboard_fab2(sch_1):page56_i169:rsvd(297)"
				( attribute "CDS_NOT_ON_SYM" "TRUE"
					( Origin gFrontEnd )
				)
			)
			( pin "@baseboard_fab2_lib.baseboard_fab2(sch_1):page56_i169:rsvd(298)"
				( attribute "PN" "B7"
					( Origin gPackager )
				)
				( objectStatus "U2D1.B7" )
			)
			( pin "@baseboard_fab2_lib.baseboard_fab2(sch_1):page56_i169:rsvd(299)"
				( attribute "PN" "B3"
					( Origin gPackager )
				)
				( objectStatus "U2D1.B3" )
			)
			( pin "@baseboard_fab2_lib.baseboard_fab2(sch_1):page56_i169:rsvd(300)"
				( attribute "PN" "A24"
					( Origin gPackager )
				)
				( objectStatus "U2D1.A24" )
			)
			( pin "@baseboard_fab2_lib.baseboard_fab2(sch_1):page56_i169:rsvd(301)"
				( attribute "PN" "A16"
					( Origin gPackager )
				)
				( objectStatus "U2D1.A16" )
			)
			( pin "@baseboard_fab2_lib.baseboard_fab2(sch_1):page56_i169:rsvd(302)"
				( attribute "PN" "A14"
					( Origin gPackager )
				)
				( objectStatus "U2D1.A14" )
			)
			( pin "@baseboard_fab2_lib.baseboard_fab2(sch_1):page56_i169:rsvd(303)"
				( attribute "PN" "A6"
					( Origin gPackager )
				)
				( objectStatus "U2D1.A6" )
			)
			( pin "@baseboard_fab2_lib.baseboard_fab2(sch_1):page56_i169:rsvd(304)"
				( attribute "PN" "A4"
					( Origin gPackager )
				)
				( objectStatus "U2D1.A4" )
			)
			( pin "@baseboard_fab2_lib.baseboard_fab2(sch_1):page56_i169:test_1"
				( attribute "PN" "AF45"
					( Origin gPackager )
				)
				( objectStatus "U2D1.AF45" )
			)
			( pin "@baseboard_fab2_lib.baseboard_fab2(sch_1):page56_i169:test_2"
				( attribute "PN" "AG46"
					( Origin gPackager )
				)
				( objectStatus "U2D1.AG46" )
			)
			( pin "@baseboard_fab2_lib.baseboard_fab2(sch_1):page56_i169:test_3"
				( attribute "PN" "AM13"
					( Origin gPackager )
				)
				( objectStatus "U2D1.AM13" )
			)
			( pin "@baseboard_fab2_lib.baseboard_fab2(sch_1):page56_i169:test_4"
				( attribute "PN" "AN12"
					( Origin gPackager )
				)
				( objectStatus "U2D1.AN12" )
			)
			( pin "@baseboard_fab2_lib.baseboard_fab2(sch_1):page56_i169:test_5"
				( attribute "PN" "AN14"
					( Origin gPackager )
				)
				( objectStatus "U2D1.AN14" )
			)
			( pin "@baseboard_fab2_lib.baseboard_fab2(sch_1):page56_i169:test_11"
				( attribute "PN" "AY13"
					( Origin gPackager )
				)
				( objectStatus "U2D1.AY13" )
			)
			( pin "@baseboard_fab2_lib.baseboard_fab2(sch_1):page56_i173:a"
				( attribute "PN" "1"
					( Origin gPackager )
				)
				( objectStatus "R8P3.1" )
			)
			( pin "@baseboard_fab2_lib.baseboard_fab2(sch_1):page56_i173:b"
				( attribute "PN" "2"
					( Origin gPackager )
				)
				( objectStatus "R8P3.2" )
			)
			( pin "@baseboard_fab2_lib.baseboard_fab2(sch_1):page56_i174:a"
				( attribute "PN" "1"
					( Origin gPackager )
				)
				( objectStatus "R8R1.1" )
			)
			( pin "@baseboard_fab2_lib.baseboard_fab2(sch_1):page56_i174:b"
				( attribute "PN" "2"
					( Origin gPackager )
				)
				( objectStatus "R8R1.2" )
			)
			( pin "@baseboard_fab2_lib.baseboard_fab2(sch_1):page57_i172:ddr0_act_n"
				( attribute "PN" "J60"
					( Origin gPackager )
				)
				( objectStatus "U2D1.J60" )
			)
			( pin "@baseboard_fab2_lib.baseboard_fab2(sch_1):page57_i172:ddr0_alert_n"
				( attribute "PN" "B61"
					( Origin gPackager )
				)
				( objectStatus "U2D1.B61" )
			)
			( pin "@baseboard_fab2_lib.baseboard_fab2(sch_1):page57_i172:ddr0_ba(0)"
				( attribute "PN" "C52"
					( Origin gPackager )
				)
				( objectStatus "U2D1.C52" )
			)
			( pin "@baseboard_fab2_lib.baseboard_fab2(sch_1):page57_i172:ddr0_ba(1)"
				( attribute "PN" "G54"
					( Origin gPackager )
				)
				( objectStatus "U2D1.G54" )
			)
			( pin "@baseboard_fab2_lib.baseboard_fab2(sch_1):page57_i172:ddr0_bg(0)"
				( attribute "PN" "D61"
					( Origin gPackager )
				)
				( objectStatus "U2D1.D61" )
			)
			( pin "@baseboard_fab2_lib.baseboard_fab2(sch_1):page57_i172:ddr0_bg(1)"
				( attribute "PN" "F63"
					( Origin gPackager )
				)
				( objectStatus "U2D1.F63" )
			)
			( pin "@baseboard_fab2_lib.baseboard_fab2(sch_1):page57_i172:ddr0_cid(2)"
				( attribute "PN" "G46"
					( Origin gPackager )
				)
				( objectStatus "U2D1.G46" )
			)
			( pin "@baseboard_fab2_lib.baseboard_fab2(sch_1):page57_i172:ddr0_cke(0)"
				( attribute "PN" "C62"
					( Origin gPackager )
				)
				( objectStatus "U2D1.C62" )
			)
			( pin "@baseboard_fab2_lib.baseboard_fab2(sch_1):page57_i172:ddr0_cke(1)"
				( attribute "PN" "C64"
					( Origin gPackager )
				)
				( objectStatus "U2D1.C64" )
			)
			( pin "@baseboard_fab2_lib.baseboard_fab2(sch_1):page57_i172:ddr0_cke(2)"
				( attribute "PN" "B63"
					( Origin gPackager )
				)
				( objectStatus "U2D1.B63" )
			)
			( pin "@baseboard_fab2_lib.baseboard_fab2(sch_1):page57_i172:ddr0_cke(3)"
				( attribute "PN" "D63"
					( Origin gPackager )
				)
				( objectStatus "U2D1.D63" )
			)
			( pin "@baseboard_fab2_lib.baseboard_fab2(sch_1):page57_i172:ddr0_clk_dn(0)"
				( attribute "PN" "F55"
					( Origin gPackager )
				)
				( objectStatus "U2D1.F55" )
			)
			( pin "@baseboard_fab2_lib.baseboard_fab2(sch_1):page57_i172:ddr0_clk_dn(1)"
				( attribute "PN" "C54"
					( Origin gPackager )
				)
				( objectStatus "U2D1.C54" )
			)
			( pin "@baseboard_fab2_lib.baseboard_fab2(sch_1):page57_i172:ddr0_clk_dn(2)"
				( attribute "PN" "J56"
					( Origin gPackager )
				)
				( objectStatus "U2D1.J56" )
			)
			( pin "@baseboard_fab2_lib.baseboard_fab2(sch_1):page57_i172:ddr0_clk_dn(3)"
				( attribute "PN" "C56"
					( Origin gPackager )
				)
				( objectStatus "U2D1.C56" )
			)
			( pin "@baseboard_fab2_lib.baseboard_fab2(sch_1):page57_i172:ddr0_clk_dp(0)"
				( attribute "PN" "D55"
					( Origin gPackager )
				)
				( objectStatus "U2D1.D55" )
			)
			( pin "@baseboard_fab2_lib.baseboard_fab2(sch_1):page57_i172:ddr0_clk_dp(1)"
				( attribute "PN" "B55"
					( Origin gPackager )
				)
				( objectStatus "U2D1.B55" )
			)
			( pin "@baseboard_fab2_lib.baseboard_fab2(sch_1):page57_i172:ddr0_clk_dp(2)"
				( attribute "PN" "G56"
					( Origin gPackager )
				)
				( objectStatus "U2D1.G56" )
			)
			( pin "@baseboard_fab2_lib.baseboard_fab2(sch_1):page57_i172:ddr0_clk_dp(3)"
				( attribute "PN" "B57"
					( Origin gPackager )
				)
				( objectStatus "U2D1.B57" )
			)
			( pin "@baseboard_fab2_lib.baseboard_fab2(sch_1):page57_i172:ddr0_cs_n(0)"
				( attribute "PN" "G52"
					( Origin gPackager )
				)
				( objectStatus "U2D1.G52" )
			)
			( pin "@baseboard_fab2_lib.baseboard_fab2(sch_1):page57_i172:ddr0_cs_n(1)"
				( attribute "PN" "F49"
					( Origin gPackager )
				)
				( objectStatus "U2D1.F49" )
			)
			( pin "@baseboard_fab2_lib.baseboard_fab2(sch_1):page57_i172:ddr0_cs_n(2)"
				( attribute "PN" "D47"
					( Origin gPackager )
				)
				( objectStatus "U2D1.D47" )
			)
			( pin "@baseboard_fab2_lib.baseboard_fab2(sch_1):page57_i172:ddr0_cs_n(3)"
				( attribute "PN" "F47"
					( Origin gPackager )
				)
				( objectStatus "U2D1.F47" )
			)
			( pin "@baseboard_fab2_lib.baseboard_fab2(sch_1):page57_i172:ddr0_cs_n(4)"
				( attribute "PN" "B51"
					( Origin gPackager )
				)
				( objectStatus "U2D1.B51" )
			)
			( pin "@baseboard_fab2_lib.baseboard_fab2(sch_1):page57_i172:ddr0_cs_n(5)"
				( attribute "PN" "D49"
					( Origin gPackager )
				)
				( objectStatus "U2D1.D49" )
			)
			( pin "@baseboard_fab2_lib.baseboard_fab2(sch_1):page57_i172:ddr0_cs_n(6)"
				( attribute "PN" "F45"
					( Origin gPackager )
				)
				( objectStatus "U2D1.F45" )
			)
			( pin "@baseboard_fab2_lib.baseboard_fab2(sch_1):page57_i172:ddr0_cs_n(7)"
				( attribute "PN" "K45"
					( Origin gPackager )
				)
				( objectStatus "U2D1.K45" )
			)
			( pin "@baseboard_fab2_lib.baseboard_fab2(sch_1):page57_i172:ddr0_dq(0)"
				( attribute "PN" "AN86"
					( Origin gPackager )
				)
				( objectStatus "U2D1.AN86" )
			)
			( pin "@baseboard_fab2_lib.baseboard_fab2(sch_1):page57_i172:ddr0_dq(1)"
				( attribute "PN" "AN84"
					( Origin gPackager )
				)
				( objectStatus "U2D1.AN84" )
			)
			( pin "@baseboard_fab2_lib.baseboard_fab2(sch_1):page57_i172:ddr0_dq(2)"
				( attribute "PN" "AE86"
					( Origin gPackager )
				)
				( objectStatus "U2D1.AE86" )
			)
			( pin "@baseboard_fab2_lib.baseboard_fab2(sch_1):page57_i172:ddr0_dq(3)"
				( attribute "PN" "AE84"
					( Origin gPackager )
				)
				( objectStatus "U2D1.AE84" )
			)
			( pin "@baseboard_fab2_lib.baseboard_fab2(sch_1):page57_i172:ddr0_dq(4)"
				( attribute "PN" "AR86"
					( Origin gPackager )
				)
				( objectStatus "U2D1.AR86" )
			)
			( pin "@baseboard_fab2_lib.baseboard_fab2(sch_1):page57_i172:ddr0_dq(5)"
				( attribute "PN" "AR84"
					( Origin gPackager )
				)
				( objectStatus "U2D1.AR84" )
			)
			( pin "@baseboard_fab2_lib.baseboard_fab2(sch_1):page57_i172:ddr0_dq(6)"
				( attribute "PN" "AG86"
					( Origin gPackager )
				)
				( objectStatus "U2D1.AG86" )
			)
			( pin "@baseboard_fab2_lib.baseboard_fab2(sch_1):page57_i172:ddr0_dq(7)"
				( attribute "PN" "AG84"
					( Origin gPackager )
				)
				( objectStatus "U2D1.AG84" )
			)
			( pin "@baseboard_fab2_lib.baseboard_fab2(sch_1):page57_i172:ddr0_dq(8)"
				( attribute "PN" "W86"
					( Origin gPackager )
				)
				( objectStatus "U2D1.W86" )
			)
			( pin "@baseboard_fab2_lib.baseboard_fab2(sch_1):page57_i172:ddr0_dq(9)"
				( attribute "PN" "W84"
					( Origin gPackager )
				)
				( objectStatus "U2D1.W84" )
			)
			( pin "@baseboard_fab2_lib.baseboard_fab2(sch_1):page57_i172:ddr0_dq(10)"
				( attribute "PN" "L86"
					( Origin gPackager )
				)
				( objectStatus "U2D1.L86" )
			)
			( pin "@baseboard_fab2_lib.baseboard_fab2(sch_1):page57_i172:ddr0_dq(11)"
				( attribute "PN" "L84"
					( Origin gPackager )
				)
				( objectStatus "U2D1.L84" )
			)
			( pin "@baseboard_fab2_lib.baseboard_fab2(sch_1):page57_i172:ddr0_dq(12)"
				( attribute "PN" "AA86"
					( Origin gPackager )
				)
				( objectStatus "U2D1.AA86" )
			)
			( pin "@baseboard_fab2_lib.baseboard_fab2(sch_1):page57_i172:ddr0_dq(13)"
				( attribute "PN" "AA84"
					( Origin gPackager )
				)
				( objectStatus "U2D1.AA84" )
			)
			( pin "@baseboard_fab2_lib.baseboard_fab2(sch_1):page57_i172:ddr0_dq(14)"
				( attribute "PN" "N86"
					( Origin gPackager )
				)
				( objectStatus "U2D1.N86" )
			)
			( pin "@baseboard_fab2_lib.baseboard_fab2(sch_1):page57_i172:ddr0_dq(15)"
				( attribute "PN" "N84"
					( Origin gPackager )
				)
				( objectStatus "U2D1.N84" )
			)
			( pin "@baseboard_fab2_lib.baseboard_fab2(sch_1):page57_i172:ddr0_dq(16)"
				( attribute "PN" "V81"
					( Origin gPackager )
				)
				( objectStatus "U2D1.V81" )
			)
			( pin "@baseboard_fab2_lib.baseboard_fab2(sch_1):page57_i172:ddr0_dq(17)"
				( attribute "PN" "T79"
					( Origin gPackager )
				)
				( objectStatus "U2D1.T79" )
			)
			( pin "@baseboard_fab2_lib.baseboard_fab2(sch_1):page57_i172:ddr0_dq(18)"
				( attribute "PN" "N82"
					( Origin gPackager )
				)
				( objectStatus "U2D1.N82" )
			)
			( pin "@baseboard_fab2_lib.baseboard_fab2(sch_1):page57_i172:ddr0_dq(19)"
				( attribute "PN" "M81"
					( Origin gPackager )
				)
				( objectStatus "U2D1.M81" )
			)
			( pin "@baseboard_fab2_lib.baseboard_fab2(sch_1):page57_i172:ddr0_dq(20)"
				( attribute "PN" "W80"
					( Origin gPackager )
				)
				( objectStatus "U2D1.W80" )
			)
			( pin "@baseboard_fab2_lib.baseboard_fab2(sch_1):page57_i172:ddr0_dq(21)"
				( attribute "PN" "V79"
					( Origin gPackager )
				)
				( objectStatus "U2D1.V79" )
			)
			( pin "@baseboard_fab2_lib.baseboard_fab2(sch_1):page57_i172:ddr0_dq(22)"
				( attribute "PN" "R82"
					( Origin gPackager )
				)
				( objectStatus "U2D1.R82" )
			)
			( pin "@baseboard_fab2_lib.baseboard_fab2(sch_1):page57_i172:ddr0_dq(23)"
				( attribute "PN" "N80"
					( Origin gPackager )
				)
				( objectStatus "U2D1.N80" )
			)
			( pin "@baseboard_fab2_lib.baseboard_fab2(sch_1):page57_i172:ddr0_dq(24)"
				( attribute "PN" "L76"
					( Origin gPackager )
				)
				( objectStatus "U2D1.L76" )
			)
			( pin "@baseboard_fab2_lib.baseboard_fab2(sch_1):page57_i172:ddr0_dq(25)"
				( attribute "PN" "R76"
					( Origin gPackager )
				)
				( objectStatus "U2D1.R76" )
			)
			( pin "@baseboard_fab2_lib.baseboard_fab2(sch_1):page57_i172:ddr0_dq(26)"
				( attribute "PN" "M73"
					( Origin gPackager )
				)
				( objectStatus "U2D1.M73" )
			)
			( pin "@baseboard_fab2_lib.baseboard_fab2(sch_1):page57_i172:ddr0_dq(27)"
				( attribute "PN" "P73"
					( Origin gPackager )
				)
				( objectStatus "U2D1.P73" )
			)
			( pin "@baseboard_fab2_lib.baseboard_fab2(sch_1):page57_i172:ddr0_dq(28)"
				( attribute "PN" "M77"
					( Origin gPackager )
				)
				( objectStatus "U2D1.M77" )
			)
			( pin "@baseboard_fab2_lib.baseboard_fab2(sch_1):page57_i172:ddr0_dq(29)"
				( attribute "PN" "P77"
					( Origin gPackager )
				)
				( objectStatus "U2D1.P77" )
			)
			( pin "@baseboard_fab2_lib.baseboard_fab2(sch_1):page57_i172:ddr0_dq(30)"
				( attribute "PN" "L74"
					( Origin gPackager )
				)
				( objectStatus "U2D1.L74" )
			)
			( pin "@baseboard_fab2_lib.baseboard_fab2(sch_1):page57_i172:ddr0_dq(31)"
				( attribute "PN" "R74"
					( Origin gPackager )
				)
				( objectStatus "U2D1.R74" )
			)
			( pin "@baseboard_fab2_lib.baseboard_fab2(sch_1):page57_i172:ddr0_dq(32)"
				( attribute "PN" "C42"
					( Origin gPackager )
				)
				( objectStatus "U2D1.C42" )
			)
			( pin "@baseboard_fab2_lib.baseboard_fab2(sch_1):page57_i172:ddr0_dq(33)"
				( attribute "PN" "B41"
					( Origin gPackager )
				)
				( objectStatus "U2D1.B41" )
			)
			( pin "@baseboard_fab2_lib.baseboard_fab2(sch_1):page57_i172:ddr0_dq(34)"
				( attribute "PN" "C38"
					( Origin gPackager )
				)
				( objectStatus "U2D1.C38" )
			)
			( pin "@baseboard_fab2_lib.baseboard_fab2(sch_1):page57_i172:ddr0_dq(35)"
				( attribute "PN" "E38"
					( Origin gPackager )
				)
				( objectStatus "U2D1.E38" )
			)
			( pin "@baseboard_fab2_lib.baseboard_fab2(sch_1):page57_i172:ddr0_dq(36)"
				( attribute "PN" "E42"
					( Origin gPackager )
				)
				( objectStatus "U2D1.E42" )
			)
			( pin "@baseboard_fab2_lib.baseboard_fab2(sch_1):page57_i172:ddr0_dq(37)"
				( attribute "PN" "F41"
					( Origin gPackager )
				)
				( objectStatus "U2D1.F41" )
			)
			( pin "@baseboard_fab2_lib.baseboard_fab2(sch_1):page57_i172:ddr0_dq(38)"
				( attribute "PN" "B39"
					( Origin gPackager )
				)
				( objectStatus "U2D1.B39" )
			)
			( pin "@baseboard_fab2_lib.baseboard_fab2(sch_1):page57_i172:ddr0_dq(39)"
				( attribute "PN" "F39"
					( Origin gPackager )
				)
				( objectStatus "U2D1.F39" )
			)
			( pin "@baseboard_fab2_lib.baseboard_fab2(sch_1):page57_i172:ddr0_dq(40)"
				( attribute "PN" "K37"
					( Origin gPackager )
				)
				( objectStatus "U2D1.K37" )
			)
			( pin "@baseboard_fab2_lib.baseboard_fab2(sch_1):page57_i172:ddr0_dq(41)"
				( attribute "PN" "P37"
					( Origin gPackager )
				)
				( objectStatus "U2D1.P37" )
			)
			( pin "@baseboard_fab2_lib.baseboard_fab2(sch_1):page57_i172:ddr0_dq(42)"
				( attribute "PN" "L34"
					( Origin gPackager )
				)
				( objectStatus "U2D1.L34" )
			)
			( pin "@baseboard_fab2_lib.baseboard_fab2(sch_1):page57_i172:ddr0_dq(43)"
				( attribute "PN" "N34"
					( Origin gPackager )
				)
				( objectStatus "U2D1.N34" )
			)
			( pin "@baseboard_fab2_lib.baseboard_fab2(sch_1):page57_i172:ddr0_dq(44)"
				( attribute "PN" "L38"
					( Origin gPackager )
				)
				( objectStatus "U2D1.L38" )
			)
			( pin "@baseboard_fab2_lib.baseboard_fab2(sch_1):page57_i172:ddr0_dq(45)"
				( attribute "PN" "N38"
					( Origin gPackager )
				)
				( objectStatus "U2D1.N38" )
			)
			( pin "@baseboard_fab2_lib.baseboard_fab2(sch_1):page57_i172:ddr0_dq(46)"
				( attribute "PN" "K35"
					( Origin gPackager )
				)
				( objectStatus "U2D1.K35" )
			)
			( pin "@baseboard_fab2_lib.baseboard_fab2(sch_1):page57_i172:ddr0_dq(47)"
				( attribute "PN" "P35"
					( Origin gPackager )
				)
				( objectStatus "U2D1.P35" )
			)
			( pin "@baseboard_fab2_lib.baseboard_fab2(sch_1):page57_i172:ddr0_dq(48)"
				( attribute "PN" "K31"
					( Origin gPackager )
				)
				( objectStatus "U2D1.K31" )
			)
			( pin "@baseboard_fab2_lib.baseboard_fab2(sch_1):page57_i172:ddr0_dq(49)"
				( attribute "PN" "P31"
					( Origin gPackager )
				)
				( objectStatus "U2D1.P31" )
			)
			( pin "@baseboard_fab2_lib.baseboard_fab2(sch_1):page57_i172:ddr0_dq(50)"
				( attribute "PN" "L28"
					( Origin gPackager )
				)
				( objectStatus "U2D1.L28" )
			)
			( pin "@baseboard_fab2_lib.baseboard_fab2(sch_1):page57_i172:ddr0_dq(51)"
				( attribute "PN" "N28"
					( Origin gPackager )
				)
				( objectStatus "U2D1.N28" )
			)
			( pin "@baseboard_fab2_lib.baseboard_fab2(sch_1):page57_i172:ddr0_dq(52)"
				( attribute "PN" "L32"
					( Origin gPackager )
				)
				( objectStatus "U2D1.L32" )
			)
			( pin "@baseboard_fab2_lib.baseboard_fab2(sch_1):page57_i172:ddr0_dq(53)"
				( attribute "PN" "N32"
					( Origin gPackager )
				)
				( objectStatus "U2D1.N32" )
			)
			( pin "@baseboard_fab2_lib.baseboard_fab2(sch_1):page57_i172:ddr0_dq(54)"
				( attribute "PN" "K29"
					( Origin gPackager )
				)
				( objectStatus "U2D1.K29" )
			)
			( pin "@baseboard_fab2_lib.baseboard_fab2(sch_1):page57_i172:ddr0_dq(55)"
				( attribute "PN" "P29"
					( Origin gPackager )
				)
				( objectStatus "U2D1.P29" )
			)
			( pin "@baseboard_fab2_lib.baseboard_fab2(sch_1):page57_i172:ddr0_dq(56)"
				( attribute "PN" "K25"
					( Origin gPackager )
				)
				( objectStatus "U2D1.K25" )
			)
			( pin "@baseboard_fab2_lib.baseboard_fab2(sch_1):page57_i172:ddr0_dq(57)"
				( attribute "PN" "P25"
					( Origin gPackager )
				)
				( objectStatus "U2D1.P25" )
			)
			( pin "@baseboard_fab2_lib.baseboard_fab2(sch_1):page57_i172:ddr0_dq(58)"
				( attribute "PN" "P23"
					( Origin gPackager )
				)
				( objectStatus "U2D1.P23" )
			)
			( pin "@baseboard_fab2_lib.baseboard_fab2(sch_1):page57_i172:ddr0_dq(59)"
				( attribute "PN" "T23"
					( Origin gPackager )
				)
				( objectStatus "U2D1.T23" )
			)
			( pin "@baseboard_fab2_lib.baseboard_fab2(sch_1):page57_i172:ddr0_dq(60)"
				( attribute "PN" "L26"
					( Origin gPackager )
				)
				( objectStatus "U2D1.L26" )
			)
			( pin "@baseboard_fab2_lib.baseboard_fab2(sch_1):page57_i172:ddr0_dq(61)"
				( attribute "PN" "N26"
					( Origin gPackager )
				)
				( objectStatus "U2D1.N26" )
			)
			( pin "@baseboard_fab2_lib.baseboard_fab2(sch_1):page57_i172:ddr0_dq(62)"
				( attribute "PN" "H23"
					( Origin gPackager )
				)
				( objectStatus "U2D1.H23" )
			)
			( pin "@baseboard_fab2_lib.baseboard_fab2(sch_1):page57_i172:ddr0_dq(63)"
				( attribute "PN" "K23"
					( Origin gPackager )
				)
				( objectStatus "U2D1.K23" )
			)
			( pin "@baseboard_fab2_lib.baseboard_fab2(sch_1):page57_i172:ddr0_dqs_dn(0)"
				( attribute "PN" "AJ84"
					( Origin gPackager )
				)
				( objectStatus "U2D1.AJ84" )
			)
			( pin "@baseboard_fab2_lib.baseboard_fab2(sch_1):page57_i172:ddr0_dqs_dn(1)"
				( attribute "PN" "R84"
					( Origin gPackager )
				)
				( objectStatus "U2D1.R84" )
			)
			( pin "@baseboard_fab2_lib.baseboard_fab2(sch_1):page57_i172:ddr0_dqs_dn(2)"
				( attribute "PN" "P79"
					( Origin gPackager )
				)
				( objectStatus "U2D1.P79" )
			)
			( pin "@baseboard_fab2_lib.baseboard_fab2(sch_1):page57_i172:ddr0_dqs_dn(3)"
				( attribute "PN" "T75"
					( Origin gPackager )
				)
				( objectStatus "U2D1.T75" )
			)
			( pin "@baseboard_fab2_lib.baseboard_fab2(sch_1):page57_i172:ddr0_dqs_dn(4)"
				( attribute "PN" "G40"
					( Origin gPackager )
				)
				( objectStatus "U2D1.G40" )
			)
			( pin "@baseboard_fab2_lib.baseboard_fab2(sch_1):page57_i172:ddr0_dqs_dn(5)"
				( attribute "PN" "R36"
					( Origin gPackager )
				)
				( objectStatus "U2D1.R36" )
			)
			( pin "@baseboard_fab2_lib.baseboard_fab2(sch_1):page57_i172:ddr0_dqs_dn(6)"
				( attribute "PN" "R30"
					( Origin gPackager )
				)
				( objectStatus "U2D1.R30" )
			)
			( pin "@baseboard_fab2_lib.baseboard_fab2(sch_1):page57_i172:ddr0_dqs_dn(7)"
				( attribute "PN" "N24"
					( Origin gPackager )
				)
				( objectStatus "U2D1.N24" )
			)
			( pin "@baseboard_fab2_lib.baseboard_fab2(sch_1):page57_i172:ddr0_dqs_dn(8)"
				( attribute "PN" "AH67"
					( Origin gPackager )
				)
				( objectStatus "U2D1.AH67" )
			)
			( pin "@baseboard_fab2_lib.baseboard_fab2(sch_1):page57_i172:ddr0_dqs_dn(9)"
				( attribute "PN" "AL84"
					( Origin gPackager )
				)
				( objectStatus "U2D1.AL84" )
			)
			( pin "@baseboard_fab2_lib.baseboard_fab2(sch_1):page57_i172:ddr0_dqs_dn(10)"
				( attribute "PN" "U84"
					( Origin gPackager )
				)
				( objectStatus "U2D1.U84" )
			)
			( pin "@baseboard_fab2_lib.baseboard_fab2(sch_1):page57_i172:ddr0_dqs_dn(11)"
				( attribute "PN" "U82"
					( Origin gPackager )
				)
				( objectStatus "U2D1.U82" )
			)
			( pin "@baseboard_fab2_lib.baseboard_fab2(sch_1):page57_i172:ddr0_dqs_dn(12)"
				( attribute "PN" "K75"
					( Origin gPackager )
				)
				( objectStatus "U2D1.K75" )
			)
			( pin "@baseboard_fab2_lib.baseboard_fab2(sch_1):page57_i172:ddr0_dqs_dn(13)"
				( attribute "PN" "A40"
					( Origin gPackager )
				)
				( objectStatus "U2D1.A40" )
			)
			( pin "@baseboard_fab2_lib.baseboard_fab2(sch_1):page57_i172:ddr0_dqs_dn(14)"
				( attribute "PN" "J36"
					( Origin gPackager )
				)
				( objectStatus "U2D1.J36" )
			)
			( pin "@baseboard_fab2_lib.baseboard_fab2(sch_1):page57_i172:ddr0_dqs_dn(15)"
				( attribute "PN" "J30"
					( Origin gPackager )
				)
				( objectStatus "U2D1.J30" )
			)
			( pin "@baseboard_fab2_lib.baseboard_fab2(sch_1):page57_i172:ddr0_dqs_dn(16)"
				( attribute "PN" "J24"
					( Origin gPackager )
				)
				( objectStatus "U2D1.J24" )
			)
			( pin "@baseboard_fab2_lib.baseboard_fab2(sch_1):page57_i172:ddr0_dqs_dn(17)"
				( attribute "PN" "AB67"
					( Origin gPackager )
				)
				( objectStatus "U2D1.AB67" )
			)
			( pin "@baseboard_fab2_lib.baseboard_fab2(sch_1):page57_i172:ddr0_dqs_dp(0)"
				( attribute "PN" "AH85"
					( Origin gPackager )
				)
				( objectStatus "U2D1.AH85" )
			)
			( pin "@baseboard_fab2_lib.baseboard_fab2(sch_1):page57_i172:ddr0_dqs_dp(1)"
				( attribute "PN" "P85"
					( Origin gPackager )
				)
				( objectStatus "U2D1.P85" )
			)
			( pin "@baseboard_fab2_lib.baseboard_fab2(sch_1):page57_i172:ddr0_dqs_dp(2)"
				( attribute "PN" "R80"
					( Origin gPackager )
				)
				( objectStatus "U2D1.R80" )
			)
			( pin "@baseboard_fab2_lib.baseboard_fab2(sch_1):page57_i172:ddr0_dqs_dp(3)"
				( attribute "PN" "P75"
					( Origin gPackager )
				)
				( objectStatus "U2D1.P75" )
			)
			( pin "@baseboard_fab2_lib.baseboard_fab2(sch_1):page57_i172:ddr0_dqs_dp(4)"
				( attribute "PN" "E40"
					( Origin gPackager )
				)
				( objectStatus "U2D1.E40" )
			)
			( pin "@baseboard_fab2_lib.baseboard_fab2(sch_1):page57_i172:ddr0_dqs_dp(5)"
				( attribute "PN" "N36"
					( Origin gPackager )
				)
				( objectStatus "U2D1.N36" )
			)
			( pin "@baseboard_fab2_lib.baseboard_fab2(sch_1):page57_i172:ddr0_dqs_dp(6)"
				( attribute "PN" "N30"
					( Origin gPackager )
				)
				( objectStatus "U2D1.N30" )
			)
			( pin "@baseboard_fab2_lib.baseboard_fab2(sch_1):page57_i172:ddr0_dqs_dp(7)"
				( attribute "PN" "R24"
					( Origin gPackager )
				)
				( objectStatus "U2D1.R24" )
			)
			( pin "@baseboard_fab2_lib.baseboard_fab2(sch_1):page57_i172:ddr0_dqs_dp(8)"
				( attribute "PN" "AF67"
					( Origin gPackager )
				)
				( objectStatus "U2D1.AF67" )
			)
			( pin "@baseboard_fab2_lib.baseboard_fab2(sch_1):page57_i172:ddr0_dqs_dp(9)"
				( attribute "PN" "AM85"
					( Origin gPackager )
				)
				( objectStatus "U2D1.AM85" )
			)
			( pin "@baseboard_fab2_lib.baseboard_fab2(sch_1):page57_i172:ddr0_dqs_dp(10)"
				( attribute "PN" "V85"
					( Origin gPackager )
				)
				( objectStatus "U2D1.V85" )
			)
			( pin "@baseboard_fab2_lib.baseboard_fab2(sch_1):page57_i172:ddr0_dqs_dp(11)"
				( attribute "PN" "T81"
					( Origin gPackager )
				)
				( objectStatus "U2D1.T81" )
			)
			( pin "@baseboard_fab2_lib.baseboard_fab2(sch_1):page57_i172:ddr0_dqs_dp(12)"
				( attribute "PN" "M75"
					( Origin gPackager )
				)
				( objectStatus "U2D1.M75" )
			)
			( pin "@baseboard_fab2_lib.baseboard_fab2(sch_1):page57_i172:ddr0_dqs_dp(13)"
				( attribute "PN" "C40"
					( Origin gPackager )
				)
				( objectStatus "U2D1.C40" )
			)
			( pin "@baseboard_fab2_lib.baseboard_fab2(sch_1):page57_i172:ddr0_dqs_dp(14)"
				( attribute "PN" "L36"
					( Origin gPackager )
				)
				( objectStatus "U2D1.L36" )
			)
			( pin "@baseboard_fab2_lib.baseboard_fab2(sch_1):page57_i172:ddr0_dqs_dp(15)"
				( attribute "PN" "L30"
					( Origin gPackager )
				)
				( objectStatus "U2D1.L30" )
			)
			( pin "@baseboard_fab2_lib.baseboard_fab2(sch_1):page57_i172:ddr0_dqs_dp(16)"
				( attribute "PN" "L24"
					( Origin gPackager )
				)
				( objectStatus "U2D1.L24" )
			)
			( pin "@baseboard_fab2_lib.baseboard_fab2(sch_1):page57_i172:ddr0_dqs_dp(17)"
				( attribute "PN" "AD67"
					( Origin gPackager )
				)
				( objectStatus "U2D1.AD67" )
			)
			( pin "@baseboard_fab2_lib.baseboard_fab2(sch_1):page57_i172:ddr0_ecc(0)"
				( attribute "PN" "AC68"
					( Origin gPackager )
				)
				( objectStatus "U2D1.AC68" )
			)
			( pin "@baseboard_fab2_lib.baseboard_fab2(sch_1):page57_i172:ddr0_ecc(1)"
				( attribute "PN" "AG68"
					( Origin gPackager )
				)
				( objectStatus "U2D1.AG68" )
			)
			( pin "@baseboard_fab2_lib.baseboard_fab2(sch_1):page57_i172:ddr0_ecc(2)"
				( attribute "PN" "AD65"
					( Origin gPackager )
				)
				( objectStatus "U2D1.AD65" )
			)
			( pin "@baseboard_fab2_lib.baseboard_fab2(sch_1):page57_i172:ddr0_ecc(3)"
				( attribute "PN" "AF65"
					( Origin gPackager )
				)
				( objectStatus "U2D1.AF65" )
			)
			( pin "@baseboard_fab2_lib.baseboard_fab2(sch_1):page57_i172:ddr0_ecc(4)"
				( attribute "PN" "AD69"
					( Origin gPackager )
				)
				( objectStatus "U2D1.AD69" )
			)
			( pin "@baseboard_fab2_lib.baseboard_fab2(sch_1):page57_i172:ddr0_ecc(5)"
				( attribute "PN" "AF69"
					( Origin gPackager )
				)
				( objectStatus "U2D1.AF69" )
			)
			( pin "@baseboard_fab2_lib.baseboard_fab2(sch_1):page57_i172:ddr0_ecc(6)"
				( attribute "PN" "AC66"
					( Origin gPackager )
				)
				( objectStatus "U2D1.AC66" )
			)
			( pin "@baseboard_fab2_lib.baseboard_fab2(sch_1):page57_i172:ddr0_ecc(7)"
				( attribute "PN" "AG66"
					( Origin gPackager )
				)
				( objectStatus "U2D1.AG66" )
			)
			( pin "@baseboard_fab2_lib.baseboard_fab2(sch_1):page57_i172:ddr0_ma(0)"
				( attribute "PN" "F53"
					( Origin gPackager )
				)
				( objectStatus "U2D1.F53" )
			)
			( pin "@baseboard_fab2_lib.baseboard_fab2(sch_1):page57_i172:ddr0_ma(1)"
				( attribute "PN" "F57"
					( Origin gPackager )
				)
				( objectStatus "U2D1.F57" )
			)
			( pin "@baseboard_fab2_lib.baseboard_fab2(sch_1):page57_i172:ddr0_ma(2)"
				( attribute "PN" "D57"
					( Origin gPackager )
				)
				( objectStatus "U2D1.D57" )
			)
			( pin "@baseboard_fab2_lib.baseboard_fab2(sch_1):page57_i172:ddr0_ma(3)"
				( attribute "PN" "C58"
					( Origin gPackager )
				)
				( objectStatus "U2D1.C58" )
			)
			( pin "@baseboard_fab2_lib.baseboard_fab2(sch_1):page57_i172:ddr0_ma(4)"
				( attribute "PN" "G58"
					( Origin gPackager )
				)
				( objectStatus "U2D1.G58" )
			)
			( pin "@baseboard_fab2_lib.baseboard_fab2(sch_1):page57_i172:ddr0_ma(5)"
				( attribute "PN" "F59"
					( Origin gPackager )
				)
				( objectStatus "U2D1.F59" )
			)
			( pin "@baseboard_fab2_lib.baseboard_fab2(sch_1):page57_i172:ddr0_ma(6)"
				( attribute "PN" "D59"
					( Origin gPackager )
				)
				( objectStatus "U2D1.D59" )
			)
			( pin "@baseboard_fab2_lib.baseboard_fab2(sch_1):page57_i172:ddr0_ma(7)"
				( attribute "PN" "G60"
					( Origin gPackager )
				)
				( objectStatus "U2D1.G60" )
			)
			( pin "@baseboard_fab2_lib.baseboard_fab2(sch_1):page57_i172:ddr0_ma(8)"
				( attribute "PN" "C60"
					( Origin gPackager )
				)
				( objectStatus "U2D1.C60" )
			)
			( pin "@baseboard_fab2_lib.baseboard_fab2(sch_1):page57_i172:ddr0_ma(9)"
				( attribute "PN" "F61"
					( Origin gPackager )
				)
				( objectStatus "U2D1.F61" )
			)
			( pin "@baseboard_fab2_lib.baseboard_fab2(sch_1):page57_i172:ddr0_ma(10)"
				( attribute "PN" "J54"
					( Origin gPackager )
				)
				( objectStatus "U2D1.J54" )
			)
			( pin "@baseboard_fab2_lib.baseboard_fab2(sch_1):page57_i172:ddr0_ma(11)"
				( attribute "PN" "G62"
					( Origin gPackager )
				)
				( objectStatus "U2D1.G62" )
			)
			( pin "@baseboard_fab2_lib.baseboard_fab2(sch_1):page57_i172:ddr0_ma(12)"
				( attribute "PN" "J64"
					( Origin gPackager )
				)
				( objectStatus "U2D1.J64" )
			)
			( pin "@baseboard_fab2_lib.baseboard_fab2(sch_1):page57_i172:ddr0_ma(13)"
				( attribute "PN" "J48"
					( Origin gPackager )
				)
				( objectStatus "U2D1.J48" )
			)
			( pin "@baseboard_fab2_lib.baseboard_fab2(sch_1):page57_i172:ddr0_ma(14)"
				( attribute "PN" "F51"
					( Origin gPackager )
				)
				( objectStatus "U2D1.F51" )
			)
			( pin "@baseboard_fab2_lib.baseboard_fab2(sch_1):page57_i172:ddr0_ma(15)"
				( attribute "PN" "K49"
					( Origin gPackager )
				)
				( objectStatus "U2D1.K49" )
			)
			( pin "@baseboard_fab2_lib.baseboard_fab2(sch_1):page57_i172:ddr0_ma(16)"
				( attribute "PN" "D51"
					( Origin gPackager )
				)
				( objectStatus "U2D1.D51" )
			)
			( pin "@baseboard_fab2_lib.baseboard_fab2(sch_1):page57_i172:ddr0_ma(17)"
				( attribute "PN" "K47"
					( Origin gPackager )
				)
				( objectStatus "U2D1.K47" )
			)
			( pin "@baseboard_fab2_lib.baseboard_fab2(sch_1):page57_i172:ddr0_odt(0)"
				( attribute "PN" "C50"
					( Origin gPackager )
				)
				( objectStatus "U2D1.C50" )
			)
			( pin "@baseboard_fab2_lib.baseboard_fab2(sch_1):page57_i172:ddr0_odt(1)"
				( attribute "PN" "C48"
					( Origin gPackager )
				)
				( objectStatus "U2D1.C48" )
			)
			( pin "@baseboard_fab2_lib.baseboard_fab2(sch_1):page57_i172:ddr0_odt(2)"
				( attribute "PN" "G50"
					( Origin gPackager )
				)
				( objectStatus "U2D1.G50" )
			)
			( pin "@baseboard_fab2_lib.baseboard_fab2(sch_1):page57_i172:ddr0_odt(3)"
				( attribute "PN" "G48"
					( Origin gPackager )
				)
				( objectStatus "U2D1.G48" )
			)
			( pin "@baseboard_fab2_lib.baseboard_fab2(sch_1):page57_i172:ddr0_par"
				( attribute "PN" "D53"
					( Origin gPackager )
				)
				( objectStatus "U2D1.D53" )
			)
			( pin "@baseboard_fab2_lib.baseboard_fab2(sch_1):page58_i172:ddr1_act_n"
				( attribute "PN" "T63"
					( Origin gPackager )
				)
				( objectStatus "U2D1.T63" )
			)
			( pin "@baseboard_fab2_lib.baseboard_fab2(sch_1):page58_i172:ddr1_alert_n"
				( attribute "PN" "W62"
					( Origin gPackager )
				)
				( objectStatus "U2D1.W62" )
			)
			( pin "@baseboard_fab2_lib.baseboard_fab2(sch_1):page58_i172:ddr1_ba(0)"
				( attribute "PN" "T53"
					( Origin gPackager )
				)
				( objectStatus "U2D1.T53" )
			)
			( pin "@baseboard_fab2_lib.baseboard_fab2(sch_1):page58_i172:ddr1_ba(1)"
				( attribute "PN" "K55"
					( Origin gPackager )
				)
				( objectStatus "U2D1.K55" )
			)
			( pin "@baseboard_fab2_lib.baseboard_fab2(sch_1):page58_i172:ddr1_bg(0)"
				( attribute "PN" "M61"
					( Origin gPackager )
				)
				( objectStatus "U2D1.M61" )
			)
			( pin "@baseboard_fab2_lib.baseboard_fab2(sch_1):page58_i172:ddr1_bg(1)"
				( attribute "PN" "N60"
					( Origin gPackager )
				)
				( objectStatus "U2D1.N60" )
			)
			( pin "@baseboard_fab2_lib.baseboard_fab2(sch_1):page58_i172:ddr1_cid(2)"
				( attribute "PN" "M47"
					( Origin gPackager )
				)
				( objectStatus "U2D1.M47" )
			)
			( pin "@baseboard_fab2_lib.baseboard_fab2(sch_1):page58_i172:ddr1_cke(0)"
				( attribute "PN" "N62"
					( Origin gPackager )
				)
				( objectStatus "U2D1.N62" )
			)
			( pin "@baseboard_fab2_lib.baseboard_fab2(sch_1):page58_i172:ddr1_cke(1)"
				( attribute "PN" "R64"
					( Origin gPackager )
				)
				( objectStatus "U2D1.R64" )
			)
			( pin "@baseboard_fab2_lib.baseboard_fab2(sch_1):page58_i172:ddr1_cke(2)"
				( attribute "PN" "K63"
					( Origin gPackager )
				)
				( objectStatus "U2D1.K63" )
			)
			( pin "@baseboard_fab2_lib.baseboard_fab2(sch_1):page58_i172:ddr1_cke(3)"
				( attribute "PN" "L64"
					( Origin gPackager )
				)
				( objectStatus "U2D1.L64" )
			)
			( pin "@baseboard_fab2_lib.baseboard_fab2(sch_1):page58_i172:ddr1_clk_dn(0)"
				( attribute "PN" "M53"
					( Origin gPackager )
				)
				( objectStatus "U2D1.M53" )
			)
			( pin "@baseboard_fab2_lib.baseboard_fab2(sch_1):page58_i172:ddr1_clk_dn(1)"
				( attribute "PN" "R54"
					( Origin gPackager )
				)
				( objectStatus "U2D1.R54" )
			)
			( pin "@baseboard_fab2_lib.baseboard_fab2(sch_1):page58_i172:ddr1_clk_dn(2)"
				( attribute "PN" "N56"
					( Origin gPackager )
				)
				( objectStatus "U2D1.N56" )
			)
			( pin "@baseboard_fab2_lib.baseboard_fab2(sch_1):page58_i172:ddr1_clk_dn(3)"
				( attribute "PN" "R56"
					( Origin gPackager )
				)
				( objectStatus "U2D1.R56" )
			)
			( pin "@baseboard_fab2_lib.baseboard_fab2(sch_1):page58_i172:ddr1_clk_dp(0)"
				( attribute "PN" "N54"
					( Origin gPackager )
				)
				( objectStatus "U2D1.N54" )
			)
			( pin "@baseboard_fab2_lib.baseboard_fab2(sch_1):page58_i172:ddr1_clk_dp(1)"
				( attribute "PN" "T55"
					( Origin gPackager )
				)
				( objectStatus "U2D1.T55" )
			)
			( pin "@baseboard_fab2_lib.baseboard_fab2(sch_1):page58_i172:ddr1_clk_dp(2)"
				( attribute "PN" "M57"
					( Origin gPackager )
				)
				( objectStatus "U2D1.M57" )
			)
			( pin "@baseboard_fab2_lib.baseboard_fab2(sch_1):page58_i172:ddr1_clk_dp(3)"
				( attribute "PN" "T57"
					( Origin gPackager )
				)
				( objectStatus "U2D1.T57" )
			)
			( pin "@baseboard_fab2_lib.baseboard_fab2(sch_1):page58_i172:ddr1_cs_n(0)"
				( attribute "PN" "K51"
					( Origin gPackager )
				)
				( objectStatus "U2D1.K51" )
			)
			( pin "@baseboard_fab2_lib.baseboard_fab2(sch_1):page58_i172:ddr1_cs_n(1)"
				( attribute "PN" "R50"
					( Origin gPackager )
				)
				( objectStatus "U2D1.R50" )
			)
			( pin "@baseboard_fab2_lib.baseboard_fab2(sch_1):page58_i172:ddr1_cs_n(2)"
				( attribute "PN" "N46"
					( Origin gPackager )
				)
				( objectStatus "U2D1.N46" )
			)
			( pin "@baseboard_fab2_lib.baseboard_fab2(sch_1):page58_i172:ddr1_cs_n(3)"
				( attribute "PN" "V47"
					( Origin gPackager )
				)
				( objectStatus "U2D1.V47" )
			)
			( pin "@baseboard_fab2_lib.baseboard_fab2(sch_1):page58_i172:ddr1_cs_n(4)"
				( attribute "PN" "J50"
					( Origin gPackager )
				)
				( objectStatus "U2D1.J50" )
			)
			( pin "@baseboard_fab2_lib.baseboard_fab2(sch_1):page58_i172:ddr1_cs_n(5)"
				( attribute "PN" "T49"
					( Origin gPackager )
				)
				( objectStatus "U2D1.T49" )
			)
			( pin "@baseboard_fab2_lib.baseboard_fab2(sch_1):page58_i172:ddr1_cs_n(6)"
				( attribute "PN" "M45"
					( Origin gPackager )
				)
				( objectStatus "U2D1.M45" )
			)
			( pin "@baseboard_fab2_lib.baseboard_fab2(sch_1):page58_i172:ddr1_cs_n(7)"
				( attribute "PN" "R46"
					( Origin gPackager )
				)
				( objectStatus "U2D1.R46" )
			)
			( pin "@baseboard_fab2_lib.baseboard_fab2(sch_1):page58_i172:ddr1_dq(0)"
				( attribute "PN" "AV81"
					( Origin gPackager )
				)
				( objectStatus "U2D1.AV81" )
			)
			( pin "@baseboard_fab2_lib.baseboard_fab2(sch_1):page58_i172:ddr1_dq(1)"
				( attribute "PN" "AT79"
					( Origin gPackager )
				)
				( objectStatus "U2D1.AT79" )
			)
			( pin "@baseboard_fab2_lib.baseboard_fab2(sch_1):page58_i172:ddr1_dq(2)"
				( attribute "PN" "AN82"
					( Origin gPackager )
				)
				( objectStatus "U2D1.AN82" )
			)
			( pin "@baseboard_fab2_lib.baseboard_fab2(sch_1):page58_i172:ddr1_dq(3)"
				( attribute "PN" "AM81"
					( Origin gPackager )
				)
				( objectStatus "U2D1.AM81" )
			)
			( pin "@baseboard_fab2_lib.baseboard_fab2(sch_1):page58_i172:ddr1_dq(4)"
				( attribute "PN" "AW80"
					( Origin gPackager )
				)
				( objectStatus "U2D1.AW80" )
			)
			( pin "@baseboard_fab2_lib.baseboard_fab2(sch_1):page58_i172:ddr1_dq(5)"
				( attribute "PN" "AV79"
					( Origin gPackager )
				)
				( objectStatus "U2D1.AV79" )
			)
			( pin "@baseboard_fab2_lib.baseboard_fab2(sch_1):page58_i172:ddr1_dq(6)"
				( attribute "PN" "AR82"
					( Origin gPackager )
				)
				( objectStatus "U2D1.AR82" )
			)
			( pin "@baseboard_fab2_lib.baseboard_fab2(sch_1):page58_i172:ddr1_dq(7)"
				( attribute "PN" "AN80"
					( Origin gPackager )
				)
				( objectStatus "U2D1.AN80" )
			)
			( pin "@baseboard_fab2_lib.baseboard_fab2(sch_1):page58_i172:ddr1_dq(8)"
				( attribute "PN" "AH81"
					( Origin gPackager )
				)
				( objectStatus "U2D1.AH81" )
			)
			( pin "@baseboard_fab2_lib.baseboard_fab2(sch_1):page58_i172:ddr1_dq(9)"
				( attribute "PN" "AF79"
					( Origin gPackager )
				)
				( objectStatus "U2D1.AF79" )
			)
			( pin "@baseboard_fab2_lib.baseboard_fab2(sch_1):page58_i172:ddr1_dq(10)"
				( attribute "PN" "AC82"
					( Origin gPackager )
				)
				( objectStatus "U2D1.AC82" )
			)
			( pin "@baseboard_fab2_lib.baseboard_fab2(sch_1):page58_i172:ddr1_dq(11)"
				( attribute "PN" "AB81"
					( Origin gPackager )
				)
				( objectStatus "U2D1.AB81" )
			)
			( pin "@baseboard_fab2_lib.baseboard_fab2(sch_1):page58_i172:ddr1_dq(12)"
				( attribute "PN" "AJ80"
					( Origin gPackager )
				)
				( objectStatus "U2D1.AJ80" )
			)
			( pin "@baseboard_fab2_lib.baseboard_fab2(sch_1):page58_i172:ddr1_dq(13)"
				( attribute "PN" "AH79"
					( Origin gPackager )
				)
				( objectStatus "U2D1.AH79" )
			)
			( pin "@baseboard_fab2_lib.baseboard_fab2(sch_1):page58_i172:ddr1_dq(14)"
				( attribute "PN" "AE82"
					( Origin gPackager )
				)
				( objectStatus "U2D1.AE82" )
			)
			( pin "@baseboard_fab2_lib.baseboard_fab2(sch_1):page58_i172:ddr1_dq(15)"
				( attribute "PN" "AC80"
					( Origin gPackager )
				)
				( objectStatus "U2D1.AC80" )
			)
			( pin "@baseboard_fab2_lib.baseboard_fab2(sch_1):page58_i172:ddr1_dq(16)"
				( attribute "PN" "E80"
					( Origin gPackager )
				)
				( objectStatus "U2D1.E80" )
			)
			( pin "@baseboard_fab2_lib.baseboard_fab2(sch_1):page58_i172:ddr1_dq(17)"
				( attribute "PN" "J80"
					( Origin gPackager )
				)
				( objectStatus "U2D1.J80" )
			)
			( pin "@baseboard_fab2_lib.baseboard_fab2(sch_1):page58_i172:ddr1_dq(18)"
				( attribute "PN" "F77"
					( Origin gPackager )
				)
				( objectStatus "U2D1.F77" )
			)
			( pin "@baseboard_fab2_lib.baseboard_fab2(sch_1):page58_i172:ddr1_dq(19)"
				( attribute "PN" "H77"
					( Origin gPackager )
				)
				( objectStatus "U2D1.H77" )
			)
			( pin "@baseboard_fab2_lib.baseboard_fab2(sch_1):page58_i172:ddr1_dq(20)"
				( attribute "PN" "F81"
					( Origin gPackager )
				)
				( objectStatus "U2D1.F81" )
			)
			( pin "@baseboard_fab2_lib.baseboard_fab2(sch_1):page58_i172:ddr1_dq(21)"
				( attribute "PN" "H81"
					( Origin gPackager )
				)
				( objectStatus "U2D1.H81" )
			)
			( pin "@baseboard_fab2_lib.baseboard_fab2(sch_1):page58_i172:ddr1_dq(22)"
				( attribute "PN" "E78"
					( Origin gPackager )
				)
				( objectStatus "U2D1.E78" )
			)
			( pin "@baseboard_fab2_lib.baseboard_fab2(sch_1):page58_i172:ddr1_dq(23)"
				( attribute "PN" "J78"
					( Origin gPackager )
				)
				( objectStatus "U2D1.J78" )
			)
			( pin "@baseboard_fab2_lib.baseboard_fab2(sch_1):page58_i172:ddr1_dq(24)"
				( attribute "PN" "D75"
					( Origin gPackager )
				)
				( objectStatus "U2D1.D75" )
			)
			( pin "@baseboard_fab2_lib.baseboard_fab2(sch_1):page58_i172:ddr1_dq(25)"
				( attribute "PN" "C74"
					( Origin gPackager )
				)
				( objectStatus "U2D1.C74" )
			)
			( pin "@baseboard_fab2_lib.baseboard_fab2(sch_1):page58_i172:ddr1_dq(26)"
				( attribute "PN" "D71"
					( Origin gPackager )
				)
				( objectStatus "U2D1.D71" )
			)
			( pin "@baseboard_fab2_lib.baseboard_fab2(sch_1):page58_i172:ddr1_dq(27)"
				( attribute "PN" "F71"
					( Origin gPackager )
				)
				( objectStatus "U2D1.F71" )
			)
			( pin "@baseboard_fab2_lib.baseboard_fab2(sch_1):page58_i172:ddr1_dq(28)"
				( attribute "PN" "F75"
					( Origin gPackager )
				)
				( objectStatus "U2D1.F75" )
			)
			( pin "@baseboard_fab2_lib.baseboard_fab2(sch_1):page58_i172:ddr1_dq(29)"
				( attribute "PN" "G74"
					( Origin gPackager )
				)
				( objectStatus "U2D1.G74" )
			)
			( pin "@baseboard_fab2_lib.baseboard_fab2(sch_1):page58_i172:ddr1_dq(30)"
				( attribute "PN" "C72"
					( Origin gPackager )
				)
				( objectStatus "U2D1.C72" )
			)
			( pin "@baseboard_fab2_lib.baseboard_fab2(sch_1):page58_i172:ddr1_dq(31)"
				( attribute "PN" "G72"
					( Origin gPackager )
				)
				( objectStatus "U2D1.G72" )
			)
			( pin "@baseboard_fab2_lib.baseboard_fab2(sch_1):page58_i172:ddr1_dq(32)"
				( attribute "PN" "K43"
					( Origin gPackager )
				)
				( objectStatus "U2D1.K43" )
			)
			( pin "@baseboard_fab2_lib.baseboard_fab2(sch_1):page58_i172:ddr1_dq(33)"
				( attribute "PN" "H43"
					( Origin gPackager )
				)
				( objectStatus "U2D1.H43" )
			)
			( pin "@baseboard_fab2_lib.baseboard_fab2(sch_1):page58_i172:ddr1_dq(34)"
				( attribute "PN" "L40"
					( Origin gPackager )
				)
				( objectStatus "U2D1.L40" )
			)
			( pin "@baseboard_fab2_lib.baseboard_fab2(sch_1):page58_i172:ddr1_dq(35)"
				( attribute "PN" "N40"
					( Origin gPackager )
				)
				( objectStatus "U2D1.N40" )
			)
			( pin "@baseboard_fab2_lib.baseboard_fab2(sch_1):page58_i172:ddr1_dq(36)"
				( attribute "PN" "P43"
					( Origin gPackager )
				)
				( objectStatus "U2D1.P43" )
			)
			( pin "@baseboard_fab2_lib.baseboard_fab2(sch_1):page58_i172:ddr1_dq(37)"
				( attribute "PN" "T43"
					( Origin gPackager )
				)
				( objectStatus "U2D1.T43" )
			)
			( pin "@baseboard_fab2_lib.baseboard_fab2(sch_1):page58_i172:ddr1_dq(38)"
				( attribute "PN" "K41"
					( Origin gPackager )
				)
				( objectStatus "U2D1.K41" )
			)
			( pin "@baseboard_fab2_lib.baseboard_fab2(sch_1):page58_i172:ddr1_dq(39)"
				( attribute "PN" "P41"
					( Origin gPackager )
				)
				( objectStatus "U2D1.P41" )
			)
			( pin "@baseboard_fab2_lib.baseboard_fab2(sch_1):page58_i172:ddr1_dq(40)"
				( attribute "PN" "C36"
					( Origin gPackager )
				)
				( objectStatus "U2D1.C36" )
			)
			( pin "@baseboard_fab2_lib.baseboard_fab2(sch_1):page58_i172:ddr1_dq(41)"
				( attribute "PN" "B35"
					( Origin gPackager )
				)
				( objectStatus "U2D1.B35" )
			)
			( pin "@baseboard_fab2_lib.baseboard_fab2(sch_1):page58_i172:ddr1_dq(42)"
				( attribute "PN" "C32"
					( Origin gPackager )
				)
				( objectStatus "U2D1.C32" )
			)
			( pin "@baseboard_fab2_lib.baseboard_fab2(sch_1):page58_i172:ddr1_dq(43)"
				( attribute "PN" "E32"
					( Origin gPackager )
				)
				( objectStatus "U2D1.E32" )
			)
			( pin "@baseboard_fab2_lib.baseboard_fab2(sch_1):page58_i172:ddr1_dq(44)"
				( attribute "PN" "E36"
					( Origin gPackager )
				)
				( objectStatus "U2D1.E36" )
			)
			( pin "@baseboard_fab2_lib.baseboard_fab2(sch_1):page58_i172:ddr1_dq(45)"
				( attribute "PN" "F35"
					( Origin gPackager )
				)
				( objectStatus "U2D1.F35" )
			)
			( pin "@baseboard_fab2_lib.baseboard_fab2(sch_1):page58_i172:ddr1_dq(46)"
				( attribute "PN" "B33"
					( Origin gPackager )
				)
				( objectStatus "U2D1.B33" )
			)
			( pin "@baseboard_fab2_lib.baseboard_fab2(sch_1):page58_i172:ddr1_dq(47)"
				( attribute "PN" "F33"
					( Origin gPackager )
				)
				( objectStatus "U2D1.F33" )
			)
			( pin "@baseboard_fab2_lib.baseboard_fab2(sch_1):page58_i172:ddr1_dq(48)"
				( attribute "PN" "C30"
					( Origin gPackager )
				)
				( objectStatus "U2D1.C30" )
			)
			( pin "@baseboard_fab2_lib.baseboard_fab2(sch_1):page58_i172:ddr1_dq(49)"
				( attribute "PN" "B29"
					( Origin gPackager )
				)
				( objectStatus "U2D1.B29" )
			)
			( pin "@baseboard_fab2_lib.baseboard_fab2(sch_1):page58_i172:ddr1_dq(50)"
				( attribute "PN" "C26"
					( Origin gPackager )
				)
				( objectStatus "U2D1.C26" )
			)
			( pin "@baseboard_fab2_lib.baseboard_fab2(sch_1):page58_i172:ddr1_dq(51)"
				( attribute "PN" "E26"
					( Origin gPackager )
				)
				( objectStatus "U2D1.E26" )
			)
			( pin "@baseboard_fab2_lib.baseboard_fab2(sch_1):page58_i172:ddr1_dq(52)"
				( attribute "PN" "E30"
					( Origin gPackager )
				)
				( objectStatus "U2D1.E30" )
			)
			( pin "@baseboard_fab2_lib.baseboard_fab2(sch_1):page58_i172:ddr1_dq(53)"
				( attribute "PN" "F29"
					( Origin gPackager )
				)
				( objectStatus "U2D1.F29" )
			)
			( pin "@baseboard_fab2_lib.baseboard_fab2(sch_1):page58_i172:ddr1_dq(54)"
				( attribute "PN" "B27"
					( Origin gPackager )
				)
				( objectStatus "U2D1.B27" )
			)
			( pin "@baseboard_fab2_lib.baseboard_fab2(sch_1):page58_i172:ddr1_dq(55)"
				( attribute "PN" "F27"
					( Origin gPackager )
				)
				( objectStatus "U2D1.F27" )
			)
			( pin "@baseboard_fab2_lib.baseboard_fab2(sch_1):page58_i172:ddr1_dq(56)"
				( attribute "PN" "U28"
					( Origin gPackager )
				)
				( objectStatus "U2D1.U28" )
			)
			( pin "@baseboard_fab2_lib.baseboard_fab2(sch_1):page58_i172:ddr1_dq(57)"
				( attribute "PN" "AA28"
					( Origin gPackager )
				)
				( objectStatus "U2D1.AA28" )
			)
			( pin "@baseboard_fab2_lib.baseboard_fab2(sch_1):page58_i172:ddr1_dq(58)"
				( attribute "PN" "V25"
					( Origin gPackager )
				)
				( objectStatus "U2D1.V25" )
			)
			( pin "@baseboard_fab2_lib.baseboard_fab2(sch_1):page58_i172:ddr1_dq(59)"
				( attribute "PN" "Y25"
					( Origin gPackager )
				)
				( objectStatus "U2D1.Y25" )
			)
			( pin "@baseboard_fab2_lib.baseboard_fab2(sch_1):page58_i172:ddr1_dq(60)"
				( attribute "PN" "V29"
					( Origin gPackager )
				)
				( objectStatus "U2D1.V29" )
			)
			( pin "@baseboard_fab2_lib.baseboard_fab2(sch_1):page58_i172:ddr1_dq(61)"
				( attribute "PN" "Y29"
					( Origin gPackager )
				)
				( objectStatus "U2D1.Y29" )
			)
			( pin "@baseboard_fab2_lib.baseboard_fab2(sch_1):page58_i172:ddr1_dq(62)"
				( attribute "PN" "U26"
					( Origin gPackager )
				)
				( objectStatus "U2D1.U26" )
			)
			( pin "@baseboard_fab2_lib.baseboard_fab2(sch_1):page58_i172:ddr1_dq(63)"
				( attribute "PN" "AA26"
					( Origin gPackager )
				)
				( objectStatus "U2D1.AA26" )
			)
			( pin "@baseboard_fab2_lib.baseboard_fab2(sch_1):page58_i172:ddr1_dqs_dn(0)"
				( attribute "PN" "AP79"
					( Origin gPackager )
				)
				( objectStatus "U2D1.AP79" )
			)
			( pin "@baseboard_fab2_lib.baseboard_fab2(sch_1):page58_i172:ddr1_dqs_dn(1)"
				( attribute "PN" "AD79"
					( Origin gPackager )
				)
				( objectStatus "U2D1.AD79" )
			)
			( pin "@baseboard_fab2_lib.baseboard_fab2(sch_1):page58_i172:ddr1_dqs_dn(2)"
				( attribute "PN" "K79"
					( Origin gPackager )
				)
				( objectStatus "U2D1.K79" )
			)
			( pin "@baseboard_fab2_lib.baseboard_fab2(sch_1):page58_i172:ddr1_dqs_dn(3)"
				( attribute "PN" "H73"
					( Origin gPackager )
				)
				( objectStatus "U2D1.H73" )
			)
			( pin "@baseboard_fab2_lib.baseboard_fab2(sch_1):page58_i172:ddr1_dqs_dn(4)"
				( attribute "PN" "N42"
					( Origin gPackager )
				)
				( objectStatus "U2D1.N42" )
			)
			( pin "@baseboard_fab2_lib.baseboard_fab2(sch_1):page58_i172:ddr1_dqs_dn(5)"
				( attribute "PN" "G34"
					( Origin gPackager )
				)
				( objectStatus "U2D1.G34" )
			)
			( pin "@baseboard_fab2_lib.baseboard_fab2(sch_1):page58_i172:ddr1_dqs_dn(6)"
				( attribute "PN" "G28"
					( Origin gPackager )
				)
				( objectStatus "U2D1.G28" )
			)
			( pin "@baseboard_fab2_lib.baseboard_fab2(sch_1):page58_i172:ddr1_dqs_dn(7)"
				( attribute "PN" "AB27"
					( Origin gPackager )
				)
				( objectStatus "U2D1.AB27" )
			)
			( pin "@baseboard_fab2_lib.baseboard_fab2(sch_1):page58_i172:ddr1_dqs_dn(8)"
				( attribute "PN" "N68"
					( Origin gPackager )
				)
				( objectStatus "U2D1.N68" )
			)
			( pin "@baseboard_fab2_lib.baseboard_fab2(sch_1):page58_i172:ddr1_dqs_dn(9)"
				( attribute "PN" "AU82"
					( Origin gPackager )
				)
				( objectStatus "U2D1.AU82" )
			)
			( pin "@baseboard_fab2_lib.baseboard_fab2(sch_1):page58_i172:ddr1_dqs_dn(10)"
				( attribute "PN" "AG82"
					( Origin gPackager )
				)
				( objectStatus "U2D1.AG82" )
			)
			( pin "@baseboard_fab2_lib.baseboard_fab2(sch_1):page58_i172:ddr1_dqs_dn(11)"
				( attribute "PN" "D79"
					( Origin gPackager )
				)
				( objectStatus "U2D1.D79" )
			)
			( pin "@baseboard_fab2_lib.baseboard_fab2(sch_1):page58_i172:ddr1_dqs_dn(12)"
				( attribute "PN" "B73"
					( Origin gPackager )
				)
				( objectStatus "U2D1.B73" )
			)
			( pin "@baseboard_fab2_lib.baseboard_fab2(sch_1):page58_i172:ddr1_dqs_dn(13)"
				( attribute "PN" "J42"
					( Origin gPackager )
				)
				( objectStatus "U2D1.J42" )
			)
			( pin "@baseboard_fab2_lib.baseboard_fab2(sch_1):page58_i172:ddr1_dqs_dn(14)"
				( attribute "PN" "A34"
					( Origin gPackager )
				)
				( objectStatus "U2D1.A34" )
			)
			( pin "@baseboard_fab2_lib.baseboard_fab2(sch_1):page58_i172:ddr1_dqs_dn(15)"
				( attribute "PN" "A28"
					( Origin gPackager )
				)
				( objectStatus "U2D1.A28" )
			)
			( pin "@baseboard_fab2_lib.baseboard_fab2(sch_1):page58_i172:ddr1_dqs_dn(16)"
				( attribute "PN" "T27"
					( Origin gPackager )
				)
				( objectStatus "U2D1.T27" )
			)
			( pin "@baseboard_fab2_lib.baseboard_fab2(sch_1):page58_i172:ddr1_dqs_dn(17)"
				( attribute "PN" "G68"
					( Origin gPackager )
				)
				( objectStatus "U2D1.G68" )
			)
			( pin "@baseboard_fab2_lib.baseboard_fab2(sch_1):page58_i172:ddr1_dqs_dp(0)"
				( attribute "PN" "AR80"
					( Origin gPackager )
				)
				( objectStatus "U2D1.AR80" )
			)
			( pin "@baseboard_fab2_lib.baseboard_fab2(sch_1):page58_i172:ddr1_dqs_dp(1)"
				( attribute "PN" "AE80"
					( Origin gPackager )
				)
				( objectStatus "U2D1.AE80" )
			)
			( pin "@baseboard_fab2_lib.baseboard_fab2(sch_1):page58_i172:ddr1_dqs_dp(2)"
				( attribute "PN" "H79"
					( Origin gPackager )
				)
				( objectStatus "U2D1.H79" )
			)
			( pin "@baseboard_fab2_lib.baseboard_fab2(sch_1):page58_i172:ddr1_dqs_dp(3)"
				( attribute "PN" "F73"
					( Origin gPackager )
				)
				( objectStatus "U2D1.F73" )
			)
			( pin "@baseboard_fab2_lib.baseboard_fab2(sch_1):page58_i172:ddr1_dqs_dp(4)"
				( attribute "PN" "R42"
					( Origin gPackager )
				)
				( objectStatus "U2D1.R42" )
			)
			( pin "@baseboard_fab2_lib.baseboard_fab2(sch_1):page58_i172:ddr1_dqs_dp(5)"
				( attribute "PN" "E34"
					( Origin gPackager )
				)
				( objectStatus "U2D1.E34" )
			)
			( pin "@baseboard_fab2_lib.baseboard_fab2(sch_1):page58_i172:ddr1_dqs_dp(6)"
				( attribute "PN" "E28"
					( Origin gPackager )
				)
				( objectStatus "U2D1.E28" )
			)
			( pin "@baseboard_fab2_lib.baseboard_fab2(sch_1):page58_i172:ddr1_dqs_dp(7)"
				( attribute "PN" "Y27"
					( Origin gPackager )
				)
				( objectStatus "U2D1.Y27" )
			)
			( pin "@baseboard_fab2_lib.baseboard_fab2(sch_1):page58_i172:ddr1_dqs_dp(8)"
				( attribute "PN" "L68"
					( Origin gPackager )
				)
				( objectStatus "U2D1.L68" )
			)
			( pin "@baseboard_fab2_lib.baseboard_fab2(sch_1):page58_i172:ddr1_dqs_dp(9)"
				( attribute "PN" "AT81"
					( Origin gPackager )
				)
				( objectStatus "U2D1.AT81" )
			)
			( pin "@baseboard_fab2_lib.baseboard_fab2(sch_1):page58_i172:ddr1_dqs_dp(10)"
				( attribute "PN" "AF81"
					( Origin gPackager )
				)
				( objectStatus "U2D1.AF81" )
			)
			( pin "@baseboard_fab2_lib.baseboard_fab2(sch_1):page58_i172:ddr1_dqs_dp(11)"
				( attribute "PN" "F79"
					( Origin gPackager )
				)
				( objectStatus "U2D1.F79" )
			)
			( pin "@baseboard_fab2_lib.baseboard_fab2(sch_1):page58_i172:ddr1_dqs_dp(12)"
				( attribute "PN" "D73"
					( Origin gPackager )
				)
				( objectStatus "U2D1.D73" )
			)
			( pin "@baseboard_fab2_lib.baseboard_fab2(sch_1):page58_i172:ddr1_dqs_dp(13)"
				( attribute "PN" "L42"
					( Origin gPackager )
				)
				( objectStatus "U2D1.L42" )
			)
			( pin "@baseboard_fab2_lib.baseboard_fab2(sch_1):page58_i172:ddr1_dqs_dp(14)"
				( attribute "PN" "C34"
					( Origin gPackager )
				)
				( objectStatus "U2D1.C34" )
			)
			( pin "@baseboard_fab2_lib.baseboard_fab2(sch_1):page58_i172:ddr1_dqs_dp(15)"
				( attribute "PN" "C28"
					( Origin gPackager )
				)
				( objectStatus "U2D1.C28" )
			)
			( pin "@baseboard_fab2_lib.baseboard_fab2(sch_1):page58_i172:ddr1_dqs_dp(16)"
				( attribute "PN" "V27"
					( Origin gPackager )
				)
				( objectStatus "U2D1.V27" )
			)
			( pin "@baseboard_fab2_lib.baseboard_fab2(sch_1):page58_i172:ddr1_dqs_dp(17)"
				( attribute "PN" "J68"
					( Origin gPackager )
				)
				( objectStatus "U2D1.J68" )
			)
			( pin "@baseboard_fab2_lib.baseboard_fab2(sch_1):page58_i172:ddr1_ecc(0)"
				( attribute "PN" "J70"
					( Origin gPackager )
				)
				( objectStatus "U2D1.J70" )
			)
			( pin "@baseboard_fab2_lib.baseboard_fab2(sch_1):page58_i172:ddr1_ecc(1)"
				( attribute "PN" "H69"
					( Origin gPackager )
				)
				( objectStatus "U2D1.H69" )
			)
			( pin "@baseboard_fab2_lib.baseboard_fab2(sch_1):page58_i172:ddr1_ecc(2)"
				( attribute "PN" "J66"
					( Origin gPackager )
				)
				( objectStatus "U2D1.J66" )
			)
			( pin "@baseboard_fab2_lib.baseboard_fab2(sch_1):page58_i172:ddr1_ecc(3)"
				( attribute "PN" "L66"
					( Origin gPackager )
				)
				( objectStatus "U2D1.L66" )
			)
			( pin "@baseboard_fab2_lib.baseboard_fab2(sch_1):page58_i172:ddr1_ecc(4)"
				( attribute "PN" "L70"
					( Origin gPackager )
				)
				( objectStatus "U2D1.L70" )
			)
			( pin "@baseboard_fab2_lib.baseboard_fab2(sch_1):page58_i172:ddr1_ecc(5)"
				( attribute "PN" "M69"
					( Origin gPackager )
				)
				( objectStatus "U2D1.M69" )
			)
			( pin "@baseboard_fab2_lib.baseboard_fab2(sch_1):page58_i172:ddr1_ecc(6)"
				( attribute "PN" "H67"
					( Origin gPackager )
				)
				( objectStatus "U2D1.H67" )
			)
			( pin "@baseboard_fab2_lib.baseboard_fab2(sch_1):page58_i172:ddr1_ecc(7)"
				( attribute "PN" "M67"
					( Origin gPackager )
				)
				( objectStatus "U2D1.M67" )
			)
			( pin "@baseboard_fab2_lib.baseboard_fab2(sch_1):page58_i172:ddr1_ma(0)"
				( attribute "PN" "J52"
					( Origin gPackager )
				)
				( objectStatus "U2D1.J52" )
			)
			( pin "@baseboard_fab2_lib.baseboard_fab2(sch_1):page58_i172:ddr1_ma(1)"
				( attribute "PN" "J58"
					( Origin gPackager )
				)
				( objectStatus "U2D1.J58" )
			)
			( pin "@baseboard_fab2_lib.baseboard_fab2(sch_1):page58_i172:ddr1_ma(2)"
				( attribute "PN" "K57"
					( Origin gPackager )
				)
				( objectStatus "U2D1.K57" )
			)
			( pin "@baseboard_fab2_lib.baseboard_fab2(sch_1):page58_i172:ddr1_ma(3)"
				( attribute "PN" "N58"
					( Origin gPackager )
				)
				( objectStatus "U2D1.N58" )
			)
			( pin "@baseboard_fab2_lib.baseboard_fab2(sch_1):page58_i172:ddr1_ma(4)"
				( attribute "PN" "M59"
					( Origin gPackager )
				)
				( objectStatus "U2D1.M59" )
			)
			( pin "@baseboard_fab2_lib.baseboard_fab2(sch_1):page58_i172:ddr1_ma(5)"
				( attribute "PN" "R58"
					( Origin gPackager )
				)
				( objectStatus "U2D1.R58" )
			)
			( pin "@baseboard_fab2_lib.baseboard_fab2(sch_1):page58_i172:ddr1_ma(6)"
				( attribute "PN" "T59"
					( Origin gPackager )
				)
				( objectStatus "U2D1.T59" )
			)
			( pin "@baseboard_fab2_lib.baseboard_fab2(sch_1):page58_i172:ddr1_ma(7)"
				( attribute "PN" "V61"
					( Origin gPackager )
				)
				( objectStatus "U2D1.V61" )
			)
			( pin "@baseboard_fab2_lib.baseboard_fab2(sch_1):page58_i172:ddr1_ma(8)"
				( attribute "PN" "W60"
					( Origin gPackager )
				)
				( objectStatus "U2D1.W60" )
			)
			( pin "@baseboard_fab2_lib.baseboard_fab2(sch_1):page58_i172:ddr1_ma(9)"
				( attribute "PN" "K59"
					( Origin gPackager )
				)
				( objectStatus "U2D1.K59" )
			)
			( pin "@baseboard_fab2_lib.baseboard_fab2(sch_1):page58_i172:ddr1_ma(10)"
				( attribute "PN" "M55"
					( Origin gPackager )
				)
				( objectStatus "U2D1.M55" )
			)
			( pin "@baseboard_fab2_lib.baseboard_fab2(sch_1):page58_i172:ddr1_ma(11)"
				( attribute "PN" "R60"
					( Origin gPackager )
				)
				( objectStatus "U2D1.R60" )
			)
			( pin "@baseboard_fab2_lib.baseboard_fab2(sch_1):page58_i172:ddr1_ma(12)"
				( attribute "PN" "T61"
					( Origin gPackager )
				)
				( objectStatus "U2D1.T61" )
			)
			( pin "@baseboard_fab2_lib.baseboard_fab2(sch_1):page58_i172:ddr1_ma(13)"
				( attribute "PN" "M51"
					( Origin gPackager )
				)
				( objectStatus "U2D1.M51" )
			)
			( pin "@baseboard_fab2_lib.baseboard_fab2(sch_1):page58_i172:ddr1_ma(14)"
				( attribute "PN" "T51"
					( Origin gPackager )
				)
				( objectStatus "U2D1.T51" )
			)
			( pin "@baseboard_fab2_lib.baseboard_fab2(sch_1):page58_i172:ddr1_ma(15)"
				( attribute "PN" "N52"
					( Origin gPackager )
				)
				( objectStatus "U2D1.N52" )
			)
			( pin "@baseboard_fab2_lib.baseboard_fab2(sch_1):page58_i172:ddr1_ma(16)"
				( attribute "PN" "R52"
					( Origin gPackager )
				)
				( objectStatus "U2D1.R52" )
			)
			( pin "@baseboard_fab2_lib.baseboard_fab2(sch_1):page58_i172:ddr1_ma(17)"
				( attribute "PN" "N48"
					( Origin gPackager )
				)
				( objectStatus "U2D1.N48" )
			)
			( pin "@baseboard_fab2_lib.baseboard_fab2(sch_1):page58_i172:ddr1_odt(0)"
				( attribute "PN" "N50"
					( Origin gPackager )
				)
				( objectStatus "U2D1.N50" )
			)
			( pin "@baseboard_fab2_lib.baseboard_fab2(sch_1):page58_i172:ddr1_odt(1)"
				( attribute "PN" "R48"
					( Origin gPackager )
				)
				( objectStatus "U2D1.R48" )
			)
			( pin "@baseboard_fab2_lib.baseboard_fab2(sch_1):page58_i172:ddr1_odt(2)"
				( attribute "PN" "M49"
					( Origin gPackager )
				)
				( objectStatus "U2D1.M49" )
			)
			( pin "@baseboard_fab2_lib.baseboard_fab2(sch_1):page58_i172:ddr1_odt(3)"
				( attribute "PN" "T47"
					( Origin gPackager )
				)
				( objectStatus "U2D1.T47" )
			)
			( pin "@baseboard_fab2_lib.baseboard_fab2(sch_1):page58_i172:ddr1_par"
				( attribute "PN" "K53"
					( Origin gPackager )
				)
				( objectStatus "U2D1.K53" )
			)
			( pin "@baseboard_fab2_lib.baseboard_fab2(sch_1):page59_i172:ddr2_act_n"
				( attribute "PN" "AB61"
					( Origin gPackager )
				)
				( objectStatus "U2D1.AB61" )
			)
			( pin "@baseboard_fab2_lib.baseboard_fab2(sch_1):page59_i172:ddr2_alert_n"
				( attribute "PN" "AD61"
					( Origin gPackager )
				)
				( objectStatus "U2D1.AD61" )
			)
			( pin "@baseboard_fab2_lib.baseboard_fab2(sch_1):page59_i172:ddr2_ba(0)"
				( attribute "PN" "W52"
					( Origin gPackager )
				)
				( objectStatus "U2D1.W52" )
			)
			( pin "@baseboard_fab2_lib.baseboard_fab2(sch_1):page59_i172:ddr2_ba(1)"
				( attribute "PN" "AE56"
					( Origin gPackager )
				)
				( objectStatus "U2D1.AE56" )
			)
			( pin "@baseboard_fab2_lib.baseboard_fab2(sch_1):page59_i172:ddr2_bg(0)"
				( attribute "PN" "AA60"
					( Origin gPackager )
				)
				( objectStatus "U2D1.AA60" )
			)
			( pin "@baseboard_fab2_lib.baseboard_fab2(sch_1):page59_i172:ddr2_bg(1)"
				( attribute "PN" "AE62"
					( Origin gPackager )
				)
				( objectStatus "U2D1.AE62" )
			)
			( pin "@baseboard_fab2_lib.baseboard_fab2(sch_1):page59_i172:ddr2_cid(2)"
				( attribute "PN" "AB45"
					( Origin gPackager )
				)
				( objectStatus "U2D1.AB45" )
			)
			( pin "@baseboard_fab2_lib.baseboard_fab2(sch_1):page59_i172:ddr2_cke(0)"
				( attribute "PN" "AA62"
					( Origin gPackager )
				)
				( objectStatus "U2D1.AA62" )
			)
			( pin "@baseboard_fab2_lib.baseboard_fab2(sch_1):page59_i172:ddr2_cke(1)"
				( attribute "PN" "AD63"
					( Origin gPackager )
				)
				( objectStatus "U2D1.AD63" )
			)
			( pin "@baseboard_fab2_lib.baseboard_fab2(sch_1):page59_i172:ddr2_cke(2)"
				( attribute "PN" "V63"
					( Origin gPackager )
				)
				( objectStatus "U2D1.V63" )
			)
			( pin "@baseboard_fab2_lib.baseboard_fab2(sch_1):page59_i172:ddr2_cke(3)"
				( attribute "PN" "AB63"
					( Origin gPackager )
				)
				( objectStatus "U2D1.AB63" )
			)
			( pin "@baseboard_fab2_lib.baseboard_fab2(sch_1):page59_i172:ddr2_clk_dn(0)"
				( attribute "PN" "AA54"
					( Origin gPackager )
				)
				( objectStatus "U2D1.AA54" )
			)
			( pin "@baseboard_fab2_lib.baseboard_fab2(sch_1):page59_i172:ddr2_clk_dn(1)"
				( attribute "PN" "W54"
					( Origin gPackager )
				)
				( objectStatus "U2D1.W54" )
			)
			( pin "@baseboard_fab2_lib.baseboard_fab2(sch_1):page59_i172:ddr2_clk_dn(2)"
				( attribute "PN" "AA56"
					( Origin gPackager )
				)
				( objectStatus "U2D1.AA56" )
			)
			( pin "@baseboard_fab2_lib.baseboard_fab2(sch_1):page59_i172:ddr2_clk_dn(3)"
				( attribute "PN" "W56"
					( Origin gPackager )
				)
				( objectStatus "U2D1.W56" )
			)
			( pin "@baseboard_fab2_lib.baseboard_fab2(sch_1):page59_i172:ddr2_clk_dp(0)"
				( attribute "PN" "AB55"
					( Origin gPackager )
				)
				( objectStatus "U2D1.AB55" )
			)
			( pin "@baseboard_fab2_lib.baseboard_fab2(sch_1):page59_i172:ddr2_clk_dp(1)"
				( attribute "PN" "V55"
					( Origin gPackager )
				)
				( objectStatus "U2D1.V55" )
			)
			( pin "@baseboard_fab2_lib.baseboard_fab2(sch_1):page59_i172:ddr2_clk_dp(2)"
				( attribute "PN" "AB57"
					( Origin gPackager )
				)
				( objectStatus "U2D1.AB57" )
			)
			( pin "@baseboard_fab2_lib.baseboard_fab2(sch_1):page59_i172:ddr2_clk_dp(3)"
				( attribute "PN" "V57"
					( Origin gPackager )
				)
				( objectStatus "U2D1.V57" )
			)
			( pin "@baseboard_fab2_lib.baseboard_fab2(sch_1):page59_i172:ddr2_cs_n(0)"
				( attribute "PN" "V51"
					( Origin gPackager )
				)
				( objectStatus "U2D1.V51" )
			)
			( pin "@baseboard_fab2_lib.baseboard_fab2(sch_1):page59_i172:ddr2_cs_n(1)"
				( attribute "PN" "AB49"
					( Origin gPackager )
				)
				( objectStatus "U2D1.AB49" )
			)
			( pin "@baseboard_fab2_lib.baseboard_fab2(sch_1):page59_i172:ddr2_cs_n(2)"
				( attribute "PN" "W46"
					( Origin gPackager )
				)
				( objectStatus "U2D1.W46" )
			)
			( pin "@baseboard_fab2_lib.baseboard_fab2(sch_1):page59_i172:ddr2_cs_n(3)"
				( attribute "PN" "AA46"
					( Origin gPackager )
				)
				( objectStatus "U2D1.AA46" )
			)
			( pin "@baseboard_fab2_lib.baseboard_fab2(sch_1):page59_i172:ddr2_cs_n(4)"
				( attribute "PN" "AB51"
					( Origin gPackager )
				)
				( objectStatus "U2D1.AB51" )
			)
			( pin "@baseboard_fab2_lib.baseboard_fab2(sch_1):page59_i172:ddr2_cs_n(5)"
				( attribute "PN" "W48"
					( Origin gPackager )
				)
				( objectStatus "U2D1.W48" )
			)
			( pin "@baseboard_fab2_lib.baseboard_fab2(sch_1):page59_i172:ddr2_cs_n(6)"
				( attribute "PN" "T45"
					( Origin gPackager )
				)
				( objectStatus "U2D1.T45" )
			)
			( pin "@baseboard_fab2_lib.baseboard_fab2(sch_1):page59_i172:ddr2_cs_n(7)"
				( attribute "PN" "V45"
					( Origin gPackager )
				)
				( objectStatus "U2D1.V45" )
			)
			( pin "@baseboard_fab2_lib.baseboard_fab2(sch_1):page59_i172:ddr2_dq(0)"
				( attribute "PN" "AR76"
					( Origin gPackager )
				)
				( objectStatus "U2D1.AR76" )
			)
			( pin "@baseboard_fab2_lib.baseboard_fab2(sch_1):page59_i172:ddr2_dq(1)"
				( attribute "PN" "AN74"
					( Origin gPackager )
				)
				( objectStatus "U2D1.AN74" )
			)
			( pin "@baseboard_fab2_lib.baseboard_fab2(sch_1):page59_i172:ddr2_dq(2)"
				( attribute "PN" "AK77"
					( Origin gPackager )
				)
				( objectStatus "U2D1.AK77" )
			)
			( pin "@baseboard_fab2_lib.baseboard_fab2(sch_1):page59_i172:ddr2_dq(3)"
				( attribute "PN" "AJ76"
					( Origin gPackager )
				)
				( objectStatus "U2D1.AJ76" )
			)
			( pin "@baseboard_fab2_lib.baseboard_fab2(sch_1):page59_i172:ddr2_dq(4)"
				( attribute "PN" "AT75"
					( Origin gPackager )
				)
				( objectStatus "U2D1.AT75" )
			)
			( pin "@baseboard_fab2_lib.baseboard_fab2(sch_1):page59_i172:ddr2_dq(5)"
				( attribute "PN" "AR74"
					( Origin gPackager )
				)
				( objectStatus "U2D1.AR74" )
			)
			( pin "@baseboard_fab2_lib.baseboard_fab2(sch_1):page59_i172:ddr2_dq(6)"
				( attribute "PN" "AM77"
					( Origin gPackager )
				)
				( objectStatus "U2D1.AM77" )
			)
			( pin "@baseboard_fab2_lib.baseboard_fab2(sch_1):page59_i172:ddr2_dq(7)"
				( attribute "PN" "AK75"
					( Origin gPackager )
				)
				( objectStatus "U2D1.AK75" )
			)
			( pin "@baseboard_fab2_lib.baseboard_fab2(sch_1):page59_i172:ddr2_dq(8)"
				( attribute "PN" "AE76"
					( Origin gPackager )
				)
				( objectStatus "U2D1.AE76" )
			)
			( pin "@baseboard_fab2_lib.baseboard_fab2(sch_1):page59_i172:ddr2_dq(9)"
				( attribute "PN" "AC74"
					( Origin gPackager )
				)
				( objectStatus "U2D1.AC74" )
			)
			( pin "@baseboard_fab2_lib.baseboard_fab2(sch_1):page59_i172:ddr2_dq(10)"
				( attribute "PN" "Y77"
					( Origin gPackager )
				)
				( objectStatus "U2D1.Y77" )
			)
			( pin "@baseboard_fab2_lib.baseboard_fab2(sch_1):page59_i172:ddr2_dq(11)"
				( attribute "PN" "W76"
					( Origin gPackager )
				)
				( objectStatus "U2D1.W76" )
			)
			( pin "@baseboard_fab2_lib.baseboard_fab2(sch_1):page59_i172:ddr2_dq(12)"
				( attribute "PN" "AF75"
					( Origin gPackager )
				)
				( objectStatus "U2D1.AF75" )
			)
			( pin "@baseboard_fab2_lib.baseboard_fab2(sch_1):page59_i172:ddr2_dq(13)"
				( attribute "PN" "AE74"
					( Origin gPackager )
				)
				( objectStatus "U2D1.AE74" )
			)
			( pin "@baseboard_fab2_lib.baseboard_fab2(sch_1):page59_i172:ddr2_dq(14)"
				( attribute "PN" "AB77"
					( Origin gPackager )
				)
				( objectStatus "U2D1.AB77" )
			)
			( pin "@baseboard_fab2_lib.baseboard_fab2(sch_1):page59_i172:ddr2_dq(15)"
				( attribute "PN" "Y75"
					( Origin gPackager )
				)
				( objectStatus "U2D1.Y75" )
			)
			( pin "@baseboard_fab2_lib.baseboard_fab2(sch_1):page59_i172:ddr2_dq(16)"
				( attribute "PN" "W72"
					( Origin gPackager )
				)
				( objectStatus "U2D1.W72" )
			)
			( pin "@baseboard_fab2_lib.baseboard_fab2(sch_1):page59_i172:ddr2_dq(17)"
				( attribute "PN" "AA70"
					( Origin gPackager )
				)
				( objectStatus "U2D1.AA70" )
			)
			( pin "@baseboard_fab2_lib.baseboard_fab2(sch_1):page59_i172:ddr2_dq(18)"
				( attribute "PN" "R70"
					( Origin gPackager )
				)
				( objectStatus "U2D1.R70" )
			)
			( pin "@baseboard_fab2_lib.baseboard_fab2(sch_1):page59_i172:ddr2_dq(19)"
				( attribute "PN" "T69"
					( Origin gPackager )
				)
				( objectStatus "U2D1.T69" )
			)
			( pin "@baseboard_fab2_lib.baseboard_fab2(sch_1):page59_i172:ddr2_dq(20)"
				( attribute "PN" "AA72"
					( Origin gPackager )
				)
				( objectStatus "U2D1.AA72" )
			)
			( pin "@baseboard_fab2_lib.baseboard_fab2(sch_1):page59_i172:ddr2_dq(21)"
				( attribute "PN" "AB71"
					( Origin gPackager )
				)
				( objectStatus "U2D1.AB71" )
			)
			( pin "@baseboard_fab2_lib.baseboard_fab2(sch_1):page59_i172:ddr2_dq(22)"
				( attribute "PN" "T71"
					( Origin gPackager )
				)
				( objectStatus "U2D1.T71" )
			)
			( pin "@baseboard_fab2_lib.baseboard_fab2(sch_1):page59_i172:ddr2_dq(23)"
				( attribute "PN" "V69"
					( Origin gPackager )
				)
				( objectStatus "U2D1.V69" )
			)
			( pin "@baseboard_fab2_lib.baseboard_fab2(sch_1):page59_i172:ddr2_dq(24)"
				( attribute "PN" "AM67"
					( Origin gPackager )
				)
				( objectStatus "U2D1.AM67" )
			)
			( pin "@baseboard_fab2_lib.baseboard_fab2(sch_1):page59_i172:ddr2_dq(25)"
				( attribute "PN" "AT67"
					( Origin gPackager )
				)
				( objectStatus "U2D1.AT67" )
			)
			( pin "@baseboard_fab2_lib.baseboard_fab2(sch_1):page59_i172:ddr2_dq(26)"
				( attribute "PN" "AN64"
					( Origin gPackager )
				)
				( objectStatus "U2D1.AN64" )
			)
			( pin "@baseboard_fab2_lib.baseboard_fab2(sch_1):page59_i172:ddr2_dq(27)"
				( attribute "PN" "AR64"
					( Origin gPackager )
				)
				( objectStatus "U2D1.AR64" )
			)
			( pin "@baseboard_fab2_lib.baseboard_fab2(sch_1):page59_i172:ddr2_dq(28)"
				( attribute "PN" "AN68"
					( Origin gPackager )
				)
				( objectStatus "U2D1.AN68" )
			)
			( pin "@baseboard_fab2_lib.baseboard_fab2(sch_1):page59_i172:ddr2_dq(29)"
				( attribute "PN" "AR68"
					( Origin gPackager )
				)
				( objectStatus "U2D1.AR68" )
			)
			( pin "@baseboard_fab2_lib.baseboard_fab2(sch_1):page59_i172:ddr2_dq(30)"
				( attribute "PN" "AM65"
					( Origin gPackager )
				)
				( objectStatus "U2D1.AM65" )
			)
			( pin "@baseboard_fab2_lib.baseboard_fab2(sch_1):page59_i172:ddr2_dq(31)"
				( attribute "PN" "AT65"
					( Origin gPackager )
				)
				( objectStatus "U2D1.AT65" )
			)
			( pin "@baseboard_fab2_lib.baseboard_fab2(sch_1):page59_i172:ddr2_dq(32)"
				( attribute "PN" "U40"
					( Origin gPackager )
				)
				( objectStatus "U2D1.U40" )
			)
			( pin "@baseboard_fab2_lib.baseboard_fab2(sch_1):page59_i172:ddr2_dq(33)"
				( attribute "PN" "AA40"
					( Origin gPackager )
				)
				( objectStatus "U2D1.AA40" )
			)
			( pin "@baseboard_fab2_lib.baseboard_fab2(sch_1):page59_i172:ddr2_dq(34)"
				( attribute "PN" "V37"
					( Origin gPackager )
				)
				( objectStatus "U2D1.V37" )
			)
			( pin "@baseboard_fab2_lib.baseboard_fab2(sch_1):page59_i172:ddr2_dq(35)"
				( attribute "PN" "Y37"
					( Origin gPackager )
				)
				( objectStatus "U2D1.Y37" )
			)
			( pin "@baseboard_fab2_lib.baseboard_fab2(sch_1):page59_i172:ddr2_dq(36)"
				( attribute "PN" "V41"
					( Origin gPackager )
				)
				( objectStatus "U2D1.V41" )
			)
			( pin "@baseboard_fab2_lib.baseboard_fab2(sch_1):page59_i172:ddr2_dq(37)"
				( attribute "PN" "Y41"
					( Origin gPackager )
				)
				( objectStatus "U2D1.Y41" )
			)
			( pin "@baseboard_fab2_lib.baseboard_fab2(sch_1):page59_i172:ddr2_dq(38)"
				( attribute "PN" "U38"
					( Origin gPackager )
				)
				( objectStatus "U2D1.U38" )
			)
			( pin "@baseboard_fab2_lib.baseboard_fab2(sch_1):page59_i172:ddr2_dq(39)"
				( attribute "PN" "AA38"
					( Origin gPackager )
				)
				( objectStatus "U2D1.AA38" )
			)
			( pin "@baseboard_fab2_lib.baseboard_fab2(sch_1):page59_i172:ddr2_dq(40)"
				( attribute "PN" "U34"
					( Origin gPackager )
				)
				( objectStatus "U2D1.U34" )
			)
			( pin "@baseboard_fab2_lib.baseboard_fab2(sch_1):page59_i172:ddr2_dq(41)"
				( attribute "PN" "AA34"
					( Origin gPackager )
				)
				( objectStatus "U2D1.AA34" )
			)
			( pin "@baseboard_fab2_lib.baseboard_fab2(sch_1):page59_i172:ddr2_dq(42)"
				( attribute "PN" "V31"
					( Origin gPackager )
				)
				( objectStatus "U2D1.V31" )
			)
			( pin "@baseboard_fab2_lib.baseboard_fab2(sch_1):page59_i172:ddr2_dq(43)"
				( attribute "PN" "Y31"
					( Origin gPackager )
				)
				( objectStatus "U2D1.Y31" )
			)
			( pin "@baseboard_fab2_lib.baseboard_fab2(sch_1):page59_i172:ddr2_dq(44)"
				( attribute "PN" "V35"
					( Origin gPackager )
				)
				( objectStatus "U2D1.V35" )
			)
			( pin "@baseboard_fab2_lib.baseboard_fab2(sch_1):page59_i172:ddr2_dq(45)"
				( attribute "PN" "Y35"
					( Origin gPackager )
				)
				( objectStatus "U2D1.Y35" )
			)
			( pin "@baseboard_fab2_lib.baseboard_fab2(sch_1):page59_i172:ddr2_dq(46)"
				( attribute "PN" "U32"
					( Origin gPackager )
				)
				( objectStatus "U2D1.U32" )
			)
			( pin "@baseboard_fab2_lib.baseboard_fab2(sch_1):page59_i172:ddr2_dq(47)"
				( attribute "PN" "AA32"
					( Origin gPackager )
				)
				( objectStatus "U2D1.AA32" )
			)
			( pin "@baseboard_fab2_lib.baseboard_fab2(sch_1):page59_i172:ddr2_dq(48)"
				( attribute "PN" "AD31"
					( Origin gPackager )
				)
				( objectStatus "U2D1.AD31" )
			)
			( pin "@baseboard_fab2_lib.baseboard_fab2(sch_1):page59_i172:ddr2_dq(49)"
				( attribute "PN" "AH31"
					( Origin gPackager )
				)
				( objectStatus "U2D1.AH31" )
			)
			( pin "@baseboard_fab2_lib.baseboard_fab2(sch_1):page59_i172:ddr2_dq(50)"
				( attribute "PN" "AE28"
					( Origin gPackager )
				)
				( objectStatus "U2D1.AE28" )
			)
			( pin "@baseboard_fab2_lib.baseboard_fab2(sch_1):page59_i172:ddr2_dq(51)"
				( attribute "PN" "AG28"
					( Origin gPackager )
				)
				( objectStatus "U2D1.AG28" )
			)
			( pin "@baseboard_fab2_lib.baseboard_fab2(sch_1):page59_i172:ddr2_dq(52)"
				( attribute "PN" "AE32"
					( Origin gPackager )
				)
				( objectStatus "U2D1.AE32" )
			)
			( pin "@baseboard_fab2_lib.baseboard_fab2(sch_1):page59_i172:ddr2_dq(53)"
				( attribute "PN" "AG32"
					( Origin gPackager )
				)
				( objectStatus "U2D1.AG32" )
			)
			( pin "@baseboard_fab2_lib.baseboard_fab2(sch_1):page59_i172:ddr2_dq(54)"
				( attribute "PN" "AD29"
					( Origin gPackager )
				)
				( objectStatus "U2D1.AD29" )
			)
			( pin "@baseboard_fab2_lib.baseboard_fab2(sch_1):page59_i172:ddr2_dq(55)"
				( attribute "PN" "AH29"
					( Origin gPackager )
				)
				( objectStatus "U2D1.AH29" )
			)
			( pin "@baseboard_fab2_lib.baseboard_fab2(sch_1):page59_i172:ddr2_dq(56)"
				( attribute "PN" "AD25"
					( Origin gPackager )
				)
				( objectStatus "U2D1.AD25" )
			)
			( pin "@baseboard_fab2_lib.baseboard_fab2(sch_1):page59_i172:ddr2_dq(57)"
				( attribute "PN" "AH25"
					( Origin gPackager )
				)
				( objectStatus "U2D1.AH25" )
			)
			( pin "@baseboard_fab2_lib.baseboard_fab2(sch_1):page59_i172:ddr2_dq(58)"
				( attribute "PN" "AE22"
					( Origin gPackager )
				)
				( objectStatus "U2D1.AE22" )
			)
			( pin "@baseboard_fab2_lib.baseboard_fab2(sch_1):page59_i172:ddr2_dq(59)"
				( attribute "PN" "AG22"
					( Origin gPackager )
				)
				( objectStatus "U2D1.AG22" )
			)
			( pin "@baseboard_fab2_lib.baseboard_fab2(sch_1):page59_i172:ddr2_dq(60)"
				( attribute "PN" "AE26"
					( Origin gPackager )
				)
				( objectStatus "U2D1.AE26" )
			)
			( pin "@baseboard_fab2_lib.baseboard_fab2(sch_1):page59_i172:ddr2_dq(61)"
				( attribute "PN" "AG26"
					( Origin gPackager )
				)
				( objectStatus "U2D1.AG26" )
			)
			( pin "@baseboard_fab2_lib.baseboard_fab2(sch_1):page59_i172:ddr2_dq(62)"
				( attribute "PN" "AD23"
					( Origin gPackager )
				)
				( objectStatus "U2D1.AD23" )
			)
			( pin "@baseboard_fab2_lib.baseboard_fab2(sch_1):page59_i172:ddr2_dq(63)"
				( attribute "PN" "AH23"
					( Origin gPackager )
				)
				( objectStatus "U2D1.AH23" )
			)
			( pin "@baseboard_fab2_lib.baseboard_fab2(sch_1):page59_i172:ddr2_dqs_dn(0)"
				( attribute "PN" "AL74"
					( Origin gPackager )
				)
				( objectStatus "U2D1.AL74" )
			)
			( pin "@baseboard_fab2_lib.baseboard_fab2(sch_1):page59_i172:ddr2_dqs_dn(1)"
				( attribute "PN" "AA74"
					( Origin gPackager )
				)
				( objectStatus "U2D1.AA74" )
			)
			( pin "@baseboard_fab2_lib.baseboard_fab2(sch_1):page59_i172:ddr2_dqs_dn(2)"
				( attribute "PN" "Y69"
					( Origin gPackager )
				)
				( objectStatus "U2D1.Y69" )
			)
			( pin "@baseboard_fab2_lib.baseboard_fab2(sch_1):page59_i172:ddr2_dqs_dn(3)"
				( attribute "PN" "AU66"
					( Origin gPackager )
				)
				( objectStatus "U2D1.AU66" )
			)
			( pin "@baseboard_fab2_lib.baseboard_fab2(sch_1):page59_i172:ddr2_dqs_dn(4)"
				( attribute "PN" "AB39"
					( Origin gPackager )
				)
				( objectStatus "U2D1.AB39" )
			)
			( pin "@baseboard_fab2_lib.baseboard_fab2(sch_1):page59_i172:ddr2_dqs_dn(5)"
				( attribute "PN" "AB33"
					( Origin gPackager )
				)
				( objectStatus "U2D1.AB33" )
			)
			( pin "@baseboard_fab2_lib.baseboard_fab2(sch_1):page59_i172:ddr2_dqs_dn(6)"
				( attribute "PN" "AJ30"
					( Origin gPackager )
				)
				( objectStatus "U2D1.AJ30" )
			)
			( pin "@baseboard_fab2_lib.baseboard_fab2(sch_1):page59_i172:ddr2_dqs_dn(7)"
				( attribute "PN" "AJ24"
					( Origin gPackager )
				)
				( objectStatus "U2D1.AJ24" )
			)
			( pin "@baseboard_fab2_lib.baseboard_fab2(sch_1):page59_i172:ddr2_dqs_dn(8)"
				( attribute "PN" "BB71"
					( Origin gPackager )
				)
				( objectStatus "U2D1.BB71" )
			)
			( pin "@baseboard_fab2_lib.baseboard_fab2(sch_1):page59_i172:ddr2_dqs_dn(9)"
				( attribute "PN" "AP77"
					( Origin gPackager )
				)
				( objectStatus "U2D1.AP77" )
			)
			( pin "@baseboard_fab2_lib.baseboard_fab2(sch_1):page59_i172:ddr2_dqs_dn(10)"
				( attribute "PN" "AD77"
					( Origin gPackager )
				)
				( objectStatus "U2D1.AD77" )
			)
			( pin "@baseboard_fab2_lib.baseboard_fab2(sch_1):page59_i172:ddr2_dqs_dn(11)"
				( attribute "PN" "U72"
					( Origin gPackager )
				)
				( objectStatus "U2D1.U72" )
			)
			( pin "@baseboard_fab2_lib.baseboard_fab2(sch_1):page59_i172:ddr2_dqs_dn(12)"
				( attribute "PN" "AL66"
					( Origin gPackager )
				)
				( objectStatus "U2D1.AL66" )
			)
			( pin "@baseboard_fab2_lib.baseboard_fab2(sch_1):page59_i172:ddr2_dqs_dn(13)"
				( attribute "PN" "T39"
					( Origin gPackager )
				)
				( objectStatus "U2D1.T39" )
			)
			( pin "@baseboard_fab2_lib.baseboard_fab2(sch_1):page59_i172:ddr2_dqs_dn(14)"
				( attribute "PN" "T33"
					( Origin gPackager )
				)
				( objectStatus "U2D1.T33" )
			)
			( pin "@baseboard_fab2_lib.baseboard_fab2(sch_1):page59_i172:ddr2_dqs_dn(15)"
				( attribute "PN" "AC30"
					( Origin gPackager )
				)
				( objectStatus "U2D1.AC30" )
			)
			( pin "@baseboard_fab2_lib.baseboard_fab2(sch_1):page59_i172:ddr2_dqs_dn(16)"
				( attribute "PN" "AC24"
					( Origin gPackager )
				)
				( objectStatus "U2D1.AC24" )
			)
			( pin "@baseboard_fab2_lib.baseboard_fab2(sch_1):page59_i172:ddr2_dqs_dn(17)"
				( attribute "PN" "AT71"
					( Origin gPackager )
				)
				( objectStatus "U2D1.AT71" )
			)
			( pin "@baseboard_fab2_lib.baseboard_fab2(sch_1):page59_i172:ddr2_dqs_dp(0)"
				( attribute "PN" "AM75"
					( Origin gPackager )
				)
				( objectStatus "U2D1.AM75" )
			)
			( pin "@baseboard_fab2_lib.baseboard_fab2(sch_1):page59_i172:ddr2_dqs_dp(1)"
				( attribute "PN" "AB75"
					( Origin gPackager )
				)
				( objectStatus "U2D1.AB75" )
			)
			( pin "@baseboard_fab2_lib.baseboard_fab2(sch_1):page59_i172:ddr2_dqs_dp(2)"
				( attribute "PN" "W70"
					( Origin gPackager )
				)
				( objectStatus "U2D1.W70" )
			)
			( pin "@baseboard_fab2_lib.baseboard_fab2(sch_1):page59_i172:ddr2_dqs_dp(3)"
				( attribute "PN" "AR66"
					( Origin gPackager )
				)
				( objectStatus "U2D1.AR66" )
			)
			( pin "@baseboard_fab2_lib.baseboard_fab2(sch_1):page59_i172:ddr2_dqs_dp(4)"
				( attribute "PN" "Y39"
					( Origin gPackager )
				)
				( objectStatus "U2D1.Y39" )
			)
			( pin "@baseboard_fab2_lib.baseboard_fab2(sch_1):page59_i172:ddr2_dqs_dp(5)"
				( attribute "PN" "Y33"
					( Origin gPackager )
				)
				( objectStatus "U2D1.Y33" )
			)
			( pin "@baseboard_fab2_lib.baseboard_fab2(sch_1):page59_i172:ddr2_dqs_dp(6)"
				( attribute "PN" "AG30"
					( Origin gPackager )
				)
				( objectStatus "U2D1.AG30" )
			)
			( pin "@baseboard_fab2_lib.baseboard_fab2(sch_1):page59_i172:ddr2_dqs_dp(7)"
				( attribute "PN" "AG24"
					( Origin gPackager )
				)
				( objectStatus "U2D1.AG24" )
			)
			( pin "@baseboard_fab2_lib.baseboard_fab2(sch_1):page59_i172:ddr2_dqs_dp(8)"
				( attribute "PN" "AY71"
					( Origin gPackager )
				)
				( objectStatus "U2D1.AY71" )
			)
			( pin "@baseboard_fab2_lib.baseboard_fab2(sch_1):page59_i172:ddr2_dqs_dp(9)"
				( attribute "PN" "AN76"
					( Origin gPackager )
				)
				( objectStatus "U2D1.AN76" )
			)
			( pin "@baseboard_fab2_lib.baseboard_fab2(sch_1):page59_i172:ddr2_dqs_dp(10)"
				( attribute "PN" "AC76"
					( Origin gPackager )
				)
				( objectStatus "U2D1.AC76" )
			)
			( pin "@baseboard_fab2_lib.baseboard_fab2(sch_1):page59_i172:ddr2_dqs_dp(11)"
				( attribute "PN" "V71"
					( Origin gPackager )
				)
				( objectStatus "U2D1.V71" )
			)
			( pin "@baseboard_fab2_lib.baseboard_fab2(sch_1):page59_i172:ddr2_dqs_dp(12)"
				( attribute "PN" "AN66"
					( Origin gPackager )
				)
				( objectStatus "U2D1.AN66" )
			)
			( pin "@baseboard_fab2_lib.baseboard_fab2(sch_1):page59_i172:ddr2_dqs_dp(13)"
				( attribute "PN" "V39"
					( Origin gPackager )
				)
				( objectStatus "U2D1.V39" )
			)
			( pin "@baseboard_fab2_lib.baseboard_fab2(sch_1):page59_i172:ddr2_dqs_dp(14)"
				( attribute "PN" "V33"
					( Origin gPackager )
				)
				( objectStatus "U2D1.V33" )
			)
			( pin "@baseboard_fab2_lib.baseboard_fab2(sch_1):page59_i172:ddr2_dqs_dp(15)"
				( attribute "PN" "AE30"
					( Origin gPackager )
				)
				( objectStatus "U2D1.AE30" )
			)
			( pin "@baseboard_fab2_lib.baseboard_fab2(sch_1):page59_i172:ddr2_dqs_dp(16)"
				( attribute "PN" "AE24"
					( Origin gPackager )
				)
				( objectStatus "U2D1.AE24" )
			)
			( pin "@baseboard_fab2_lib.baseboard_fab2(sch_1):page59_i172:ddr2_dqs_dp(17)"
				( attribute "PN" "AV71"
					( Origin gPackager )
				)
				( objectStatus "U2D1.AV71" )
			)
			( pin "@baseboard_fab2_lib.baseboard_fab2(sch_1):page59_i172:ddr2_ecc(0)"
				( attribute "PN" "AU72"
					( Origin gPackager )
				)
				( objectStatus "U2D1.AU72" )
			)
			( pin "@baseboard_fab2_lib.baseboard_fab2(sch_1):page59_i172:ddr2_ecc(1)"
				( attribute "PN" "BA72"
					( Origin gPackager )
				)
				( objectStatus "U2D1.BA72" )
			)
			( pin "@baseboard_fab2_lib.baseboard_fab2(sch_1):page59_i172:ddr2_ecc(2)"
				( attribute "PN" "AV69"
					( Origin gPackager )
				)
				( objectStatus "U2D1.AV69" )
			)
			( pin "@baseboard_fab2_lib.baseboard_fab2(sch_1):page59_i172:ddr2_ecc(3)"
				( attribute "PN" "AY69"
					( Origin gPackager )
				)
				( objectStatus "U2D1.AY69" )
			)
			( pin "@baseboard_fab2_lib.baseboard_fab2(sch_1):page59_i172:ddr2_ecc(4)"
				( attribute "PN" "AV73"
					( Origin gPackager )
				)
				( objectStatus "U2D1.AV73" )
			)
			( pin "@baseboard_fab2_lib.baseboard_fab2(sch_1):page59_i172:ddr2_ecc(5)"
				( attribute "PN" "AY73"
					( Origin gPackager )
				)
				( objectStatus "U2D1.AY73" )
			)
			( pin "@baseboard_fab2_lib.baseboard_fab2(sch_1):page59_i172:ddr2_ecc(6)"
				( attribute "PN" "AU70"
					( Origin gPackager )
				)
				( objectStatus "U2D1.AU70" )
			)
			( pin "@baseboard_fab2_lib.baseboard_fab2(sch_1):page59_i172:ddr2_ecc(7)"
				( attribute "PN" "BA70"
					( Origin gPackager )
				)
				( objectStatus "U2D1.BA70" )
			)
			( pin "@baseboard_fab2_lib.baseboard_fab2(sch_1):page59_i172:ddr2_ma(0)"
				( attribute "PN" "AB53"
					( Origin gPackager )
				)
				( objectStatus "U2D1.AB53" )
			)
			( pin "@baseboard_fab2_lib.baseboard_fab2(sch_1):page59_i172:ddr2_ma(1)"
				( attribute "PN" "AE58"
					( Origin gPackager )
				)
				( objectStatus "U2D1.AE58" )
			)
			( pin "@baseboard_fab2_lib.baseboard_fab2(sch_1):page59_i172:ddr2_ma(2)"
				( attribute "PN" "AD57"
					( Origin gPackager )
				)
				( objectStatus "U2D1.AD57" )
			)
			( pin "@baseboard_fab2_lib.baseboard_fab2(sch_1):page59_i172:ddr2_ma(3)"
				( attribute "PN" "W58"
					( Origin gPackager )
				)
				( objectStatus "U2D1.W58" )
			)
			( pin "@baseboard_fab2_lib.baseboard_fab2(sch_1):page59_i172:ddr2_ma(4)"
				( attribute "PN" "AA58"
					( Origin gPackager )
				)
				( objectStatus "U2D1.AA58" )
			)
			( pin "@baseboard_fab2_lib.baseboard_fab2(sch_1):page59_i172:ddr2_ma(5)"
				( attribute "PN" "V59"
					( Origin gPackager )
				)
				( objectStatus "U2D1.V59" )
			)
			( pin "@baseboard_fab2_lib.baseboard_fab2(sch_1):page59_i172:ddr2_ma(6)"
				( attribute "PN" "AB59"
					( Origin gPackager )
				)
				( objectStatus "U2D1.AB59" )
			)
			( pin "@baseboard_fab2_lib.baseboard_fab2(sch_1):page59_i172:ddr2_ma(7)"
				( attribute "PN" "AE60"
					( Origin gPackager )
				)
				( objectStatus "U2D1.AE60" )
			)
			( pin "@baseboard_fab2_lib.baseboard_fab2(sch_1):page59_i172:ddr2_ma(8)"
				( attribute "PN" "AD59"
					( Origin gPackager )
				)
				( objectStatus "U2D1.AD59" )
			)
			( pin "@baseboard_fab2_lib.baseboard_fab2(sch_1):page59_i172:ddr2_ma(9)"
				( attribute "PN" "AG58"
					( Origin gPackager )
				)
				( objectStatus "U2D1.AG58" )
			)
			( pin "@baseboard_fab2_lib.baseboard_fab2(sch_1):page59_i172:ddr2_ma(10)"
				( attribute "PN" "AD55"
					( Origin gPackager )
				)
				( objectStatus "U2D1.AD55" )
			)
			( pin "@baseboard_fab2_lib.baseboard_fab2(sch_1):page59_i172:ddr2_ma(11)"
				( attribute "PN" "AG60"
					( Origin gPackager )
				)
				( objectStatus "U2D1.AG60" )
			)
			( pin "@baseboard_fab2_lib.baseboard_fab2(sch_1):page59_i172:ddr2_ma(12)"
				( attribute "PN" "AG62"
					( Origin gPackager )
				)
				( objectStatus "U2D1.AG62" )
			)
			( pin "@baseboard_fab2_lib.baseboard_fab2(sch_1):page59_i172:ddr2_ma(13)"
				( attribute "PN" "AD53"
					( Origin gPackager )
				)
				( objectStatus "U2D1.AD53" )
			)
			( pin "@baseboard_fab2_lib.baseboard_fab2(sch_1):page59_i172:ddr2_ma(14)"
				( attribute "PN" "W50"
					( Origin gPackager )
				)
				( objectStatus "U2D1.W50" )
			)
			( pin "@baseboard_fab2_lib.baseboard_fab2(sch_1):page59_i172:ddr2_ma(15)"
				( attribute "PN" "AE54"
					( Origin gPackager )
				)
				( objectStatus "U2D1.AE54" )
			)
			( pin "@baseboard_fab2_lib.baseboard_fab2(sch_1):page59_i172:ddr2_ma(16)"
				( attribute "PN" "AA52"
					( Origin gPackager )
				)
				( objectStatus "U2D1.AA52" )
			)
			( pin "@baseboard_fab2_lib.baseboard_fab2(sch_1):page59_i172:ddr2_ma(17)"
				( attribute "PN" "AC46"
					( Origin gPackager )
				)
				( objectStatus "U2D1.AC46" )
			)
			( pin "@baseboard_fab2_lib.baseboard_fab2(sch_1):page59_i172:ddr2_odt(0)"
				( attribute "PN" "AA50"
					( Origin gPackager )
				)
				( objectStatus "U2D1.AA50" )
			)
			( pin "@baseboard_fab2_lib.baseboard_fab2(sch_1):page59_i172:ddr2_odt(1)"
				( attribute "PN" "AA48"
					( Origin gPackager )
				)
				( objectStatus "U2D1.AA48" )
			)
			( pin "@baseboard_fab2_lib.baseboard_fab2(sch_1):page59_i172:ddr2_odt(2)"
				( attribute "PN" "V49"
					( Origin gPackager )
				)
				( objectStatus "U2D1.V49" )
			)
			( pin "@baseboard_fab2_lib.baseboard_fab2(sch_1):page59_i172:ddr2_odt(3)"
				( attribute "PN" "AB47"
					( Origin gPackager )
				)
				( objectStatus "U2D1.AB47" )
			)
			( pin "@baseboard_fab2_lib.baseboard_fab2(sch_1):page59_i172:ddr2_par"
				( attribute "PN" "V53"
					( Origin gPackager )
				)
				( objectStatus "U2D1.V53" )
			)
			( pin "@baseboard_fab2_lib.baseboard_fab2(sch_1):page60_i172:ddr3_act_n"
				( attribute "PN" "DW60"
					( Origin gPackager )
				)
				( objectStatus "U2D1.DW60" )
			)
			( pin "@baseboard_fab2_lib.baseboard_fab2(sch_1):page60_i172:ddr3_alert_n"
				( attribute "PN" "ED63"
					( Origin gPackager )
				)
				( objectStatus "U2D1.ED63" )
			)
			( pin "@baseboard_fab2_lib.baseboard_fab2(sch_1):page60_i172:ddr3_ba(0)"
				( attribute "PN" "EE52"
					( Origin gPackager )
				)
				( objectStatus "U2D1.EE52" )
			)
			( pin "@baseboard_fab2_lib.baseboard_fab2(sch_1):page60_i172:ddr3_ba(1)"
				( attribute "PN" "EA54"
					( Origin gPackager )
				)
				( objectStatus "U2D1.EA54" )
			)
			( pin "@baseboard_fab2_lib.baseboard_fab2(sch_1):page60_i172:ddr3_bg(0)"
				( attribute "PN" "ED61"
					( Origin gPackager )
				)
				( objectStatus "U2D1.ED61" )
			)
			( pin "@baseboard_fab2_lib.baseboard_fab2(sch_1):page60_i172:ddr3_bg(1)"
				( attribute "PN" "DW62"
					( Origin gPackager )
				)
				( objectStatus "U2D1.DW62" )
			)
			( pin "@baseboard_fab2_lib.baseboard_fab2(sch_1):page60_i172:ddr3_cid(2)"
				( attribute "PN" "DV47"
					( Origin gPackager )
				)
				( objectStatus "U2D1.DV47" )
			)
			( pin "@baseboard_fab2_lib.baseboard_fab2(sch_1):page60_i172:ddr3_cke(0)"
				( attribute "PN" "EE62"
					( Origin gPackager )
				)
				( objectStatus "U2D1.EE62" )
			)
			( pin "@baseboard_fab2_lib.baseboard_fab2(sch_1):page60_i172:ddr3_cke(1)"
				( attribute "PN" "EF63"
					( Origin gPackager )
				)
				( objectStatus "U2D1.EF63" )
			)
			( pin "@baseboard_fab2_lib.baseboard_fab2(sch_1):page60_i172:ddr3_cke(2)"
				( attribute "PN" "EA62"
					( Origin gPackager )
				)
				( objectStatus "U2D1.EA62" )
			)
			( pin "@baseboard_fab2_lib.baseboard_fab2(sch_1):page60_i172:ddr3_cke(3)"
				( attribute "PN" "EB63"
					( Origin gPackager )
				)
				( objectStatus "U2D1.EB63" )
			)
			( pin "@baseboard_fab2_lib.baseboard_fab2(sch_1):page60_i172:ddr3_clk_dn(0)"
				( attribute "PN" "ED55"
					( Origin gPackager )
				)
				( objectStatus "U2D1.ED55" )
			)
			( pin "@baseboard_fab2_lib.baseboard_fab2(sch_1):page60_i172:ddr3_clk_dn(1)"
				( attribute "PN" "EF55"
					( Origin gPackager )
				)
				( objectStatus "U2D1.EF55" )
			)
			( pin "@baseboard_fab2_lib.baseboard_fab2(sch_1):page60_i172:ddr3_clk_dn(2)"
				( attribute "PN" "DW56"
					( Origin gPackager )
				)
				( objectStatus "U2D1.DW56" )
			)
			( pin "@baseboard_fab2_lib.baseboard_fab2(sch_1):page60_i172:ddr3_clk_dn(3)"
				( attribute "PN" "EF57"
					( Origin gPackager )
				)
				( objectStatus "U2D1.EF57" )
			)
			( pin "@baseboard_fab2_lib.baseboard_fab2(sch_1):page60_i172:ddr3_clk_dp(0)"
				( attribute "PN" "EB55"
					( Origin gPackager )
				)
				( objectStatus "U2D1.EB55" )
			)
			( pin "@baseboard_fab2_lib.baseboard_fab2(sch_1):page60_i172:ddr3_clk_dp(1)"
				( attribute "PN" "EE54"
					( Origin gPackager )
				)
				( objectStatus "U2D1.EE54" )
			)
			( pin "@baseboard_fab2_lib.baseboard_fab2(sch_1):page60_i172:ddr3_clk_dp(2)"
				( attribute "PN" "EA56"
					( Origin gPackager )
				)
				( objectStatus "U2D1.EA56" )
			)
			( pin "@baseboard_fab2_lib.baseboard_fab2(sch_1):page60_i172:ddr3_clk_dp(3)"
				( attribute "PN" "EE56"
					( Origin gPackager )
				)
				( objectStatus "U2D1.EE56" )
			)
			( pin "@baseboard_fab2_lib.baseboard_fab2(sch_1):page60_i172:ddr3_cs_n(0)"
				( attribute "PN" "EF51"
					( Origin gPackager )
				)
				( objectStatus "U2D1.EF51" )
			)
			( pin "@baseboard_fab2_lib.baseboard_fab2(sch_1):page60_i172:ddr3_cs_n(1)"
				( attribute "PN" "ED49"
					( Origin gPackager )
				)
				( objectStatus "U2D1.ED49" )
			)
			( pin "@baseboard_fab2_lib.baseboard_fab2(sch_1):page60_i172:ddr3_cs_n(2)"
				( attribute "PN" "ED47"
					( Origin gPackager )
				)
				( objectStatus "U2D1.ED47" )
			)
			( pin "@baseboard_fab2_lib.baseboard_fab2(sch_1):page60_i172:ddr3_cs_n(3)"
				( attribute "PN" "EB47"
					( Origin gPackager )
				)
				( objectStatus "U2D1.EB47" )
			)
			( pin "@baseboard_fab2_lib.baseboard_fab2(sch_1):page60_i172:ddr3_cs_n(4)"
				( attribute "PN" "EB51"
					( Origin gPackager )
				)
				( objectStatus "U2D1.EB51" )
			)
			( pin "@baseboard_fab2_lib.baseboard_fab2(sch_1):page60_i172:ddr3_cs_n(5)"
				( attribute "PN" "EB49"
					( Origin gPackager )
				)
				( objectStatus "U2D1.EB49" )
			)
			( pin "@baseboard_fab2_lib.baseboard_fab2(sch_1):page60_i172:ddr3_cs_n(6)"
				( attribute "PN" "DV45"
					( Origin gPackager )
				)
				( objectStatus "U2D1.DV45" )
			)
			( pin "@baseboard_fab2_lib.baseboard_fab2(sch_1):page60_i172:ddr3_cs_n(7)"
				( attribute "PN" "EB45"
					( Origin gPackager )
				)
				( objectStatus "U2D1.EB45" )
			)
			( pin "@baseboard_fab2_lib.baseboard_fab2(sch_1):page60_i172:ddr3_dq(0)"
				( attribute "PN" "CN84"
					( Origin gPackager )
				)
				( objectStatus "U2D1.CN84" )
			)
			( pin "@baseboard_fab2_lib.baseboard_fab2(sch_1):page60_i172:ddr3_dq(1)"
				( attribute "PN" "CN86"
					( Origin gPackager )
				)
				( objectStatus "U2D1.CN86" )
			)
			( pin "@baseboard_fab2_lib.baseboard_fab2(sch_1):page60_i172:ddr3_dq(2)"
				( attribute "PN" "DA86"
					( Origin gPackager )
				)
				( objectStatus "U2D1.DA86" )
			)
			( pin "@baseboard_fab2_lib.baseboard_fab2(sch_1):page60_i172:ddr3_dq(3)"
				( attribute "PN" "DA84"
					( Origin gPackager )
				)
				( objectStatus "U2D1.DA84" )
			)
			( pin "@baseboard_fab2_lib.baseboard_fab2(sch_1):page60_i172:ddr3_dq(4)"
				( attribute "PN" "CL84"
					( Origin gPackager )
				)
				( objectStatus "U2D1.CL84" )
			)
			( pin "@baseboard_fab2_lib.baseboard_fab2(sch_1):page60_i172:ddr3_dq(5)"
				( attribute "PN" "CL86"
					( Origin gPackager )
				)
				( objectStatus "U2D1.CL86" )
			)
			( pin "@baseboard_fab2_lib.baseboard_fab2(sch_1):page60_i172:ddr3_dq(6)"
				( attribute "PN" "CW86"
					( Origin gPackager )
				)
				( objectStatus "U2D1.CW86" )
			)
			( pin "@baseboard_fab2_lib.baseboard_fab2(sch_1):page60_i172:ddr3_dq(7)"
				( attribute "PN" "CW84"
					( Origin gPackager )
				)
				( objectStatus "U2D1.CW84" )
			)
			( pin "@baseboard_fab2_lib.baseboard_fab2(sch_1):page60_i172:ddr3_dq(8)"
				( attribute "PN" "DG84"
					( Origin gPackager )
				)
				( objectStatus "U2D1.DG84" )
			)
			( pin "@baseboard_fab2_lib.baseboard_fab2(sch_1):page60_i172:ddr3_dq(9)"
				( attribute "PN" "DH85"
					( Origin gPackager )
				)
				( objectStatus "U2D1.DH85" )
			)
			( pin "@baseboard_fab2_lib.baseboard_fab2(sch_1):page60_i172:ddr3_dq(10)"
				( attribute "PN" "DV83"
					( Origin gPackager )
				)
				( objectStatus "U2D1.DV83" )
			)
			( pin "@baseboard_fab2_lib.baseboard_fab2(sch_1):page60_i172:ddr3_dq(11)"
				( attribute "PN" "DY83"
					( Origin gPackager )
				)
				( objectStatus "U2D1.DY83" )
			)
			( pin "@baseboard_fab2_lib.baseboard_fab2(sch_1):page60_i172:ddr3_dq(12)"
				( attribute "PN" "DD85"
					( Origin gPackager )
				)
				( objectStatus "U2D1.DD85" )
			)
			( pin "@baseboard_fab2_lib.baseboard_fab2(sch_1):page60_i172:ddr3_dq(13)"
				( attribute "PN" "DE84"
					( Origin gPackager )
				)
				( objectStatus "U2D1.DE84" )
			)
			( pin "@baseboard_fab2_lib.baseboard_fab2(sch_1):page60_i172:ddr3_dq(14)"
				( attribute "PN" "DR84"
					( Origin gPackager )
				)
				( objectStatus "U2D1.DR84" )
			)
			( pin "@baseboard_fab2_lib.baseboard_fab2(sch_1):page60_i172:ddr3_dq(15)"
				( attribute "PN" "DV85"
					( Origin gPackager )
				)
				( objectStatus "U2D1.DV85" )
			)
			( pin "@baseboard_fab2_lib.baseboard_fab2(sch_1):page60_i172:ddr3_dq(16)"
				( attribute "PN" "DM79"
					( Origin gPackager )
				)
				( objectStatus "U2D1.DM79" )
			)
			( pin "@baseboard_fab2_lib.baseboard_fab2(sch_1):page60_i172:ddr3_dq(17)"
				( attribute "PN" "DK81"
					( Origin gPackager )
				)
				( objectStatus "U2D1.DK81" )
			)
			( pin "@baseboard_fab2_lib.baseboard_fab2(sch_1):page60_i172:ddr3_dq(18)"
				( attribute "PN" "DT81"
					( Origin gPackager )
				)
				( objectStatus "U2D1.DT81" )
			)
			( pin "@baseboard_fab2_lib.baseboard_fab2(sch_1):page60_i172:ddr3_dq(19)"
				( attribute "PN" "DR82"
					( Origin gPackager )
				)
				( objectStatus "U2D1.DR82" )
			)
			( pin "@baseboard_fab2_lib.baseboard_fab2(sch_1):page60_i172:ddr3_dq(20)"
				( attribute "PN" "DK79"
					( Origin gPackager )
				)
				( objectStatus "U2D1.DK79" )
			)
			( pin "@baseboard_fab2_lib.baseboard_fab2(sch_1):page60_i172:ddr3_dq(21)"
				( attribute "PN" "DJ80"
					( Origin gPackager )
				)
				( objectStatus "U2D1.DJ80" )
			)
			( pin "@baseboard_fab2_lib.baseboard_fab2(sch_1):page60_i172:ddr3_dq(22)"
				( attribute "PN" "DR80"
					( Origin gPackager )
				)
				( objectStatus "U2D1.DR80" )
			)
			( pin "@baseboard_fab2_lib.baseboard_fab2(sch_1):page60_i172:ddr3_dq(23)"
				( attribute "PN" "DN82"
					( Origin gPackager )
				)
				( objectStatus "U2D1.DN82" )
			)
			( pin "@baseboard_fab2_lib.baseboard_fab2(sch_1):page60_i172:ddr3_dq(24)"
				( attribute "PN" "DN76"
					( Origin gPackager )
				)
				( objectStatus "U2D1.DN76" )
			)
			( pin "@baseboard_fab2_lib.baseboard_fab2(sch_1):page60_i172:ddr3_dq(25)"
				( attribute "PN" "DU76"
					( Origin gPackager )
				)
				( objectStatus "U2D1.DU76" )
			)
			( pin "@baseboard_fab2_lib.baseboard_fab2(sch_1):page60_i172:ddr3_dq(26)"
				( attribute "PN" "DP73"
					( Origin gPackager )
				)
				( objectStatus "U2D1.DP73" )
			)
			( pin "@baseboard_fab2_lib.baseboard_fab2(sch_1):page60_i172:ddr3_dq(27)"
				( attribute "PN" "DT73"
					( Origin gPackager )
				)
				( objectStatus "U2D1.DT73" )
			)
			( pin "@baseboard_fab2_lib.baseboard_fab2(sch_1):page60_i172:ddr3_dq(28)"
				( attribute "PN" "DP77"
					( Origin gPackager )
				)
				( objectStatus "U2D1.DP77" )
			)
			( pin "@baseboard_fab2_lib.baseboard_fab2(sch_1):page60_i172:ddr3_dq(29)"
				( attribute "PN" "DT77"
					( Origin gPackager )
				)
				( objectStatus "U2D1.DT77" )
			)
			( pin "@baseboard_fab2_lib.baseboard_fab2(sch_1):page60_i172:ddr3_dq(30)"
				( attribute "PN" "DN74"
					( Origin gPackager )
				)
				( objectStatus "U2D1.DN74" )
			)
			( pin "@baseboard_fab2_lib.baseboard_fab2(sch_1):page60_i172:ddr3_dq(31)"
				( attribute "PN" "DU74"
					( Origin gPackager )
				)
				( objectStatus "U2D1.DU74" )
			)
			( pin "@baseboard_fab2_lib.baseboard_fab2(sch_1):page60_i172:ddr3_dq(32)"
				( attribute "PN" "EC40"
					( Origin gPackager )
				)
				( objectStatus "U2D1.EC40" )
			)
			( pin "@baseboard_fab2_lib.baseboard_fab2(sch_1):page60_i172:ddr3_dq(33)"
				( attribute "PN" "ED39"
					( Origin gPackager )
				)
				( objectStatus "U2D1.ED39" )
			)
			( pin "@baseboard_fab2_lib.baseboard_fab2(sch_1):page60_i172:ddr3_dq(34)"
				( attribute "PN" "EA36"
					( Origin gPackager )
				)
				( objectStatus "U2D1.EA36" )
			)
			( pin "@baseboard_fab2_lib.baseboard_fab2(sch_1):page60_i172:ddr3_dq(35)"
				( attribute "PN" "EC36"
					( Origin gPackager )
				)
				( objectStatus "U2D1.EC36" )
			)
			( pin "@baseboard_fab2_lib.baseboard_fab2(sch_1):page60_i172:ddr3_dq(36)"
				( attribute "PN" "DY39"
					( Origin gPackager )
				)
				( objectStatus "U2D1.DY39" )
			)
			( pin "@baseboard_fab2_lib.baseboard_fab2(sch_1):page60_i172:ddr3_dq(37)"
				( attribute "PN" "EA40"
					( Origin gPackager )
				)
				( objectStatus "U2D1.EA40" )
			)
			( pin "@baseboard_fab2_lib.baseboard_fab2(sch_1):page60_i172:ddr3_dq(38)"
				( attribute "PN" "DY37"
					( Origin gPackager )
				)
				( objectStatus "U2D1.DY37" )
			)
			( pin "@baseboard_fab2_lib.baseboard_fab2(sch_1):page60_i172:ddr3_dq(39)"
				( attribute "PN" "ED37"
					( Origin gPackager )
				)
				( objectStatus "U2D1.ED37" )
			)
			( pin "@baseboard_fab2_lib.baseboard_fab2(sch_1):page60_i172:ddr3_dq(40)"
				( attribute "PN" "DN36"
					( Origin gPackager )
				)
				( objectStatus "U2D1.DN36" )
			)
			( pin "@baseboard_fab2_lib.baseboard_fab2(sch_1):page60_i172:ddr3_dq(41)"
				( attribute "PN" "DU36"
					( Origin gPackager )
				)
				( objectStatus "U2D1.DU36" )
			)
			( pin "@baseboard_fab2_lib.baseboard_fab2(sch_1):page60_i172:ddr3_dq(42)"
				( attribute "PN" "DP33"
					( Origin gPackager )
				)
				( objectStatus "U2D1.DP33" )
			)
			( pin "@baseboard_fab2_lib.baseboard_fab2(sch_1):page60_i172:ddr3_dq(43)"
				( attribute "PN" "DT33"
					( Origin gPackager )
				)
				( objectStatus "U2D1.DT33" )
			)
			( pin "@baseboard_fab2_lib.baseboard_fab2(sch_1):page60_i172:ddr3_dq(44)"
				( attribute "PN" "DP37"
					( Origin gPackager )
				)
				( objectStatus "U2D1.DP37" )
			)
			( pin "@baseboard_fab2_lib.baseboard_fab2(sch_1):page60_i172:ddr3_dq(45)"
				( attribute "PN" "DT37"
					( Origin gPackager )
				)
				( objectStatus "U2D1.DT37" )
			)
			( pin "@baseboard_fab2_lib.baseboard_fab2(sch_1):page60_i172:ddr3_dq(46)"
				( attribute "PN" "DN34"
					( Origin gPackager )
				)
				( objectStatus "U2D1.DN34" )
			)
			( pin "@baseboard_fab2_lib.baseboard_fab2(sch_1):page60_i172:ddr3_dq(47)"
				( attribute "PN" "DU34"
					( Origin gPackager )
				)
				( objectStatus "U2D1.DU34" )
			)
			( pin "@baseboard_fab2_lib.baseboard_fab2(sch_1):page60_i172:ddr3_dq(48)"
				( attribute "PN" "DN30"
					( Origin gPackager )
				)
				( objectStatus "U2D1.DN30" )
			)
			( pin "@baseboard_fab2_lib.baseboard_fab2(sch_1):page60_i172:ddr3_dq(49)"
				( attribute "PN" "DU30"
					( Origin gPackager )
				)
				( objectStatus "U2D1.DU30" )
			)
			( pin "@baseboard_fab2_lib.baseboard_fab2(sch_1):page60_i172:ddr3_dq(50)"
				( attribute "PN" "DP27"
					( Origin gPackager )
				)
				( objectStatus "U2D1.DP27" )
			)
			( pin "@baseboard_fab2_lib.baseboard_fab2(sch_1):page60_i172:ddr3_dq(51)"
				( attribute "PN" "DT27"
					( Origin gPackager )
				)
				( objectStatus "U2D1.DT27" )
			)
			( pin "@baseboard_fab2_lib.baseboard_fab2(sch_1):page60_i172:ddr3_dq(52)"
				( attribute "PN" "DP31"
					( Origin gPackager )
				)
				( objectStatus "U2D1.DP31" )
			)
			( pin "@baseboard_fab2_lib.baseboard_fab2(sch_1):page60_i172:ddr3_dq(53)"
				( attribute "PN" "DT31"
					( Origin gPackager )
				)
				( objectStatus "U2D1.DT31" )
			)
			( pin "@baseboard_fab2_lib.baseboard_fab2(sch_1):page60_i172:ddr3_dq(54)"
				( attribute "PN" "DN28"
					( Origin gPackager )
				)
				( objectStatus "U2D1.DN28" )
			)
			( pin "@baseboard_fab2_lib.baseboard_fab2(sch_1):page60_i172:ddr3_dq(55)"
				( attribute "PN" "DU28"
					( Origin gPackager )
				)
				( objectStatus "U2D1.DU28" )
			)
			( pin "@baseboard_fab2_lib.baseboard_fab2(sch_1):page60_i172:ddr3_dq(56)"
				( attribute "PN" "DN24"
					( Origin gPackager )
				)
				( objectStatus "U2D1.DN24" )
			)
			( pin "@baseboard_fab2_lib.baseboard_fab2(sch_1):page60_i172:ddr3_dq(57)"
				( attribute "PN" "DU24"
					( Origin gPackager )
				)
				( objectStatus "U2D1.DU24" )
			)
			( pin "@baseboard_fab2_lib.baseboard_fab2(sch_1):page60_i172:ddr3_dq(58)"
				( attribute "PN" "DY21"
					( Origin gPackager )
				)
				( objectStatus "U2D1.DY21" )
			)
			( pin "@baseboard_fab2_lib.baseboard_fab2(sch_1):page60_i172:ddr3_dq(59)"
				( attribute "PN" "EB21"
					( Origin gPackager )
				)
				( objectStatus "U2D1.EB21" )
			)
			( pin "@baseboard_fab2_lib.baseboard_fab2(sch_1):page60_i172:ddr3_dq(60)"
				( attribute "PN" "DP25"
					( Origin gPackager )
				)
				( objectStatus "U2D1.DP25" )
			)
			( pin "@baseboard_fab2_lib.baseboard_fab2(sch_1):page60_i172:ddr3_dq(61)"
				( attribute "PN" "DT25"
					( Origin gPackager )
				)
				( objectStatus "U2D1.DT25" )
			)
			( pin "@baseboard_fab2_lib.baseboard_fab2(sch_1):page60_i172:ddr3_dq(62)"
				( attribute "PN" "EC22"
					( Origin gPackager )
				)
				( objectStatus "U2D1.EC22" )
			)
			( pin "@baseboard_fab2_lib.baseboard_fab2(sch_1):page60_i172:ddr3_dq(63)"
				( attribute "PN" "DW22"
					( Origin gPackager )
				)
				( objectStatus "U2D1.DW22" )
			)
			( pin "@baseboard_fab2_lib.baseboard_fab2(sch_1):page60_i172:ddr3_dqs_dn(0)"
				( attribute "PN" "CU84"
					( Origin gPackager )
				)
				( objectStatus "U2D1.CU84" )
			)
			( pin "@baseboard_fab2_lib.baseboard_fab2(sch_1):page60_i172:ddr3_dqs_dn(1)"
				( attribute "PN" "DN84"
					( Origin gPackager )
				)
				( objectStatus "U2D1.DN84" )
			)
			( pin "@baseboard_fab2_lib.baseboard_fab2(sch_1):page60_i172:ddr3_dqs_dn(2)"
				( attribute "PN" "DL82"
					( Origin gPackager )
				)
				( objectStatus "U2D1.DL82" )
			)
			( pin "@baseboard_fab2_lib.baseboard_fab2(sch_1):page60_i172:ddr3_dqs_dn(3)"
				( attribute "PN" "DV75"
					( Origin gPackager )
				)
				( objectStatus "U2D1.DV75" )
			)
			( pin "@baseboard_fab2_lib.baseboard_fab2(sch_1):page60_i172:ddr3_dqs_dn(4)"
				( attribute "PN" "EE38"
					( Origin gPackager )
				)
				( objectStatus "U2D1.EE38" )
			)
			( pin "@baseboard_fab2_lib.baseboard_fab2(sch_1):page60_i172:ddr3_dqs_dn(5)"
				( attribute "PN" "DV35"
					( Origin gPackager )
				)
				( objectStatus "U2D1.DV35" )
			)
			( pin "@baseboard_fab2_lib.baseboard_fab2(sch_1):page60_i172:ddr3_dqs_dn(6)"
				( attribute "PN" "DV29"
					( Origin gPackager )
				)
				( objectStatus "U2D1.DV29" )
			)
			( pin "@baseboard_fab2_lib.baseboard_fab2(sch_1):page60_i172:ddr3_dqs_dn(7)"
				( attribute "PN" "DV23"
					( Origin gPackager )
				)
				( objectStatus "U2D1.DV23" )
			)
			( pin "@baseboard_fab2_lib.baseboard_fab2(sch_1):page60_i172:ddr3_dqs_dn(8)"
				( attribute "PN" "DF67"
					( Origin gPackager )
				)
				( objectStatus "U2D1.DF67" )
			)
			( pin "@baseboard_fab2_lib.baseboard_fab2(sch_1):page60_i172:ddr3_dqs_dn(9)"
				( attribute "PN" "CR84"
					( Origin gPackager )
				)
				( objectStatus "U2D1.CR84" )
			)
			( pin "@baseboard_fab2_lib.baseboard_fab2(sch_1):page60_i172:ddr3_dqs_dn(10)"
				( attribute "PN" "DM85"
					( Origin gPackager )
				)
				( objectStatus "U2D1.DM85" )
			)
			( pin "@baseboard_fab2_lib.baseboard_fab2(sch_1):page60_i172:ddr3_dqs_dn(11)"
				( attribute "PN" "DN80"
					( Origin gPackager )
				)
				( objectStatus "U2D1.DN80" )
			)
			( pin "@baseboard_fab2_lib.baseboard_fab2(sch_1):page60_i172:ddr3_dqs_dn(12)"
				( attribute "PN" "DP75"
					( Origin gPackager )
				)
				( objectStatus "U2D1.DP75" )
			)
			( pin "@baseboard_fab2_lib.baseboard_fab2(sch_1):page60_i172:ddr3_dqs_dn(13)"
				( attribute "PN" "EA38"
					( Origin gPackager )
				)
				( objectStatus "U2D1.EA38" )
			)
			( pin "@baseboard_fab2_lib.baseboard_fab2(sch_1):page60_i172:ddr3_dqs_dn(14)"
				( attribute "PN" "DP35"
					( Origin gPackager )
				)
				( objectStatus "U2D1.DP35" )
			)
			( pin "@baseboard_fab2_lib.baseboard_fab2(sch_1):page60_i172:ddr3_dqs_dn(15)"
				( attribute "PN" "DM29"
					( Origin gPackager )
				)
				( objectStatus "U2D1.DM29" )
			)
			( pin "@baseboard_fab2_lib.baseboard_fab2(sch_1):page60_i172:ddr3_dqs_dn(16)"
				( attribute "PN" "DM23"
					( Origin gPackager )
				)
				( objectStatus "U2D1.DM23" )
			)
			( pin "@baseboard_fab2_lib.baseboard_fab2(sch_1):page60_i172:ddr3_dqs_dn(17)"
				( attribute "PN" "DB67"
					( Origin gPackager )
				)
				( objectStatus "U2D1.DB67" )
			)
			( pin "@baseboard_fab2_lib.baseboard_fab2(sch_1):page60_i172:ddr3_dqs_dp(0)"
				( attribute "PN" "CV85"
					( Origin gPackager )
				)
				( objectStatus "U2D1.CV85" )
			)
			( pin "@baseboard_fab2_lib.baseboard_fab2(sch_1):page60_i172:ddr3_dqs_dp(1)"
				( attribute "PN" "DP85"
					( Origin gPackager )
				)
				( objectStatus "U2D1.DP85" )
			)
			( pin "@baseboard_fab2_lib.baseboard_fab2(sch_1):page60_i172:ddr3_dqs_dp(2)"
				( attribute "PN" "DM81"
					( Origin gPackager )
				)
				( objectStatus "U2D1.DM81" )
			)
			( pin "@baseboard_fab2_lib.baseboard_fab2(sch_1):page60_i172:ddr3_dqs_dp(3)"
				( attribute "PN" "DT75"
					( Origin gPackager )
				)
				( objectStatus "U2D1.DT75" )
			)
			( pin "@baseboard_fab2_lib.baseboard_fab2(sch_1):page60_i172:ddr3_dqs_dp(4)"
				( attribute "PN" "EC38"
					( Origin gPackager )
				)
				( objectStatus "U2D1.EC38" )
			)
			( pin "@baseboard_fab2_lib.baseboard_fab2(sch_1):page60_i172:ddr3_dqs_dp(5)"
				( attribute "PN" "DT35"
					( Origin gPackager )
				)
				( objectStatus "U2D1.DT35" )
			)
			( pin "@baseboard_fab2_lib.baseboard_fab2(sch_1):page60_i172:ddr3_dqs_dp(6)"
				( attribute "PN" "DT29"
					( Origin gPackager )
				)
				( objectStatus "U2D1.DT29" )
			)
			( pin "@baseboard_fab2_lib.baseboard_fab2(sch_1):page60_i172:ddr3_dqs_dp(7)"
				( attribute "PN" "DT23"
					( Origin gPackager )
				)
				( objectStatus "U2D1.DT23" )
			)
			( pin "@baseboard_fab2_lib.baseboard_fab2(sch_1):page60_i172:ddr3_dqs_dp(8)"
				( attribute "PN" "DD67"
					( Origin gPackager )
				)
				( objectStatus "U2D1.DD67" )
			)
			( pin "@baseboard_fab2_lib.baseboard_fab2(sch_1):page60_i172:ddr3_dqs_dp(9)"
				( attribute "PN" "CP85"
					( Origin gPackager )
				)
				( objectStatus "U2D1.CP85" )
			)
			( pin "@baseboard_fab2_lib.baseboard_fab2(sch_1):page60_i172:ddr3_dqs_dp(10)"
				( attribute "PN" "DL84"
					( Origin gPackager )
				)
				( objectStatus "U2D1.DL84" )
			)
			( pin "@baseboard_fab2_lib.baseboard_fab2(sch_1):page60_i172:ddr3_dqs_dp(11)"
				( attribute "PN" "DP79"
					( Origin gPackager )
				)
				( objectStatus "U2D1.DP79" )
			)
			( pin "@baseboard_fab2_lib.baseboard_fab2(sch_1):page60_i172:ddr3_dqs_dp(12)"
				( attribute "PN" "DM75"
					( Origin gPackager )
				)
				( objectStatus "U2D1.DM75" )
			)
			( pin "@baseboard_fab2_lib.baseboard_fab2(sch_1):page60_i172:ddr3_dqs_dp(13)"
				( attribute "PN" "DW38"
					( Origin gPackager )
				)
				( objectStatus "U2D1.DW38" )
			)
			( pin "@baseboard_fab2_lib.baseboard_fab2(sch_1):page60_i172:ddr3_dqs_dp(14)"
				( attribute "PN" "DM35"
					( Origin gPackager )
				)
				( objectStatus "U2D1.DM35" )
			)
			( pin "@baseboard_fab2_lib.baseboard_fab2(sch_1):page60_i172:ddr3_dqs_dp(15)"
				( attribute "PN" "DP29"
					( Origin gPackager )
				)
				( objectStatus "U2D1.DP29" )
			)
			( pin "@baseboard_fab2_lib.baseboard_fab2(sch_1):page60_i172:ddr3_dqs_dp(16)"
				( attribute "PN" "DP23"
					( Origin gPackager )
				)
				( objectStatus "U2D1.DP23" )
			)
			( pin "@baseboard_fab2_lib.baseboard_fab2(sch_1):page60_i172:ddr3_dqs_dp(17)"
				( attribute "PN" "CY67"
					( Origin gPackager )
				)
				( objectStatus "U2D1.CY67" )
			)
			( pin "@baseboard_fab2_lib.baseboard_fab2(sch_1):page60_i172:ddr3_ecc(0)"
				( attribute "PN" "DA68"
					( Origin gPackager )
				)
				( objectStatus "U2D1.DA68" )
			)
			( pin "@baseboard_fab2_lib.baseboard_fab2(sch_1):page60_i172:ddr3_ecc(1)"
				( attribute "PN" "DE68"
					( Origin gPackager )
				)
				( objectStatus "U2D1.DE68" )
			)
			( pin "@baseboard_fab2_lib.baseboard_fab2(sch_1):page60_i172:ddr3_ecc(2)"
				( attribute "PN" "DB65"
					( Origin gPackager )
				)
				( objectStatus "U2D1.DB65" )
			)
			( pin "@baseboard_fab2_lib.baseboard_fab2(sch_1):page60_i172:ddr3_ecc(3)"
				( attribute "PN" "DD65"
					( Origin gPackager )
				)
				( objectStatus "U2D1.DD65" )
			)
			( pin "@baseboard_fab2_lib.baseboard_fab2(sch_1):page60_i172:ddr3_ecc(4)"
				( attribute "PN" "DB69"
					( Origin gPackager )
				)
				( objectStatus "U2D1.DB69" )
			)
			( pin "@baseboard_fab2_lib.baseboard_fab2(sch_1):page60_i172:ddr3_ecc(5)"
				( attribute "PN" "DD69"
					( Origin gPackager )
				)
				( objectStatus "U2D1.DD69" )
			)
			( pin "@baseboard_fab2_lib.baseboard_fab2(sch_1):page60_i172:ddr3_ecc(6)"
				( attribute "PN" "DA66"
					( Origin gPackager )
				)
				( objectStatus "U2D1.DA66" )
			)
			( pin "@baseboard_fab2_lib.baseboard_fab2(sch_1):page60_i172:ddr3_ecc(7)"
				( attribute "PN" "DE66"
					( Origin gPackager )
				)
				( objectStatus "U2D1.DE66" )
			)
			( pin "@baseboard_fab2_lib.baseboard_fab2(sch_1):page60_i172:ddr3_ma(0)"
				( attribute "PN" "EB53"
					( Origin gPackager )
				)
				( objectStatus "U2D1.EB53" )
			)
			( pin "@baseboard_fab2_lib.baseboard_fab2(sch_1):page60_i172:ddr3_ma(1)"
				( attribute "PN" "ED57"
					( Origin gPackager )
				)
				( objectStatus "U2D1.ED57" )
			)
			( pin "@baseboard_fab2_lib.baseboard_fab2(sch_1):page60_i172:ddr3_ma(2)"
				( attribute "PN" "EE58"
					( Origin gPackager )
				)
				( objectStatus "U2D1.EE58" )
			)
			( pin "@baseboard_fab2_lib.baseboard_fab2(sch_1):page60_i172:ddr3_ma(3)"
				( attribute "PN" "EB57"
					( Origin gPackager )
				)
				( objectStatus "U2D1.EB57" )
			)
			( pin "@baseboard_fab2_lib.baseboard_fab2(sch_1):page60_i172:ddr3_ma(4)"
				( attribute "PN" "ED59"
					( Origin gPackager )
				)
				( objectStatus "U2D1.ED59" )
			)
			( pin "@baseboard_fab2_lib.baseboard_fab2(sch_1):page60_i172:ddr3_ma(5)"
				( attribute "PN" "EA58"
					( Origin gPackager )
				)
				( objectStatus "U2D1.EA58" )
			)
			( pin "@baseboard_fab2_lib.baseboard_fab2(sch_1):page60_i172:ddr3_ma(6)"
				( attribute "PN" "EE60"
					( Origin gPackager )
				)
				( objectStatus "U2D1.EE60" )
			)
			( pin "@baseboard_fab2_lib.baseboard_fab2(sch_1):page60_i172:ddr3_ma(7)"
				( attribute "PN" "EA60"
					( Origin gPackager )
				)
				( objectStatus "U2D1.EA60" )
			)
			( pin "@baseboard_fab2_lib.baseboard_fab2(sch_1):page60_i172:ddr3_ma(8)"
				( attribute "PN" "EB59"
					( Origin gPackager )
				)
				( objectStatus "U2D1.EB59" )
			)
			( pin "@baseboard_fab2_lib.baseboard_fab2(sch_1):page60_i172:ddr3_ma(9)"
				( attribute "PN" "EF61"
					( Origin gPackager )
				)
				( objectStatus "U2D1.EF61" )
			)
			( pin "@baseboard_fab2_lib.baseboard_fab2(sch_1):page60_i172:ddr3_ma(10)"
				( attribute "PN" "DW54"
					( Origin gPackager )
				)
				( objectStatus "U2D1.DW54" )
			)
			( pin "@baseboard_fab2_lib.baseboard_fab2(sch_1):page60_i172:ddr3_ma(11)"
				( attribute "PN" "EB61"
					( Origin gPackager )
				)
				( objectStatus "U2D1.EB61" )
			)
			( pin "@baseboard_fab2_lib.baseboard_fab2(sch_1):page60_i172:ddr3_ma(12)"
				( attribute "PN" "DT63"
					( Origin gPackager )
				)
				( objectStatus "U2D1.DT63" )
			)
			( pin "@baseboard_fab2_lib.baseboard_fab2(sch_1):page60_i172:ddr3_ma(13)"
				( attribute "PN" "DW48"
					( Origin gPackager )
				)
				( objectStatus "U2D1.DW48" )
			)
			( pin "@baseboard_fab2_lib.baseboard_fab2(sch_1):page60_i172:ddr3_ma(14)"
				( attribute "PN" "ED51"
					( Origin gPackager )
				)
				( objectStatus "U2D1.ED51" )
			)
			( pin "@baseboard_fab2_lib.baseboard_fab2(sch_1):page60_i172:ddr3_ma(15)"
				( attribute "PN" "DV49"
					( Origin gPackager )
				)
				( objectStatus "U2D1.DV49" )
			)
			( pin "@baseboard_fab2_lib.baseboard_fab2(sch_1):page60_i172:ddr3_ma(16)"
				( attribute "PN" "EA52"
					( Origin gPackager )
				)
				( objectStatus "U2D1.EA52" )
			)
			( pin "@baseboard_fab2_lib.baseboard_fab2(sch_1):page60_i172:ddr3_ma(17)"
				( attribute "PN" "EA46"
					( Origin gPackager )
				)
				( objectStatus "U2D1.EA46" )
			)
			( pin "@baseboard_fab2_lib.baseboard_fab2(sch_1):page60_i172:ddr3_odt(0)"
				( attribute "PN" "EE50"
					( Origin gPackager )
				)
				( objectStatus "U2D1.EE50" )
			)
			( pin "@baseboard_fab2_lib.baseboard_fab2(sch_1):page60_i172:ddr3_odt(1)"
				( attribute "PN" "EE48"
					( Origin gPackager )
				)
				( objectStatus "U2D1.EE48" )
			)
			( pin "@baseboard_fab2_lib.baseboard_fab2(sch_1):page60_i172:ddr3_odt(2)"
				( attribute "PN" "EA50"
					( Origin gPackager )
				)
				( objectStatus "U2D1.EA50" )
			)
			( pin "@baseboard_fab2_lib.baseboard_fab2(sch_1):page60_i172:ddr3_odt(3)"
				( attribute "PN" "EA48"
					( Origin gPackager )
				)
				( objectStatus "U2D1.EA48" )
			)
			( pin "@baseboard_fab2_lib.baseboard_fab2(sch_1):page60_i172:ddr3_par"
				( attribute "PN" "ED53"
					( Origin gPackager )
				)
				( objectStatus "U2D1.ED53" )
			)
			( pin "@baseboard_fab2_lib.baseboard_fab2(sch_1):page61_i172:ddr4_act_n"
				( attribute "PN" "DR62"
					( Origin gPackager )
				)
				( objectStatus "U2D1.DR62" )
			)
			( pin "@baseboard_fab2_lib.baseboard_fab2(sch_1):page61_i172:ddr4_alert_n"
				( attribute "PN" "DT61"
					( Origin gPackager )
				)
				( objectStatus "U2D1.DT61" )
			)
			( pin "@baseboard_fab2_lib.baseboard_fab2(sch_1):page61_i172:ddr4_ba(0)"
				( attribute "PN" "DM53"
					( Origin gPackager )
				)
				( objectStatus "U2D1.DM53" )
			)
			( pin "@baseboard_fab2_lib.baseboard_fab2(sch_1):page61_i172:ddr4_ba(1)"
				( attribute "PN" "DV55"
					( Origin gPackager )
				)
				( objectStatus "U2D1.DV55" )
			)
			( pin "@baseboard_fab2_lib.baseboard_fab2(sch_1):page61_i172:ddr4_bg(0)"
				( attribute "PN" "DJ62"
					( Origin gPackager )
				)
				( objectStatus "U2D1.DJ62" )
			)
			( pin "@baseboard_fab2_lib.baseboard_fab2(sch_1):page61_i172:ddr4_bg(1)"
				( attribute "PN" "DM61"
					( Origin gPackager )
				)
				( objectStatus "U2D1.DM61" )
			)
			( pin "@baseboard_fab2_lib.baseboard_fab2(sch_1):page61_i172:ddr4_cid(2)"
				( attribute "PN" "DT47"
					( Origin gPackager )
				)
				( objectStatus "U2D1.DT47" )
			)
			( pin "@baseboard_fab2_lib.baseboard_fab2(sch_1):page61_i172:ddr4_cke(0)"
				( attribute "PN" "DM63"
					( Origin gPackager )
				)
				( objectStatus "U2D1.DM63" )
			)
			( pin "@baseboard_fab2_lib.baseboard_fab2(sch_1):page61_i172:ddr4_cke(1)"
				( attribute "PN" "DN64"
					( Origin gPackager )
				)
				( objectStatus "U2D1.DN64" )
			)
			( pin "@baseboard_fab2_lib.baseboard_fab2(sch_1):page61_i172:ddr4_cke(2)"
				( attribute "PN" "DL64"
					( Origin gPackager )
				)
				( objectStatus "U2D1.DL64" )
			)
			( pin "@baseboard_fab2_lib.baseboard_fab2(sch_1):page61_i172:ddr4_cke(3)"
				( attribute "PN" "DR64"
					( Origin gPackager )
				)
				( objectStatus "U2D1.DR64" )
			)
			( pin "@baseboard_fab2_lib.baseboard_fab2(sch_1):page61_i172:ddr4_clk_dn(0)"
				( attribute "PN" "DM55"
					( Origin gPackager )
				)
				( objectStatus "U2D1.DM55" )
			)
			( pin "@baseboard_fab2_lib.baseboard_fab2(sch_1):page61_i172:ddr4_clk_dn(1)"
				( attribute "PN" "DR54"
					( Origin gPackager )
				)
				( objectStatus "U2D1.DR54" )
			)
			( pin "@baseboard_fab2_lib.baseboard_fab2(sch_1):page61_i172:ddr4_clk_dn(2)"
				( attribute "PN" "DM57"
					( Origin gPackager )
				)
				( objectStatus "U2D1.DM57" )
			)
			( pin "@baseboard_fab2_lib.baseboard_fab2(sch_1):page61_i172:ddr4_clk_dn(3)"
				( attribute "PN" "DT57"
					( Origin gPackager )
				)
				( objectStatus "U2D1.DT57" )
			)
			( pin "@baseboard_fab2_lib.baseboard_fab2(sch_1):page61_i172:ddr4_clk_dp(0)"
				( attribute "PN" "DN54"
					( Origin gPackager )
				)
				( objectStatus "U2D1.DN54" )
			)
			( pin "@baseboard_fab2_lib.baseboard_fab2(sch_1):page61_i172:ddr4_clk_dp(1)"
				( attribute "PN" "DT53"
					( Origin gPackager )
				)
				( objectStatus "U2D1.DT53" )
			)
			( pin "@baseboard_fab2_lib.baseboard_fab2(sch_1):page61_i172:ddr4_clk_dp(2)"
				( attribute "PN" "DN56"
					( Origin gPackager )
				)
				( objectStatus "U2D1.DN56" )
			)
			( pin "@baseboard_fab2_lib.baseboard_fab2(sch_1):page61_i172:ddr4_clk_dp(3)"
				( attribute "PN" "DR56"
					( Origin gPackager )
				)
				( objectStatus "U2D1.DR56" )
			)
			( pin "@baseboard_fab2_lib.baseboard_fab2(sch_1):page61_i172:ddr4_cs_n(0)"
				( attribute "PN" "DV51"
					( Origin gPackager )
				)
				( objectStatus "U2D1.DV51" )
			)
			( pin "@baseboard_fab2_lib.baseboard_fab2(sch_1):page61_i172:ddr4_cs_n(1)"
				( attribute "PN" "DN50"
					( Origin gPackager )
				)
				( objectStatus "U2D1.DN50" )
			)
			( pin "@baseboard_fab2_lib.baseboard_fab2(sch_1):page61_i172:ddr4_cs_n(2)"
				( attribute "PN" "DR46"
					( Origin gPackager )
				)
				( objectStatus "U2D1.DR46" )
			)
			( pin "@baseboard_fab2_lib.baseboard_fab2(sch_1):page61_i172:ddr4_cs_n(3)"
				( attribute "PN" "DK47"
					( Origin gPackager )
				)
				( objectStatus "U2D1.DK47" )
			)
			( pin "@baseboard_fab2_lib.baseboard_fab2(sch_1):page61_i172:ddr4_cs_n(4)"
				( attribute "PN" "DW50"
					( Origin gPackager )
				)
				( objectStatus "U2D1.DW50" )
			)
			( pin "@baseboard_fab2_lib.baseboard_fab2(sch_1):page61_i172:ddr4_cs_n(5)"
				( attribute "PN" "DM49"
					( Origin gPackager )
				)
				( objectStatus "U2D1.DM49" )
			)
			( pin "@baseboard_fab2_lib.baseboard_fab2(sch_1):page61_i172:ddr4_cs_n(6)"
				( attribute "PN" "DT45"
					( Origin gPackager )
				)
				( objectStatus "U2D1.DT45" )
			)
			( pin "@baseboard_fab2_lib.baseboard_fab2(sch_1):page61_i172:ddr4_cs_n(7)"
				( attribute "PN" "DN46"
					( Origin gPackager )
				)
				( objectStatus "U2D1.DN46" )
			)
			( pin "@baseboard_fab2_lib.baseboard_fab2(sch_1):page61_i172:ddr4_dq(0)"
				( attribute "PN" "CM79"
					( Origin gPackager )
				)
				( objectStatus "U2D1.CM79" )
			)
			( pin "@baseboard_fab2_lib.baseboard_fab2(sch_1):page61_i172:ddr4_dq(1)"
				( attribute "PN" "CK81"
					( Origin gPackager )
				)
				( objectStatus "U2D1.CK81" )
			)
			( pin "@baseboard_fab2_lib.baseboard_fab2(sch_1):page61_i172:ddr4_dq(2)"
				( attribute "PN" "CT81"
					( Origin gPackager )
				)
				( objectStatus "U2D1.CT81" )
			)
			( pin "@baseboard_fab2_lib.baseboard_fab2(sch_1):page61_i172:ddr4_dq(3)"
				( attribute "PN" "CR82"
					( Origin gPackager )
				)
				( objectStatus "U2D1.CR82" )
			)
			( pin "@baseboard_fab2_lib.baseboard_fab2(sch_1):page61_i172:ddr4_dq(4)"
				( attribute "PN" "CK79"
					( Origin gPackager )
				)
				( objectStatus "U2D1.CK79" )
			)
			( pin "@baseboard_fab2_lib.baseboard_fab2(sch_1):page61_i172:ddr4_dq(5)"
				( attribute "PN" "CJ80"
					( Origin gPackager )
				)
				( objectStatus "U2D1.CJ80" )
			)
			( pin "@baseboard_fab2_lib.baseboard_fab2(sch_1):page61_i172:ddr4_dq(6)"
				( attribute "PN" "CR80"
					( Origin gPackager )
				)
				( objectStatus "U2D1.CR80" )
			)
			( pin "@baseboard_fab2_lib.baseboard_fab2(sch_1):page61_i172:ddr4_dq(7)"
				( attribute "PN" "CN82"
					( Origin gPackager )
				)
				( objectStatus "U2D1.CN82" )
			)
			( pin "@baseboard_fab2_lib.baseboard_fab2(sch_1):page61_i172:ddr4_dq(8)"
				( attribute "PN" "DB79"
					( Origin gPackager )
				)
				( objectStatus "U2D1.DB79" )
			)
			( pin "@baseboard_fab2_lib.baseboard_fab2(sch_1):page61_i172:ddr4_dq(9)"
				( attribute "PN" "CY81"
					( Origin gPackager )
				)
				( objectStatus "U2D1.CY81" )
			)
			( pin "@baseboard_fab2_lib.baseboard_fab2(sch_1):page61_i172:ddr4_dq(10)"
				( attribute "PN" "DE80"
					( Origin gPackager )
				)
				( objectStatus "U2D1.DE80" )
			)
			( pin "@baseboard_fab2_lib.baseboard_fab2(sch_1):page61_i172:ddr4_dq(11)"
				( attribute "PN" "DF81"
					( Origin gPackager )
				)
				( objectStatus "U2D1.DF81" )
			)
			( pin "@baseboard_fab2_lib.baseboard_fab2(sch_1):page61_i172:ddr4_dq(12)"
				( attribute "PN" "CY79"
					( Origin gPackager )
				)
				( objectStatus "U2D1.CY79" )
			)
			( pin "@baseboard_fab2_lib.baseboard_fab2(sch_1):page61_i172:ddr4_dq(13)"
				( attribute "PN" "CW80"
					( Origin gPackager )
				)
				( objectStatus "U2D1.CW80" )
			)
			( pin "@baseboard_fab2_lib.baseboard_fab2(sch_1):page61_i172:ddr4_dq(14)"
				( attribute "PN" "DC82"
					( Origin gPackager )
				)
				( objectStatus "U2D1.DC82" )
			)
			( pin "@baseboard_fab2_lib.baseboard_fab2(sch_1):page61_i172:ddr4_dq(15)"
				( attribute "PN" "DE82"
					( Origin gPackager )
				)
				( objectStatus "U2D1.DE82" )
			)
			( pin "@baseboard_fab2_lib.baseboard_fab2(sch_1):page61_i172:ddr4_dq(16)"
				( attribute "PN" "DW80"
					( Origin gPackager )
				)
				( objectStatus "U2D1.DW80" )
			)
			( pin "@baseboard_fab2_lib.baseboard_fab2(sch_1):page61_i172:ddr4_dq(17)"
				( attribute "PN" "EC80"
					( Origin gPackager )
				)
				( objectStatus "U2D1.EC80" )
			)
			( pin "@baseboard_fab2_lib.baseboard_fab2(sch_1):page61_i172:ddr4_dq(18)"
				( attribute "PN" "DY77"
					( Origin gPackager )
				)
				( objectStatus "U2D1.DY77" )
			)
			( pin "@baseboard_fab2_lib.baseboard_fab2(sch_1):page61_i172:ddr4_dq(19)"
				( attribute "PN" "EB77"
					( Origin gPackager )
				)
				( objectStatus "U2D1.EB77" )
			)
			( pin "@baseboard_fab2_lib.baseboard_fab2(sch_1):page61_i172:ddr4_dq(20)"
				( attribute "PN" "DY81"
					( Origin gPackager )
				)
				( objectStatus "U2D1.DY81" )
			)
			( pin "@baseboard_fab2_lib.baseboard_fab2(sch_1):page61_i172:ddr4_dq(21)"
				( attribute "PN" "EB81"
					( Origin gPackager )
				)
				( objectStatus "U2D1.EB81" )
			)
			( pin "@baseboard_fab2_lib.baseboard_fab2(sch_1):page61_i172:ddr4_dq(22)"
				( attribute "PN" "DW78"
					( Origin gPackager )
				)
				( objectStatus "U2D1.DW78" )
			)
			( pin "@baseboard_fab2_lib.baseboard_fab2(sch_1):page61_i172:ddr4_dq(23)"
				( attribute "PN" "EC78"
					( Origin gPackager )
				)
				( objectStatus "U2D1.EC78" )
			)
			( pin "@baseboard_fab2_lib.baseboard_fab2(sch_1):page61_i172:ddr4_dq(24)"
				( attribute "PN" "ED75"
					( Origin gPackager )
				)
				( objectStatus "U2D1.ED75" )
			)
			( pin "@baseboard_fab2_lib.baseboard_fab2(sch_1):page61_i172:ddr4_dq(25)"
				( attribute "PN" "EE74"
					( Origin gPackager )
				)
				( objectStatus "U2D1.EE74" )
			)
			( pin "@baseboard_fab2_lib.baseboard_fab2(sch_1):page61_i172:ddr4_dq(26)"
				( attribute "PN" "EB71"
					( Origin gPackager )
				)
				( objectStatus "U2D1.EB71" )
			)
			( pin "@baseboard_fab2_lib.baseboard_fab2(sch_1):page61_i172:ddr4_dq(27)"
				( attribute "PN" "ED71"
					( Origin gPackager )
				)
				( objectStatus "U2D1.ED71" )
			)
			( pin "@baseboard_fab2_lib.baseboard_fab2(sch_1):page61_i172:ddr4_dq(28)"
				( attribute "PN" "EA74"
					( Origin gPackager )
				)
				( objectStatus "U2D1.EA74" )
			)
			( pin "@baseboard_fab2_lib.baseboard_fab2(sch_1):page61_i172:ddr4_dq(29)"
				( attribute "PN" "EB75"
					( Origin gPackager )
				)
				( objectStatus "U2D1.EB75" )
			)
			( pin "@baseboard_fab2_lib.baseboard_fab2(sch_1):page61_i172:ddr4_dq(30)"
				( attribute "PN" "EA72"
					( Origin gPackager )
				)
				( objectStatus "U2D1.EA72" )
			)
			( pin "@baseboard_fab2_lib.baseboard_fab2(sch_1):page61_i172:ddr4_dq(31)"
				( attribute "PN" "EE72"
					( Origin gPackager )
				)
				( objectStatus "U2D1.EE72" )
			)
			( pin "@baseboard_fab2_lib.baseboard_fab2(sch_1):page61_i172:ddr4_dq(32)"
				( attribute "PN" "DU42"
					( Origin gPackager )
				)
				( objectStatus "U2D1.DU42" )
			)
			( pin "@baseboard_fab2_lib.baseboard_fab2(sch_1):page61_i172:ddr4_dq(33)"
				( attribute "PN" "DW42"
					( Origin gPackager )
				)
				( objectStatus "U2D1.DW42" )
			)
			( pin "@baseboard_fab2_lib.baseboard_fab2(sch_1):page61_i172:ddr4_dq(34)"
				( attribute "PN" "DP39"
					( Origin gPackager )
				)
				( objectStatus "U2D1.DP39" )
			)
			( pin "@baseboard_fab2_lib.baseboard_fab2(sch_1):page61_i172:ddr4_dq(35)"
				( attribute "PN" "DT39"
					( Origin gPackager )
				)
				( objectStatus "U2D1.DT39" )
			)
			( pin "@baseboard_fab2_lib.baseboard_fab2(sch_1):page61_i172:ddr4_dq(36)"
				( attribute "PN" "DL42"
					( Origin gPackager )
				)
				( objectStatus "U2D1.DL42" )
			)
			( pin "@baseboard_fab2_lib.baseboard_fab2(sch_1):page61_i172:ddr4_dq(37)"
				( attribute "PN" "DN42"
					( Origin gPackager )
				)
				( objectStatus "U2D1.DN42" )
			)
			( pin "@baseboard_fab2_lib.baseboard_fab2(sch_1):page61_i172:ddr4_dq(38)"
				( attribute "PN" "DN40"
					( Origin gPackager )
				)
				( objectStatus "U2D1.DN40" )
			)
			( pin "@baseboard_fab2_lib.baseboard_fab2(sch_1):page61_i172:ddr4_dq(39)"
				( attribute "PN" "DU40"
					( Origin gPackager )
				)
				( objectStatus "U2D1.DU40" )
			)
			( pin "@baseboard_fab2_lib.baseboard_fab2(sch_1):page61_i172:ddr4_dq(40)"
				( attribute "PN" "EC34"
					( Origin gPackager )
				)
				( objectStatus "U2D1.EC34" )
			)
			( pin "@baseboard_fab2_lib.baseboard_fab2(sch_1):page61_i172:ddr4_dq(41)"
				( attribute "PN" "ED33"
					( Origin gPackager )
				)
				( objectStatus "U2D1.ED33" )
			)
			( pin "@baseboard_fab2_lib.baseboard_fab2(sch_1):page61_i172:ddr4_dq(42)"
				( attribute "PN" "EA30"
					( Origin gPackager )
				)
				( objectStatus "U2D1.EA30" )
			)
			( pin "@baseboard_fab2_lib.baseboard_fab2(sch_1):page61_i172:ddr4_dq(43)"
				( attribute "PN" "EC30"
					( Origin gPackager )
				)
				( objectStatus "U2D1.EC30" )
			)
			( pin "@baseboard_fab2_lib.baseboard_fab2(sch_1):page61_i172:ddr4_dq(44)"
				( attribute "PN" "DY33"
					( Origin gPackager )
				)
				( objectStatus "U2D1.DY33" )
			)
			( pin "@baseboard_fab2_lib.baseboard_fab2(sch_1):page61_i172:ddr4_dq(45)"
				( attribute "PN" "EA34"
					( Origin gPackager )
				)
				( objectStatus "U2D1.EA34" )
			)
			( pin "@baseboard_fab2_lib.baseboard_fab2(sch_1):page61_i172:ddr4_dq(46)"
				( attribute "PN" "DY31"
					( Origin gPackager )
				)
				( objectStatus "U2D1.DY31" )
			)
			( pin "@baseboard_fab2_lib.baseboard_fab2(sch_1):page61_i172:ddr4_dq(47)"
				( attribute "PN" "ED31"
					( Origin gPackager )
				)
				( objectStatus "U2D1.ED31" )
			)
			( pin "@baseboard_fab2_lib.baseboard_fab2(sch_1):page61_i172:ddr4_dq(48)"
				( attribute "PN" "EC28"
					( Origin gPackager )
				)
				( objectStatus "U2D1.EC28" )
			)
			( pin "@baseboard_fab2_lib.baseboard_fab2(sch_1):page61_i172:ddr4_dq(49)"
				( attribute "PN" "ED27"
					( Origin gPackager )
				)
				( objectStatus "U2D1.ED27" )
			)
			( pin "@baseboard_fab2_lib.baseboard_fab2(sch_1):page61_i172:ddr4_dq(50)"
				( attribute "PN" "EA24"
					( Origin gPackager )
				)
				( objectStatus "U2D1.EA24" )
			)
			( pin "@baseboard_fab2_lib.baseboard_fab2(sch_1):page61_i172:ddr4_dq(51)"
				( attribute "PN" "EC24"
					( Origin gPackager )
				)
				( objectStatus "U2D1.EC24" )
			)
			( pin "@baseboard_fab2_lib.baseboard_fab2(sch_1):page61_i172:ddr4_dq(52)"
				( attribute "PN" "DY27"
					( Origin gPackager )
				)
				( objectStatus "U2D1.DY27" )
			)
			( pin "@baseboard_fab2_lib.baseboard_fab2(sch_1):page61_i172:ddr4_dq(53)"
				( attribute "PN" "EA28"
					( Origin gPackager )
				)
				( objectStatus "U2D1.EA28" )
			)
			( pin "@baseboard_fab2_lib.baseboard_fab2(sch_1):page61_i172:ddr4_dq(54)"
				( attribute "PN" "DY25"
					( Origin gPackager )
				)
				( objectStatus "U2D1.DY25" )
			)
			( pin "@baseboard_fab2_lib.baseboard_fab2(sch_1):page61_i172:ddr4_dq(55)"
				( attribute "PN" "ED25"
					( Origin gPackager )
				)
				( objectStatus "U2D1.ED25" )
			)
			( pin "@baseboard_fab2_lib.baseboard_fab2(sch_1):page61_i172:ddr4_dq(56)"
				( attribute "PN" "DF27"
					( Origin gPackager )
				)
				( objectStatus "U2D1.DF27" )
			)
			( pin "@baseboard_fab2_lib.baseboard_fab2(sch_1):page61_i172:ddr4_dq(57)"
				( attribute "PN" "DK27"
					( Origin gPackager )
				)
				( objectStatus "U2D1.DK27" )
			)
			( pin "@baseboard_fab2_lib.baseboard_fab2(sch_1):page61_i172:ddr4_dq(58)"
				( attribute "PN" "DD25"
					( Origin gPackager )
				)
				( objectStatus "U2D1.DD25" )
			)
			( pin "@baseboard_fab2_lib.baseboard_fab2(sch_1):page61_i172:ddr4_dq(59)"
				( attribute "PN" "DJ24"
					( Origin gPackager )
				)
				( objectStatus "U2D1.DJ24" )
			)
			( pin "@baseboard_fab2_lib.baseboard_fab2(sch_1):page61_i172:ddr4_dq(60)"
				( attribute "PN" "DG28"
					( Origin gPackager )
				)
				( objectStatus "U2D1.DG28" )
			)
			( pin "@baseboard_fab2_lib.baseboard_fab2(sch_1):page61_i172:ddr4_dq(61)"
				( attribute "PN" "DJ28"
					( Origin gPackager )
				)
				( objectStatus "U2D1.DJ28" )
			)
			( pin "@baseboard_fab2_lib.baseboard_fab2(sch_1):page61_i172:ddr4_dq(62)"
				( attribute "PN" "DF25"
					( Origin gPackager )
				)
				( objectStatus "U2D1.DF25" )
			)
			( pin "@baseboard_fab2_lib.baseboard_fab2(sch_1):page61_i172:ddr4_dq(63)"
				( attribute "PN" "DK25"
					( Origin gPackager )
				)
				( objectStatus "U2D1.DK25" )
			)
			( pin "@baseboard_fab2_lib.baseboard_fab2(sch_1):page61_i172:ddr4_dqs_dn(0)"
				( attribute "PN" "CL82"
					( Origin gPackager )
				)
				( objectStatus "U2D1.CL82" )
			)
			( pin "@baseboard_fab2_lib.baseboard_fab2(sch_1):page61_i172:ddr4_dqs_dn(1)"
				( attribute "PN" "DA82"
					( Origin gPackager )
				)
				( objectStatus "U2D1.DA82" )
			)
			( pin "@baseboard_fab2_lib.baseboard_fab2(sch_1):page61_i172:ddr4_dqs_dn(2)"
				( attribute "PN" "ED79"
					( Origin gPackager )
				)
				( objectStatus "U2D1.ED79" )
			)
			( pin "@baseboard_fab2_lib.baseboard_fab2(sch_1):page61_i172:ddr4_dqs_dn(3)"
				( attribute "PN" "EF73"
					( Origin gPackager )
				)
				( objectStatus "U2D1.EF73" )
			)
			( pin "@baseboard_fab2_lib.baseboard_fab2(sch_1):page61_i172:ddr4_dqs_dn(4)"
				( attribute "PN" "DV41"
					( Origin gPackager )
				)
				( objectStatus "U2D1.DV41" )
			)
			( pin "@baseboard_fab2_lib.baseboard_fab2(sch_1):page61_i172:ddr4_dqs_dn(5)"
				( attribute "PN" "EE32"
					( Origin gPackager )
				)
				( objectStatus "U2D1.EE32" )
			)
			( pin "@baseboard_fab2_lib.baseboard_fab2(sch_1):page61_i172:ddr4_dqs_dn(6)"
				( attribute "PN" "EE26"
					( Origin gPackager )
				)
				( objectStatus "U2D1.EE26" )
			)
			( pin "@baseboard_fab2_lib.baseboard_fab2(sch_1):page61_i172:ddr4_dqs_dn(7)"
				( attribute "PN" "DL26"
					( Origin gPackager )
				)
				( objectStatus "U2D1.DL26" )
			)
			( pin "@baseboard_fab2_lib.baseboard_fab2(sch_1):page61_i172:ddr4_dqs_dn(8)"
				( attribute "PN" "EB67"
					( Origin gPackager )
				)
				( objectStatus "U2D1.EB67" )
			)
			( pin "@baseboard_fab2_lib.baseboard_fab2(sch_1):page61_i172:ddr4_dqs_dn(9)"
				( attribute "PN" "CN80"
					( Origin gPackager )
				)
				( objectStatus "U2D1.CN80" )
			)
			( pin "@baseboard_fab2_lib.baseboard_fab2(sch_1):page61_i172:ddr4_dqs_dn(10)"
				( attribute "PN" "DC80"
					( Origin gPackager )
				)
				( objectStatus "U2D1.DC80" )
			)
			( pin "@baseboard_fab2_lib.baseboard_fab2(sch_1):page61_i172:ddr4_dqs_dn(11)"
				( attribute "PN" "DY79"
					( Origin gPackager )
				)
				( objectStatus "U2D1.DY79" )
			)
			( pin "@baseboard_fab2_lib.baseboard_fab2(sch_1):page61_i172:ddr4_dqs_dn(12)"
				( attribute "PN" "EB73"
					( Origin gPackager )
				)
				( objectStatus "U2D1.EB73" )
			)
			( pin "@baseboard_fab2_lib.baseboard_fab2(sch_1):page61_i172:ddr4_dqs_dn(13)"
				( attribute "PN" "DP41"
					( Origin gPackager )
				)
				( objectStatus "U2D1.DP41" )
			)
			( pin "@baseboard_fab2_lib.baseboard_fab2(sch_1):page61_i172:ddr4_dqs_dn(14)"
				( attribute "PN" "EA32"
					( Origin gPackager )
				)
				( objectStatus "U2D1.EA32" )
			)
			( pin "@baseboard_fab2_lib.baseboard_fab2(sch_1):page61_i172:ddr4_dqs_dn(15)"
				( attribute "PN" "EA26"
					( Origin gPackager )
				)
				( objectStatus "U2D1.EA26" )
			)
			( pin "@baseboard_fab2_lib.baseboard_fab2(sch_1):page61_i172:ddr4_dqs_dn(16)"
				( attribute "PN" "DG26"
					( Origin gPackager )
				)
				( objectStatus "U2D1.DG26" )
			)
			( pin "@baseboard_fab2_lib.baseboard_fab2(sch_1):page61_i172:ddr4_dqs_dn(17)"
				( attribute "PN" "DV67"
					( Origin gPackager )
				)
				( objectStatus "U2D1.DV67" )
			)
			( pin "@baseboard_fab2_lib.baseboard_fab2(sch_1):page61_i172:ddr4_dqs_dp(0)"
				( attribute "PN" "CM81"
					( Origin gPackager )
				)
				( objectStatus "U2D1.CM81" )
			)
			( pin "@baseboard_fab2_lib.baseboard_fab2(sch_1):page61_i172:ddr4_dqs_dp(1)"
				( attribute "PN" "DB81"
					( Origin gPackager )
				)
				( objectStatus "U2D1.DB81" )
			)
			( pin "@baseboard_fab2_lib.baseboard_fab2(sch_1):page61_i172:ddr4_dqs_dp(2)"
				( attribute "PN" "EB79"
					( Origin gPackager )
				)
				( objectStatus "U2D1.EB79" )
			)
			( pin "@baseboard_fab2_lib.baseboard_fab2(sch_1):page61_i172:ddr4_dqs_dp(3)"
				( attribute "PN" "ED73"
					( Origin gPackager )
				)
				( objectStatus "U2D1.ED73" )
			)
			( pin "@baseboard_fab2_lib.baseboard_fab2(sch_1):page61_i172:ddr4_dqs_dp(4)"
				( attribute "PN" "DT41"
					( Origin gPackager )
				)
				( objectStatus "U2D1.DT41" )
			)
			( pin "@baseboard_fab2_lib.baseboard_fab2(sch_1):page61_i172:ddr4_dqs_dp(5)"
				( attribute "PN" "EC32"
					( Origin gPackager )
				)
				( objectStatus "U2D1.EC32" )
			)
			( pin "@baseboard_fab2_lib.baseboard_fab2(sch_1):page61_i172:ddr4_dqs_dp(6)"
				( attribute "PN" "EC26"
					( Origin gPackager )
				)
				( objectStatus "U2D1.EC26" )
			)
			( pin "@baseboard_fab2_lib.baseboard_fab2(sch_1):page61_i172:ddr4_dqs_dp(7)"
				( attribute "PN" "DJ26"
					( Origin gPackager )
				)
				( objectStatus "U2D1.DJ26" )
			)
			( pin "@baseboard_fab2_lib.baseboard_fab2(sch_1):page61_i172:ddr4_dqs_dp(8)"
				( attribute "PN" "DY67"
					( Origin gPackager )
				)
				( objectStatus "U2D1.DY67" )
			)
			( pin "@baseboard_fab2_lib.baseboard_fab2(sch_1):page61_i172:ddr4_dqs_dp(9)"
				( attribute "PN" "CP79"
					( Origin gPackager )
				)
				( objectStatus "U2D1.CP79" )
			)
			( pin "@baseboard_fab2_lib.baseboard_fab2(sch_1):page61_i172:ddr4_dqs_dp(10)"
				( attribute "PN" "DD79"
					( Origin gPackager )
				)
				( objectStatus "U2D1.DD79" )
			)
			( pin "@baseboard_fab2_lib.baseboard_fab2(sch_1):page61_i172:ddr4_dqs_dp(11)"
				( attribute "PN" "DV79"
					( Origin gPackager )
				)
				( objectStatus "U2D1.DV79" )
			)
			( pin "@baseboard_fab2_lib.baseboard_fab2(sch_1):page61_i172:ddr4_dqs_dp(12)"
				( attribute "PN" "DY73"
					( Origin gPackager )
				)
				( objectStatus "U2D1.DY73" )
			)
			( pin "@baseboard_fab2_lib.baseboard_fab2(sch_1):page61_i172:ddr4_dqs_dp(13)"
				( attribute "PN" "DM41"
					( Origin gPackager )
				)
				( objectStatus "U2D1.DM41" )
			)
			( pin "@baseboard_fab2_lib.baseboard_fab2(sch_1):page61_i172:ddr4_dqs_dp(14)"
				( attribute "PN" "DW32"
					( Origin gPackager )
				)
				( objectStatus "U2D1.DW32" )
			)
			( pin "@baseboard_fab2_lib.baseboard_fab2(sch_1):page61_i172:ddr4_dqs_dp(15)"
				( attribute "PN" "DW26"
					( Origin gPackager )
				)
				( objectStatus "U2D1.DW26" )
			)
			( pin "@baseboard_fab2_lib.baseboard_fab2(sch_1):page61_i172:ddr4_dqs_dp(16)"
				( attribute "PN" "DE26"
					( Origin gPackager )
				)
				( objectStatus "U2D1.DE26" )
			)
			( pin "@baseboard_fab2_lib.baseboard_fab2(sch_1):page61_i172:ddr4_dqs_dp(17)"
				( attribute "PN" "DT67"
					( Origin gPackager )
				)
				( objectStatus "U2D1.DT67" )
			)
			( pin "@baseboard_fab2_lib.baseboard_fab2(sch_1):page61_i172:ddr4_ecc(0)"
				( attribute "PN" "DY69"
					( Origin gPackager )
				)
				( objectStatus "U2D1.DY69" )
			)
			( pin "@baseboard_fab2_lib.baseboard_fab2(sch_1):page61_i172:ddr4_ecc(1)"
				( attribute "PN" "EA68"
					( Origin gPackager )
				)
				( objectStatus "U2D1.EA68" )
			)
			( pin "@baseboard_fab2_lib.baseboard_fab2(sch_1):page61_i172:ddr4_ecc(2)"
				( attribute "PN" "DV65"
					( Origin gPackager )
				)
				( objectStatus "U2D1.DV65" )
			)
			( pin "@baseboard_fab2_lib.baseboard_fab2(sch_1):page61_i172:ddr4_ecc(3)"
				( attribute "PN" "DY65"
					( Origin gPackager )
				)
				( objectStatus "U2D1.DY65" )
			)
			( pin "@baseboard_fab2_lib.baseboard_fab2(sch_1):page61_i172:ddr4_ecc(4)"
				( attribute "PN" "DU68"
					( Origin gPackager )
				)
				( objectStatus "U2D1.DU68" )
			)
			( pin "@baseboard_fab2_lib.baseboard_fab2(sch_1):page61_i172:ddr4_ecc(5)"
				( attribute "PN" "DV69"
					( Origin gPackager )
				)
				( objectStatus "U2D1.DV69" )
			)
			( pin "@baseboard_fab2_lib.baseboard_fab2(sch_1):page61_i172:ddr4_ecc(6)"
				( attribute "PN" "DU66"
					( Origin gPackager )
				)
				( objectStatus "U2D1.DU66" )
			)
			( pin "@baseboard_fab2_lib.baseboard_fab2(sch_1):page61_i172:ddr4_ecc(7)"
				( attribute "PN" "EA66"
					( Origin gPackager )
				)
				( objectStatus "U2D1.EA66" )
			)
			( pin "@baseboard_fab2_lib.baseboard_fab2(sch_1):page61_i172:ddr4_ma(0)"
				( attribute "PN" "DW52"
					( Origin gPackager )
				)
				( objectStatus "U2D1.DW52" )
			)
			( pin "@baseboard_fab2_lib.baseboard_fab2(sch_1):page61_i172:ddr4_ma(1)"
				( attribute "PN" "DW58"
					( Origin gPackager )
				)
				( objectStatus "U2D1.DW58" )
			)
			( pin "@baseboard_fab2_lib.baseboard_fab2(sch_1):page61_i172:ddr4_ma(2)"
				( attribute "PN" "DV57"
					( Origin gPackager )
				)
				( objectStatus "U2D1.DV57" )
			)
			( pin "@baseboard_fab2_lib.baseboard_fab2(sch_1):page61_i172:ddr4_ma(3)"
				( attribute "PN" "DR58"
					( Origin gPackager )
				)
				( objectStatus "U2D1.DR58" )
			)
			( pin "@baseboard_fab2_lib.baseboard_fab2(sch_1):page61_i172:ddr4_ma(4)"
				( attribute "PN" "DT59"
					( Origin gPackager )
				)
				( objectStatus "U2D1.DT59" )
			)
			( pin "@baseboard_fab2_lib.baseboard_fab2(sch_1):page61_i172:ddr4_ma(5)"
				( attribute "PN" "DN58"
					( Origin gPackager )
				)
				( objectStatus "U2D1.DN58" )
			)
			( pin "@baseboard_fab2_lib.baseboard_fab2(sch_1):page61_i172:ddr4_ma(6)"
				( attribute "PN" "DM59"
					( Origin gPackager )
				)
				( objectStatus "U2D1.DM59" )
			)
			( pin "@baseboard_fab2_lib.baseboard_fab2(sch_1):page61_i172:ddr4_ma(7)"
				( attribute "PN" "DK61"
					( Origin gPackager )
				)
				( objectStatus "U2D1.DK61" )
			)
			( pin "@baseboard_fab2_lib.baseboard_fab2(sch_1):page61_i172:ddr4_ma(8)"
				( attribute "PN" "DJ60"
					( Origin gPackager )
				)
				( objectStatus "U2D1.DJ60" )
			)
			( pin "@baseboard_fab2_lib.baseboard_fab2(sch_1):page61_i172:ddr4_ma(9)"
				( attribute "PN" "DV59"
					( Origin gPackager )
				)
				( objectStatus "U2D1.DV59" )
			)
			( pin "@baseboard_fab2_lib.baseboard_fab2(sch_1):page61_i172:ddr4_ma(10)"
				( attribute "PN" "DT55"
					( Origin gPackager )
				)
				( objectStatus "U2D1.DT55" )
			)
			( pin "@baseboard_fab2_lib.baseboard_fab2(sch_1):page61_i172:ddr4_ma(11)"
				( attribute "PN" "DR60"
					( Origin gPackager )
				)
				( objectStatus "U2D1.DR60" )
			)
			( pin "@baseboard_fab2_lib.baseboard_fab2(sch_1):page61_i172:ddr4_ma(12)"
				( attribute "PN" "DN60"
					( Origin gPackager )
				)
				( objectStatus "U2D1.DN60" )
			)
			( pin "@baseboard_fab2_lib.baseboard_fab2(sch_1):page61_i172:ddr4_ma(13)"
				( attribute "PN" "DT51"
					( Origin gPackager )
				)
				( objectStatus "U2D1.DT51" )
			)
			( pin "@baseboard_fab2_lib.baseboard_fab2(sch_1):page61_i172:ddr4_ma(14)"
				( attribute "PN" "DM51"
					( Origin gPackager )
				)
				( objectStatus "U2D1.DM51" )
			)
			( pin "@baseboard_fab2_lib.baseboard_fab2(sch_1):page61_i172:ddr4_ma(15)"
				( attribute "PN" "DR52"
					( Origin gPackager )
				)
				( objectStatus "U2D1.DR52" )
			)
			( pin "@baseboard_fab2_lib.baseboard_fab2(sch_1):page61_i172:ddr4_ma(16)"
				( attribute "PN" "DN52"
					( Origin gPackager )
				)
				( objectStatus "U2D1.DN52" )
			)
			( pin "@baseboard_fab2_lib.baseboard_fab2(sch_1):page61_i172:ddr4_ma(17)"
				( attribute "PN" "DR48"
					( Origin gPackager )
				)
				( objectStatus "U2D1.DR48" )
			)
			( pin "@baseboard_fab2_lib.baseboard_fab2(sch_1):page61_i172:ddr4_odt(0)"
				( attribute "PN" "DR50"
					( Origin gPackager )
				)
				( objectStatus "U2D1.DR50" )
			)
			( pin "@baseboard_fab2_lib.baseboard_fab2(sch_1):page61_i172:ddr4_odt(1)"
				( attribute "PN" "DN48"
					( Origin gPackager )
				)
				( objectStatus "U2D1.DN48" )
			)
			( pin "@baseboard_fab2_lib.baseboard_fab2(sch_1):page61_i172:ddr4_odt(2)"
				( attribute "PN" "DT49"
					( Origin gPackager )
				)
				( objectStatus "U2D1.DT49" )
			)
			( pin "@baseboard_fab2_lib.baseboard_fab2(sch_1):page61_i172:ddr4_odt(3)"
				( attribute "PN" "DM47"
					( Origin gPackager )
				)
				( objectStatus "U2D1.DM47" )
			)
			( pin "@baseboard_fab2_lib.baseboard_fab2(sch_1):page61_i172:ddr4_par"
				( attribute "PN" "DV53"
					( Origin gPackager )
				)
				( objectStatus "U2D1.DV53" )
			)
			( pin "@baseboard_fab2_lib.baseboard_fab2(sch_1):page62_i172:ddr5_act_n"
				( attribute "PN" "DC62"
					( Origin gPackager )
				)
				( objectStatus "U2D1.DC62" )
			)
			( pin "@baseboard_fab2_lib.baseboard_fab2(sch_1):page62_i172:ddr5_alert_n"
				( attribute "PN" "DD61"
					( Origin gPackager )
				)
				( objectStatus "U2D1.DD61" )
			)
			( pin "@baseboard_fab2_lib.baseboard_fab2(sch_1):page62_i172:ddr5_ba(0)"
				( attribute "PN" "DJ52"
					( Origin gPackager )
				)
				( objectStatus "U2D1.DJ52" )
			)
			( pin "@baseboard_fab2_lib.baseboard_fab2(sch_1):page62_i172:ddr5_ba(1)"
				( attribute "PN" "DC56"
					( Origin gPackager )
				)
				( objectStatus "U2D1.DC56" )
			)
			( pin "@baseboard_fab2_lib.baseboard_fab2(sch_1):page62_i172:ddr5_bg(0)"
				( attribute "PN" "DA62"
					( Origin gPackager )
				)
				( objectStatus "U2D1.DA62" )
			)
			( pin "@baseboard_fab2_lib.baseboard_fab2(sch_1):page62_i172:ddr5_bg(1)"
				( attribute "PN" "DF61"
					( Origin gPackager )
				)
				( objectStatus "U2D1.DF61" )
			)
			( pin "@baseboard_fab2_lib.baseboard_fab2(sch_1):page62_i172:ddr5_cid(2)"
				( attribute "PN" "DF45"
					( Origin gPackager )
				)
				( objectStatus "U2D1.DF45" )
			)
			( pin "@baseboard_fab2_lib.baseboard_fab2(sch_1):page62_i172:ddr5_cke(0)"
				( attribute "PN" "DG62"
					( Origin gPackager )
				)
				( objectStatus "U2D1.DG62" )
			)
			( pin "@baseboard_fab2_lib.baseboard_fab2(sch_1):page62_i172:ddr5_cke(1)"
				( attribute "PN" "DD63"
					( Origin gPackager )
				)
				( objectStatus "U2D1.DD63" )
			)
			( pin "@baseboard_fab2_lib.baseboard_fab2(sch_1):page62_i172:ddr5_cke(2)"
				( attribute "PN" "DK63"
					( Origin gPackager )
				)
				( objectStatus "U2D1.DK63" )
			)
			( pin "@baseboard_fab2_lib.baseboard_fab2(sch_1):page62_i172:ddr5_cke(3)"
				( attribute "PN" "DF63"
					( Origin gPackager )
				)
				( objectStatus "U2D1.DF63" )
			)
			( pin "@baseboard_fab2_lib.baseboard_fab2(sch_1):page62_i172:ddr5_clk_dn(0)"
				( attribute "PN" "DK55"
					( Origin gPackager )
				)
				( objectStatus "U2D1.DK55" )
			)
			( pin "@baseboard_fab2_lib.baseboard_fab2(sch_1):page62_i172:ddr5_clk_dn(1)"
				( attribute "PN" "DF55"
					( Origin gPackager )
				)
				( objectStatus "U2D1.DF55" )
			)
			( pin "@baseboard_fab2_lib.baseboard_fab2(sch_1):page62_i172:ddr5_clk_dn(2)"
				( attribute "PN" "DK57"
					( Origin gPackager )
				)
				( objectStatus "U2D1.DK57" )
			)
			( pin "@baseboard_fab2_lib.baseboard_fab2(sch_1):page62_i172:ddr5_clk_dn(3)"
				( attribute "PN" "DF57"
					( Origin gPackager )
				)
				( objectStatus "U2D1.DF57" )
			)
			( pin "@baseboard_fab2_lib.baseboard_fab2(sch_1):page62_i172:ddr5_clk_dp(0)"
				( attribute "PN" "DJ54"
					( Origin gPackager )
				)
				( objectStatus "U2D1.DJ54" )
			)
			( pin "@baseboard_fab2_lib.baseboard_fab2(sch_1):page62_i172:ddr5_clk_dp(1)"
				( attribute "PN" "DG54"
					( Origin gPackager )
				)
				( objectStatus "U2D1.DG54" )
			)
			( pin "@baseboard_fab2_lib.baseboard_fab2(sch_1):page62_i172:ddr5_clk_dp(2)"
				( attribute "PN" "DJ56"
					( Origin gPackager )
				)
				( objectStatus "U2D1.DJ56" )
			)
			( pin "@baseboard_fab2_lib.baseboard_fab2(sch_1):page62_i172:ddr5_clk_dp(3)"
				( attribute "PN" "DG56"
					( Origin gPackager )
				)
				( objectStatus "U2D1.DG56" )
			)
			( pin "@baseboard_fab2_lib.baseboard_fab2(sch_1):page62_i172:ddr5_cs_n(0)"
				( attribute "PN" "DK51"
					( Origin gPackager )
				)
				( objectStatus "U2D1.DK51" )
			)
			( pin "@baseboard_fab2_lib.baseboard_fab2(sch_1):page62_i172:ddr5_cs_n(1)"
				( attribute "PN" "DF49"
					( Origin gPackager )
				)
				( objectStatus "U2D1.DF49" )
			)
			( pin "@baseboard_fab2_lib.baseboard_fab2(sch_1):page62_i172:ddr5_cs_n(2)"
				( attribute "PN" "DJ46"
					( Origin gPackager )
				)
				( objectStatus "U2D1.DJ46" )
			)
			( pin "@baseboard_fab2_lib.baseboard_fab2(sch_1):page62_i172:ddr5_cs_n(3)"
				( attribute "PN" "DG46"
					( Origin gPackager )
				)
				( objectStatus "U2D1.DG46" )
			)
			( pin "@baseboard_fab2_lib.baseboard_fab2(sch_1):page62_i172:ddr5_cs_n(4)"
				( attribute "PN" "DF51"
					( Origin gPackager )
				)
				( objectStatus "U2D1.DF51" )
			)
			( pin "@baseboard_fab2_lib.baseboard_fab2(sch_1):page62_i172:ddr5_cs_n(5)"
				( attribute "PN" "DJ48"
					( Origin gPackager )
				)
				( objectStatus "U2D1.DJ48" )
			)
			( pin "@baseboard_fab2_lib.baseboard_fab2(sch_1):page62_i172:ddr5_cs_n(6)"
				( attribute "PN" "DM45"
					( Origin gPackager )
				)
				( objectStatus "U2D1.DM45" )
			)
			( pin "@baseboard_fab2_lib.baseboard_fab2(sch_1):page62_i172:ddr5_cs_n(7)"
				( attribute "PN" "DK45"
					( Origin gPackager )
				)
				( objectStatus "U2D1.DK45" )
			)
			( pin "@baseboard_fab2_lib.baseboard_fab2(sch_1):page62_i172:ddr5_dq(0)"
				( attribute "PN" "CR74"
					( Origin gPackager )
				)
				( objectStatus "U2D1.CR74" )
			)
			( pin "@baseboard_fab2_lib.baseboard_fab2(sch_1):page62_i172:ddr5_dq(1)"
				( attribute "PN" "CN76"
					( Origin gPackager )
				)
				( objectStatus "U2D1.CN76" )
			)
			( pin "@baseboard_fab2_lib.baseboard_fab2(sch_1):page62_i172:ddr5_dq(2)"
				( attribute "PN" "CW76"
					( Origin gPackager )
				)
				( objectStatus "U2D1.CW76" )
			)
			( pin "@baseboard_fab2_lib.baseboard_fab2(sch_1):page62_i172:ddr5_dq(3)"
				( attribute "PN" "CV77"
					( Origin gPackager )
				)
				( objectStatus "U2D1.CV77" )
			)
			( pin "@baseboard_fab2_lib.baseboard_fab2(sch_1):page62_i172:ddr5_dq(4)"
				( attribute "PN" "CN74"
					( Origin gPackager )
				)
				( objectStatus "U2D1.CN74" )
			)
			( pin "@baseboard_fab2_lib.baseboard_fab2(sch_1):page62_i172:ddr5_dq(5)"
				( attribute "PN" "CM75"
					( Origin gPackager )
				)
				( objectStatus "U2D1.CM75" )
			)
			( pin "@baseboard_fab2_lib.baseboard_fab2(sch_1):page62_i172:ddr5_dq(6)"
				( attribute "PN" "CV75"
					( Origin gPackager )
				)
				( objectStatus "U2D1.CV75" )
			)
			( pin "@baseboard_fab2_lib.baseboard_fab2(sch_1):page62_i172:ddr5_dq(7)"
				( attribute "PN" "CT77"
					( Origin gPackager )
				)
				( objectStatus "U2D1.CT77" )
			)
			( pin "@baseboard_fab2_lib.baseboard_fab2(sch_1):page62_i172:ddr5_dq(8)"
				( attribute "PN" "DE74"
					( Origin gPackager )
				)
				( objectStatus "U2D1.DE74" )
			)
			( pin "@baseboard_fab2_lib.baseboard_fab2(sch_1):page62_i172:ddr5_dq(9)"
				( attribute "PN" "DC76"
					( Origin gPackager )
				)
				( objectStatus "U2D1.DC76" )
			)
			( pin "@baseboard_fab2_lib.baseboard_fab2(sch_1):page62_i172:ddr5_dq(10)"
				( attribute "PN" "DH75"
					( Origin gPackager )
				)
				( objectStatus "U2D1.DH75" )
			)
			( pin "@baseboard_fab2_lib.baseboard_fab2(sch_1):page62_i172:ddr5_dq(11)"
				( attribute "PN" "DJ76"
					( Origin gPackager )
				)
				( objectStatus "U2D1.DJ76" )
			)
			( pin "@baseboard_fab2_lib.baseboard_fab2(sch_1):page62_i172:ddr5_dq(12)"
				( attribute "PN" "DC74"
					( Origin gPackager )
				)
				( objectStatus "U2D1.DC74" )
			)
			( pin "@baseboard_fab2_lib.baseboard_fab2(sch_1):page62_i172:ddr5_dq(13)"
				( attribute "PN" "DB75"
					( Origin gPackager )
				)
				( objectStatus "U2D1.DB75" )
			)
			( pin "@baseboard_fab2_lib.baseboard_fab2(sch_1):page62_i172:ddr5_dq(14)"
				( attribute "PN" "DF77"
					( Origin gPackager )
				)
				( objectStatus "U2D1.DF77" )
			)
			( pin "@baseboard_fab2_lib.baseboard_fab2(sch_1):page62_i172:ddr5_dq(15)"
				( attribute "PN" "DH77"
					( Origin gPackager )
				)
				( objectStatus "U2D1.DH77" )
			)
			( pin "@baseboard_fab2_lib.baseboard_fab2(sch_1):page62_i172:ddr5_dq(16)"
				( attribute "PN" "DG70"
					( Origin gPackager )
				)
				( objectStatus "U2D1.DG70" )
			)
			( pin "@baseboard_fab2_lib.baseboard_fab2(sch_1):page62_i172:ddr5_dq(17)"
				( attribute "PN" "DJ72"
					( Origin gPackager )
				)
				( objectStatus "U2D1.DJ72" )
			)
			( pin "@baseboard_fab2_lib.baseboard_fab2(sch_1):page62_i172:ddr5_dq(18)"
				( attribute "PN" "DM69"
					( Origin gPackager )
				)
				( objectStatus "U2D1.DM69" )
			)
			( pin "@baseboard_fab2_lib.baseboard_fab2(sch_1):page62_i172:ddr5_dq(19)"
				( attribute "PN" "DN70"
					( Origin gPackager )
				)
				( objectStatus "U2D1.DN70" )
			)
			( pin "@baseboard_fab2_lib.baseboard_fab2(sch_1):page62_i172:ddr5_dq(20)"
				( attribute "PN" "DF71"
					( Origin gPackager )
				)
				( objectStatus "U2D1.DF71" )
			)
			( pin "@baseboard_fab2_lib.baseboard_fab2(sch_1):page62_i172:ddr5_dq(21)"
				( attribute "PN" "DG72"
					( Origin gPackager )
				)
				( objectStatus "U2D1.DG72" )
			)
			( pin "@baseboard_fab2_lib.baseboard_fab2(sch_1):page62_i172:ddr5_dq(22)"
				( attribute "PN" "DK69"
					( Origin gPackager )
				)
				( objectStatus "U2D1.DK69" )
			)
			( pin "@baseboard_fab2_lib.baseboard_fab2(sch_1):page62_i172:ddr5_dq(23)"
				( attribute "PN" "DM71"
					( Origin gPackager )
				)
				( objectStatus "U2D1.DM71" )
			)
			( pin "@baseboard_fab2_lib.baseboard_fab2(sch_1):page62_i172:ddr5_dq(24)"
				( attribute "PN" "CN66"
					( Origin gPackager )
				)
				( objectStatus "U2D1.CN66" )
			)
			( pin "@baseboard_fab2_lib.baseboard_fab2(sch_1):page62_i172:ddr5_dq(25)"
				( attribute "PN" "CU66"
					( Origin gPackager )
				)
				( objectStatus "U2D1.CU66" )
			)
			( pin "@baseboard_fab2_lib.baseboard_fab2(sch_1):page62_i172:ddr5_dq(26)"
				( attribute "PN" "CP63"
					( Origin gPackager )
				)
				( objectStatus "U2D1.CP63" )
			)
			( pin "@baseboard_fab2_lib.baseboard_fab2(sch_1):page62_i172:ddr5_dq(27)"
				( attribute "PN" "CT63"
					( Origin gPackager )
				)
				( objectStatus "U2D1.CT63" )
			)
			( pin "@baseboard_fab2_lib.baseboard_fab2(sch_1):page62_i172:ddr5_dq(28)"
				( attribute "PN" "CP67"
					( Origin gPackager )
				)
				( objectStatus "U2D1.CP67" )
			)
			( pin "@baseboard_fab2_lib.baseboard_fab2(sch_1):page62_i172:ddr5_dq(29)"
				( attribute "PN" "CT67"
					( Origin gPackager )
				)
				( objectStatus "U2D1.CT67" )
			)
			( pin "@baseboard_fab2_lib.baseboard_fab2(sch_1):page62_i172:ddr5_dq(30)"
				( attribute "PN" "CN64"
					( Origin gPackager )
				)
				( objectStatus "U2D1.CN64" )
			)
			( pin "@baseboard_fab2_lib.baseboard_fab2(sch_1):page62_i172:ddr5_dq(31)"
				( attribute "PN" "CU64"
					( Origin gPackager )
				)
				( objectStatus "U2D1.CU64" )
			)
			( pin "@baseboard_fab2_lib.baseboard_fab2(sch_1):page62_i172:ddr5_dq(32)"
				( attribute "PN" "DD41"
					( Origin gPackager )
				)
				( objectStatus "U2D1.DD41" )
			)
			( pin "@baseboard_fab2_lib.baseboard_fab2(sch_1):page62_i172:ddr5_dq(33)"
				( attribute "PN" "DG42"
					( Origin gPackager )
				)
				( objectStatus "U2D1.DG42" )
			)
			( pin "@baseboard_fab2_lib.baseboard_fab2(sch_1):page62_i172:ddr5_dq(34)"
				( attribute "PN" "DE38"
					( Origin gPackager )
				)
				( objectStatus "U2D1.DE38" )
			)
			( pin "@baseboard_fab2_lib.baseboard_fab2(sch_1):page62_i172:ddr5_dq(35)"
				( attribute "PN" "DG38"
					( Origin gPackager )
				)
				( objectStatus "U2D1.DG38" )
			)
			( pin "@baseboard_fab2_lib.baseboard_fab2(sch_1):page62_i172:ddr5_dq(36)"
				( attribute "PN" "DA42"
					( Origin gPackager )
				)
				( objectStatus "U2D1.DA42" )
			)
			( pin "@baseboard_fab2_lib.baseboard_fab2(sch_1):page62_i172:ddr5_dq(37)"
				( attribute "PN" "DE42"
					( Origin gPackager )
				)
				( objectStatus "U2D1.DE42" )
			)
			( pin "@baseboard_fab2_lib.baseboard_fab2(sch_1):page62_i172:ddr5_dq(38)"
				( attribute "PN" "DD39"
					( Origin gPackager )
				)
				( objectStatus "U2D1.DD39" )
			)
			( pin "@baseboard_fab2_lib.baseboard_fab2(sch_1):page62_i172:ddr5_dq(39)"
				( attribute "PN" "DH39"
					( Origin gPackager )
				)
				( objectStatus "U2D1.DH39" )
			)
			( pin "@baseboard_fab2_lib.baseboard_fab2(sch_1):page62_i172:ddr5_dq(40)"
				( attribute "PN" "DF33"
					( Origin gPackager )
				)
				( objectStatus "U2D1.DF33" )
			)
			( pin "@baseboard_fab2_lib.baseboard_fab2(sch_1):page62_i172:ddr5_dq(41)"
				( attribute "PN" "DK33"
					( Origin gPackager )
				)
				( objectStatus "U2D1.DK33" )
			)
			( pin "@baseboard_fab2_lib.baseboard_fab2(sch_1):page62_i172:ddr5_dq(42)"
				( attribute "PN" "DG30"
					( Origin gPackager )
				)
				( objectStatus "U2D1.DG30" )
			)
			( pin "@baseboard_fab2_lib.baseboard_fab2(sch_1):page62_i172:ddr5_dq(43)"
				( attribute "PN" "DJ30"
					( Origin gPackager )
				)
				( objectStatus "U2D1.DJ30" )
			)
			( pin "@baseboard_fab2_lib.baseboard_fab2(sch_1):page62_i172:ddr5_dq(44)"
				( attribute "PN" "DG34"
					( Origin gPackager )
				)
				( objectStatus "U2D1.DG34" )
			)
			( pin "@baseboard_fab2_lib.baseboard_fab2(sch_1):page62_i172:ddr5_dq(45)"
				( attribute "PN" "DJ34"
					( Origin gPackager )
				)
				( objectStatus "U2D1.DJ34" )
			)
			( pin "@baseboard_fab2_lib.baseboard_fab2(sch_1):page62_i172:ddr5_dq(46)"
				( attribute "PN" "DF31"
					( Origin gPackager )
				)
				( objectStatus "U2D1.DF31" )
			)
			( pin "@baseboard_fab2_lib.baseboard_fab2(sch_1):page62_i172:ddr5_dq(47)"
				( attribute "PN" "DK31"
					( Origin gPackager )
				)
				( objectStatus "U2D1.DK31" )
			)
			( pin "@baseboard_fab2_lib.baseboard_fab2(sch_1):page62_i172:ddr5_dq(48)"
				( attribute "PN" "CW36"
					( Origin gPackager )
				)
				( objectStatus "U2D1.CW36" )
			)
			( pin "@baseboard_fab2_lib.baseboard_fab2(sch_1):page62_i172:ddr5_dq(49)"
				( attribute "PN" "DC36"
					( Origin gPackager )
				)
				( objectStatus "U2D1.DC36" )
			)
			( pin "@baseboard_fab2_lib.baseboard_fab2(sch_1):page62_i172:ddr5_dq(50)"
				( attribute "PN" "CY33"
					( Origin gPackager )
				)
				( objectStatus "U2D1.CY33" )
			)
			( pin "@baseboard_fab2_lib.baseboard_fab2(sch_1):page62_i172:ddr5_dq(51)"
				( attribute "PN" "DB33"
					( Origin gPackager )
				)
				( objectStatus "U2D1.DB33" )
			)
			( pin "@baseboard_fab2_lib.baseboard_fab2(sch_1):page62_i172:ddr5_dq(52)"
				( attribute "PN" "CY37"
					( Origin gPackager )
				)
				( objectStatus "U2D1.CY37" )
			)
			( pin "@baseboard_fab2_lib.baseboard_fab2(sch_1):page62_i172:ddr5_dq(53)"
				( attribute "PN" "DB37"
					( Origin gPackager )
				)
				( objectStatus "U2D1.DB37" )
			)
			( pin "@baseboard_fab2_lib.baseboard_fab2(sch_1):page62_i172:ddr5_dq(54)"
				( attribute "PN" "CW34"
					( Origin gPackager )
				)
				( objectStatus "U2D1.CW34" )
			)
			( pin "@baseboard_fab2_lib.baseboard_fab2(sch_1):page62_i172:ddr5_dq(55)"
				( attribute "PN" "DC34"
					( Origin gPackager )
				)
				( objectStatus "U2D1.DC34" )
			)
			( pin "@baseboard_fab2_lib.baseboard_fab2(sch_1):page62_i172:ddr5_dq(56)"
				( attribute "PN" "CW30"
					( Origin gPackager )
				)
				( objectStatus "U2D1.CW30" )
			)
			( pin "@baseboard_fab2_lib.baseboard_fab2(sch_1):page62_i172:ddr5_dq(57)"
				( attribute "PN" "DC30"
					( Origin gPackager )
				)
				( objectStatus "U2D1.DC30" )
			)
			( pin "@baseboard_fab2_lib.baseboard_fab2(sch_1):page62_i172:ddr5_dq(58)"
				( attribute "PN" "CY27"
					( Origin gPackager )
				)
				( objectStatus "U2D1.CY27" )
			)
			( pin "@baseboard_fab2_lib.baseboard_fab2(sch_1):page62_i172:ddr5_dq(59)"
				( attribute "PN" "DB27"
					( Origin gPackager )
				)
				( objectStatus "U2D1.DB27" )
			)
			( pin "@baseboard_fab2_lib.baseboard_fab2(sch_1):page62_i172:ddr5_dq(60)"
				( attribute "PN" "CY31"
					( Origin gPackager )
				)
				( objectStatus "U2D1.CY31" )
			)
			( pin "@baseboard_fab2_lib.baseboard_fab2(sch_1):page62_i172:ddr5_dq(61)"
				( attribute "PN" "DB31"
					( Origin gPackager )
				)
				( objectStatus "U2D1.DB31" )
			)
			( pin "@baseboard_fab2_lib.baseboard_fab2(sch_1):page62_i172:ddr5_dq(62)"
				( attribute "PN" "CW28"
					( Origin gPackager )
				)
				( objectStatus "U2D1.CW28" )
			)
			( pin "@baseboard_fab2_lib.baseboard_fab2(sch_1):page62_i172:ddr5_dq(63)"
				( attribute "PN" "DC28"
					( Origin gPackager )
				)
				( objectStatus "U2D1.DC28" )
			)
			( pin "@baseboard_fab2_lib.baseboard_fab2(sch_1):page62_i172:ddr5_dqs_dn(0)"
				( attribute "PN" "CP77"
					( Origin gPackager )
				)
				( objectStatus "U2D1.CP77" )
			)
			( pin "@baseboard_fab2_lib.baseboard_fab2(sch_1):page62_i172:ddr5_dqs_dn(1)"
				( attribute "PN" "DD77"
					( Origin gPackager )
				)
				( objectStatus "U2D1.DD77" )
			)
			( pin "@baseboard_fab2_lib.baseboard_fab2(sch_1):page62_i172:ddr5_dqs_dn(2)"
				( attribute "PN" "DL72"
					( Origin gPackager )
				)
				( objectStatus "U2D1.DL72" )
			)
			( pin "@baseboard_fab2_lib.baseboard_fab2(sch_1):page62_i172:ddr5_dqs_dn(3)"
				( attribute "PN" "CV65"
					( Origin gPackager )
				)
				( objectStatus "U2D1.CV65" )
			)
			( pin "@baseboard_fab2_lib.baseboard_fab2(sch_1):page62_i172:ddr5_dqs_dn(4)"
				( attribute "PN" "DG40"
					( Origin gPackager )
				)
				( objectStatus "U2D1.DG40" )
			)
			( pin "@baseboard_fab2_lib.baseboard_fab2(sch_1):page62_i172:ddr5_dqs_dn(5)"
				( attribute "PN" "DL32"
					( Origin gPackager )
				)
				( objectStatus "U2D1.DL32" )
			)
			( pin "@baseboard_fab2_lib.baseboard_fab2(sch_1):page62_i172:ddr5_dqs_dn(6)"
				( attribute "PN" "DD35"
					( Origin gPackager )
				)
				( objectStatus "U2D1.DD35" )
			)
			( pin "@baseboard_fab2_lib.baseboard_fab2(sch_1):page62_i172:ddr5_dqs_dn(7)"
				( attribute "PN" "DD29"
					( Origin gPackager )
				)
				( objectStatus "U2D1.DD29" )
			)
			( pin "@baseboard_fab2_lib.baseboard_fab2(sch_1):page62_i172:ddr5_dqs_dn(8)"
				( attribute "PN" "CN70"
					( Origin gPackager )
				)
				( objectStatus "U2D1.CN70" )
			)
			( pin "@baseboard_fab2_lib.baseboard_fab2(sch_1):page62_i172:ddr5_dqs_dn(9)"
				( attribute "PN" "CT75"
					( Origin gPackager )
				)
				( objectStatus "U2D1.CT75" )
			)
			( pin "@baseboard_fab2_lib.baseboard_fab2(sch_1):page62_i172:ddr5_dqs_dn(10)"
				( attribute "PN" "DF75"
					( Origin gPackager )
				)
				( objectStatus "U2D1.DF75" )
			)
			( pin "@baseboard_fab2_lib.baseboard_fab2(sch_1):page62_i172:ddr5_dqs_dn(11)"
				( attribute "PN" "DJ70"
					( Origin gPackager )
				)
				( objectStatus "U2D1.DJ70" )
			)
			( pin "@baseboard_fab2_lib.baseboard_fab2(sch_1):page62_i172:ddr5_dqs_dn(12)"
				( attribute "PN" "CP65"
					( Origin gPackager )
				)
				( objectStatus "U2D1.CP65" )
			)
			( pin "@baseboard_fab2_lib.baseboard_fab2(sch_1):page62_i172:ddr5_dqs_dn(13)"
				( attribute "PN" "DE40"
					( Origin gPackager )
				)
				( objectStatus "U2D1.DE40" )
			)
			( pin "@baseboard_fab2_lib.baseboard_fab2(sch_1):page62_i172:ddr5_dqs_dn(14)"
				( attribute "PN" "DG32"
					( Origin gPackager )
				)
				( objectStatus "U2D1.DG32" )
			)
			( pin "@baseboard_fab2_lib.baseboard_fab2(sch_1):page62_i172:ddr5_dqs_dn(15)"
				( attribute "PN" "CY35"
					( Origin gPackager )
				)
				( objectStatus "U2D1.CY35" )
			)
			( pin "@baseboard_fab2_lib.baseboard_fab2(sch_1):page62_i172:ddr5_dqs_dn(16)"
				( attribute "PN" "CY29"
					( Origin gPackager )
				)
				( objectStatus "U2D1.CY29" )
			)
			( pin "@baseboard_fab2_lib.baseboard_fab2(sch_1):page62_i172:ddr5_dqs_dn(17)"
				( attribute "PN" "CJ70"
					( Origin gPackager )
				)
				( objectStatus "U2D1.CJ70" )
			)
			( pin "@baseboard_fab2_lib.baseboard_fab2(sch_1):page62_i172:ddr5_dqs_dp(0)"
				( attribute "PN" "CR76"
					( Origin gPackager )
				)
				( objectStatus "U2D1.CR76" )
			)
			( pin "@baseboard_fab2_lib.baseboard_fab2(sch_1):page62_i172:ddr5_dqs_dp(1)"
				( attribute "PN" "DE76"
					( Origin gPackager )
				)
				( objectStatus "U2D1.DE76" )
			)
			( pin "@baseboard_fab2_lib.baseboard_fab2(sch_1):page62_i172:ddr5_dqs_dp(2)"
				( attribute "PN" "DK71"
					( Origin gPackager )
				)
				( objectStatus "U2D1.DK71" )
			)
			( pin "@baseboard_fab2_lib.baseboard_fab2(sch_1):page62_i172:ddr5_dqs_dp(3)"
				( attribute "PN" "CT65"
					( Origin gPackager )
				)
				( objectStatus "U2D1.CT65" )
			)
			( pin "@baseboard_fab2_lib.baseboard_fab2(sch_1):page62_i172:ddr5_dqs_dp(4)"
				( attribute "PN" "DJ40"
					( Origin gPackager )
				)
				( objectStatus "U2D1.DJ40" )
			)
			( pin "@baseboard_fab2_lib.baseboard_fab2(sch_1):page62_i172:ddr5_dqs_dp(5)"
				( attribute "PN" "DJ32"
					( Origin gPackager )
				)
				( objectStatus "U2D1.DJ32" )
			)
			( pin "@baseboard_fab2_lib.baseboard_fab2(sch_1):page62_i172:ddr5_dqs_dp(6)"
				( attribute "PN" "DB35"
					( Origin gPackager )
				)
				( objectStatus "U2D1.DB35" )
			)
			( pin "@baseboard_fab2_lib.baseboard_fab2(sch_1):page62_i172:ddr5_dqs_dp(7)"
				( attribute "PN" "DB29"
					( Origin gPackager )
				)
				( objectStatus "U2D1.DB29" )
			)
			( pin "@baseboard_fab2_lib.baseboard_fab2(sch_1):page62_i172:ddr5_dqs_dp(8)"
				( attribute "PN" "CL70"
					( Origin gPackager )
				)
				( objectStatus "U2D1.CL70" )
			)
			( pin "@baseboard_fab2_lib.baseboard_fab2(sch_1):page62_i172:ddr5_dqs_dp(9)"
				( attribute "PN" "CU74"
					( Origin gPackager )
				)
				( objectStatus "U2D1.CU74" )
			)
			( pin "@baseboard_fab2_lib.baseboard_fab2(sch_1):page62_i172:ddr5_dqs_dp(10)"
				( attribute "PN" "DG74"
					( Origin gPackager )
				)
				( objectStatus "U2D1.DG74" )
			)
			( pin "@baseboard_fab2_lib.baseboard_fab2(sch_1):page62_i172:ddr5_dqs_dp(11)"
				( attribute "PN" "DH69"
					( Origin gPackager )
				)
				( objectStatus "U2D1.DH69" )
			)
			( pin "@baseboard_fab2_lib.baseboard_fab2(sch_1):page62_i172:ddr5_dqs_dp(12)"
				( attribute "PN" "CM65"
					( Origin gPackager )
				)
				( objectStatus "U2D1.CM65" )
			)
			( pin "@baseboard_fab2_lib.baseboard_fab2(sch_1):page62_i172:ddr5_dqs_dp(13)"
				( attribute "PN" "DC40"
					( Origin gPackager )
				)
				( objectStatus "U2D1.DC40" )
			)
			( pin "@baseboard_fab2_lib.baseboard_fab2(sch_1):page62_i172:ddr5_dqs_dp(14)"
				( attribute "PN" "DE32"
					( Origin gPackager )
				)
				( objectStatus "U2D1.DE32" )
			)
			( pin "@baseboard_fab2_lib.baseboard_fab2(sch_1):page62_i172:ddr5_dqs_dp(15)"
				( attribute "PN" "CV35"
					( Origin gPackager )
				)
				( objectStatus "U2D1.CV35" )
			)
			( pin "@baseboard_fab2_lib.baseboard_fab2(sch_1):page62_i172:ddr5_dqs_dp(16)"
				( attribute "PN" "CV29"
					( Origin gPackager )
				)
				( objectStatus "U2D1.CV29" )
			)
			( pin "@baseboard_fab2_lib.baseboard_fab2(sch_1):page62_i172:ddr5_dqs_dp(17)"
				( attribute "PN" "CG70"
					( Origin gPackager )
				)
				( objectStatus "U2D1.CG70" )
			)
			( pin "@baseboard_fab2_lib.baseboard_fab2(sch_1):page62_i172:ddr5_ecc(0)"
				( attribute "PN" "CH71"
					( Origin gPackager )
				)
				( objectStatus "U2D1.CH71" )
			)
			( pin "@baseboard_fab2_lib.baseboard_fab2(sch_1):page62_i172:ddr5_ecc(1)"
				( attribute "PN" "CM71"
					( Origin gPackager )
				)
				( objectStatus "U2D1.CM71" )
			)
			( pin "@baseboard_fab2_lib.baseboard_fab2(sch_1):page62_i172:ddr5_ecc(2)"
				( attribute "PN" "CJ68"
					( Origin gPackager )
				)
				( objectStatus "U2D1.CJ68" )
			)
			( pin "@baseboard_fab2_lib.baseboard_fab2(sch_1):page62_i172:ddr5_ecc(3)"
				( attribute "PN" "CL68"
					( Origin gPackager )
				)
				( objectStatus "U2D1.CL68" )
			)
			( pin "@baseboard_fab2_lib.baseboard_fab2(sch_1):page62_i172:ddr5_ecc(4)"
				( attribute "PN" "CJ72"
					( Origin gPackager )
				)
				( objectStatus "U2D1.CJ72" )
			)
			( pin "@baseboard_fab2_lib.baseboard_fab2(sch_1):page62_i172:ddr5_ecc(5)"
				( attribute "PN" "CL72"
					( Origin gPackager )
				)
				( objectStatus "U2D1.CL72" )
			)
			( pin "@baseboard_fab2_lib.baseboard_fab2(sch_1):page62_i172:ddr5_ecc(6)"
				( attribute "PN" "CH69"
					( Origin gPackager )
				)
				( objectStatus "U2D1.CH69" )
			)
			( pin "@baseboard_fab2_lib.baseboard_fab2(sch_1):page62_i172:ddr5_ecc(7)"
				( attribute "PN" "CM69"
					( Origin gPackager )
				)
				( objectStatus "U2D1.CM69" )
			)
			( pin "@baseboard_fab2_lib.baseboard_fab2(sch_1):page62_i172:ddr5_ma(0)"
				( attribute "PN" "DF53"
					( Origin gPackager )
				)
				( objectStatus "U2D1.DF53" )
			)
			( pin "@baseboard_fab2_lib.baseboard_fab2(sch_1):page62_i172:ddr5_ma(1)"
				( attribute "PN" "DC58"
					( Origin gPackager )
				)
				( objectStatus "U2D1.DC58" )
			)
			( pin "@baseboard_fab2_lib.baseboard_fab2(sch_1):page62_i172:ddr5_ma(2)"
				( attribute "PN" "DD57"
					( Origin gPackager )
				)
				( objectStatus "U2D1.DD57" )
			)
			( pin "@baseboard_fab2_lib.baseboard_fab2(sch_1):page62_i172:ddr5_ma(3)"
				( attribute "PN" "DG58"
					( Origin gPackager )
				)
				( objectStatus "U2D1.DG58" )
			)
			( pin "@baseboard_fab2_lib.baseboard_fab2(sch_1):page62_i172:ddr5_ma(4)"
				( attribute "PN" "DJ58"
					( Origin gPackager )
				)
				( objectStatus "U2D1.DJ58" )
			)
			( pin "@baseboard_fab2_lib.baseboard_fab2(sch_1):page62_i172:ddr5_ma(5)"
				( attribute "PN" "DF59"
					( Origin gPackager )
				)
				( objectStatus "U2D1.DF59" )
			)
			( pin "@baseboard_fab2_lib.baseboard_fab2(sch_1):page62_i172:ddr5_ma(6)"
				( attribute "PN" "DK59"
					( Origin gPackager )
				)
				( objectStatus "U2D1.DK59" )
			)
			( pin "@baseboard_fab2_lib.baseboard_fab2(sch_1):page62_i172:ddr5_ma(7)"
				( attribute "PN" "DC60"
					( Origin gPackager )
				)
				( objectStatus "U2D1.DC60" )
			)
			( pin "@baseboard_fab2_lib.baseboard_fab2(sch_1):page62_i172:ddr5_ma(8)"
				( attribute "PN" "DD59"
					( Origin gPackager )
				)
				( objectStatus "U2D1.DD59" )
			)
			( pin "@baseboard_fab2_lib.baseboard_fab2(sch_1):page62_i172:ddr5_ma(9)"
				( attribute "PN" "DA58"
					( Origin gPackager )
				)
				( objectStatus "U2D1.DA58" )
			)
			( pin "@baseboard_fab2_lib.baseboard_fab2(sch_1):page62_i172:ddr5_ma(10)"
				( attribute "PN" "DD55"
					( Origin gPackager )
				)
				( objectStatus "U2D1.DD55" )
			)
			( pin "@baseboard_fab2_lib.baseboard_fab2(sch_1):page62_i172:ddr5_ma(11)"
				( attribute "PN" "DA60"
					( Origin gPackager )
				)
				( objectStatus "U2D1.DA60" )
			)
			( pin "@baseboard_fab2_lib.baseboard_fab2(sch_1):page62_i172:ddr5_ma(12)"
				( attribute "PN" "DG60"
					( Origin gPackager )
				)
				( objectStatus "U2D1.DG60" )
			)
			( pin "@baseboard_fab2_lib.baseboard_fab2(sch_1):page62_i172:ddr5_ma(13)"
				( attribute "PN" "DD53"
					( Origin gPackager )
				)
				( objectStatus "U2D1.DD53" )
			)
			( pin "@baseboard_fab2_lib.baseboard_fab2(sch_1):page62_i172:ddr5_ma(14)"
				( attribute "PN" "DJ50"
					( Origin gPackager )
				)
				( objectStatus "U2D1.DJ50" )
			)
			( pin "@baseboard_fab2_lib.baseboard_fab2(sch_1):page62_i172:ddr5_ma(15)"
				( attribute "PN" "DC54"
					( Origin gPackager )
				)
				( objectStatus "U2D1.DC54" )
			)
			( pin "@baseboard_fab2_lib.baseboard_fab2(sch_1):page62_i172:ddr5_ma(16)"
				( attribute "PN" "DG52"
					( Origin gPackager )
				)
				( objectStatus "U2D1.DG52" )
			)
			( pin "@baseboard_fab2_lib.baseboard_fab2(sch_1):page62_i172:ddr5_ma(17)"
				( attribute "PN" "DE46"
					( Origin gPackager )
				)
				( objectStatus "U2D1.DE46" )
			)
			( pin "@baseboard_fab2_lib.baseboard_fab2(sch_1):page62_i172:ddr5_odt(0)"
				( attribute "PN" "DG50"
					( Origin gPackager )
				)
				( objectStatus "U2D1.DG50" )
			)
			( pin "@baseboard_fab2_lib.baseboard_fab2(sch_1):page62_i172:ddr5_odt(1)"
				( attribute "PN" "DG48"
					( Origin gPackager )
				)
				( objectStatus "U2D1.DG48" )
			)
			( pin "@baseboard_fab2_lib.baseboard_fab2(sch_1):page62_i172:ddr5_odt(2)"
				( attribute "PN" "DK49"
					( Origin gPackager )
				)
				( objectStatus "U2D1.DK49" )
			)
			( pin "@baseboard_fab2_lib.baseboard_fab2(sch_1):page62_i172:ddr5_odt(3)"
				( attribute "PN" "DF47"
					( Origin gPackager )
				)
				( objectStatus "U2D1.DF47" )
			)
			( pin "@baseboard_fab2_lib.baseboard_fab2(sch_1):page62_i172:ddr5_par"
				( attribute "PN" "DK53"
					( Origin gPackager )
				)
				( objectStatus "U2D1.DK53" )
			)
			( pin "@baseboard_fab2_lib.baseboard_fab2(sch_1):page63_i23:cd_hfi0_i2cclk"
				( attribute "PN" "BN22"
					( Origin gPackager )
				)
				( objectStatus "U2D1.BN22" )
			)
			( pin "@baseboard_fab2_lib.baseboard_fab2(sch_1):page63_i23:cd_hfi0_i2cdat"
				( attribute "PN" "BP23"
					( Origin gPackager )
				)
				( objectStatus "U2D1.BP23" )
			)
			( pin "@baseboard_fab2_lib.baseboard_fab2(sch_1):page63_i23:cd_hfi0_int_n"
				( attribute "PN" "BP19"
					( Origin gPackager )
				)
				( objectStatus "U2D1.BP19" )
			)
			( pin "@baseboard_fab2_lib.baseboard_fab2(sch_1):page63_i23:cd_hfi0_led_n"
				( attribute "PN" "BK21"
					( Origin gPackager )
				)
				( objectStatus "U2D1.BK21" )
			)
			( pin "@baseboard_fab2_lib.baseboard_fab2(sch_1):page63_i23:cd_hfi0_modprst_n"
				( attribute "PN" "BR20"
					( Origin gPackager )
				)
				( objectStatus "U2D1.BR20" )
			)
			( pin "@baseboard_fab2_lib.baseboard_fab2(sch_1):page63_i23:cd_hfi0_reset_n"
				( attribute "PN" "BN24"
					( Origin gPackager )
				)
				( objectStatus "U2D1.BN24" )
			)
			( pin "@baseboard_fab2_lib.baseboard_fab2(sch_1):page63_i23:cd_hfi1_i2cclk"
				( attribute "PN" "BJ22"
					( Origin gPackager )
				)
				( objectStatus "U2D1.BJ22" )
			)
			( pin "@baseboard_fab2_lib.baseboard_fab2(sch_1):page63_i23:cd_hfi1_i2cdat"
				( attribute "PN" "BH23"
					( Origin gPackager )
				)
				( objectStatus "U2D1.BH23" )
			)
			( pin "@baseboard_fab2_lib.baseboard_fab2(sch_1):page63_i23:cd_hfi1_int_n"
				( attribute "PN" "BM21"
					( Origin gPackager )
				)
				( objectStatus "U2D1.BM21" )
			)
			( pin "@baseboard_fab2_lib.baseboard_fab2(sch_1):page63_i23:cd_hfi1_led_n"
				( attribute "PN" "BM23"
					( Origin gPackager )
				)
				( objectStatus "U2D1.BM23" )
			)
			( pin "@baseboard_fab2_lib.baseboard_fab2(sch_1):page63_i23:cd_hfi1_modprst_n"
				( attribute "PN" "BT19"
					( Origin gPackager )
				)
				( objectStatus "U2D1.BT19" )
			)
			( pin "@baseboard_fab2_lib.baseboard_fab2(sch_1):page63_i23:cd_hfi1_reset_n"
				( attribute "PN" "BK23"
					( Origin gPackager )
				)
				( objectStatus "U2D1.BK23" )
			)
			( pin "@baseboard_fab2_lib.baseboard_fab2(sch_1):page63_i23:cd_hfi_refclk_dn"
				( attribute "PN" "BE16"
					( Origin gPackager )
				)
				( objectStatus "U2D1.BE16" )
			)
			( pin "@baseboard_fab2_lib.baseboard_fab2(sch_1):page63_i23:cd_hfi_refclk_dp"
				( attribute "PN" "BG16"
					( Origin gPackager )
				)
				( objectStatus "U2D1.BG16" )
			)
			( pin "@baseboard_fab2_lib.baseboard_fab2(sch_1):page63_i23:cd_pe_refclk_dn"
				( attribute "PN" "BU24"
					( Origin gPackager )
				)
				( objectStatus "U2D1.BU24" )
			)
			( pin "@baseboard_fab2_lib.baseboard_fab2(sch_1):page63_i23:cd_pe_refclk_dp"
				( attribute "PN" "BW24"
					( Origin gPackager )
				)
				( objectStatus "U2D1.BW24" )
			)
			( pin "@baseboard_fab2_lib.baseboard_fab2(sch_1):page63_i23:cd_por_n"
				( attribute "PN" "CF25"
					( Origin gPackager )
				)
				( objectStatus "U2D1.CF25" )
			)
			( pin "@baseboard_fab2_lib.baseboard_fab2(sch_1):page63_i23:cd_tclk"
				( attribute "PN" "CB23"
					( Origin gPackager )
				)
				( objectStatus "U2D1.CB23" )
			)
			( pin "@baseboard_fab2_lib.baseboard_fab2(sch_1):page63_i23:cd_tdi"
				( attribute "PN" "BY21"
					( Origin gPackager )
				)
				( objectStatus "U2D1.BY21" )
			)
			( pin "@baseboard_fab2_lib.baseboard_fab2(sch_1):page63_i23:cd_tdo"
				( attribute "PN" "CC22"
					( Origin gPackager )
				)
				( objectStatus "U2D1.CC22" )
			)
			( pin "@baseboard_fab2_lib.baseboard_fab2(sch_1):page63_i23:cd_tms"
				( attribute "PN" "CE24"
					( Origin gPackager )
				)
				( objectStatus "U2D1.CE24" )
			)
			( pin "@baseboard_fab2_lib.baseboard_fab2(sch_1):page63_i23:cd_trst_n"
				( attribute "PN" "CD23"
					( Origin gPackager )
				)
				( objectStatus "U2D1.CD23" )
			)
			( pin "@baseboard_fab2_lib.baseboard_fab2(sch_1):page63_i23:dmi_rx_dn(0)"
				( attribute "PN" "CK9"
					( Origin gPackager )
				)
				( objectStatus "U2D1.CK9" )
			)
			( pin "@baseboard_fab2_lib.baseboard_fab2(sch_1):page63_i23:dmi_rx_dn(1)"
				( attribute "PN" "CM11"
					( Origin gPackager )
				)
				( objectStatus "U2D1.CM11" )
			)
			( pin "@baseboard_fab2_lib.baseboard_fab2(sch_1):page63_i23:dmi_rx_dn(2)"
				( attribute "PN" "CR12"
					( Origin gPackager )
				)
				( objectStatus "U2D1.CR12" )
			)
			( pin "@baseboard_fab2_lib.baseboard_fab2(sch_1):page63_i23:dmi_rx_dn(3)"
				( attribute "PN" "CT11"
					( Origin gPackager )
				)
				( objectStatus "U2D1.CT11" )
			)
			( pin "@baseboard_fab2_lib.baseboard_fab2(sch_1):page63_i23:dmi_rx_dp(0)"
				( attribute "PN" "CL10"
					( Origin gPackager )
				)
				( objectStatus "U2D1.CL10" )
			)
			( pin "@baseboard_fab2_lib.baseboard_fab2(sch_1):page63_i23:dmi_rx_dp(1)"
				( attribute "PN" "CN10"
					( Origin gPackager )
				)
				( objectStatus "U2D1.CN10" )
			)
			( pin "@baseboard_fab2_lib.baseboard_fab2(sch_1):page63_i23:dmi_rx_dp(2)"
				( attribute "PN" "CP11"
					( Origin gPackager )
				)
				( objectStatus "U2D1.CP11" )
			)
			( pin "@baseboard_fab2_lib.baseboard_fab2(sch_1):page63_i23:dmi_rx_dp(3)"
				( attribute "PN" "CV11"
					( Origin gPackager )
				)
				( objectStatus "U2D1.CV11" )
			)
			( pin "@baseboard_fab2_lib.baseboard_fab2(sch_1):page63_i23:dmi_tx_dn(0)"
				( attribute "PN" "CG4"
					( Origin gPackager )
				)
				( objectStatus "U2D1.CG4" )
			)
			( pin "@baseboard_fab2_lib.baseboard_fab2(sch_1):page63_i23:dmi_tx_dn(1)"
				( attribute "PN" "CJ4"
					( Origin gPackager )
				)
				( objectStatus "U2D1.CJ4" )
			)
			( pin "@baseboard_fab2_lib.baseboard_fab2(sch_1):page63_i23:dmi_tx_dn(2)"
				( attribute "PN" "CN4"
					( Origin gPackager )
				)
				( objectStatus "U2D1.CN4" )
			)
			( pin "@baseboard_fab2_lib.baseboard_fab2(sch_1):page63_i23:dmi_tx_dn(3)"
				( attribute "PN" "CP5"
					( Origin gPackager )
				)
				( objectStatus "U2D1.CP5" )
			)
			( pin "@baseboard_fab2_lib.baseboard_fab2(sch_1):page63_i23:dmi_tx_dp(0)"
				( attribute "PN" "CH5"
					( Origin gPackager )
				)
				( objectStatus "U2D1.CH5" )
			)
			( pin "@baseboard_fab2_lib.baseboard_fab2(sch_1):page63_i23:dmi_tx_dp(1)"
				( attribute "PN" "CL4"
					( Origin gPackager )
				)
				( objectStatus "U2D1.CL4" )
			)
			( pin "@baseboard_fab2_lib.baseboard_fab2(sch_1):page63_i23:dmi_tx_dp(2)"
				( attribute "PN" "CM3"
					( Origin gPackager )
				)
				( objectStatus "U2D1.CM3" )
			)
			( pin "@baseboard_fab2_lib.baseboard_fab2(sch_1):page63_i23:dmi_tx_dp(3)"
				( attribute "PN" "CR4"
					( Origin gPackager )
				)
				( objectStatus "U2D1.CR4" )
			)
			( pin "@baseboard_fab2_lib.baseboard_fab2(sch_1):page63_i23:rsvd(172)"
				( attribute "PN" "BA76"
					( Origin gPackager )
				)
				( objectStatus "U2D1.BA76" )
			)
			( pin "@baseboard_fab2_lib.baseboard_fab2(sch_1):page63_i23:rsvd(173)"
				( attribute "PN" "BA66"
					( Origin gPackager )
				)
				( objectStatus "U2D1.BA66" )
			)
			( pin "@baseboard_fab2_lib.baseboard_fab2(sch_1):page63_i23:rsvd(174)"
				( attribute "PN" "BA64"
					( Origin gPackager )
				)
				( objectStatus "U2D1.BA64" )
			)
			( pin "@baseboard_fab2_lib.baseboard_fab2(sch_1):page63_i23:rsvd(175)"
				( attribute "PN" "BA22"
					( Origin gPackager )
				)
				( objectStatus "U2D1.BA22" )
			)
			( pin "@baseboard_fab2_lib.baseboard_fab2(sch_1):page63_i23:rsvd(176)"
				( attribute "PN" "BA18"
					( Origin gPackager )
				)
				( objectStatus "U2D1.BA18" )
			)
			( pin "@baseboard_fab2_lib.baseboard_fab2(sch_1):page63_i23:rsvd(177)"
				( attribute "PN" "BA16"
					( Origin gPackager )
				)
				( objectStatus "U2D1.BA16" )
			)
			( pin "@baseboard_fab2_lib.baseboard_fab2(sch_1):page63_i23:rsvd(178)"
				( attribute "PN" "BA14"
					( Origin gPackager )
				)
				( objectStatus "U2D1.BA14" )
			)
			( pin "@baseboard_fab2_lib.baseboard_fab2(sch_1):page63_i23:rsvd(179)"
				( attribute "PN" "AY77"
					( Origin gPackager )
				)
				( objectStatus "U2D1.AY77" )
			)
			( pin "@baseboard_fab2_lib.baseboard_fab2(sch_1):page63_i23:rsvd(180)"
				( attribute "PN" "AY75"
					( Origin gPackager )
				)
				( objectStatus "U2D1.AY75" )
			)
			( pin "@baseboard_fab2_lib.baseboard_fab2(sch_1):page63_i23:rsvd(181)"
				( attribute "PN" "AY67"
					( Origin gPackager )
				)
				( objectStatus "U2D1.AY67" )
			)
			( pin "@baseboard_fab2_lib.baseboard_fab2(sch_1):page63_i23:rsvd(182)"
				( attribute "PN" "AY65"
					( Origin gPackager )
				)
				( objectStatus "U2D1.AY65" )
			)
			( pin "@baseboard_fab2_lib.baseboard_fab2(sch_1):page63_i23:rsvd(183)"
				( attribute "PN" "AW76"
					( Origin gPackager )
				)
				( objectStatus "U2D1.AW76" )
			)
			( pin "@baseboard_fab2_lib.baseboard_fab2(sch_1):page63_i23:rsvd(184)"
				( attribute "PN" "AW64"
					( Origin gPackager )
				)
				( objectStatus "U2D1.AW64" )
			)
			( pin "@baseboard_fab2_lib.baseboard_fab2(sch_1):page63_i23:rsvd(185)"
				( attribute "CDS_NOT_ON_SYM" "TRUE"
					( Origin gFrontEnd )
				)
			)
			( pin "@baseboard_fab2_lib.baseboard_fab2(sch_1):page63_i23:rsvd(186)"
				( attribute "PN" "AV77"
					( Origin gPackager )
				)
				( objectStatus "U2D1.AV77" )
			)
			( pin "@baseboard_fab2_lib.baseboard_fab2(sch_1):page63_i23:rsvd(187)"
				( attribute "PN" "AT25"
					( Origin gPackager )
				)
				( objectStatus "U2D1.AT25" )
			)
			( pin "@baseboard_fab2_lib.baseboard_fab2(sch_1):page63_i23:rsvd(188)"
				( attribute "PN" "AT23"
					( Origin gPackager )
				)
				( objectStatus "U2D1.AT23" )
			)
			( pin "@baseboard_fab2_lib.baseboard_fab2(sch_1):page63_i23:rsvd(189)"
				( attribute "PN" "AT13"
					( Origin gPackager )
				)
				( objectStatus "U2D1.AT13" )
			)
			( pin "@baseboard_fab2_lib.baseboard_fab2(sch_1):page63_i23:rsvd(190)"
				( attribute "PN" "AR62"
					( Origin gPackager )
				)
				( objectStatus "U2D1.AR62" )
			)
			( pin "@baseboard_fab2_lib.baseboard_fab2(sch_1):page63_i23:rsvd(191)"
				( attribute "PN" "AR26"
					( Origin gPackager )
				)
				( objectStatus "U2D1.AR26" )
			)
			( pin "@baseboard_fab2_lib.baseboard_fab2(sch_1):page63_i23:rsvd(192)"
				( attribute "PN" "AR22"
					( Origin gPackager )
				)
				( objectStatus "U2D1.AR22" )
			)
			( pin "@baseboard_fab2_lib.baseboard_fab2(sch_1):page63_i23:rsvd(193)"
				( attribute "PN" "AR20"
					( Origin gPackager )
				)
				( objectStatus "U2D1.AR20" )
			)
			( pin "@baseboard_fab2_lib.baseboard_fab2(sch_1):page64_i68:pe1_rx_dn(0)"
				( attribute "PN" "CW8"
					( Origin gPackager )
				)
				( objectStatus "U2D1.CW8" )
			)
			( pin "@baseboard_fab2_lib.baseboard_fab2(sch_1):page64_i68:pe1_rx_dn(1)"
				( attribute "PN" "DA8"
					( Origin gPackager )
				)
				( objectStatus "U2D1.DA8" )
			)
			( pin "@baseboard_fab2_lib.baseboard_fab2(sch_1):page64_i68:pe1_rx_dn(2)"
				( attribute "PN" "DC8"
					( Origin gPackager )
				)
				( objectStatus "U2D1.DC8" )
			)
			( pin "@baseboard_fab2_lib.baseboard_fab2(sch_1):page64_i68:pe1_rx_dn(3)"
				( attribute "PN" "DC10"
					( Origin gPackager )
				)
				( objectStatus "U2D1.DC10" )
			)
			( pin "@baseboard_fab2_lib.baseboard_fab2(sch_1):page64_i68:pe1_rx_dn(4)"
				( attribute "PN" "DE10"
					( Origin gPackager )
				)
				( objectStatus "U2D1.DE10" )
			)
			( pin "@baseboard_fab2_lib.baseboard_fab2(sch_1):page64_i68:pe1_rx_dn(5)"
				( attribute "PN" "DH9"
					( Origin gPackager )
				)
				( objectStatus "U2D1.DH9" )
			)
			( pin "@baseboard_fab2_lib.baseboard_fab2(sch_1):page64_i68:pe1_rx_dn(6)"
				( attribute "PN" "DK9"
					( Origin gPackager )
				)
				( objectStatus "U2D1.DK9" )
			)
			( pin "@baseboard_fab2_lib.baseboard_fab2(sch_1):page64_i68:pe1_rx_dn(7)"
				( attribute "PN" "DM9"
					( Origin gPackager )
				)
				( objectStatus "U2D1.DM9" )
			)
			( pin "@baseboard_fab2_lib.baseboard_fab2(sch_1):page64_i68:pe1_rx_dn(8)"
				( attribute "PN" "DM11"
					( Origin gPackager )
				)
				( objectStatus "U2D1.DM11" )
			)
			( pin "@baseboard_fab2_lib.baseboard_fab2(sch_1):page64_i68:pe1_rx_dn(9)"
				( attribute "PN" "DP11"
					( Origin gPackager )
				)
				( objectStatus "U2D1.DP11" )
			)
			( pin "@baseboard_fab2_lib.baseboard_fab2(sch_1):page64_i68:pe1_rx_dn(10)"
				( attribute "PN" "DT11"
					( Origin gPackager )
				)
				( objectStatus "U2D1.DT11" )
			)
			( pin "@baseboard_fab2_lib.baseboard_fab2(sch_1):page64_i68:pe1_rx_dn(11)"
				( attribute "PN" "DT13"
					( Origin gPackager )
				)
				( objectStatus "U2D1.DT13" )
			)
			( pin "@baseboard_fab2_lib.baseboard_fab2(sch_1):page64_i68:pe1_rx_dn(12)"
				( attribute "PN" "DV13"
					( Origin gPackager )
				)
				( objectStatus "U2D1.DV13" )
			)
			( pin "@baseboard_fab2_lib.baseboard_fab2(sch_1):page64_i68:pe1_rx_dn(13)"
				( attribute "PN" "DW14"
					( Origin gPackager )
				)
				( objectStatus "U2D1.DW14" )
			)
			( pin "@baseboard_fab2_lib.baseboard_fab2(sch_1):page64_i68:pe1_rx_dn(14)"
				( attribute "PN" "DY15"
					( Origin gPackager )
				)
				( objectStatus "U2D1.DY15" )
			)
			( pin "@baseboard_fab2_lib.baseboard_fab2(sch_1):page64_i68:pe1_rx_dn(15)"
				( attribute "PN" "DU16"
					( Origin gPackager )
				)
				( objectStatus "U2D1.DU16" )
			)
			( pin "@baseboard_fab2_lib.baseboard_fab2(sch_1):page64_i68:pe1_rx_dp(0)"
				( attribute "PN" "CU8"
					( Origin gPackager )
				)
				( objectStatus "U2D1.CU8" )
			)
			( pin "@baseboard_fab2_lib.baseboard_fab2(sch_1):page64_i68:pe1_rx_dp(1)"
				( attribute "PN" "CY7"
					( Origin gPackager )
				)
				( objectStatus "U2D1.CY7" )
			)
			( pin "@baseboard_fab2_lib.baseboard_fab2(sch_1):page64_i68:pe1_rx_dp(2)"
				( attribute "PN" "DB9"
					( Origin gPackager )
				)
				( objectStatus "U2D1.DB9" )
			)
			( pin "@baseboard_fab2_lib.baseboard_fab2(sch_1):page64_i68:pe1_rx_dp(3)"
				( attribute "PN" "DA10"
					( Origin gPackager )
				)
				( objectStatus "U2D1.DA10" )
			)
			( pin "@baseboard_fab2_lib.baseboard_fab2(sch_1):page64_i68:pe1_rx_dp(4)"
				( attribute "PN" "DD9"
					( Origin gPackager )
				)
				( objectStatus "U2D1.DD9" )
			)
			( pin "@baseboard_fab2_lib.baseboard_fab2(sch_1):page64_i68:pe1_rx_dp(5)"
				( attribute "PN" "DF9"
					( Origin gPackager )
				)
				( objectStatus "U2D1.DF9" )
			)
			( pin "@baseboard_fab2_lib.baseboard_fab2(sch_1):page64_i68:pe1_rx_dp(6)"
				( attribute "PN" "DJ8"
					( Origin gPackager )
				)
				( objectStatus "U2D1.DJ8" )
			)
			( pin "@baseboard_fab2_lib.baseboard_fab2(sch_1):page64_i68:pe1_rx_dp(7)"
				( attribute "PN" "DL10"
					( Origin gPackager )
				)
				( objectStatus "U2D1.DL10" )
			)
			( pin "@baseboard_fab2_lib.baseboard_fab2(sch_1):page64_i68:pe1_rx_dp(8)"
				( attribute "PN" "DK11"
					( Origin gPackager )
				)
				( objectStatus "U2D1.DK11" )
			)
			( pin "@baseboard_fab2_lib.baseboard_fab2(sch_1):page64_i68:pe1_rx_dp(9)"
				( attribute "PN" "DN10"
					( Origin gPackager )
				)
				( objectStatus "U2D1.DN10" )
			)
			( pin "@baseboard_fab2_lib.baseboard_fab2(sch_1):page64_i68:pe1_rx_dp(10)"
				( attribute "PN" "DR12"
					( Origin gPackager )
				)
				( objectStatus "U2D1.DR12" )
			)
			( pin "@baseboard_fab2_lib.baseboard_fab2(sch_1):page64_i68:pe1_rx_dp(11)"
				( attribute "PN" "DP13"
					( Origin gPackager )
				)
				( objectStatus "U2D1.DP13" )
			)
			( pin "@baseboard_fab2_lib.baseboard_fab2(sch_1):page64_i68:pe1_rx_dp(12)"
				( attribute "PN" "DU12"
					( Origin gPackager )
				)
				( objectStatus "U2D1.DU12" )
			)
			( pin "@baseboard_fab2_lib.baseboard_fab2(sch_1):page64_i68:pe1_rx_dp(13)"
				( attribute "PN" "DY13"
					( Origin gPackager )
				)
				( objectStatus "U2D1.DY13" )
			)
			( pin "@baseboard_fab2_lib.baseboard_fab2(sch_1):page64_i68:pe1_rx_dp(14)"
				( attribute "PN" "DV15"
					( Origin gPackager )
				)
				( objectStatus "U2D1.DV15" )
			)
			( pin "@baseboard_fab2_lib.baseboard_fab2(sch_1):page64_i68:pe1_rx_dp(15)"
				( attribute "PN" "DT15"
					( Origin gPackager )
				)
				( objectStatus "U2D1.DT15" )
			)
			( pin "@baseboard_fab2_lib.baseboard_fab2(sch_1):page64_i68:pe1_tx_dn(0)"
				( attribute "PN" "DA2"
					( Origin gPackager )
				)
				( objectStatus "U2D1.DA2" )
			)
			( pin "@baseboard_fab2_lib.baseboard_fab2(sch_1):page64_i68:pe1_tx_dn(1)"
				( attribute "PN" "DC2"
					( Origin gPackager )
				)
				( objectStatus "U2D1.DC2" )
			)
			( pin "@baseboard_fab2_lib.baseboard_fab2(sch_1):page64_i68:pe1_tx_dn(2)"
				( attribute "PN" "DE2"
					( Origin gPackager )
				)
				( objectStatus "U2D1.DE2" )
			)
			( pin "@baseboard_fab2_lib.baseboard_fab2(sch_1):page64_i68:pe1_tx_dn(3)"
				( attribute "PN" "DE4"
					( Origin gPackager )
				)
				( objectStatus "U2D1.DE4" )
			)
			( pin "@baseboard_fab2_lib.baseboard_fab2(sch_1):page64_i68:pe1_tx_dn(4)"
				( attribute "PN" "DG4"
					( Origin gPackager )
				)
				( objectStatus "U2D1.DG4" )
			)
			( pin "@baseboard_fab2_lib.baseboard_fab2(sch_1):page64_i68:pe1_tx_dn(5)"
				( attribute "PN" "DK3"
					( Origin gPackager )
				)
				( objectStatus "U2D1.DK3" )
			)
			( pin "@baseboard_fab2_lib.baseboard_fab2(sch_1):page64_i68:pe1_tx_dn(6)"
				( attribute "PN" "DM3"
					( Origin gPackager )
				)
				( objectStatus "U2D1.DM3" )
			)
			( pin "@baseboard_fab2_lib.baseboard_fab2(sch_1):page64_i68:pe1_tx_dn(7)"
				( attribute "PN" "DN4"
					( Origin gPackager )
				)
				( objectStatus "U2D1.DN4" )
			)
			( pin "@baseboard_fab2_lib.baseboard_fab2(sch_1):page64_i68:pe1_tx_dn(8)"
				( attribute "PN" "DT5"
					( Origin gPackager )
				)
				( objectStatus "U2D1.DT5" )
			)
			( pin "@baseboard_fab2_lib.baseboard_fab2(sch_1):page64_i68:pe1_tx_dn(9)"
				( attribute "PN" "DV3"
					( Origin gPackager )
				)
				( objectStatus "U2D1.DV3" )
			)
			( pin "@baseboard_fab2_lib.baseboard_fab2(sch_1):page64_i68:pe1_tx_dn(10)"
				( attribute "PN" "DW4"
					( Origin gPackager )
				)
				( objectStatus "U2D1.DW4" )
			)
			( pin "@baseboard_fab2_lib.baseboard_fab2(sch_1):page64_i68:pe1_tx_dn(11)"
				( attribute "PN" "DU6"
					( Origin gPackager )
				)
				( objectStatus "U2D1.DU6" )
			)
			( pin "@baseboard_fab2_lib.baseboard_fab2(sch_1):page64_i68:pe1_tx_dn(12)"
				( attribute "PN" "DV7"
					( Origin gPackager )
				)
				( objectStatus "U2D1.DV7" )
			)
			( pin "@baseboard_fab2_lib.baseboard_fab2(sch_1):page64_i68:pe1_tx_dn(13)"
				( attribute "PN" "DY7"
					( Origin gPackager )
				)
				( objectStatus "U2D1.DY7" )
			)
			( pin "@baseboard_fab2_lib.baseboard_fab2(sch_1):page64_i68:pe1_tx_dn(14)"
				( attribute "PN" "EA8"
					( Origin gPackager )
				)
				( objectStatus "U2D1.EA8" )
			)
			( pin "@baseboard_fab2_lib.baseboard_fab2(sch_1):page64_i68:pe1_tx_dn(15)"
				( attribute "PN" "ED9"
					( Origin gPackager )
				)
				( objectStatus "U2D1.ED9" )
			)
			( pin "@baseboard_fab2_lib.baseboard_fab2(sch_1):page64_i68:pe1_tx_dp(0)"
				( attribute "PN" "CW2"
					( Origin gPackager )
				)
				( objectStatus "U2D1.CW2" )
			)
			( pin "@baseboard_fab2_lib.baseboard_fab2(sch_1):page64_i68:pe1_tx_dp(1)"
				( attribute "PN" "DB1"
					( Origin gPackager )
				)
				( objectStatus "U2D1.DB1" )
			)
			( pin "@baseboard_fab2_lib.baseboard_fab2(sch_1):page64_i68:pe1_tx_dp(2)"
				( attribute "PN" "DD3"
					( Origin gPackager )
				)
				( objectStatus "U2D1.DD3" )
			)
			( pin "@baseboard_fab2_lib.baseboard_fab2(sch_1):page64_i68:pe1_tx_dp(3)"
				( attribute "PN" "DC4"
					( Origin gPackager )
				)
				( objectStatus "U2D1.DC4" )
			)
			( pin "@baseboard_fab2_lib.baseboard_fab2(sch_1):page64_i68:pe1_tx_dp(4)"
				( attribute "PN" "DF3"
					( Origin gPackager )
				)
				( objectStatus "U2D1.DF3" )
			)
			( pin "@baseboard_fab2_lib.baseboard_fab2(sch_1):page64_i68:pe1_tx_dp(5)"
				( attribute "PN" "DH3"
					( Origin gPackager )
				)
				( objectStatus "U2D1.DH3" )
			)
			( pin "@baseboard_fab2_lib.baseboard_fab2(sch_1):page64_i68:pe1_tx_dp(6)"
				( attribute "PN" "DL2"
					( Origin gPackager )
				)
				( objectStatus "U2D1.DL2" )
			)
			( pin "@baseboard_fab2_lib.baseboard_fab2(sch_1):page64_i68:pe1_tx_dp(7)"
				( attribute "PN" "DP3"
					( Origin gPackager )
				)
				( objectStatus "U2D1.DP3" )
			)
			( pin "@baseboard_fab2_lib.baseboard_fab2(sch_1):page64_i68:pe1_tx_dp(8)"
				( attribute "PN" "DR4"
					( Origin gPackager )
				)
				( objectStatus "U2D1.DR4" )
			)
			( pin "@baseboard_fab2_lib.baseboard_fab2(sch_1):page64_i68:pe1_tx_dp(9)"
				( attribute "PN" "DU2"
					( Origin gPackager )
				)
				( objectStatus "U2D1.DU2" )
			)
			( pin "@baseboard_fab2_lib.baseboard_fab2(sch_1):page64_i68:pe1_tx_dp(10)"
				( attribute "PN" "DU4"
					( Origin gPackager )
				)
				( objectStatus "U2D1.DU4" )
			)
			( pin "@baseboard_fab2_lib.baseboard_fab2(sch_1):page64_i68:pe1_tx_dp(11)"
				( attribute "PN" "DV5"
					( Origin gPackager )
				)
				( objectStatus "U2D1.DV5" )
			)
			( pin "@baseboard_fab2_lib.baseboard_fab2(sch_1):page64_i68:pe1_tx_dp(12)"
				( attribute "PN" "DT7"
					( Origin gPackager )
				)
				( objectStatus "U2D1.DT7" )
			)
			( pin "@baseboard_fab2_lib.baseboard_fab2(sch_1):page64_i68:pe1_tx_dp(13)"
				( attribute "PN" "DW6"
					( Origin gPackager )
				)
				( objectStatus "U2D1.DW6" )
			)
			( pin "@baseboard_fab2_lib.baseboard_fab2(sch_1):page64_i68:pe1_tx_dp(14)"
				( attribute "PN" "EB7"
					( Origin gPackager )
				)
				( objectStatus "U2D1.EB7" )
			)
			( pin "@baseboard_fab2_lib.baseboard_fab2(sch_1):page64_i68:pe1_tx_dp(15)"
				( attribute "PN" "EC8"
					( Origin gPackager )
				)
				( objectStatus "U2D1.EC8" )
			)
			( pin "@baseboard_fab2_lib.baseboard_fab2(sch_1):page65_i68:pe2_rx_dn(0)"
				( attribute "PN" "CT9"
					( Origin gPackager )
				)
				( objectStatus "U2D1.CT9" )
			)
			( pin "@baseboard_fab2_lib.baseboard_fab2(sch_1):page65_i68:pe2_rx_dn(1)"
				( attribute "PN" "CP9"
					( Origin gPackager )
				)
				( objectStatus "U2D1.CP9" )
			)
			( pin "@baseboard_fab2_lib.baseboard_fab2(sch_1):page65_i68:pe2_rx_dn(2)"
				( attribute "PN" "CP7"
					( Origin gPackager )
				)
				( objectStatus "U2D1.CP7" )
			)
			( pin "@baseboard_fab2_lib.baseboard_fab2(sch_1):page65_i68:pe2_rx_dn(3)"
				( attribute "PN" "CM7"
					( Origin gPackager )
				)
				( objectStatus "U2D1.CM7" )
			)
			( pin "@baseboard_fab2_lib.baseboard_fab2(sch_1):page65_i68:pe2_rx_dn(4)"
				( attribute "PN" "CK7"
					( Origin gPackager )
				)
				( objectStatus "U2D1.CK7" )
			)
			( pin "@baseboard_fab2_lib.baseboard_fab2(sch_1):page65_i68:pe2_rx_dn(5)"
				( attribute "PN" "CG8"
					( Origin gPackager )
				)
				( objectStatus "U2D1.CG8" )
			)
			( pin "@baseboard_fab2_lib.baseboard_fab2(sch_1):page65_i68:pe2_rx_dn(6)"
				( attribute "PN" "CE6"
					( Origin gPackager )
				)
				( objectStatus "U2D1.CE6" )
			)
			( pin "@baseboard_fab2_lib.baseboard_fab2(sch_1):page65_i68:pe2_rx_dn(7)"
				( attribute "PN" "CE8"
					( Origin gPackager )
				)
				( objectStatus "U2D1.CE8" )
			)
			( pin "@baseboard_fab2_lib.baseboard_fab2(sch_1):page65_i68:pe2_rx_dn(8)"
				( attribute "PN" "BY9"
					( Origin gPackager )
				)
				( objectStatus "U2D1.BY9" )
			)
			( pin "@baseboard_fab2_lib.baseboard_fab2(sch_1):page65_i68:pe2_rx_dn(9)"
				( attribute "PN" "BY7"
					( Origin gPackager )
				)
				( objectStatus "U2D1.BY7" )
			)
			( pin "@baseboard_fab2_lib.baseboard_fab2(sch_1):page65_i68:pe2_rx_dn(10)"
				( attribute "PN" "BV7"
					( Origin gPackager )
				)
				( objectStatus "U2D1.BV7" )
			)
			( pin "@baseboard_fab2_lib.baseboard_fab2(sch_1):page65_i68:pe2_rx_dn(11)"
				( attribute "PN" "BT7"
					( Origin gPackager )
				)
				( objectStatus "U2D1.BT7" )
			)
			( pin "@baseboard_fab2_lib.baseboard_fab2(sch_1):page65_i68:pe2_rx_dn(12)"
				( attribute "PN" "BR8"
					( Origin gPackager )
				)
				( objectStatus "U2D1.BR8" )
			)
			( pin "@baseboard_fab2_lib.baseboard_fab2(sch_1):page65_i68:pe2_rx_dn(13)"
				( attribute "PN" "BN8"
					( Origin gPackager )
				)
				( objectStatus "U2D1.BN8" )
			)
			( pin "@baseboard_fab2_lib.baseboard_fab2(sch_1):page65_i68:pe2_rx_dn(14)"
				( attribute "PN" "BL8"
					( Origin gPackager )
				)
				( objectStatus "U2D1.BL8" )
			)
			( pin "@baseboard_fab2_lib.baseboard_fab2(sch_1):page65_i68:pe2_rx_dn(15)"
				( attribute "PN" "BK9"
					( Origin gPackager )
				)
				( objectStatus "U2D1.BK9" )
			)
			( pin "@baseboard_fab2_lib.baseboard_fab2(sch_1):page65_i68:pe2_rx_dp(0)"
				( attribute "PN" "CR8"
					( Origin gPackager )
				)
				( objectStatus "U2D1.CR8" )
			)
			( pin "@baseboard_fab2_lib.baseboard_fab2(sch_1):page65_i68:pe2_rx_dp(1)"
				( attribute "PN" "CM9"
					( Origin gPackager )
				)
				( objectStatus "U2D1.CM9" )
			)
			( pin "@baseboard_fab2_lib.baseboard_fab2(sch_1):page65_i68:pe2_rx_dp(2)"
				( attribute "PN" "CN8"
					( Origin gPackager )
				)
				( objectStatus "U2D1.CN8" )
			)
			( pin "@baseboard_fab2_lib.baseboard_fab2(sch_1):page65_i68:pe2_rx_dp(3)"
				( attribute "PN" "CL6"
					( Origin gPackager )
				)
				( objectStatus "U2D1.CL6" )
			)
			( pin "@baseboard_fab2_lib.baseboard_fab2(sch_1):page65_i68:pe2_rx_dp(4)"
				( attribute "PN" "CH7"
					( Origin gPackager )
				)
				( objectStatus "U2D1.CH7" )
			)
			( pin "@baseboard_fab2_lib.baseboard_fab2(sch_1):page65_i68:pe2_rx_dp(5)"
				( attribute "PN" "CF7"
					( Origin gPackager )
				)
				( objectStatus "U2D1.CF7" )
			)
			( pin "@baseboard_fab2_lib.baseboard_fab2(sch_1):page65_i68:pe2_rx_dp(6)"
				( attribute "PN" "CD7"
					( Origin gPackager )
				)
				( objectStatus "U2D1.CD7" )
			)
			( pin "@baseboard_fab2_lib.baseboard_fab2(sch_1):page65_i68:pe2_rx_dp(7)"
				( attribute "PN" "CC8"
					( Origin gPackager )
				)
				( objectStatus "U2D1.CC8" )
			)
			( pin "@baseboard_fab2_lib.baseboard_fab2(sch_1):page65_i68:pe2_rx_dp(8)"
				( attribute "PN" "BV9"
					( Origin gPackager )
				)
				( objectStatus "U2D1.BV9" )
			)
			( pin "@baseboard_fab2_lib.baseboard_fab2(sch_1):page65_i68:pe2_rx_dp(9)"
				( attribute "PN" "BW8"
					( Origin gPackager )
				)
				( objectStatus "U2D1.BW8" )
			)
			( pin "@baseboard_fab2_lib.baseboard_fab2(sch_1):page65_i68:pe2_rx_dp(10)"
				( attribute "PN" "BU6"
					( Origin gPackager )
				)
				( objectStatus "U2D1.BU6" )
			)
			( pin "@baseboard_fab2_lib.baseboard_fab2(sch_1):page65_i68:pe2_rx_dp(11)"
				( attribute "PN" "BP7"
					( Origin gPackager )
				)
				( objectStatus "U2D1.BP7" )
			)
			( pin "@baseboard_fab2_lib.baseboard_fab2(sch_1):page65_i68:pe2_rx_dp(12)"
				( attribute "PN" "BP9"
					( Origin gPackager )
				)
				( objectStatus "U2D1.BP9" )
			)
			( pin "@baseboard_fab2_lib.baseboard_fab2(sch_1):page65_i68:pe2_rx_dp(13)"
				( attribute "PN" "BM7"
					( Origin gPackager )
				)
				( objectStatus "U2D1.BM7" )
			)
			( pin "@baseboard_fab2_lib.baseboard_fab2(sch_1):page65_i68:pe2_rx_dp(14)"
				( attribute "PN" "BJ8"
					( Origin gPackager )
				)
				( objectStatus "U2D1.BJ8" )
			)
			( pin "@baseboard_fab2_lib.baseboard_fab2(sch_1):page65_i68:pe2_rx_dp(15)"
				( attribute "PN" "BJ10"
					( Origin gPackager )
				)
				( objectStatus "U2D1.BJ10" )
			)
			( pin "@baseboard_fab2_lib.baseboard_fab2(sch_1):page65_i68:pe2_tx_dn(0)"
				( attribute "PN" "CY3"
					( Origin gPackager )
				)
				( objectStatus "U2D1.CY3" )
			)
			( pin "@baseboard_fab2_lib.baseboard_fab2(sch_1):page65_i68:pe2_tx_dn(1)"
				( attribute "PN" "CV3"
					( Origin gPackager )
				)
				( objectStatus "U2D1.CV3" )
			)
			( pin "@baseboard_fab2_lib.baseboard_fab2(sch_1):page65_i68:pe2_tx_dn(2)"
				( attribute "PN" "CT1"
					( Origin gPackager )
				)
				( objectStatus "U2D1.CT1" )
			)
			( pin "@baseboard_fab2_lib.baseboard_fab2(sch_1):page65_i68:pe2_tx_dn(3)"
				( attribute "PN" "CT3"
					( Origin gPackager )
				)
				( objectStatus "U2D1.CT3" )
			)
			( pin "@baseboard_fab2_lib.baseboard_fab2(sch_1):page65_i68:pe2_tx_dn(4)"
				( attribute "PN" "CM1"
					( Origin gPackager )
				)
				( objectStatus "U2D1.CM1" )
			)
			( pin "@baseboard_fab2_lib.baseboard_fab2(sch_1):page65_i68:pe2_tx_dn(5)"
				( attribute "PN" "CL2"
					( Origin gPackager )
				)
				( objectStatus "U2D1.CL2" )
			)
			( pin "@baseboard_fab2_lib.baseboard_fab2(sch_1):page65_i68:pe2_tx_dn(6)"
				( attribute "PN" "CG2"
					( Origin gPackager )
				)
				( objectStatus "U2D1.CG2" )
			)
			( pin "@baseboard_fab2_lib.baseboard_fab2(sch_1):page65_i68:pe2_tx_dn(7)"
				( attribute "PN" "CF3"
					( Origin gPackager )
				)
				( objectStatus "U2D1.CF3" )
			)
			( pin "@baseboard_fab2_lib.baseboard_fab2(sch_1):page65_i68:pe2_tx_dn(8)"
				( attribute "PN" "CC2"
					( Origin gPackager )
				)
				( objectStatus "U2D1.CC2" )
			)
			( pin "@baseboard_fab2_lib.baseboard_fab2(sch_1):page65_i68:pe2_tx_dn(9)"
				( attribute "PN" "CB3"
					( Origin gPackager )
				)
				( objectStatus "U2D1.CB3" )
			)
			( pin "@baseboard_fab2_lib.baseboard_fab2(sch_1):page65_i68:pe2_tx_dn(10)"
				( attribute "PN" "CA4"
					( Origin gPackager )
				)
				( objectStatus "U2D1.CA4" )
			)
			( pin "@baseboard_fab2_lib.baseboard_fab2(sch_1):page65_i68:pe2_tx_dn(11)"
				( attribute "PN" "BW4"
					( Origin gPackager )
				)
				( objectStatus "U2D1.BW4" )
			)
			( pin "@baseboard_fab2_lib.baseboard_fab2(sch_1):page65_i68:pe2_tx_dn(12)"
				( attribute "PN" "BU4"
					( Origin gPackager )
				)
				( objectStatus "U2D1.BU4" )
			)
			( pin "@baseboard_fab2_lib.baseboard_fab2(sch_1):page65_i68:pe2_tx_dn(13)"
				( attribute "PN" "BP5"
					( Origin gPackager )
				)
				( objectStatus "U2D1.BP5" )
			)
			( pin "@baseboard_fab2_lib.baseboard_fab2(sch_1):page65_i68:pe2_tx_dn(14)"
				( attribute "PN" "BL4"
					( Origin gPackager )
				)
				( objectStatus "U2D1.BL4" )
			)
			( pin "@baseboard_fab2_lib.baseboard_fab2(sch_1):page65_i68:pe2_tx_dn(15)"
				( attribute "PN" "BM5"
					( Origin gPackager )
				)
				( objectStatus "U2D1.BM5" )
			)
			( pin "@baseboard_fab2_lib.baseboard_fab2(sch_1):page65_i68:pe2_tx_dp(0)"
				( attribute "PN" "CW4"
					( Origin gPackager )
				)
				( objectStatus "U2D1.CW4" )
			)
			( pin "@baseboard_fab2_lib.baseboard_fab2(sch_1):page65_i68:pe2_tx_dp(1)"
				( attribute "PN" "CU2"
					( Origin gPackager )
				)
				( objectStatus "U2D1.CU2" )
			)
			( pin "@baseboard_fab2_lib.baseboard_fab2(sch_1):page65_i68:pe2_tx_dp(2)"
				( attribute "PN" "CR2"
					( Origin gPackager )
				)
				( objectStatus "U2D1.CR2" )
			)
			( pin "@baseboard_fab2_lib.baseboard_fab2(sch_1):page65_i68:pe2_tx_dp(3)"
				( attribute "PN" "CP3"
					( Origin gPackager )
				)
				( objectStatus "U2D1.CP3" )
			)
			( pin "@baseboard_fab2_lib.baseboard_fab2(sch_1):page65_i68:pe2_tx_dp(4)"
				( attribute "PN" "CK1"
					( Origin gPackager )
				)
				( objectStatus "U2D1.CK1" )
			)
			( pin "@baseboard_fab2_lib.baseboard_fab2(sch_1):page65_i68:pe2_tx_dp(5)"
				( attribute "PN" "CK3"
					( Origin gPackager )
				)
				( objectStatus "U2D1.CK3" )
			)
			( pin "@baseboard_fab2_lib.baseboard_fab2(sch_1):page65_i68:pe2_tx_dp(6)"
				( attribute "PN" "CE2"
					( Origin gPackager )
				)
				( objectStatus "U2D1.CE2" )
			)
			( pin "@baseboard_fab2_lib.baseboard_fab2(sch_1):page65_i68:pe2_tx_dp(7)"
				( attribute "PN" "CE4"
					( Origin gPackager )
				)
				( objectStatus "U2D1.CE4" )
			)
			( pin "@baseboard_fab2_lib.baseboard_fab2(sch_1):page65_i68:pe2_tx_dp(8)"
				( attribute "PN" "CD3"
					( Origin gPackager )
				)
				( objectStatus "U2D1.CD3" )
			)
			( pin "@baseboard_fab2_lib.baseboard_fab2(sch_1):page65_i68:pe2_tx_dp(9)"
				( attribute "PN" "BY3"
					( Origin gPackager )
				)
				( objectStatus "U2D1.BY3" )
			)
			( pin "@baseboard_fab2_lib.baseboard_fab2(sch_1):page65_i68:pe2_tx_dp(10)"
				( attribute "PN" "BY5"
					( Origin gPackager )
				)
				( objectStatus "U2D1.BY5" )
			)
			( pin "@baseboard_fab2_lib.baseboard_fab2(sch_1):page65_i68:pe2_tx_dp(11)"
				( attribute "PN" "BV3"
					( Origin gPackager )
				)
				( objectStatus "U2D1.BV3" )
			)
			( pin "@baseboard_fab2_lib.baseboard_fab2(sch_1):page65_i68:pe2_tx_dp(12)"
				( attribute "PN" "BR4"
					( Origin gPackager )
				)
				( objectStatus "U2D1.BR4" )
			)
			( pin "@baseboard_fab2_lib.baseboard_fab2(sch_1):page65_i68:pe2_tx_dp(13)"
				( attribute "PN" "BN4"
					( Origin gPackager )
				)
				( objectStatus "U2D1.BN4" )
			)
			( pin "@baseboard_fab2_lib.baseboard_fab2(sch_1):page65_i68:pe2_tx_dp(14)"
				( attribute "PN" "BM3"
					( Origin gPackager )
				)
				( objectStatus "U2D1.BM3" )
			)
			( pin "@baseboard_fab2_lib.baseboard_fab2(sch_1):page65_i68:pe2_tx_dp(15)"
				( attribute "PN" "BK5"
					( Origin gPackager )
				)
				( objectStatus "U2D1.BK5" )
			)
			( pin "@baseboard_fab2_lib.baseboard_fab2(sch_1):page66_i84:pe3_rx_dn(0)"
				( attribute "PN" "EA18"
					( Origin gPackager )
				)
				( objectStatus "U2D1.EA18" )
			)
			( pin "@baseboard_fab2_lib.baseboard_fab2(sch_1):page66_i84:pe3_rx_dn(1)"
				( attribute "PN" "DW18"
					( Origin gPackager )
				)
				( objectStatus "U2D1.DW18" )
			)
			( pin "@baseboard_fab2_lib.baseboard_fab2(sch_1):page66_i84:pe3_rx_dn(2)"
				( attribute "PN" "DW16"
					( Origin gPackager )
				)
				( objectStatus "U2D1.DW16" )
			)
			( pin "@baseboard_fab2_lib.baseboard_fab2(sch_1):page66_i84:pe3_rx_dn(3)"
				( attribute "PN" "DT19"
					( Origin gPackager )
				)
				( objectStatus "U2D1.DT19" )
			)
			( pin "@baseboard_fab2_lib.baseboard_fab2(sch_1):page66_i84:pe3_rx_dn(4)"
				( attribute "PN" "DR16"
					( Origin gPackager )
				)
				( objectStatus "U2D1.DR16" )
			)
			( pin "@baseboard_fab2_lib.baseboard_fab2(sch_1):page66_i84:pe3_rx_dn(5)"
				( attribute "PN" "DR14"
					( Origin gPackager )
				)
				( objectStatus "U2D1.DR14" )
			)
			( pin "@baseboard_fab2_lib.baseboard_fab2(sch_1):page66_i84:pe3_rx_dn(6)"
				( attribute "PN" "DN14"
					( Origin gPackager )
				)
				( objectStatus "U2D1.DN14" )
			)
			( pin "@baseboard_fab2_lib.baseboard_fab2(sch_1):page66_i84:pe3_rx_dn(7)"
				( attribute "PN" "DL14"
					( Origin gPackager )
				)
				( objectStatus "U2D1.DL14" )
			)
			( pin "@baseboard_fab2_lib.baseboard_fab2(sch_1):page66_i84:pe3_rx_dn(8)"
				( attribute "PN" "DL12"
					( Origin gPackager )
				)
				( objectStatus "U2D1.DL12" )
			)
			( pin "@baseboard_fab2_lib.baseboard_fab2(sch_1):page66_i84:pe3_rx_dn(9)"
				( attribute "PN" "DJ12"
					( Origin gPackager )
				)
				( objectStatus "U2D1.DJ12" )
			)
			( pin "@baseboard_fab2_lib.baseboard_fab2(sch_1):page66_i84:pe3_rx_dn(10)"
				( attribute "PN" "DG12"
					( Origin gPackager )
				)
				( objectStatus "U2D1.DG12" )
			)
			( pin "@baseboard_fab2_lib.baseboard_fab2(sch_1):page66_i84:pe3_rx_dn(11)"
				( attribute "PN" "DG10"
					( Origin gPackager )
				)
				( objectStatus "U2D1.DG10" )
			)
			( pin "@baseboard_fab2_lib.baseboard_fab2(sch_1):page66_i84:pe3_rx_dn(12)"
				( attribute "PN" "DD13"
					( Origin gPackager )
				)
				( objectStatus "U2D1.DD13" )
			)
			( pin "@baseboard_fab2_lib.baseboard_fab2(sch_1):page66_i84:pe3_rx_dn(13)"
				( attribute "PN" "DB11"
					( Origin gPackager )
				)
				( objectStatus "U2D1.DB11" )
			)
			( pin "@baseboard_fab2_lib.baseboard_fab2(sch_1):page66_i84:pe3_rx_dn(14)"
				( attribute "PN" "CY11"
					( Origin gPackager )
				)
				( objectStatus "U2D1.CY11" )
			)
			( pin "@baseboard_fab2_lib.baseboard_fab2(sch_1):page66_i84:pe3_rx_dn(15)"
				( attribute "PN" "CV9"
					( Origin gPackager )
				)
				( objectStatus "U2D1.CV9" )
			)
			( pin "@baseboard_fab2_lib.baseboard_fab2(sch_1):page66_i84:pe3_rx_dp(0)"
				( attribute "PN" "DY17"
					( Origin gPackager )
				)
				( objectStatus "U2D1.DY17" )
			)
			( pin "@baseboard_fab2_lib.baseboard_fab2(sch_1):page66_i84:pe3_rx_dp(1)"
				( attribute "PN" "DU18"
					( Origin gPackager )
				)
				( objectStatus "U2D1.DU18" )
			)
			( pin "@baseboard_fab2_lib.baseboard_fab2(sch_1):page66_i84:pe3_rx_dp(2)"
				( attribute "PN" "DV17"
					( Origin gPackager )
				)
				( objectStatus "U2D1.DV17" )
			)
			( pin "@baseboard_fab2_lib.baseboard_fab2(sch_1):page66_i84:pe3_rx_dp(3)"
				( attribute "PN" "DR18"
					( Origin gPackager )
				)
				( objectStatus "U2D1.DR18" )
			)
			( pin "@baseboard_fab2_lib.baseboard_fab2(sch_1):page66_i84:pe3_rx_dp(4)"
				( attribute "PN" "DN16"
					( Origin gPackager )
				)
				( objectStatus "U2D1.DN16" )
			)
			( pin "@baseboard_fab2_lib.baseboard_fab2(sch_1):page66_i84:pe3_rx_dp(5)"
				( attribute "PN" "DP15"
					( Origin gPackager )
				)
				( objectStatus "U2D1.DP15" )
			)
			( pin "@baseboard_fab2_lib.baseboard_fab2(sch_1):page66_i84:pe3_rx_dp(6)"
				( attribute "PN" "DM13"
					( Origin gPackager )
				)
				( objectStatus "U2D1.DM13" )
			)
			( pin "@baseboard_fab2_lib.baseboard_fab2(sch_1):page66_i84:pe3_rx_dp(7)"
				( attribute "PN" "DJ14"
					( Origin gPackager )
				)
				( objectStatus "U2D1.DJ14" )
			)
			( pin "@baseboard_fab2_lib.baseboard_fab2(sch_1):page66_i84:pe3_rx_dp(8)"
				( attribute "PN" "DK13"
					( Origin gPackager )
				)
				( objectStatus "U2D1.DK13" )
			)
			( pin "@baseboard_fab2_lib.baseboard_fab2(sch_1):page66_i84:pe3_rx_dp(9)"
				( attribute "PN" "DH11"
					( Origin gPackager )
				)
				( objectStatus "U2D1.DH11" )
			)
			( pin "@baseboard_fab2_lib.baseboard_fab2(sch_1):page66_i84:pe3_rx_dp(10)"
				( attribute "PN" "DE12"
					( Origin gPackager )
				)
				( objectStatus "U2D1.DE12" )
			)
			( pin "@baseboard_fab2_lib.baseboard_fab2(sch_1):page66_i84:pe3_rx_dp(11)"
				( attribute "PN" "DF11"
					( Origin gPackager )
				)
				( objectStatus "U2D1.DF11" )
			)
			( pin "@baseboard_fab2_lib.baseboard_fab2(sch_1):page66_i84:pe3_rx_dp(12)"
				( attribute "PN" "DC12"
					( Origin gPackager )
				)
				( objectStatus "U2D1.DC12" )
			)
			( pin "@baseboard_fab2_lib.baseboard_fab2(sch_1):page66_i84:pe3_rx_dp(13)"
				( attribute "PN" "DA12"
					( Origin gPackager )
				)
				( objectStatus "U2D1.DA12" )
			)
			( pin "@baseboard_fab2_lib.baseboard_fab2(sch_1):page66_i84:pe3_rx_dp(14)"
				( attribute "PN" "CW10"
					( Origin gPackager )
				)
				( objectStatus "U2D1.CW10" )
			)
			( pin "@baseboard_fab2_lib.baseboard_fab2(sch_1):page66_i84:pe3_rx_dp(15)"
				( attribute "PN" "CU10"
					( Origin gPackager )
				)
				( objectStatus "U2D1.CU10" )
			)
			( pin "@baseboard_fab2_lib.baseboard_fab2(sch_1):page66_i84:pe3_tx_dn(0)"
				( attribute "PN" "EE14"
					( Origin gPackager )
				)
				( objectStatus "U2D1.EE14" )
			)
			( pin "@baseboard_fab2_lib.baseboard_fab2(sch_1):page66_i84:pe3_tx_dn(1)"
				( attribute "PN" "EE12"
					( Origin gPackager )
				)
				( objectStatus "U2D1.EE12" )
			)
			( pin "@baseboard_fab2_lib.baseboard_fab2(sch_1):page66_i84:pe3_tx_dn(2)"
				( attribute "PN" "EC12"
					( Origin gPackager )
				)
				( objectStatus "U2D1.EC12" )
			)
			( pin "@baseboard_fab2_lib.baseboard_fab2(sch_1):page66_i84:pe3_tx_dn(3)"
				( attribute "PN" "DY11"
					( Origin gPackager )
				)
				( objectStatus "U2D1.DY11" )
			)
			( pin "@baseboard_fab2_lib.baseboard_fab2(sch_1):page66_i84:pe3_tx_dn(4)"
				( attribute "PN" "EB9"
					( Origin gPackager )
				)
				( objectStatus "U2D1.EB9" )
			)
			( pin "@baseboard_fab2_lib.baseboard_fab2(sch_1):page66_i84:pe3_tx_dn(5)"
				( attribute "PN" "DW10"
					( Origin gPackager )
				)
				( objectStatus "U2D1.DW10" )
			)
			( pin "@baseboard_fab2_lib.baseboard_fab2(sch_1):page66_i84:pe3_tx_dn(6)"
				( attribute "PN" "DU8"
					( Origin gPackager )
				)
				( objectStatus "U2D1.DU8" )
			)
			( pin "@baseboard_fab2_lib.baseboard_fab2(sch_1):page66_i84:pe3_tx_dn(7)"
				( attribute "PN" "DR8"
					( Origin gPackager )
				)
				( objectStatus "U2D1.DR8" )
			)
			( pin "@baseboard_fab2_lib.baseboard_fab2(sch_1):page66_i84:pe3_tx_dn(8)"
				( attribute "PN" "DM7"
					( Origin gPackager )
				)
				( objectStatus "U2D1.DM7" )
			)
			( pin "@baseboard_fab2_lib.baseboard_fab2(sch_1):page66_i84:pe3_tx_dn(9)"
				( attribute "PN" "DP5"
					( Origin gPackager )
				)
				( objectStatus "U2D1.DP5" )
			)
			( pin "@baseboard_fab2_lib.baseboard_fab2(sch_1):page66_i84:pe3_tx_dn(10)"
				( attribute "PN" "DL6"
					( Origin gPackager )
				)
				( objectStatus "U2D1.DL6" )
			)
			( pin "@baseboard_fab2_lib.baseboard_fab2(sch_1):page66_i84:pe3_tx_dn(11)"
				( attribute "PN" "DJ4"
					( Origin gPackager )
				)
				( objectStatus "U2D1.DJ4" )
			)
			( pin "@baseboard_fab2_lib.baseboard_fab2(sch_1):page66_i84:pe3_tx_dn(12)"
				( attribute "PN" "DJ6"
					( Origin gPackager )
				)
				( objectStatus "U2D1.DJ6" )
			)
			( pin "@baseboard_fab2_lib.baseboard_fab2(sch_1):page66_i84:pe3_tx_dn(13)"
				( attribute "PN" "DD5"
					( Origin gPackager )
				)
				( objectStatus "U2D1.DD5" )
			)
			( pin "@baseboard_fab2_lib.baseboard_fab2(sch_1):page66_i84:pe3_tx_dn(14)"
				( attribute "PN" "DB5"
					( Origin gPackager )
				)
				( objectStatus "U2D1.DB5" )
			)
			( pin "@baseboard_fab2_lib.baseboard_fab2(sch_1):page66_i84:pe3_tx_dn(15)"
				( attribute "PN" "CY5"
					( Origin gPackager )
				)
				( objectStatus "U2D1.CY5" )
			)
			( pin "@baseboard_fab2_lib.baseboard_fab2(sch_1):page66_i84:pe3_tx_dp(0)"
				( attribute "PN" "EC14"
					( Origin gPackager )
				)
				( objectStatus "U2D1.EC14" )
			)
			( pin "@baseboard_fab2_lib.baseboard_fab2(sch_1):page66_i84:pe3_tx_dp(1)"
				( attribute "PN" "ED13"
					( Origin gPackager )
				)
				( objectStatus "U2D1.ED13" )
			)
			( pin "@baseboard_fab2_lib.baseboard_fab2(sch_1):page66_i84:pe3_tx_dp(2)"
				( attribute "PN" "EB11"
					( Origin gPackager )
				)
				( objectStatus "U2D1.EB11" )
			)
			( pin "@baseboard_fab2_lib.baseboard_fab2(sch_1):page66_i84:pe3_tx_dp(3)"
				( attribute "PN" "EA10"
					( Origin gPackager )
				)
				( objectStatus "U2D1.EA10" )
			)
			( pin "@baseboard_fab2_lib.baseboard_fab2(sch_1):page66_i84:pe3_tx_dp(4)"
				( attribute "PN" "DY9"
					( Origin gPackager )
				)
				( objectStatus "U2D1.DY9" )
			)
			( pin "@baseboard_fab2_lib.baseboard_fab2(sch_1):page66_i84:pe3_tx_dp(5)"
				( attribute "PN" "DV9"
					( Origin gPackager )
				)
				( objectStatus "U2D1.DV9" )
			)
			( pin "@baseboard_fab2_lib.baseboard_fab2(sch_1):page66_i84:pe3_tx_dp(6)"
				( attribute "PN" "DT9"
					( Origin gPackager )
				)
				( objectStatus "U2D1.DT9" )
			)
			( pin "@baseboard_fab2_lib.baseboard_fab2(sch_1):page66_i84:pe3_tx_dp(7)"
				( attribute "PN" "DP7"
					( Origin gPackager )
				)
				( objectStatus "U2D1.DP7" )
			)
			( pin "@baseboard_fab2_lib.baseboard_fab2(sch_1):page66_i84:pe3_tx_dp(8)"
				( attribute "PN" "DN6"
					( Origin gPackager )
				)
				( objectStatus "U2D1.DN6" )
			)
			( pin "@baseboard_fab2_lib.baseboard_fab2(sch_1):page66_i84:pe3_tx_dp(9)"
				( attribute "PN" "DM5"
					( Origin gPackager )
				)
				( objectStatus "U2D1.DM5" )
			)
			( pin "@baseboard_fab2_lib.baseboard_fab2(sch_1):page66_i84:pe3_tx_dp(10)"
				( attribute "PN" "DK5"
					( Origin gPackager )
				)
				( objectStatus "U2D1.DK5" )
			)
			( pin "@baseboard_fab2_lib.baseboard_fab2(sch_1):page66_i84:pe3_tx_dp(11)"
				( attribute "PN" "DH5"
					( Origin gPackager )
				)
				( objectStatus "U2D1.DH5" )
			)
			( pin "@baseboard_fab2_lib.baseboard_fab2(sch_1):page66_i84:pe3_tx_dp(12)"
				( attribute "PN" "DG6"
					( Origin gPackager )
				)
				( objectStatus "U2D1.DG6" )
			)
			( pin "@baseboard_fab2_lib.baseboard_fab2(sch_1):page66_i84:pe3_tx_dp(13)"
				( attribute "PN" "DC6"
					( Origin gPackager )
				)
				( objectStatus "U2D1.DC6" )
			)
			( pin "@baseboard_fab2_lib.baseboard_fab2(sch_1):page66_i84:pe3_tx_dp(14)"
				( attribute "PN" "DA4"
					( Origin gPackager )
				)
				( objectStatus "U2D1.DA4" )
			)
			( pin "@baseboard_fab2_lib.baseboard_fab2(sch_1):page66_i84:pe3_tx_dp(15)"
				( attribute "PN" "CV5"
					( Origin gPackager )
				)
				( objectStatus "U2D1.CV5" )
			)
			( pin "@baseboard_fab2_lib.baseboard_fab2(sch_1):page67_i132:upi0_rx_dn(0)"
				( attribute "PN" "AC10"
					( Origin gPackager )
				)
				( objectStatus "U2D1.AC10" )
			)
			( pin "@baseboard_fab2_lib.baseboard_fab2(sch_1):page67_i132:upi0_rx_dn(1)"
				( attribute "PN" "AA8"
					( Origin gPackager )
				)
				( objectStatus "U2D1.AA8" )
			)
			( pin "@baseboard_fab2_lib.baseboard_fab2(sch_1):page67_i132:upi0_rx_dn(2)"
				( attribute "PN" "AB7"
					( Origin gPackager )
				)
				( objectStatus "U2D1.AB7" )
			)
			( pin "@baseboard_fab2_lib.baseboard_fab2(sch_1):page67_i132:upi0_rx_dn(3)"
				( attribute "PN" "AD5"
					( Origin gPackager )
				)
				( objectStatus "U2D1.AD5" )
			)
			( pin "@baseboard_fab2_lib.baseboard_fab2(sch_1):page67_i132:upi0_rx_dn(4)"
				( attribute "PN" "AE6"
					( Origin gPackager )
				)
				( objectStatus "U2D1.AE6" )
			)
			( pin "@baseboard_fab2_lib.baseboard_fab2(sch_1):page67_i132:upi0_rx_dn(5)"
				( attribute "PN" "AG8"
					( Origin gPackager )
				)
				( objectStatus "U2D1.AG8" )
			)
			( pin "@baseboard_fab2_lib.baseboard_fab2(sch_1):page67_i132:upi0_rx_dn(6)"
				( attribute "PN" "AJ6"
					( Origin gPackager )
				)
				( objectStatus "U2D1.AJ6" )
			)
			( pin "@baseboard_fab2_lib.baseboard_fab2(sch_1):page67_i132:upi0_rx_dn(7)"
				( attribute "PN" "AL6"
					( Origin gPackager )
				)
				( objectStatus "U2D1.AL6" )
			)
			( pin "@baseboard_fab2_lib.baseboard_fab2(sch_1):page67_i132:upi0_rx_dn(8)"
				( attribute "PN" "AK7"
					( Origin gPackager )
				)
				( objectStatus "U2D1.AK7" )
			)
			( pin "@baseboard_fab2_lib.baseboard_fab2(sch_1):page67_i132:upi0_rx_dn(9)"
				( attribute "PN" "AM9"
					( Origin gPackager )
				)
				( objectStatus "U2D1.AM9" )
			)
			( pin "@baseboard_fab2_lib.baseboard_fab2(sch_1):page67_i132:upi0_rx_dn(10)"
				( attribute "PN" "AP7"
					( Origin gPackager )
				)
				( objectStatus "U2D1.AP7" )
			)
			( pin "@baseboard_fab2_lib.baseboard_fab2(sch_1):page67_i132:upi0_rx_dn(11)"
				( attribute "PN" "AR8"
					( Origin gPackager )
				)
				( objectStatus "U2D1.AR8" )
			)
			( pin "@baseboard_fab2_lib.baseboard_fab2(sch_1):page67_i132:upi0_rx_dn(12)"
				( attribute "PN" "AU10"
					( Origin gPackager )
				)
				( objectStatus "U2D1.AU10" )
			)
			( pin "@baseboard_fab2_lib.baseboard_fab2(sch_1):page67_i132:upi0_rx_dn(13)"
				( attribute "PN" "BA8"
					( Origin gPackager )
				)
				( objectStatus "U2D1.BA8" )
			)
			( pin "@baseboard_fab2_lib.baseboard_fab2(sch_1):page67_i132:upi0_rx_dn(14)"
				( attribute "PN" "BC6"
					( Origin gPackager )
				)
				( objectStatus "U2D1.BC6" )
			)
			( pin "@baseboard_fab2_lib.baseboard_fab2(sch_1):page67_i132:upi0_rx_dn(15)"
				( attribute "PN" "BD7"
					( Origin gPackager )
				)
				( objectStatus "U2D1.BD7" )
			)
			( pin "@baseboard_fab2_lib.baseboard_fab2(sch_1):page67_i132:upi0_rx_dn(16)"
				( attribute "PN" "AW8"
					( Origin gPackager )
				)
				( objectStatus "U2D1.AW8" )
			)
			( pin "@baseboard_fab2_lib.baseboard_fab2(sch_1):page67_i132:upi0_rx_dn(17)"
				( attribute "PN" "AY9"
					( Origin gPackager )
				)
				( objectStatus "U2D1.AY9" )
			)
			( pin "@baseboard_fab2_lib.baseboard_fab2(sch_1):page67_i132:upi0_rx_dn(18)"
				( attribute "PN" "BD9"
					( Origin gPackager )
				)
				( objectStatus "U2D1.BD9" )
			)
			( pin "@baseboard_fab2_lib.baseboard_fab2(sch_1):page67_i132:upi0_rx_dn(19)"
				( attribute "PN" "BB11"
					( Origin gPackager )
				)
				( objectStatus "U2D1.BB11" )
			)
			( pin "@baseboard_fab2_lib.baseboard_fab2(sch_1):page67_i132:upi0_rx_dp(0)"
				( attribute "PN" "AB9"
					( Origin gPackager )
				)
				( objectStatus "U2D1.AB9" )
			)
			( pin "@baseboard_fab2_lib.baseboard_fab2(sch_1):page67_i132:upi0_rx_dp(1)"
				( attribute "PN" "AC8"
					( Origin gPackager )
				)
				( objectStatus "U2D1.AC8" )
			)
			( pin "@baseboard_fab2_lib.baseboard_fab2(sch_1):page67_i132:upi0_rx_dp(2)"
				( attribute "PN" "AA6"
					( Origin gPackager )
				)
				( objectStatus "U2D1.AA6" )
			)
			( pin "@baseboard_fab2_lib.baseboard_fab2(sch_1):page67_i132:upi0_rx_dp(3)"
				( attribute "PN" "AC6"
					( Origin gPackager )
				)
				( objectStatus "U2D1.AC6" )
			)
			( pin "@baseboard_fab2_lib.baseboard_fab2(sch_1):page67_i132:upi0_rx_dp(4)"
				( attribute "PN" "AG6"
					( Origin gPackager )
				)
				( objectStatus "U2D1.AG6" )
			)
			( pin "@baseboard_fab2_lib.baseboard_fab2(sch_1):page67_i132:upi0_rx_dp(5)"
				( attribute "PN" "AF7"
					( Origin gPackager )
				)
				( objectStatus "U2D1.AF7" )
			)
			( pin "@baseboard_fab2_lib.baseboard_fab2(sch_1):page67_i132:upi0_rx_dp(6)"
				( attribute "PN" "AH7"
					( Origin gPackager )
				)
				( objectStatus "U2D1.AH7" )
			)
			( pin "@baseboard_fab2_lib.baseboard_fab2(sch_1):page67_i132:upi0_rx_dp(7)"
				( attribute "PN" "AK5"
					( Origin gPackager )
				)
				( objectStatus "U2D1.AK5" )
			)
			( pin "@baseboard_fab2_lib.baseboard_fab2(sch_1):page67_i132:upi0_rx_dp(8)"
				( attribute "PN" "AM7"
					( Origin gPackager )
				)
				( objectStatus "U2D1.AM7" )
			)
			( pin "@baseboard_fab2_lib.baseboard_fab2(sch_1):page67_i132:upi0_rx_dp(9)"
				( attribute "PN" "AL8"
					( Origin gPackager )
				)
				( objectStatus "U2D1.AL8" )
			)
			( pin "@baseboard_fab2_lib.baseboard_fab2(sch_1):page67_i132:upi0_rx_dp(10)"
				( attribute "PN" "AN8"
					( Origin gPackager )
				)
				( objectStatus "U2D1.AN8" )
			)
			( pin "@baseboard_fab2_lib.baseboard_fab2(sch_1):page67_i132:upi0_rx_dp(11)"
				( attribute "PN" "AU8"
					( Origin gPackager )
				)
				( objectStatus "U2D1.AU8" )
			)
			( pin "@baseboard_fab2_lib.baseboard_fab2(sch_1):page67_i132:upi0_rx_dp(12)"
				( attribute "PN" "AT9"
					( Origin gPackager )
				)
				( objectStatus "U2D1.AT9" )
			)
			( pin "@baseboard_fab2_lib.baseboard_fab2(sch_1):page67_i132:upi0_rx_dp(13)"
				( attribute "PN" "AY7"
					( Origin gPackager )
				)
				( objectStatus "U2D1.AY7" )
			)
			( pin "@baseboard_fab2_lib.baseboard_fab2(sch_1):page67_i132:upi0_rx_dp(14)"
				( attribute "PN" "BB7"
					( Origin gPackager )
				)
				( objectStatus "U2D1.BB7" )
			)
			( pin "@baseboard_fab2_lib.baseboard_fab2(sch_1):page67_i132:upi0_rx_dp(15)"
				( attribute "PN" "BF7"
					( Origin gPackager )
				)
				( objectStatus "U2D1.BF7" )
			)
			( pin "@baseboard_fab2_lib.baseboard_fab2(sch_1):page67_i132:upi0_rx_dp(16)"
				( attribute "PN" "AV9"
					( Origin gPackager )
				)
				( objectStatus "U2D1.AV9" )
			)
			( pin "@baseboard_fab2_lib.baseboard_fab2(sch_1):page67_i132:upi0_rx_dp(17)"
				( attribute "PN" "BB9"
					( Origin gPackager )
				)
				( objectStatus "U2D1.BB9" )
			)
			( pin "@baseboard_fab2_lib.baseboard_fab2(sch_1):page67_i132:upi0_rx_dp(18)"
				( attribute "PN" "BC10"
					( Origin gPackager )
				)
				( objectStatus "U2D1.BC10" )
			)
			( pin "@baseboard_fab2_lib.baseboard_fab2(sch_1):page67_i132:upi0_rx_dp(19)"
				( attribute "PN" "BA10"
					( Origin gPackager )
				)
				( objectStatus "U2D1.BA10" )
			)
			( pin "@baseboard_fab2_lib.baseboard_fab2(sch_1):page67_i132:upi0_tx_dn(0)"
				( attribute "PN" "N2"
					( Origin gPackager )
				)
				( objectStatus "U2D1.N2" )
			)
			( pin "@baseboard_fab2_lib.baseboard_fab2(sch_1):page67_i132:upi0_tx_dn(1)"
				( attribute "PN" "P1"
					( Origin gPackager )
				)
				( objectStatus "U2D1.P1" )
			)
			( pin "@baseboard_fab2_lib.baseboard_fab2(sch_1):page67_i132:upi0_tx_dn(2)"
				( attribute "PN" "V3"
					( Origin gPackager )
				)
				( objectStatus "U2D1.V3" )
			)
			( pin "@baseboard_fab2_lib.baseboard_fab2(sch_1):page67_i132:upi0_tx_dn(3)"
				( attribute "PN" "Y1"
					( Origin gPackager )
				)
				( objectStatus "U2D1.Y1" )
			)
			( pin "@baseboard_fab2_lib.baseboard_fab2(sch_1):page67_i132:upi0_tx_dn(4)"
				( attribute "PN" "AB3"
					( Origin gPackager )
				)
				( objectStatus "U2D1.AB3" )
			)
			( pin "@baseboard_fab2_lib.baseboard_fab2(sch_1):page67_i132:upi0_tx_dn(5)"
				( attribute "PN" "AC2"
					( Origin gPackager )
				)
				( objectStatus "U2D1.AC2" )
			)
			( pin "@baseboard_fab2_lib.baseboard_fab2(sch_1):page67_i132:upi0_tx_dn(6)"
				( attribute "PN" "AG4"
					( Origin gPackager )
				)
				( objectStatus "U2D1.AG4" )
			)
			( pin "@baseboard_fab2_lib.baseboard_fab2(sch_1):page67_i132:upi0_tx_dn(7)"
				( attribute "PN" "AE2"
					( Origin gPackager )
				)
				( objectStatus "U2D1.AE2" )
			)
			( pin "@baseboard_fab2_lib.baseboard_fab2(sch_1):page67_i132:upi0_tx_dn(8)"
				( attribute "PN" "AH3"
					( Origin gPackager )
				)
				( objectStatus "U2D1.AH3" )
			)
			( pin "@baseboard_fab2_lib.baseboard_fab2(sch_1):page67_i132:upi0_tx_dn(9)"
				( attribute "PN" "AL2"
					( Origin gPackager )
				)
				( objectStatus "U2D1.AL2" )
			)
			( pin "@baseboard_fab2_lib.baseboard_fab2(sch_1):page67_i132:upi0_tx_dn(10)"
				( attribute "PN" "AM3"
					( Origin gPackager )
				)
				( objectStatus "U2D1.AM3" )
			)
			( pin "@baseboard_fab2_lib.baseboard_fab2(sch_1):page67_i132:upi0_tx_dn(11)"
				( attribute "PN" "AN4"
					( Origin gPackager )
				)
				( objectStatus "U2D1.AN4" )
			)
			( pin "@baseboard_fab2_lib.baseboard_fab2(sch_1):page67_i132:upi0_tx_dn(12)"
				( attribute "PN" "AT1"
					( Origin gPackager )
				)
				( objectStatus "U2D1.AT1" )
			)
			( pin "@baseboard_fab2_lib.baseboard_fab2(sch_1):page67_i132:upi0_tx_dn(13)"
				( attribute "PN" "AT3"
					( Origin gPackager )
				)
				( objectStatus "U2D1.AT3" )
			)
			( pin "@baseboard_fab2_lib.baseboard_fab2(sch_1):page67_i132:upi0_tx_dn(14)"
				( attribute "PN" "AU4"
					( Origin gPackager )
				)
				( objectStatus "U2D1.AU4" )
			)
			( pin "@baseboard_fab2_lib.baseboard_fab2(sch_1):page67_i132:upi0_tx_dn(15)"
				( attribute "PN" "AV5"
					( Origin gPackager )
				)
				( objectStatus "U2D1.AV5" )
			)
			( pin "@baseboard_fab2_lib.baseboard_fab2(sch_1):page67_i132:upi0_tx_dn(16)"
				( attribute "PN" "BA4"
					( Origin gPackager )
				)
				( objectStatus "U2D1.BA4" )
			)
			( pin "@baseboard_fab2_lib.baseboard_fab2(sch_1):page67_i132:upi0_tx_dn(17)"
				( attribute "PN" "BB3"
					( Origin gPackager )
				)
				( objectStatus "U2D1.BB3" )
			)
			( pin "@baseboard_fab2_lib.baseboard_fab2(sch_1):page67_i132:upi0_tx_dn(18)"
				( attribute "PN" "BF3"
					( Origin gPackager )
				)
				( objectStatus "U2D1.BF3" )
			)
			( pin "@baseboard_fab2_lib.baseboard_fab2(sch_1):page67_i132:upi0_tx_dn(19)"
				( attribute "PN" "BG4"
					( Origin gPackager )
				)
				( objectStatus "U2D1.BG4" )
			)
			( pin "@baseboard_fab2_lib.baseboard_fab2(sch_1):page67_i132:upi0_tx_dp(0)"
				( attribute "PN" "M1"
					( Origin gPackager )
				)
				( objectStatus "U2D1.M1" )
			)
			( pin "@baseboard_fab2_lib.baseboard_fab2(sch_1):page67_i132:upi0_tx_dp(1)"
				( attribute "PN" "T1"
					( Origin gPackager )
				)
				( objectStatus "U2D1.T1" )
			)
			( pin "@baseboard_fab2_lib.baseboard_fab2(sch_1):page67_i132:upi0_tx_dp(2)"
				( attribute "PN" "Y3"
					( Origin gPackager )
				)
				( objectStatus "U2D1.Y3" )
			)
			( pin "@baseboard_fab2_lib.baseboard_fab2(sch_1):page67_i132:upi0_tx_dp(3)"
				( attribute "PN" "W2"
					( Origin gPackager )
				)
				( objectStatus "U2D1.W2" )
			)
			( pin "@baseboard_fab2_lib.baseboard_fab2(sch_1):page67_i132:upi0_tx_dp(4)"
				( attribute "PN" "AA2"
					( Origin gPackager )
				)
				( objectStatus "U2D1.AA2" )
			)
			( pin "@baseboard_fab2_lib.baseboard_fab2(sch_1):page67_i132:upi0_tx_dp(5)"
				( attribute "PN" "AD1"
					( Origin gPackager )
				)
				( objectStatus "U2D1.AD1" )
			)
			( pin "@baseboard_fab2_lib.baseboard_fab2(sch_1):page67_i132:upi0_tx_dp(6)"
				( attribute "PN" "AF3"
					( Origin gPackager )
				)
				( objectStatus "U2D1.AF3" )
			)
			( pin "@baseboard_fab2_lib.baseboard_fab2(sch_1):page67_i132:upi0_tx_dp(7)"
				( attribute "PN" "AG2"
					( Origin gPackager )
				)
				( objectStatus "U2D1.AG2" )
			)
			( pin "@baseboard_fab2_lib.baseboard_fab2(sch_1):page67_i132:upi0_tx_dp(8)"
				( attribute "PN" "AJ2"
					( Origin gPackager )
				)
				( objectStatus "U2D1.AJ2" )
			)
			( pin "@baseboard_fab2_lib.baseboard_fab2(sch_1):page67_i132:upi0_tx_dp(9)"
				( attribute "PN" "AK1"
					( Origin gPackager )
				)
				( objectStatus "U2D1.AK1" )
			)
			( pin "@baseboard_fab2_lib.baseboard_fab2(sch_1):page67_i132:upi0_tx_dp(10)"
				( attribute "PN" "AK3"
					( Origin gPackager )
				)
				( objectStatus "U2D1.AK3" )
			)
			( pin "@baseboard_fab2_lib.baseboard_fab2(sch_1):page67_i132:upi0_tx_dp(11)"
				( attribute "PN" "AP3"
					( Origin gPackager )
				)
				( objectStatus "U2D1.AP3" )
			)
			( pin "@baseboard_fab2_lib.baseboard_fab2(sch_1):page67_i132:upi0_tx_dp(12)"
				( attribute "PN" "AP1"
					( Origin gPackager )
				)
				( objectStatus "U2D1.AP1" )
			)
			( pin "@baseboard_fab2_lib.baseboard_fab2(sch_1):page67_i132:upi0_tx_dp(13)"
				( attribute "PN" "AR2"
					( Origin gPackager )
				)
				( objectStatus "U2D1.AR2" )
			)
			( pin "@baseboard_fab2_lib.baseboard_fab2(sch_1):page67_i132:upi0_tx_dp(14)"
				( attribute "PN" "AR4"
					( Origin gPackager )
				)
				( objectStatus "U2D1.AR4" )
			)
			( pin "@baseboard_fab2_lib.baseboard_fab2(sch_1):page67_i132:upi0_tx_dp(15)"
				( attribute "PN" "AW4"
					( Origin gPackager )
				)
				( objectStatus "U2D1.AW4" )
			)
			( pin "@baseboard_fab2_lib.baseboard_fab2(sch_1):page67_i132:upi0_tx_dp(16)"
				( attribute "PN" "AY3"
					( Origin gPackager )
				)
				( objectStatus "U2D1.AY3" )
			)
			( pin "@baseboard_fab2_lib.baseboard_fab2(sch_1):page67_i132:upi0_tx_dp(17)"
				( attribute "PN" "BC2"
					( Origin gPackager )
				)
				( objectStatus "U2D1.BC2" )
			)
			( pin "@baseboard_fab2_lib.baseboard_fab2(sch_1):page67_i132:upi0_tx_dp(18)"
				( attribute "PN" "BD3"
					( Origin gPackager )
				)
				( objectStatus "U2D1.BD3" )
			)
			( pin "@baseboard_fab2_lib.baseboard_fab2(sch_1):page67_i132:upi0_tx_dp(19)"
				( attribute "PN" "BH3"
					( Origin gPackager )
				)
				( objectStatus "U2D1.BH3" )
			)
			( pin "@baseboard_fab2_lib.baseboard_fab2(sch_1):page68_i125:upi1_rx_dn(0)"
				( attribute "PN" "T5"
					( Origin gPackager )
				)
				( objectStatus "U2D1.T5" )
			)
			( pin "@baseboard_fab2_lib.baseboard_fab2(sch_1):page68_i125:upi1_rx_dn(1)"
				( attribute "PN" "P7"
					( Origin gPackager )
				)
				( objectStatus "U2D1.P7" )
			)
			( pin "@baseboard_fab2_lib.baseboard_fab2(sch_1):page68_i125:upi1_rx_dn(2)"
				( attribute "PN" "V7"
					( Origin gPackager )
				)
				( objectStatus "U2D1.V7" )
			)
			( pin "@baseboard_fab2_lib.baseboard_fab2(sch_1):page68_i125:upi1_rx_dn(3)"
				( attribute "PN" "T9"
					( Origin gPackager )
				)
				( objectStatus "U2D1.T9" )
			)
			( pin "@baseboard_fab2_lib.baseboard_fab2(sch_1):page68_i125:upi1_rx_dn(4)"
				( attribute "PN" "P9"
					( Origin gPackager )
				)
				( objectStatus "U2D1.P9" )
			)
			( pin "@baseboard_fab2_lib.baseboard_fab2(sch_1):page68_i125:upi1_rx_dn(5)"
				( attribute "PN" "R10"
					( Origin gPackager )
				)
				( objectStatus "U2D1.R10" )
			)
			( pin "@baseboard_fab2_lib.baseboard_fab2(sch_1):page68_i125:upi1_rx_dn(6)"
				( attribute "PN" "U12"
					( Origin gPackager )
				)
				( objectStatus "U2D1.U12" )
			)
			( pin "@baseboard_fab2_lib.baseboard_fab2(sch_1):page68_i125:upi1_rx_dn(7)"
				( attribute "PN" "L12"
					( Origin gPackager )
				)
				( objectStatus "U2D1.L12" )
			)
			( pin "@baseboard_fab2_lib.baseboard_fab2(sch_1):page68_i125:upi1_rx_dn(8)"
				( attribute "PN" "N14"
					( Origin gPackager )
				)
				( objectStatus "U2D1.N14" )
			)
			( pin "@baseboard_fab2_lib.baseboard_fab2(sch_1):page68_i125:upi1_rx_dn(9)"
				( attribute "PN" "R12"
					( Origin gPackager )
				)
				( objectStatus "U2D1.R12" )
			)
			( pin "@baseboard_fab2_lib.baseboard_fab2(sch_1):page68_i125:upi1_rx_dn(10)"
				( attribute "PN" "R16"
					( Origin gPackager )
				)
				( objectStatus "U2D1.R16" )
			)
			( pin "@baseboard_fab2_lib.baseboard_fab2(sch_1):page68_i125:upi1_rx_dn(11)"
				( attribute "PN" "P17"
					( Origin gPackager )
				)
				( objectStatus "U2D1.P17" )
			)
			( pin "@baseboard_fab2_lib.baseboard_fab2(sch_1):page68_i125:upi1_rx_dn(12)"
				( attribute "PN" "U16"
					( Origin gPackager )
				)
				( objectStatus "U2D1.U16" )
			)
			( pin "@baseboard_fab2_lib.baseboard_fab2(sch_1):page68_i125:upi1_rx_dn(13)"
				( attribute "PN" "W18"
					( Origin gPackager )
				)
				( objectStatus "U2D1.W18" )
			)
			( pin "@baseboard_fab2_lib.baseboard_fab2(sch_1):page68_i125:upi1_rx_dn(14)"
				( attribute "PN" "R20"
					( Origin gPackager )
				)
				( objectStatus "U2D1.R20" )
			)
			( pin "@baseboard_fab2_lib.baseboard_fab2(sch_1):page68_i125:upi1_rx_dn(15)"
				( attribute "PN" "U18"
					( Origin gPackager )
				)
				( objectStatus "U2D1.U18" )
			)
			( pin "@baseboard_fab2_lib.baseboard_fab2(sch_1):page68_i125:upi1_rx_dn(16)"
				( attribute "PN" "P21"
					( Origin gPackager )
				)
				( objectStatus "U2D1.P21" )
			)
			( pin "@baseboard_fab2_lib.baseboard_fab2(sch_1):page68_i125:upi1_rx_dn(17)"
				( attribute "PN" "V19"
					( Origin gPackager )
				)
				( objectStatus "U2D1.V19" )
			)
			( pin "@baseboard_fab2_lib.baseboard_fab2(sch_1):page68_i125:upi1_rx_dn(18)"
				( attribute "PN" "Y21"
					( Origin gPackager )
				)
				( objectStatus "U2D1.Y21" )
			)
			( pin "@baseboard_fab2_lib.baseboard_fab2(sch_1):page68_i125:upi1_rx_dn(19)"
				( attribute "PN" "AB19"
					( Origin gPackager )
				)
				( objectStatus "U2D1.AB19" )
			)
			( pin "@baseboard_fab2_lib.baseboard_fab2(sch_1):page68_i125:upi1_rx_dp(0)"
				( attribute "PN" "R6"
					( Origin gPackager )
				)
				( objectStatus "U2D1.R6" )
			)
			( pin "@baseboard_fab2_lib.baseboard_fab2(sch_1):page68_i125:upi1_rx_dp(1)"
				( attribute "PN" "T7"
					( Origin gPackager )
				)
				( objectStatus "U2D1.T7" )
			)
			( pin "@baseboard_fab2_lib.baseboard_fab2(sch_1):page68_i125:upi1_rx_dp(2)"
				( attribute "PN" "U8"
					( Origin gPackager )
				)
				( objectStatus "U2D1.U8" )
			)
			( pin "@baseboard_fab2_lib.baseboard_fab2(sch_1):page68_i125:upi1_rx_dp(3)"
				( attribute "PN" "R8"
					( Origin gPackager )
				)
				( objectStatus "U2D1.R8" )
			)
			( pin "@baseboard_fab2_lib.baseboard_fab2(sch_1):page68_i125:upi1_rx_dp(4)"
				( attribute "PN" "N10"
					( Origin gPackager )
				)
				( objectStatus "U2D1.N10" )
			)
			( pin "@baseboard_fab2_lib.baseboard_fab2(sch_1):page68_i125:upi1_rx_dp(5)"
				( attribute "PN" "U10"
					( Origin gPackager )
				)
				( objectStatus "U2D1.U10" )
			)
			( pin "@baseboard_fab2_lib.baseboard_fab2(sch_1):page68_i125:upi1_rx_dp(6)"
				( attribute "PN" "T11"
					( Origin gPackager )
				)
				( objectStatus "U2D1.T11" )
			)
			( pin "@baseboard_fab2_lib.baseboard_fab2(sch_1):page68_i125:upi1_rx_dp(7)"
				( attribute "PN" "N12"
					( Origin gPackager )
				)
				( objectStatus "U2D1.N12" )
			)
			( pin "@baseboard_fab2_lib.baseboard_fab2(sch_1):page68_i125:upi1_rx_dp(8)"
				( attribute "PN" "M13"
					( Origin gPackager )
				)
				( objectStatus "U2D1.M13" )
			)
			( pin "@baseboard_fab2_lib.baseboard_fab2(sch_1):page68_i125:upi1_rx_dp(9)"
				( attribute "PN" "P13"
					( Origin gPackager )
				)
				( objectStatus "U2D1.P13" )
			)
			( pin "@baseboard_fab2_lib.baseboard_fab2(sch_1):page68_i125:upi1_rx_dp(10)"
				( attribute "PN" "T15"
					( Origin gPackager )
				)
				( objectStatus "U2D1.T15" )
			)
			( pin "@baseboard_fab2_lib.baseboard_fab2(sch_1):page68_i125:upi1_rx_dp(11)"
				( attribute "PN" "N16"
					( Origin gPackager )
				)
				( objectStatus "U2D1.N16" )
			)
			( pin "@baseboard_fab2_lib.baseboard_fab2(sch_1):page68_i125:upi1_rx_dp(12)"
				( attribute "PN" "W16"
					( Origin gPackager )
				)
				( objectStatus "U2D1.W16" )
			)
			( pin "@baseboard_fab2_lib.baseboard_fab2(sch_1):page68_i125:upi1_rx_dp(13)"
				( attribute "PN" "V17"
					( Origin gPackager )
				)
				( objectStatus "U2D1.V17" )
			)
			( pin "@baseboard_fab2_lib.baseboard_fab2(sch_1):page68_i125:upi1_rx_dp(14)"
				( attribute "PN" "P19"
					( Origin gPackager )
				)
				( objectStatus "U2D1.P19" )
			)
			( pin "@baseboard_fab2_lib.baseboard_fab2(sch_1):page68_i125:upi1_rx_dp(15)"
				( attribute "PN" "T19"
					( Origin gPackager )
				)
				( objectStatus "U2D1.T19" )
			)
			( pin "@baseboard_fab2_lib.baseboard_fab2(sch_1):page68_i125:upi1_rx_dp(16)"
				( attribute "PN" "T21"
					( Origin gPackager )
				)
				( objectStatus "U2D1.T21" )
			)
			( pin "@baseboard_fab2_lib.baseboard_fab2(sch_1):page68_i125:upi1_rx_dp(17)"
				( attribute "PN" "Y19"
					( Origin gPackager )
				)
				( objectStatus "U2D1.Y19" )
			)
			( pin "@baseboard_fab2_lib.baseboard_fab2(sch_1):page68_i125:upi1_rx_dp(18)"
				( attribute "PN" "W20"
					( Origin gPackager )
				)
				( objectStatus "U2D1.W20" )
			)
			( pin "@baseboard_fab2_lib.baseboard_fab2(sch_1):page68_i125:upi1_rx_dp(19)"
				( attribute "PN" "AA20"
					( Origin gPackager )
				)
				( objectStatus "U2D1.AA20" )
			)
			( pin "@baseboard_fab2_lib.baseboard_fab2(sch_1):page68_i125:upi1_tx_dn(0)"
				( attribute "PN" "M3"
					( Origin gPackager )
				)
				( objectStatus "U2D1.M3" )
			)
			( pin "@baseboard_fab2_lib.baseboard_fab2(sch_1):page68_i125:upi1_tx_dn(1)"
				( attribute "PN" "L4"
					( Origin gPackager )
				)
				( objectStatus "U2D1.L4" )
			)
			( pin "@baseboard_fab2_lib.baseboard_fab2(sch_1):page68_i125:upi1_tx_dn(2)"
				( attribute "PN" "K5"
					( Origin gPackager )
				)
				( objectStatus "U2D1.K5" )
			)
			( pin "@baseboard_fab2_lib.baseboard_fab2(sch_1):page68_i125:upi1_tx_dn(3)"
				( attribute "PN" "J6"
					( Origin gPackager )
				)
				( objectStatus "U2D1.J6" )
			)
			( pin "@baseboard_fab2_lib.baseboard_fab2(sch_1):page68_i125:upi1_tx_dn(4)"
				( attribute "PN" "G6"
					( Origin gPackager )
				)
				( objectStatus "U2D1.G6" )
			)
			( pin "@baseboard_fab2_lib.baseboard_fab2(sch_1):page68_i125:upi1_tx_dn(5)"
				( attribute "PN" "H7"
					( Origin gPackager )
				)
				( objectStatus "U2D1.H7" )
			)
			( pin "@baseboard_fab2_lib.baseboard_fab2(sch_1):page68_i125:upi1_tx_dn(6)"
				( attribute "PN" "K9"
					( Origin gPackager )
				)
				( objectStatus "U2D1.K9" )
			)
			( pin "@baseboard_fab2_lib.baseboard_fab2(sch_1):page68_i125:upi1_tx_dn(7)"
				( attribute "PN" "D9"
					( Origin gPackager )
				)
				( objectStatus "U2D1.D9" )
			)
			( pin "@baseboard_fab2_lib.baseboard_fab2(sch_1):page68_i125:upi1_tx_dn(8)"
				( attribute "PN" "F11"
					( Origin gPackager )
				)
				( objectStatus "U2D1.F11" )
			)
			( pin "@baseboard_fab2_lib.baseboard_fab2(sch_1):page68_i125:upi1_tx_dn(9)"
				( attribute "PN" "G10"
					( Origin gPackager )
				)
				( objectStatus "U2D1.G10" )
			)
			( pin "@baseboard_fab2_lib.baseboard_fab2(sch_1):page68_i125:upi1_tx_dn(10)"
				( attribute "PN" "E12"
					( Origin gPackager )
				)
				( objectStatus "U2D1.E12" )
			)
			( pin "@baseboard_fab2_lib.baseboard_fab2(sch_1):page68_i125:upi1_tx_dn(11)"
				( attribute "PN" "G14"
					( Origin gPackager )
				)
				( objectStatus "U2D1.G14" )
			)
			( pin "@baseboard_fab2_lib.baseboard_fab2(sch_1):page68_i125:upi1_tx_dn(12)"
				( attribute "PN" "D15"
					( Origin gPackager )
				)
				( objectStatus "U2D1.D15" )
			)
			( pin "@baseboard_fab2_lib.baseboard_fab2(sch_1):page68_i125:upi1_tx_dn(13)"
				( attribute "PN" "F15"
					( Origin gPackager )
				)
				( objectStatus "U2D1.F15" )
			)
			( pin "@baseboard_fab2_lib.baseboard_fab2(sch_1):page68_i125:upi1_tx_dn(14)"
				( attribute "PN" "H17"
					( Origin gPackager )
				)
				( objectStatus "U2D1.H17" )
			)
			( pin "@baseboard_fab2_lib.baseboard_fab2(sch_1):page68_i125:upi1_tx_dn(15)"
				( attribute "PN" "K19"
					( Origin gPackager )
				)
				( objectStatus "U2D1.K19" )
			)
			( pin "@baseboard_fab2_lib.baseboard_fab2(sch_1):page68_i125:upi1_tx_dn(16)"
				( attribute "PN" "G18"
					( Origin gPackager )
				)
				( objectStatus "U2D1.G18" )
			)
			( pin "@baseboard_fab2_lib.baseboard_fab2(sch_1):page68_i125:upi1_tx_dn(17)"
				( attribute "PN" "J20"
					( Origin gPackager )
				)
				( objectStatus "U2D1.J20" )
			)
			( pin "@baseboard_fab2_lib.baseboard_fab2(sch_1):page68_i125:upi1_tx_dn(18)"
				( attribute "PN" "F21"
					( Origin gPackager )
				)
				( objectStatus "U2D1.F21" )
			)
			( pin "@baseboard_fab2_lib.baseboard_fab2(sch_1):page68_i125:upi1_tx_dn(19)"
				( attribute "PN" "H21"
					( Origin gPackager )
				)
				( objectStatus "U2D1.H21" )
			)
			( pin "@baseboard_fab2_lib.baseboard_fab2(sch_1):page68_i125:upi1_tx_dp(0)"
				( attribute "PN" "P3"
					( Origin gPackager )
				)
				( objectStatus "U2D1.P3" )
			)
			( pin "@baseboard_fab2_lib.baseboard_fab2(sch_1):page68_i125:upi1_tx_dp(1)"
				( attribute "PN" "K3"
					( Origin gPackager )
				)
				( objectStatus "U2D1.K3" )
			)
			( pin "@baseboard_fab2_lib.baseboard_fab2(sch_1):page68_i125:upi1_tx_dp(2)"
				( attribute "PN" "M5"
					( Origin gPackager )
				)
				( objectStatus "U2D1.M5" )
			)
			( pin "@baseboard_fab2_lib.baseboard_fab2(sch_1):page68_i125:upi1_tx_dp(3)"
				( attribute "PN" "H5"
					( Origin gPackager )
				)
				( objectStatus "U2D1.H5" )
			)
			( pin "@baseboard_fab2_lib.baseboard_fab2(sch_1):page68_i125:upi1_tx_dp(4)"
				( attribute "PN" "F7"
					( Origin gPackager )
				)
				( objectStatus "U2D1.F7" )
			)
			( pin "@baseboard_fab2_lib.baseboard_fab2(sch_1):page68_i125:upi1_tx_dp(5)"
				( attribute "PN" "K7"
					( Origin gPackager )
				)
				( objectStatus "U2D1.K7" )
			)
			( pin "@baseboard_fab2_lib.baseboard_fab2(sch_1):page68_i125:upi1_tx_dp(6)"
				( attribute "PN" "J8"
					( Origin gPackager )
				)
				( objectStatus "U2D1.J8" )
			)
			( pin "@baseboard_fab2_lib.baseboard_fab2(sch_1):page68_i125:upi1_tx_dp(7)"
				( attribute "PN" "F9"
					( Origin gPackager )
				)
				( objectStatus "U2D1.F9" )
			)
			( pin "@baseboard_fab2_lib.baseboard_fab2(sch_1):page68_i125:upi1_tx_dp(8)"
				( attribute "PN" "E10"
					( Origin gPackager )
				)
				( objectStatus "U2D1.E10" )
			)
			( pin "@baseboard_fab2_lib.baseboard_fab2(sch_1):page68_i125:upi1_tx_dp(9)"
				( attribute "PN" "H9"
					( Origin gPackager )
				)
				( objectStatus "U2D1.H9" )
			)
			( pin "@baseboard_fab2_lib.baseboard_fab2(sch_1):page68_i125:upi1_tx_dp(10)"
				( attribute "PN" "G12"
					( Origin gPackager )
				)
				( objectStatus "U2D1.G12" )
			)
			( pin "@baseboard_fab2_lib.baseboard_fab2(sch_1):page68_i125:upi1_tx_dp(11)"
				( attribute "PN" "F13"
					( Origin gPackager )
				)
				( objectStatus "U2D1.F13" )
			)
			( pin "@baseboard_fab2_lib.baseboard_fab2(sch_1):page68_i125:upi1_tx_dp(12)"
				( attribute "PN" "E14"
					( Origin gPackager )
				)
				( objectStatus "U2D1.E14" )
			)
			( pin "@baseboard_fab2_lib.baseboard_fab2(sch_1):page68_i125:upi1_tx_dp(13)"
				( attribute "PN" "H15"
					( Origin gPackager )
				)
				( objectStatus "U2D1.H15" )
			)
			( pin "@baseboard_fab2_lib.baseboard_fab2(sch_1):page68_i125:upi1_tx_dp(14)"
				( attribute "PN" "G16"
					( Origin gPackager )
				)
				( objectStatus "U2D1.G16" )
			)
			( pin "@baseboard_fab2_lib.baseboard_fab2(sch_1):page68_i125:upi1_tx_dp(15)"
				( attribute "PN" "L18"
					( Origin gPackager )
				)
				( objectStatus "U2D1.L18" )
			)
			( pin "@baseboard_fab2_lib.baseboard_fab2(sch_1):page68_i125:upi1_tx_dp(16)"
				( attribute "PN" "J18"
					( Origin gPackager )
				)
				( objectStatus "U2D1.J18" )
			)
			( pin "@baseboard_fab2_lib.baseboard_fab2(sch_1):page68_i125:upi1_tx_dp(17)"
				( attribute "PN" "H19"
					( Origin gPackager )
				)
				( objectStatus "U2D1.H19" )
			)
			( pin "@baseboard_fab2_lib.baseboard_fab2(sch_1):page68_i125:upi1_tx_dp(18)"
				( attribute "PN" "G20"
					( Origin gPackager )
				)
				( objectStatus "U2D1.G20" )
			)
			( pin "@baseboard_fab2_lib.baseboard_fab2(sch_1):page68_i125:upi1_tx_dp(19)"
				( attribute "PN" "K21"
					( Origin gPackager )
				)
				( objectStatus "U2D1.K21" )
			)
			( pin "@baseboard_fab2_lib.baseboard_fab2(sch_1):page69_i1:upi2_rx_dn(0)"
				( attribute "PN" "DF23"
					( Origin gPackager )
				)
				( objectStatus "U2D1.DF23" )
			)
			( pin "@baseboard_fab2_lib.baseboard_fab2(sch_1):page69_i1:upi2_rx_dn(1)"
				( attribute "PN" "DE22"
					( Origin gPackager )
				)
				( objectStatus "U2D1.DE22" )
			)
			( pin "@baseboard_fab2_lib.baseboard_fab2(sch_1):page69_i1:upi2_rx_dn(2)"
				( attribute "PN" "DC22"
					( Origin gPackager )
				)
				( objectStatus "U2D1.DC22" )
			)
			( pin "@baseboard_fab2_lib.baseboard_fab2(sch_1):page69_i1:upi2_rx_dn(3)"
				( attribute "PN" "DB21"
					( Origin gPackager )
				)
				( objectStatus "U2D1.DB21" )
			)
			( pin "@baseboard_fab2_lib.baseboard_fab2(sch_1):page69_i1:upi2_rx_dn(4)"
				( attribute "PN" "DD19"
					( Origin gPackager )
				)
				( objectStatus "U2D1.DD19" )
			)
			( pin "@baseboard_fab2_lib.baseboard_fab2(sch_1):page69_i1:upi2_rx_dn(5)"
				( attribute "PN" "DA20"
					( Origin gPackager )
				)
				( objectStatus "U2D1.DA20" )
			)
			( pin "@baseboard_fab2_lib.baseboard_fab2(sch_1):page69_i1:upi2_rx_dn(6)"
				( attribute "PN" "CW20"
					( Origin gPackager )
				)
				( objectStatus "U2D1.CW20" )
			)
			( pin "@baseboard_fab2_lib.baseboard_fab2(sch_1):page69_i1:upi2_rx_dn(7)"
				( attribute "PN" "CV19"
					( Origin gPackager )
				)
				( objectStatus "U2D1.CV19" )
			)
			( pin "@baseboard_fab2_lib.baseboard_fab2(sch_1):page69_i1:upi2_rx_dn(8)"
				( attribute "PN" "CT21"
					( Origin gPackager )
				)
				( objectStatus "U2D1.CT21" )
			)
			( pin "@baseboard_fab2_lib.baseboard_fab2(sch_1):page69_i1:upi2_rx_dn(9)"
				( attribute "PN" "CR18"
					( Origin gPackager )
				)
				( objectStatus "U2D1.CR18" )
			)
			( pin "@baseboard_fab2_lib.baseboard_fab2(sch_1):page69_i1:upi2_rx_dn(10)"
				( attribute "PN" "CN20"
					( Origin gPackager )
				)
				( objectStatus "U2D1.CN20" )
			)
			( pin "@baseboard_fab2_lib.baseboard_fab2(sch_1):page69_i1:upi2_rx_dn(11)"
				( attribute "PN" "CP21"
					( Origin gPackager )
				)
				( objectStatus "U2D1.CP21" )
			)
			( pin "@baseboard_fab2_lib.baseboard_fab2(sch_1):page69_i1:upi2_rx_dn(12)"
				( attribute "PN" "CL16"
					( Origin gPackager )
				)
				( objectStatus "U2D1.CL16" )
			)
			( pin "@baseboard_fab2_lib.baseboard_fab2(sch_1):page69_i1:upi2_rx_dn(13)"
				( attribute "PN" "CJ18"
					( Origin gPackager )
				)
				( objectStatus "U2D1.CJ18" )
			)
			( pin "@baseboard_fab2_lib.baseboard_fab2(sch_1):page69_i1:upi2_rx_dn(14)"
				( attribute "PN" "CH17"
					( Origin gPackager )
				)
				( objectStatus "U2D1.CH17" )
			)
			( pin "@baseboard_fab2_lib.baseboard_fab2(sch_1):page69_i1:upi2_rx_dn(15)"
				( attribute "PN" "CE16"
					( Origin gPackager )
				)
				( objectStatus "U2D1.CE16" )
			)
			( pin "@baseboard_fab2_lib.baseboard_fab2(sch_1):page69_i1:upi2_rx_dn(16)"
				( attribute "PN" "CD15"
					( Origin gPackager )
				)
				( objectStatus "U2D1.CD15" )
			)
			( pin "@baseboard_fab2_lib.baseboard_fab2(sch_1):page69_i1:upi2_rx_dn(17)"
				( attribute "PN" "CF17"
					( Origin gPackager )
				)
				( objectStatus "U2D1.CF17" )
			)
			( pin "@baseboard_fab2_lib.baseboard_fab2(sch_1):page69_i1:upi2_rx_dn(18)"
				( attribute "PN" "CB15"
					( Origin gPackager )
				)
				( objectStatus "U2D1.CB15" )
			)
			( pin "@baseboard_fab2_lib.baseboard_fab2(sch_1):page69_i1:upi2_rx_dn(19)"
				( attribute "PN" "BY17"
					( Origin gPackager )
				)
				( objectStatus "U2D1.BY17" )
			)
			( pin "@baseboard_fab2_lib.baseboard_fab2(sch_1):page69_i1:upi2_rx_dp(0)"
				( attribute "PN" "DG22"
					( Origin gPackager )
				)
				( objectStatus "U2D1.DG22" )
			)
			( pin "@baseboard_fab2_lib.baseboard_fab2(sch_1):page69_i1:upi2_rx_dp(1)"
				( attribute "PN" "DD21"
					( Origin gPackager )
				)
				( objectStatus "U2D1.DD21" )
			)
			( pin "@baseboard_fab2_lib.baseboard_fab2(sch_1):page69_i1:upi2_rx_dp(2)"
				( attribute "PN" "DA22"
					( Origin gPackager )
				)
				( objectStatus "U2D1.DA22" )
			)
			( pin "@baseboard_fab2_lib.baseboard_fab2(sch_1):page69_i1:upi2_rx_dp(3)"
				( attribute "PN" "DC20"
					( Origin gPackager )
				)
				( objectStatus "U2D1.DC20" )
			)
			( pin "@baseboard_fab2_lib.baseboard_fab2(sch_1):page69_i1:upi2_rx_dp(4)"
				( attribute "PN" "DB19"
					( Origin gPackager )
				)
				( objectStatus "U2D1.DB19" )
			)
			( pin "@baseboard_fab2_lib.baseboard_fab2(sch_1):page69_i1:upi2_rx_dp(5)"
				( attribute "PN" "CY19"
					( Origin gPackager )
				)
				( objectStatus "U2D1.CY19" )
			)
			( pin "@baseboard_fab2_lib.baseboard_fab2(sch_1):page69_i1:upi2_rx_dp(6)"
				( attribute "PN" "CU20"
					( Origin gPackager )
				)
				( objectStatus "U2D1.CU20" )
			)
			( pin "@baseboard_fab2_lib.baseboard_fab2(sch_1):page69_i1:upi2_rx_dp(7)"
				( attribute "PN" "CW18"
					( Origin gPackager )
				)
				( objectStatus "U2D1.CW18" )
			)
			( pin "@baseboard_fab2_lib.baseboard_fab2(sch_1):page69_i1:upi2_rx_dp(8)"
				( attribute "PN" "CR20"
					( Origin gPackager )
				)
				( objectStatus "U2D1.CR20" )
			)
			( pin "@baseboard_fab2_lib.baseboard_fab2(sch_1):page69_i1:upi2_rx_dp(9)"
				( attribute "PN" "CN18"
					( Origin gPackager )
				)
				( objectStatus "U2D1.CN18" )
			)
			( pin "@baseboard_fab2_lib.baseboard_fab2(sch_1):page69_i1:upi2_rx_dp(10)"
				( attribute "PN" "CP19"
					( Origin gPackager )
				)
				( objectStatus "U2D1.CP19" )
			)
			( pin "@baseboard_fab2_lib.baseboard_fab2(sch_1):page69_i1:upi2_rx_dp(11)"
				( attribute "PN" "CM21"
					( Origin gPackager )
				)
				( objectStatus "U2D1.CM21" )
			)
			( pin "@baseboard_fab2_lib.baseboard_fab2(sch_1):page69_i1:upi2_rx_dp(12)"
				( attribute "PN" "CJ16"
					( Origin gPackager )
				)
				( objectStatus "U2D1.CJ16" )
			)
			( pin "@baseboard_fab2_lib.baseboard_fab2(sch_1):page69_i1:upi2_rx_dp(13)"
				( attribute "PN" "CK17"
					( Origin gPackager )
				)
				( objectStatus "U2D1.CK17" )
			)
			( pin "@baseboard_fab2_lib.baseboard_fab2(sch_1):page69_i1:upi2_rx_dp(14)"
				( attribute "PN" "CG16"
					( Origin gPackager )
				)
				( objectStatus "U2D1.CG16" )
			)
			( pin "@baseboard_fab2_lib.baseboard_fab2(sch_1):page69_i1:upi2_rx_dp(15)"
				( attribute "PN" "CF15"
					( Origin gPackager )
				)
				( objectStatus "U2D1.CF15" )
			)
			( pin "@baseboard_fab2_lib.baseboard_fab2(sch_1):page69_i1:upi2_rx_dp(16)"
				( attribute "PN" "CC14"
					( Origin gPackager )
				)
				( objectStatus "U2D1.CC14" )
			)
			( pin "@baseboard_fab2_lib.baseboard_fab2(sch_1):page69_i1:upi2_rx_dp(17)"
				( attribute "PN" "CD17"
					( Origin gPackager )
				)
				( objectStatus "U2D1.CD17" )
			)
			( pin "@baseboard_fab2_lib.baseboard_fab2(sch_1):page69_i1:upi2_rx_dp(18)"
				( attribute "PN" "BY15"
					( Origin gPackager )
				)
				( objectStatus "U2D1.BY15" )
			)
			( pin "@baseboard_fab2_lib.baseboard_fab2(sch_1):page69_i1:upi2_rx_dp(19)"
				( attribute "PN" "CA16"
					( Origin gPackager )
				)
				( objectStatus "U2D1.CA16" )
			)
			( pin "@baseboard_fab2_lib.baseboard_fab2(sch_1):page69_i1:upi2_tx_dn(0)"
				( attribute "PN" "DT21"
					( Origin gPackager )
				)
				( objectStatus "U2D1.DT21" )
			)
			( pin "@baseboard_fab2_lib.baseboard_fab2(sch_1):page69_i1:upi2_tx_dn(1)"
				( attribute "PN" "DM21"
					( Origin gPackager )
				)
				( objectStatus "U2D1.DM21" )
			)
			( pin "@baseboard_fab2_lib.baseboard_fab2(sch_1):page69_i1:upi2_tx_dn(2)"
				( attribute "PN" "DL20"
					( Origin gPackager )
				)
				( objectStatus "U2D1.DL20" )
			)
			( pin "@baseboard_fab2_lib.baseboard_fab2(sch_1):page69_i1:upi2_tx_dn(3)"
				( attribute "PN" "DG20"
					( Origin gPackager )
				)
				( objectStatus "U2D1.DG20" )
			)
			( pin "@baseboard_fab2_lib.baseboard_fab2(sch_1):page69_i1:upi2_tx_dn(4)"
				( attribute "PN" "DH19"
					( Origin gPackager )
				)
				( objectStatus "U2D1.DH19" )
			)
			( pin "@baseboard_fab2_lib.baseboard_fab2(sch_1):page69_i1:upi2_tx_dn(5)"
				( attribute "PN" "DK17"
					( Origin gPackager )
				)
				( objectStatus "U2D1.DK17" )
			)
			( pin "@baseboard_fab2_lib.baseboard_fab2(sch_1):page69_i1:upi2_tx_dn(6)"
				( attribute "PN" "DG18"
					( Origin gPackager )
				)
				( objectStatus "U2D1.DG18" )
			)
			( pin "@baseboard_fab2_lib.baseboard_fab2(sch_1):page69_i1:upi2_tx_dn(7)"
				( attribute "PN" "DD17"
					( Origin gPackager )
				)
				( objectStatus "U2D1.DD17" )
			)
			( pin "@baseboard_fab2_lib.baseboard_fab2(sch_1):page69_i1:upi2_tx_dn(8)"
				( attribute "PN" "DF15"
					( Origin gPackager )
				)
				( objectStatus "U2D1.DF15" )
			)
			( pin "@baseboard_fab2_lib.baseboard_fab2(sch_1):page69_i1:upi2_tx_dn(9)"
				( attribute "PN" "DC16"
					( Origin gPackager )
				)
				( objectStatus "U2D1.DC16" )
			)
			( pin "@baseboard_fab2_lib.baseboard_fab2(sch_1):page69_i1:upi2_tx_dn(10)"
				( attribute "PN" "DA16"
					( Origin gPackager )
				)
				( objectStatus "U2D1.DA16" )
			)
			( pin "@baseboard_fab2_lib.baseboard_fab2(sch_1):page69_i1:upi2_tx_dn(11)"
				( attribute "PN" "CW14"
					( Origin gPackager )
				)
				( objectStatus "U2D1.CW14" )
			)
			( pin "@baseboard_fab2_lib.baseboard_fab2(sch_1):page69_i1:upi2_tx_dn(12)"
				( attribute "PN" "CU14"
					( Origin gPackager )
				)
				( objectStatus "U2D1.CU14" )
			)
			( pin "@baseboard_fab2_lib.baseboard_fab2(sch_1):page69_i1:upi2_tx_dn(13)"
				( attribute "PN" "CM13"
					( Origin gPackager )
				)
				( objectStatus "U2D1.CM13" )
			)
			( pin "@baseboard_fab2_lib.baseboard_fab2(sch_1):page69_i1:upi2_tx_dn(14)"
				( attribute "PN" "CJ14"
					( Origin gPackager )
				)
				( objectStatus "U2D1.CJ14" )
			)
			( pin "@baseboard_fab2_lib.baseboard_fab2(sch_1):page69_i1:upi2_tx_dn(15)"
				( attribute "PN" "CF13"
					( Origin gPackager )
				)
				( objectStatus "U2D1.CF13" )
			)
			( pin "@baseboard_fab2_lib.baseboard_fab2(sch_1):page69_i1:upi2_tx_dn(16)"
				( attribute "PN" "CH11"
					( Origin gPackager )
				)
				( objectStatus "U2D1.CH11" )
			)
			( pin "@baseboard_fab2_lib.baseboard_fab2(sch_1):page69_i1:upi2_tx_dn(17)"
				( attribute "PN" "CE12"
					( Origin gPackager )
				)
				( objectStatus "U2D1.CE12" )
			)
			( pin "@baseboard_fab2_lib.baseboard_fab2(sch_1):page69_i1:upi2_tx_dn(18)"
				( attribute "PN" "CC10"
					( Origin gPackager )
				)
				( objectStatus "U2D1.CC10" )
			)
			( pin "@baseboard_fab2_lib.baseboard_fab2(sch_1):page69_i1:upi2_tx_dn(19)"
				( attribute "PN" "CC12"
					( Origin gPackager )
				)
				( objectStatus "U2D1.CC12" )
			)
			( pin "@baseboard_fab2_lib.baseboard_fab2(sch_1):page69_i1:upi2_tx_dp(0)"
				( attribute "PN" "DP21"
					( Origin gPackager )
				)
				( objectStatus "U2D1.DP21" )
			)
			( pin "@baseboard_fab2_lib.baseboard_fab2(sch_1):page69_i1:upi2_tx_dp(1)"
				( attribute "PN" "DN20"
					( Origin gPackager )
				)
				( objectStatus "U2D1.DN20" )
			)
			( pin "@baseboard_fab2_lib.baseboard_fab2(sch_1):page69_i1:upi2_tx_dp(2)"
				( attribute "PN" "DK19"
					( Origin gPackager )
				)
				( objectStatus "U2D1.DK19" )
			)
			( pin "@baseboard_fab2_lib.baseboard_fab2(sch_1):page69_i1:upi2_tx_dp(3)"
				( attribute "PN" "DJ20"
					( Origin gPackager )
				)
				( objectStatus "U2D1.DJ20" )
			)
			( pin "@baseboard_fab2_lib.baseboard_fab2(sch_1):page69_i1:upi2_tx_dp(4)"
				( attribute "PN" "DJ18"
					( Origin gPackager )
				)
				( objectStatus "U2D1.DJ18" )
			)
			( pin "@baseboard_fab2_lib.baseboard_fab2(sch_1):page69_i1:upi2_tx_dp(5)"
				( attribute "PN" "DH17"
					( Origin gPackager )
				)
				( objectStatus "U2D1.DH17" )
			)
			( pin "@baseboard_fab2_lib.baseboard_fab2(sch_1):page69_i1:upi2_tx_dp(6)"
				( attribute "PN" "DF17"
					( Origin gPackager )
				)
				( objectStatus "U2D1.DF17" )
			)
			( pin "@baseboard_fab2_lib.baseboard_fab2(sch_1):page69_i1:upi2_tx_dp(7)"
				( attribute "PN" "DE16"
					( Origin gPackager )
				)
				( objectStatus "U2D1.DE16" )
			)
			( pin "@baseboard_fab2_lib.baseboard_fab2(sch_1):page69_i1:upi2_tx_dp(8)"
				( attribute "PN" "DD15"
					( Origin gPackager )
				)
				( objectStatus "U2D1.DD15" )
			)
			( pin "@baseboard_fab2_lib.baseboard_fab2(sch_1):page69_i1:upi2_tx_dp(9)"
				( attribute "PN" "DB15"
					( Origin gPackager )
				)
				( objectStatus "U2D1.DB15" )
			)
			( pin "@baseboard_fab2_lib.baseboard_fab2(sch_1):page69_i1:upi2_tx_dp(10)"
				( attribute "PN" "CW16"
					( Origin gPackager )
				)
				( objectStatus "U2D1.CW16" )
			)
			( pin "@baseboard_fab2_lib.baseboard_fab2(sch_1):page69_i1:upi2_tx_dp(11)"
				( attribute "PN" "CV13"
					( Origin gPackager )
				)
				( objectStatus "U2D1.CV13" )
			)
			( pin "@baseboard_fab2_lib.baseboard_fab2(sch_1):page69_i1:upi2_tx_dp(12)"
				( attribute "PN" "CR14"
					( Origin gPackager )
				)
				( objectStatus "U2D1.CR14" )
			)
			( pin "@baseboard_fab2_lib.baseboard_fab2(sch_1):page69_i1:upi2_tx_dp(13)"
				( attribute "PN" "CK13"
					( Origin gPackager )
				)
				( objectStatus "U2D1.CK13" )
			)
			( pin "@baseboard_fab2_lib.baseboard_fab2(sch_1):page69_i1:upi2_tx_dp(14)"
				( attribute "PN" "CH13"
					( Origin gPackager )
				)
				( objectStatus "U2D1.CH13" )
			)
			( pin "@baseboard_fab2_lib.baseboard_fab2(sch_1):page69_i1:upi2_tx_dp(15)"
				( attribute "PN" "CG12"
					( Origin gPackager )
				)
				( objectStatus "U2D1.CG12" )
			)
			( pin "@baseboard_fab2_lib.baseboard_fab2(sch_1):page69_i1:upi2_tx_dp(16)"
				( attribute "PN" "CF11"
					( Origin gPackager )
				)
				( objectStatus "U2D1.CF11" )
			)
			( pin "@baseboard_fab2_lib.baseboard_fab2(sch_1):page69_i1:upi2_tx_dp(17)"
				( attribute "PN" "CD11"
					( Origin gPackager )
				)
				( objectStatus "U2D1.CD11" )
			)
			( pin "@baseboard_fab2_lib.baseboard_fab2(sch_1):page69_i1:upi2_tx_dp(18)"
				( attribute "PN" "CB11"
					( Origin gPackager )
				)
				( objectStatus "U2D1.CB11" )
			)
			( pin "@baseboard_fab2_lib.baseboard_fab2(sch_1):page69_i1:upi2_tx_dp(19)"
				( attribute "PN" "CA12"
					( Origin gPackager )
				)
				( objectStatus "U2D1.CA12" )
			)
			( pin "@baseboard_fab2_lib.baseboard_fab2(sch_1):page70_i9:rsvd(92)"
				( attribute "PN" "CH23"
					( Origin gPackager )
				)
				( objectStatus "U2D1.CH23" )
			)
			( pin "@baseboard_fab2_lib.baseboard_fab2(sch_1):page70_i9:rsvd(93)"
				( attribute "PN" "CH21"
					( Origin gPackager )
				)
				( objectStatus "U2D1.CH21" )
			)
			( pin "@baseboard_fab2_lib.baseboard_fab2(sch_1):page70_i9:rsvd(94)"
				( attribute "PN" "CG82"
					( Origin gPackager )
				)
				( objectStatus "U2D1.CG82" )
			)
			( pin "@baseboard_fab2_lib.baseboard_fab2(sch_1):page70_i9:rsvd(95)"
				( attribute "PN" "CG78"
					( Origin gPackager )
				)
				( objectStatus "U2D1.CG78" )
			)
			( pin "@baseboard_fab2_lib.baseboard_fab2(sch_1):page70_i9:rsvd(96)"
				( attribute "PN" "CG26"
					( Origin gPackager )
				)
				( objectStatus "U2D1.CG26" )
			)
			( pin "@baseboard_fab2_lib.baseboard_fab2(sch_1):page70_i9:rsvd(97)"
				( attribute "PN" "CG24"
					( Origin gPackager )
				)
				( objectStatus "U2D1.CG24" )
			)
			( pin "@baseboard_fab2_lib.baseboard_fab2(sch_1):page70_i9:rsvd(98)"
				( attribute "PN" "CG20"
					( Origin gPackager )
				)
				( objectStatus "U2D1.CG20" )
			)
			( pin "@baseboard_fab2_lib.baseboard_fab2(sch_1):page70_i9:rsvd(99)"
				( attribute "PN" "CG10"
					( Origin gPackager )
				)
				( objectStatus "U2D1.CG10" )
			)
			( pin "@baseboard_fab2_lib.baseboard_fab2(sch_1):page70_i9:rsvd(100)"
				( attribute "PN" "CF81"
					( Origin gPackager )
				)
				( objectStatus "U2D1.CF81" )
			)
			( pin "@baseboard_fab2_lib.baseboard_fab2(sch_1):page70_i9:rsvd(101)"
				( attribute "PN" "CF79"
					( Origin gPackager )
				)
				( objectStatus "U2D1.CF79" )
			)
			( pin "@baseboard_fab2_lib.baseboard_fab2(sch_1):page70_i9:rsvd(102)"
				( attribute "PN" "CF23"
					( Origin gPackager )
				)
				( objectStatus "U2D1.CF23" )
			)
			( pin "@baseboard_fab2_lib.baseboard_fab2(sch_1):page70_i9:rsvd(103)"
				( attribute "PN" "CF21"
					( Origin gPackager )
				)
				( objectStatus "U2D1.CF21" )
			)
			( pin "@baseboard_fab2_lib.baseboard_fab2(sch_1):page70_i9:rsvd(104)"
				( attribute "PN" "CF19"
					( Origin gPackager )
				)
				( objectStatus "U2D1.CF19" )
			)
			( pin "@baseboard_fab2_lib.baseboard_fab2(sch_1):page70_i9:rsvd(105)"
				( attribute "PN" "CE80"
					( Origin gPackager )
				)
				( objectStatus "U2D1.CE80" )
			)
			( pin "@baseboard_fab2_lib.baseboard_fab2(sch_1):page70_i9:rsvd(106)"
				( attribute "PN" "CE78"
					( Origin gPackager )
				)
				( objectStatus "U2D1.CE78" )
			)
			( pin "@baseboard_fab2_lib.baseboard_fab2(sch_1):page70_i9:rsvd(107)"
				( attribute "PN" "CE22"
					( Origin gPackager )
				)
				( objectStatus "U2D1.CE22" )
			)
			( pin "@baseboard_fab2_lib.baseboard_fab2(sch_1):page70_i9:rsvd(108)"
				( attribute "PN" "CD25"
					( Origin gPackager )
				)
				( objectStatus "U2D1.CD25" )
			)
			( pin "@baseboard_fab2_lib.baseboard_fab2(sch_1):page70_i9:rsvd(109)"
				( attribute "PN" "CD21"
					( Origin gPackager )
				)
				( objectStatus "U2D1.CD21" )
			)
			( pin "@baseboard_fab2_lib.baseboard_fab2(sch_1):page70_i9:rsvd(110)"
				( attribute "PN" "CD19"
					( Origin gPackager )
				)
				( objectStatus "U2D1.CD19" )
			)
			( pin "@baseboard_fab2_lib.baseboard_fab2(sch_1):page70_i9:rsvd(111)"
				( attribute "PN" "CC6"
					( Origin gPackager )
				)
				( objectStatus "U2D1.CC6" )
			)
			( pin "@baseboard_fab2_lib.baseboard_fab2(sch_1):page70_i9:rsvd(112)"
				( attribute "PN" "CC20"
					( Origin gPackager )
				)
				( objectStatus "U2D1.CC20" )
			)
			( pin "@baseboard_fab2_lib.baseboard_fab2(sch_1):page70_i9:rsvd(113)"
				( attribute "PN" "CB5"
					( Origin gPackager )
				)
				( objectStatus "U2D1.CB5" )
			)
			( pin "@baseboard_fab2_lib.baseboard_fab2(sch_1):page70_i9:rsvd(114)"
				( attribute "PN" "CB25"
					( Origin gPackager )
				)
				( objectStatus "U2D1.CB25" )
			)
			( pin "@baseboard_fab2_lib.baseboard_fab2(sch_1):page70_i9:rsvd(115)"
				( attribute "PN" "CB21"
					( Origin gPackager )
				)
				( objectStatus "U2D1.CB21" )
			)
			( pin "@baseboard_fab2_lib.baseboard_fab2(sch_1):page70_i9:rsvd(116)"
				( attribute "PN" "CB19"
					( Origin gPackager )
				)
				( objectStatus "U2D1.CB19" )
			)
			( pin "@baseboard_fab2_lib.baseboard_fab2(sch_1):page70_i9:rsvd(117)"
				( attribute "PN" "CA24"
					( Origin gPackager )
				)
				( objectStatus "U2D1.CA24" )
			)
			( pin "@baseboard_fab2_lib.baseboard_fab2(sch_1):page70_i9:rsvd(118)"
				( attribute "PN" "CA22"
					( Origin gPackager )
				)
				( objectStatus "U2D1.CA22" )
			)
			( pin "@baseboard_fab2_lib.baseboard_fab2(sch_1):page70_i9:rsvd(119)"
				( attribute "PN" "BY25"
					( Origin gPackager )
				)
				( objectStatus "U2D1.BY25" )
			)
			( pin "@baseboard_fab2_lib.baseboard_fab2(sch_1):page70_i9:rsvd(120)"
				( attribute "PN" "BY19"
					( Origin gPackager )
				)
				( objectStatus "U2D1.BY19" )
			)
			( pin "@baseboard_fab2_lib.baseboard_fab2(sch_1):page70_i9:rsvd(121)"
				( attribute "PN" "BW22"
					( Origin gPackager )
				)
				( objectStatus "U2D1.BW22" )
			)
			( pin "@baseboard_fab2_lib.baseboard_fab2(sch_1):page70_i9:rsvd(122)"
				( attribute "PN" "BW20"
					( Origin gPackager )
				)
				( objectStatus "U2D1.BW20" )
			)
			( pin "@baseboard_fab2_lib.baseboard_fab2(sch_1):page70_i9:rsvd(123)"
				( attribute "PN" "BW10"
					( Origin gPackager )
				)
				( objectStatus "U2D1.BW10" )
			)
			( pin "@baseboard_fab2_lib.baseboard_fab2(sch_1):page70_i9:rsvd(124)"
				( attribute "PN" "BV23"
					( Origin gPackager )
				)
				( objectStatus "U2D1.BV23" )
			)
			( pin "@baseboard_fab2_lib.baseboard_fab2(sch_1):page70_i9:rsvd(125)"
				( attribute "PN" "BV21"
					( Origin gPackager )
				)
				( objectStatus "U2D1.BV21" )
			)
			( pin "@baseboard_fab2_lib.baseboard_fab2(sch_1):page70_i9:rsvd(126)"
				( attribute "PN" "BV19"
					( Origin gPackager )
				)
				( objectStatus "U2D1.BV19" )
			)
			( pin "@baseboard_fab2_lib.baseboard_fab2(sch_1):page70_i9:rsvd(127)"
				( attribute "PN" "BU22"
					( Origin gPackager )
				)
				( objectStatus "U2D1.BU22" )
			)
			( pin "@baseboard_fab2_lib.baseboard_fab2(sch_1):page70_i9:rsvd(128)"
				( attribute "PN" "BU20"
					( Origin gPackager )
				)
				( objectStatus "U2D1.BU20" )
			)
			( pin "@baseboard_fab2_lib.baseboard_fab2(sch_1):page70_i9:rsvd(129)"
				( attribute "PN" "BU18"
					( Origin gPackager )
				)
				( objectStatus "U2D1.BU18" )
			)
			( pin "@baseboard_fab2_lib.baseboard_fab2(sch_1):page70_i9:rsvd(130)"
				( attribute "PN" "BR24"
					( Origin gPackager )
				)
				( objectStatus "U2D1.BR24" )
			)
			( pin "@baseboard_fab2_lib.baseboard_fab2(sch_1):page70_i9:rsvd(131)"
				( attribute "PN" "BR22"
					( Origin gPackager )
				)
				( objectStatus "U2D1.BR22" )
			)
			( pin "@baseboard_fab2_lib.baseboard_fab2(sch_1):page70_i9:rsvd(132)"
				( attribute "PN" "BP21"
					( Origin gPackager )
				)
				( objectStatus "U2D1.BP21" )
			)
			( pin "@baseboard_fab2_lib.baseboard_fab2(sch_1):page70_i9:rsvd(133)"
				( attribute "PN" "BP17"
					( Origin gPackager )
				)
				( objectStatus "U2D1.BP17" )
			)
			( pin "@baseboard_fab2_lib.baseboard_fab2(sch_1):page70_i9:rsvd(134)"
				( attribute "PN" "BN18"
					( Origin gPackager )
				)
				( objectStatus "U2D1.BN18" )
			)
			( pin "@baseboard_fab2_lib.baseboard_fab2(sch_1):page70_i9:rsvd(135)"
				( attribute "PN" "BM19"
					( Origin gPackager )
				)
				( objectStatus "U2D1.BM19" )
			)
			( pin "@baseboard_fab2_lib.baseboard_fab2(sch_1):page70_i9:rsvd(136)"
				( attribute "PN" "BM17"
					( Origin gPackager )
				)
				( objectStatus "U2D1.BM17" )
			)
			( pin "@baseboard_fab2_lib.baseboard_fab2(sch_1):page70_i9:rsvd(137)"
				( attribute "PN" "BL20"
					( Origin gPackager )
				)
				( objectStatus "U2D1.BL20" )
			)
			( pin "@baseboard_fab2_lib.baseboard_fab2(sch_1):page70_i9:rsvd(138)"
				( attribute "PN" "BL18"
					( Origin gPackager )
				)
				( objectStatus "U2D1.BL18" )
			)
			( pin "@baseboard_fab2_lib.baseboard_fab2(sch_1):page70_i9:rsvd(139)"
				( attribute "PN" "BK17"
					( Origin gPackager )
				)
				( objectStatus "U2D1.BK17" )
			)
			( pin "@baseboard_fab2_lib.baseboard_fab2(sch_1):page70_i9:rsvd(140)"
				( attribute "PN" "BJ20"
					( Origin gPackager )
				)
				( objectStatus "U2D1.BJ20" )
			)
			( pin "@baseboard_fab2_lib.baseboard_fab2(sch_1):page70_i9:rsvd(141)"
				( attribute "PN" "BJ18"
					( Origin gPackager )
				)
				( objectStatus "U2D1.BJ18" )
			)
			( pin "@baseboard_fab2_lib.baseboard_fab2(sch_1):page70_i9:rsvd(142)"
				( attribute "PN" "BJ16"
					( Origin gPackager )
				)
				( objectStatus "U2D1.BJ16" )
			)
			( pin "@baseboard_fab2_lib.baseboard_fab2(sch_1):page70_i9:rsvd(143)"
				( attribute "PN" "BH19"
					( Origin gPackager )
				)
				( objectStatus "U2D1.BH19" )
			)
			( pin "@baseboard_fab2_lib.baseboard_fab2(sch_1):page70_i9:rsvd(144)"
				( attribute "PN" "BG20"
					( Origin gPackager )
				)
				( objectStatus "U2D1.BG20" )
			)
			( pin "@baseboard_fab2_lib.baseboard_fab2(sch_1):page70_i9:rsvd(145)"
				( attribute "PN" "BG18"
					( Origin gPackager )
				)
				( objectStatus "U2D1.BG18" )
			)
			( pin "@baseboard_fab2_lib.baseboard_fab2(sch_1):page70_i9:rsvd(146)"
				( attribute "PN" "BF21"
					( Origin gPackager )
				)
				( objectStatus "U2D1.BF21" )
			)
			( pin "@baseboard_fab2_lib.baseboard_fab2(sch_1):page70_i9:rsvd(147)"
				( attribute "PN" "BE22"
					( Origin gPackager )
				)
				( objectStatus "U2D1.BE22" )
			)
			( pin "@baseboard_fab2_lib.baseboard_fab2(sch_1):page70_i9:rsvd(148)"
				( attribute "PN" "BE20"
					( Origin gPackager )
				)
				( objectStatus "U2D1.BE20" )
			)
			( pin "@baseboard_fab2_lib.baseboard_fab2(sch_1):page70_i9:rsvd(149)"
				( attribute "PN" "BE18"
					( Origin gPackager )
				)
				( objectStatus "U2D1.BE18" )
			)
			( pin "@baseboard_fab2_lib.baseboard_fab2(sch_1):page70_i9:rsvd(150)"
				( attribute "PN" "BD69"
					( Origin gPackager )
				)
				( objectStatus "U2D1.BD69" )
			)
			( pin "@baseboard_fab2_lib.baseboard_fab2(sch_1):page70_i9:rsvd(151)"
				( attribute "PN" "BD67"
					( Origin gPackager )
				)
				( objectStatus "U2D1.BD67" )
			)
			( pin "@baseboard_fab2_lib.baseboard_fab2(sch_1):page70_i9:rsvd(152)"
				( attribute "PN" "BD65"
					( Origin gPackager )
				)
				( objectStatus "U2D1.BD65" )
			)
			( pin "@baseboard_fab2_lib.baseboard_fab2(sch_1):page70_i9:rsvd(153)"
				( attribute "PN" "BD25"
					( Origin gPackager )
				)
				( objectStatus "U2D1.BD25" )
			)
			( pin "@baseboard_fab2_lib.baseboard_fab2(sch_1):page70_i9:rsvd(154)"
				( attribute "PN" "BD19"
					( Origin gPackager )
				)
				( objectStatus "U2D1.BD19" )
			)
			( pin "@baseboard_fab2_lib.baseboard_fab2(sch_1):page70_i9:rsvd(155)"
				( attribute "PN" "BD17"
					( Origin gPackager )
				)
				( objectStatus "U2D1.BD17" )
			)
			( pin "@baseboard_fab2_lib.baseboard_fab2(sch_1):page70_i9:rsvd(156)"
				( attribute "PN" "BC68"
					( Origin gPackager )
				)
				( objectStatus "U2D1.BC68" )
			)
			( pin "@baseboard_fab2_lib.baseboard_fab2(sch_1):page70_i9:rsvd(157)"
				( attribute "PN" "BC66"
					( Origin gPackager )
				)
				( objectStatus "U2D1.BC66" )
			)
			( pin "@baseboard_fab2_lib.baseboard_fab2(sch_1):page70_i9:rsvd(158)"
				( attribute "PN" "BC64"
					( Origin gPackager )
				)
				( objectStatus "U2D1.BC64" )
			)
			( pin "@baseboard_fab2_lib.baseboard_fab2(sch_1):page70_i9:rsvd(159)"
				( attribute "PN" "BC22"
					( Origin gPackager )
				)
				( objectStatus "U2D1.BC22" )
			)
			( pin "@baseboard_fab2_lib.baseboard_fab2(sch_1):page70_i9:rsvd(160)"
				( attribute "PN" "BC20"
					( Origin gPackager )
				)
				( objectStatus "U2D1.BC20" )
			)
			( pin "@baseboard_fab2_lib.baseboard_fab2(sch_1):page70_i9:rsvd(161)"
				( attribute "PN" "BC18"
					( Origin gPackager )
				)
				( objectStatus "U2D1.BC18" )
			)
			( pin "@baseboard_fab2_lib.baseboard_fab2(sch_1):page70_i9:rsvd(162)"
				( attribute "PN" "BC14"
					( Origin gPackager )
				)
				( objectStatus "U2D1.BC14" )
			)
			( pin "@baseboard_fab2_lib.baseboard_fab2(sch_1):page70_i9:rsvd(163)"
				( attribute "PN" "BB67"
					( Origin gPackager )
				)
				( objectStatus "U2D1.BB67" )
			)
			( pin "@baseboard_fab2_lib.baseboard_fab2(sch_1):page70_i9:rsvd(164)"
				( attribute "PN" "BB65"
					( Origin gPackager )
				)
				( objectStatus "U2D1.BB65" )
			)
			( pin "@baseboard_fab2_lib.baseboard_fab2(sch_1):page70_i9:rsvd(165)"
				( attribute "PN" "BB25"
					( Origin gPackager )
				)
				( objectStatus "U2D1.BB25" )
			)
			( pin "@baseboard_fab2_lib.baseboard_fab2(sch_1):page70_i9:rsvd(166)"
				( attribute "PN" "BB21"
					( Origin gPackager )
				)
				( objectStatus "U2D1.BB21" )
			)
			( pin "@baseboard_fab2_lib.baseboard_fab2(sch_1):page70_i9:rsvd(167)"
				( attribute "PN" "BB17"
					( Origin gPackager )
				)
				( objectStatus "U2D1.BB17" )
			)
			( pin "@baseboard_fab2_lib.baseboard_fab2(sch_1):page70_i9:rsvd(168)"
				( attribute "PN" "BB15"
					( Origin gPackager )
				)
				( objectStatus "U2D1.BB15" )
			)
			( pin "@baseboard_fab2_lib.baseboard_fab2(sch_1):page70_i9:rsvd(169)"
				( attribute "PN" "BB13"
					( Origin gPackager )
				)
				( objectStatus "U2D1.BB13" )
			)
			( pin "@baseboard_fab2_lib.baseboard_fab2(sch_1):page70_i9:rsvd(170)"
				( attribute "PN" "BA82"
					( Origin gPackager )
				)
				( objectStatus "U2D1.BA82" )
			)
			( pin "@baseboard_fab2_lib.baseboard_fab2(sch_1):page70_i9:rsvd(171)"
				( attribute "PN" "BA78"
					( Origin gPackager )
				)
				( objectStatus "U2D1.BA78" )
			)
			( pin "@baseboard_fab2_lib.baseboard_fab2(sch_1):page70_i9:rsvd(172)"
				( attribute "CDS_NOT_ON_SYM" "TRUE"
					( Origin gFrontEnd )
				)
			)
			( pin "@baseboard_fab2_lib.baseboard_fab2(sch_1):page70_i9:rsvd(173)"
				( attribute "CDS_NOT_ON_SYM" "TRUE"
					( Origin gFrontEnd )
				)
			)
			( pin "@baseboard_fab2_lib.baseboard_fab2(sch_1):page70_i9:rsvd(174)"
				( attribute "CDS_NOT_ON_SYM" "TRUE"
					( Origin gFrontEnd )
				)
			)
			( pin "@baseboard_fab2_lib.baseboard_fab2(sch_1):page70_i9:rsvd(175)"
				( attribute "CDS_NOT_ON_SYM" "TRUE"
					( Origin gFrontEnd )
				)
			)
			( pin "@baseboard_fab2_lib.baseboard_fab2(sch_1):page70_i9:rsvd(176)"
				( attribute "CDS_NOT_ON_SYM" "TRUE"
					( Origin gFrontEnd )
				)
			)
			( pin "@baseboard_fab2_lib.baseboard_fab2(sch_1):page70_i9:rsvd(177)"
				( attribute "CDS_NOT_ON_SYM" "TRUE"
					( Origin gFrontEnd )
				)
			)
			( pin "@baseboard_fab2_lib.baseboard_fab2(sch_1):page70_i9:rsvd(178)"
				( attribute "CDS_NOT_ON_SYM" "TRUE"
					( Origin gFrontEnd )
				)
			)
			( pin "@baseboard_fab2_lib.baseboard_fab2(sch_1):page70_i9:rsvd(179)"
				( attribute "CDS_NOT_ON_SYM" "TRUE"
					( Origin gFrontEnd )
				)
			)
			( pin "@baseboard_fab2_lib.baseboard_fab2(sch_1):page70_i9:rsvd(180)"
				( attribute "CDS_NOT_ON_SYM" "TRUE"
					( Origin gFrontEnd )
				)
			)
			( pin "@baseboard_fab2_lib.baseboard_fab2(sch_1):page70_i9:rsvd(181)"
				( attribute "CDS_NOT_ON_SYM" "TRUE"
					( Origin gFrontEnd )
				)
			)
			( pin "@baseboard_fab2_lib.baseboard_fab2(sch_1):page70_i9:rsvd(182)"
				( attribute "CDS_NOT_ON_SYM" "TRUE"
					( Origin gFrontEnd )
				)
			)
			( pin "@baseboard_fab2_lib.baseboard_fab2(sch_1):page70_i9:rsvd(183)"
				( attribute "CDS_NOT_ON_SYM" "TRUE"
					( Origin gFrontEnd )
				)
			)
			( pin "@baseboard_fab2_lib.baseboard_fab2(sch_1):page70_i9:rsvd(184)"
				( attribute "CDS_NOT_ON_SYM" "TRUE"
					( Origin gFrontEnd )
				)
			)
			( pin "@baseboard_fab2_lib.baseboard_fab2(sch_1):page70_i9:rsvd(185)"
				( attribute "CDS_NOT_ON_SYM" "TRUE"
					( Origin gFrontEnd )
				)
			)
			( pin "@baseboard_fab2_lib.baseboard_fab2(sch_1):page70_i9:rsvd(186)"
				( attribute "CDS_NOT_ON_SYM" "TRUE"
					( Origin gFrontEnd )
				)
			)
			( pin "@baseboard_fab2_lib.baseboard_fab2(sch_1):page70_i9:rsvd(187)"
				( attribute "CDS_NOT_ON_SYM" "TRUE"
					( Origin gFrontEnd )
				)
			)
			( pin "@baseboard_fab2_lib.baseboard_fab2(sch_1):page70_i9:rsvd(188)"
				( attribute "CDS_NOT_ON_SYM" "TRUE"
					( Origin gFrontEnd )
				)
			)
			( pin "@baseboard_fab2_lib.baseboard_fab2(sch_1):page70_i9:rsvd(189)"
				( attribute "CDS_NOT_ON_SYM" "TRUE"
					( Origin gFrontEnd )
				)
			)
			( pin "@baseboard_fab2_lib.baseboard_fab2(sch_1):page70_i9:rsvd(190)"
				( attribute "CDS_NOT_ON_SYM" "TRUE"
					( Origin gFrontEnd )
				)
			)
			( pin "@baseboard_fab2_lib.baseboard_fab2(sch_1):page70_i9:rsvd(191)"
				( attribute "CDS_NOT_ON_SYM" "TRUE"
					( Origin gFrontEnd )
				)
			)
			( pin "@baseboard_fab2_lib.baseboard_fab2(sch_1):page70_i9:rsvd(192)"
				( attribute "CDS_NOT_ON_SYM" "TRUE"
					( Origin gFrontEnd )
				)
			)
			( pin "@baseboard_fab2_lib.baseboard_fab2(sch_1):page70_i9:rsvd(193)"
				( attribute "CDS_NOT_ON_SYM" "TRUE"
					( Origin gFrontEnd )
				)
			)
			( pin "@baseboard_fab2_lib.baseboard_fab2(sch_1):page70_i9:rsvd(194)"
				( attribute "CDS_NOT_ON_SYM" "TRUE"
					( Origin gFrontEnd )
				)
			)
			( pin "@baseboard_fab2_lib.baseboard_fab2(sch_1):page70_i9:rsvd(195)"
				( attribute "CDS_NOT_ON_SYM" "TRUE"
					( Origin gFrontEnd )
				)
			)
			( pin "@baseboard_fab2_lib.baseboard_fab2(sch_1):page70_i9:rsvd(196)"
				( attribute "CDS_NOT_ON_SYM" "TRUE"
					( Origin gFrontEnd )
				)
			)
			( pin "@baseboard_fab2_lib.baseboard_fab2(sch_1):page70_i9:rsvd(197)"
				( attribute "CDS_NOT_ON_SYM" "TRUE"
					( Origin gFrontEnd )
				)
			)
			( pin "@baseboard_fab2_lib.baseboard_fab2(sch_1):page70_i9:rsvd(198)"
				( attribute "CDS_NOT_ON_SYM" "TRUE"
					( Origin gFrontEnd )
				)
			)
			( pin "@baseboard_fab2_lib.baseboard_fab2(sch_1):page70_i9:rsvd(199)"
				( attribute "CDS_NOT_ON_SYM" "TRUE"
					( Origin gFrontEnd )
				)
			)
			( pin "@baseboard_fab2_lib.baseboard_fab2(sch_1):page70_i9:rsvd(200)"
				( attribute "CDS_NOT_ON_SYM" "TRUE"
					( Origin gFrontEnd )
				)
			)
			( pin "@baseboard_fab2_lib.baseboard_fab2(sch_1):page70_i9:rsvd(201)"
				( attribute "CDS_NOT_ON_SYM" "TRUE"
					( Origin gFrontEnd )
				)
			)
			( pin "@baseboard_fab2_lib.baseboard_fab2(sch_1):page70_i9:rsvd(202)"
				( attribute "CDS_NOT_ON_SYM" "TRUE"
					( Origin gFrontEnd )
				)
			)
			( pin "@baseboard_fab2_lib.baseboard_fab2(sch_1):page70_i9:rsvd(203)"
				( attribute "CDS_NOT_ON_SYM" "TRUE"
					( Origin gFrontEnd )
				)
			)
			( pin "@baseboard_fab2_lib.baseboard_fab2(sch_1):page70_i9:rsvd(204)"
				( attribute "CDS_NOT_ON_SYM" "TRUE"
					( Origin gFrontEnd )
				)
			)
			( pin "@baseboard_fab2_lib.baseboard_fab2(sch_1):page70_i9:rsvd(205)"
				( attribute "CDS_NOT_ON_SYM" "TRUE"
					( Origin gFrontEnd )
				)
			)
			( pin "@baseboard_fab2_lib.baseboard_fab2(sch_1):page70_i9:rsvd(206)"
				( attribute "CDS_NOT_ON_SYM" "TRUE"
					( Origin gFrontEnd )
				)
			)
			( pin "@baseboard_fab2_lib.baseboard_fab2(sch_1):page70_i9:rsvd(207)"
				( attribute "CDS_NOT_ON_SYM" "TRUE"
					( Origin gFrontEnd )
				)
			)
			( pin "@baseboard_fab2_lib.baseboard_fab2(sch_1):page70_i9:rsvd(208)"
				( attribute "CDS_NOT_ON_SYM" "TRUE"
					( Origin gFrontEnd )
				)
			)
			( pin "@baseboard_fab2_lib.baseboard_fab2(sch_1):page70_i9:rsvd(209)"
				( attribute "CDS_NOT_ON_SYM" "TRUE"
					( Origin gFrontEnd )
				)
			)
			( pin "@baseboard_fab2_lib.baseboard_fab2(sch_1):page70_i9:rsvd(210)"
				( attribute "CDS_NOT_ON_SYM" "TRUE"
					( Origin gFrontEnd )
				)
			)
			( pin "@baseboard_fab2_lib.baseboard_fab2(sch_1):page70_i9:rsvd(211)"
				( attribute "CDS_NOT_ON_SYM" "TRUE"
					( Origin gFrontEnd )
				)
			)
			( pin "@baseboard_fab2_lib.baseboard_fab2(sch_1):page70_i9:rsvd(212)"
				( attribute "CDS_NOT_ON_SYM" "TRUE"
					( Origin gFrontEnd )
				)
			)
			( pin "@baseboard_fab2_lib.baseboard_fab2(sch_1):page70_i9:rsvd(213)"
				( attribute "CDS_NOT_ON_SYM" "TRUE"
					( Origin gFrontEnd )
				)
			)
			( pin "@baseboard_fab2_lib.baseboard_fab2(sch_1):page70_i9:rsvd(214)"
				( attribute "CDS_NOT_ON_SYM" "TRUE"
					( Origin gFrontEnd )
				)
			)
			( pin "@baseboard_fab2_lib.baseboard_fab2(sch_1):page70_i9:rsvd(215)"
				( attribute "CDS_NOT_ON_SYM" "TRUE"
					( Origin gFrontEnd )
				)
			)
			( pin "@baseboard_fab2_lib.baseboard_fab2(sch_1):page70_i9:rsvd(216)"
				( attribute "CDS_NOT_ON_SYM" "TRUE"
					( Origin gFrontEnd )
				)
			)
			( pin "@baseboard_fab2_lib.baseboard_fab2(sch_1):page70_i9:rsvd(217)"
				( attribute "CDS_NOT_ON_SYM" "TRUE"
					( Origin gFrontEnd )
				)
			)
			( pin "@baseboard_fab2_lib.baseboard_fab2(sch_1):page70_i9:rsvd(218)"
				( attribute "CDS_NOT_ON_SYM" "TRUE"
					( Origin gFrontEnd )
				)
			)
			( pin "@baseboard_fab2_lib.baseboard_fab2(sch_1):page70_i9:rsvd(219)"
				( attribute "CDS_NOT_ON_SYM" "TRUE"
					( Origin gFrontEnd )
				)
			)
			( pin "@baseboard_fab2_lib.baseboard_fab2(sch_1):page70_i9:rsvd(220)"
				( attribute "CDS_NOT_ON_SYM" "TRUE"
					( Origin gFrontEnd )
				)
			)
			( pin "@baseboard_fab2_lib.baseboard_fab2(sch_1):page70_i9:rsvd(221)"
				( attribute "CDS_NOT_ON_SYM" "TRUE"
					( Origin gFrontEnd )
				)
			)
			( pin "@baseboard_fab2_lib.baseboard_fab2(sch_1):page70_i9:rsvd(222)"
				( attribute "CDS_NOT_ON_SYM" "TRUE"
					( Origin gFrontEnd )
				)
			)
			( pin "@baseboard_fab2_lib.baseboard_fab2(sch_1):page70_i9:rsvd(223)"
				( attribute "CDS_NOT_ON_SYM" "TRUE"
					( Origin gFrontEnd )
				)
			)
			( pin "@baseboard_fab2_lib.baseboard_fab2(sch_1):page70_i9:rsvd(224)"
				( attribute "CDS_NOT_ON_SYM" "TRUE"
					( Origin gFrontEnd )
				)
			)
			( pin "@baseboard_fab2_lib.baseboard_fab2(sch_1):page70_i9:rsvd(225)"
				( attribute "CDS_NOT_ON_SYM" "TRUE"
					( Origin gFrontEnd )
				)
			)
			( pin "@baseboard_fab2_lib.baseboard_fab2(sch_1):page70_i9:rsvd(226)"
				( attribute "CDS_NOT_ON_SYM" "TRUE"
					( Origin gFrontEnd )
				)
			)
			( pin "@baseboard_fab2_lib.baseboard_fab2(sch_1):page70_i9:rsvd(227)"
				( attribute "CDS_NOT_ON_SYM" "TRUE"
					( Origin gFrontEnd )
				)
			)
			( pin "@baseboard_fab2_lib.baseboard_fab2(sch_1):page70_i9:rsvd(228)"
				( attribute "CDS_NOT_ON_SYM" "TRUE"
					( Origin gFrontEnd )
				)
			)
			( pin "@baseboard_fab2_lib.baseboard_fab2(sch_1):page70_i9:rsvd(229)"
				( attribute "CDS_NOT_ON_SYM" "TRUE"
					( Origin gFrontEnd )
				)
			)
			( pin "@baseboard_fab2_lib.baseboard_fab2(sch_1):page70_i9:rsvd(230)"
				( attribute "CDS_NOT_ON_SYM" "TRUE"
					( Origin gFrontEnd )
				)
			)
			( pin "@baseboard_fab2_lib.baseboard_fab2(sch_1):page70_i9:rsvd(231)"
				( attribute "CDS_NOT_ON_SYM" "TRUE"
					( Origin gFrontEnd )
				)
			)
			( pin "@baseboard_fab2_lib.baseboard_fab2(sch_1):page70_i9:rsvd(232)"
				( attribute "CDS_NOT_ON_SYM" "TRUE"
					( Origin gFrontEnd )
				)
			)
			( pin "@baseboard_fab2_lib.baseboard_fab2(sch_1):page70_i9:rsvd(233)"
				( attribute "CDS_NOT_ON_SYM" "TRUE"
					( Origin gFrontEnd )
				)
			)
			( pin "@baseboard_fab2_lib.baseboard_fab2(sch_1):page70_i9:rsvd(234)"
				( attribute "CDS_NOT_ON_SYM" "TRUE"
					( Origin gFrontEnd )
				)
			)
			( pin "@baseboard_fab2_lib.baseboard_fab2(sch_1):page70_i9:rsvd(235)"
				( attribute "CDS_NOT_ON_SYM" "TRUE"
					( Origin gFrontEnd )
				)
			)
			( pin "@baseboard_fab2_lib.baseboard_fab2(sch_1):page70_i9:rsvd(236)"
				( attribute "CDS_NOT_ON_SYM" "TRUE"
					( Origin gFrontEnd )
				)
			)
			( pin "@baseboard_fab2_lib.baseboard_fab2(sch_1):page70_i9:rsvd(237)"
				( attribute "CDS_NOT_ON_SYM" "TRUE"
					( Origin gFrontEnd )
				)
			)
			( pin "@baseboard_fab2_lib.baseboard_fab2(sch_1):page70_i9:rsvd(238)"
				( attribute "CDS_NOT_ON_SYM" "TRUE"
					( Origin gFrontEnd )
				)
			)
			( pin "@baseboard_fab2_lib.baseboard_fab2(sch_1):page70_i9:rsvd(239)"
				( attribute "CDS_NOT_ON_SYM" "TRUE"
					( Origin gFrontEnd )
				)
			)
			( pin "@baseboard_fab2_lib.baseboard_fab2(sch_1):page70_i9:rsvd(240)"
				( attribute "CDS_NOT_ON_SYM" "TRUE"
					( Origin gFrontEnd )
				)
			)
			( pin "@baseboard_fab2_lib.baseboard_fab2(sch_1):page70_i9:rsvd(241)"
				( attribute "CDS_NOT_ON_SYM" "TRUE"
					( Origin gFrontEnd )
				)
			)
			( pin "@baseboard_fab2_lib.baseboard_fab2(sch_1):page70_i9:rsvd(242)"
				( attribute "CDS_NOT_ON_SYM" "TRUE"
					( Origin gFrontEnd )
				)
			)
			( pin "@baseboard_fab2_lib.baseboard_fab2(sch_1):page70_i9:rsvd(243)"
				( attribute "CDS_NOT_ON_SYM" "TRUE"
					( Origin gFrontEnd )
				)
			)
			( pin "@baseboard_fab2_lib.baseboard_fab2(sch_1):page70_i9:rsvd(244)"
				( attribute "CDS_NOT_ON_SYM" "TRUE"
					( Origin gFrontEnd )
				)
			)
			( pin "@baseboard_fab2_lib.baseboard_fab2(sch_1):page70_i9:rsvd(245)"
				( attribute "CDS_NOT_ON_SYM" "TRUE"
					( Origin gFrontEnd )
				)
			)
			( pin "@baseboard_fab2_lib.baseboard_fab2(sch_1):page70_i9:rsvd(246)"
				( attribute "CDS_NOT_ON_SYM" "TRUE"
					( Origin gFrontEnd )
				)
			)
			( pin "@baseboard_fab2_lib.baseboard_fab2(sch_1):page70_i9:rsvd(247)"
				( attribute "CDS_NOT_ON_SYM" "TRUE"
					( Origin gFrontEnd )
				)
			)
			( pin "@baseboard_fab2_lib.baseboard_fab2(sch_1):page70_i9:rsvd(248)"
				( attribute "CDS_NOT_ON_SYM" "TRUE"
					( Origin gFrontEnd )
				)
			)
			( pin "@baseboard_fab2_lib.baseboard_fab2(sch_1):page70_i9:rsvd(249)"
				( attribute "CDS_NOT_ON_SYM" "TRUE"
					( Origin gFrontEnd )
				)
			)
			( pin "@baseboard_fab2_lib.baseboard_fab2(sch_1):page70_i9:rsvd(250)"
				( attribute "CDS_NOT_ON_SYM" "TRUE"
					( Origin gFrontEnd )
				)
			)
			( pin "@baseboard_fab2_lib.baseboard_fab2(sch_1):page70_i9:rsvd(251)"
				( attribute "CDS_NOT_ON_SYM" "TRUE"
					( Origin gFrontEnd )
				)
			)
			( pin "@baseboard_fab2_lib.baseboard_fab2(sch_1):page70_i9:rsvd(252)"
				( attribute "CDS_NOT_ON_SYM" "TRUE"
					( Origin gFrontEnd )
				)
			)
			( pin "@baseboard_fab2_lib.baseboard_fab2(sch_1):page70_i9:rsvd(253)"
				( attribute "CDS_NOT_ON_SYM" "TRUE"
					( Origin gFrontEnd )
				)
			)
			( pin "@baseboard_fab2_lib.baseboard_fab2(sch_1):page70_i9:rsvd(254)"
				( attribute "CDS_NOT_ON_SYM" "TRUE"
					( Origin gFrontEnd )
				)
			)
			( pin "@baseboard_fab2_lib.baseboard_fab2(sch_1):page70_i9:rsvd(255)"
				( attribute "PN" "AY83"
					( Origin gPackager )
				)
				( objectStatus "U2D1.AY83" )
			)
			( pin "@baseboard_fab2_lib.baseboard_fab2(sch_1):page70_i10:rsvd(81)"
				( attribute "PN" "CL24"
					( Origin gPackager )
				)
				( objectStatus "U2D1.CL24" )
			)
			( pin "@baseboard_fab2_lib.baseboard_fab2(sch_1):page70_i10:rsvd(82)"
				( attribute "PN" "CK77"
					( Origin gPackager )
				)
				( objectStatus "U2D1.CK77" )
			)
			( pin "@baseboard_fab2_lib.baseboard_fab2(sch_1):page70_i10:rsvd(83)"
				( attribute "PN" "CK25"
					( Origin gPackager )
				)
				( objectStatus "U2D1.CK25" )
			)
			( pin "@baseboard_fab2_lib.baseboard_fab2(sch_1):page70_i10:rsvd(84)"
				( attribute "PN" "CK23"
					( Origin gPackager )
				)
				( objectStatus "U2D1.CK23" )
			)
			( pin "@baseboard_fab2_lib.baseboard_fab2(sch_1):page70_i10:rsvd(85)"
				( attribute "PN" "CK19"
					( Origin gPackager )
				)
				( objectStatus "U2D1.CK19" )
			)
			( pin "@baseboard_fab2_lib.baseboard_fab2(sch_1):page70_i10:rsvd(86)"
				( attribute "PN" "CJ26"
					( Origin gPackager )
				)
				( objectStatus "U2D1.CJ26" )
			)
			( pin "@baseboard_fab2_lib.baseboard_fab2(sch_1):page70_i10:rsvd(87)"
				( attribute "PN" "CJ24"
					( Origin gPackager )
				)
				( objectStatus "U2D1.CJ24" )
			)
			( pin "@baseboard_fab2_lib.baseboard_fab2(sch_1):page70_i10:rsvd(88)"
				( attribute "PN" "CJ22"
					( Origin gPackager )
				)
				( objectStatus "U2D1.CJ22" )
			)
			( pin "@baseboard_fab2_lib.baseboard_fab2(sch_1):page70_i10:rsvd(89)"
				( attribute "PN" "CJ20"
					( Origin gPackager )
				)
				( objectStatus "U2D1.CJ20" )
			)
			( pin "@baseboard_fab2_lib.baseboard_fab2(sch_1):page70_i10:rsvd(90)"
				( attribute "PN" "CH77"
					( Origin gPackager )
				)
				( objectStatus "U2D1.CH77" )
			)
			( pin "@baseboard_fab2_lib.baseboard_fab2(sch_1):page70_i10:rsvd(91)"
				( attribute "PN" "CH25"
					( Origin gPackager )
				)
				( objectStatus "U2D1.CH25" )
			)
			( pin "@baseboard_fab2_lib.baseboard_fab2(sch_1):page70_i10:test_6"
				( attribute "PN" "AR16"
					( Origin gPackager )
				)
				( objectStatus "U2D1.AR16" )
			)
			( pin "@baseboard_fab2_lib.baseboard_fab2(sch_1):page70_i10:test_7"
				( attribute "PN" "AU18"
					( Origin gPackager )
				)
				( objectStatus "U2D1.AU18" )
			)
			( pin "@baseboard_fab2_lib.baseboard_fab2(sch_1):page70_i10:test_8"
				( attribute "PN" "AW16"
					( Origin gPackager )
				)
				( objectStatus "U2D1.AW16" )
			)
			( pin "@baseboard_fab2_lib.baseboard_fab2(sch_1):page70_i10:test_9"
				( attribute "PN" "AW20"
					( Origin gPackager )
				)
				( objectStatus "U2D1.AW20" )
			)
			( pin "@baseboard_fab2_lib.baseboard_fab2(sch_1):page70_i10:test_10"
				( attribute "PN" "AW22"
					( Origin gPackager )
				)
				( objectStatus "U2D1.AW22" )
			)
			( pin "@baseboard_fab2_lib.baseboard_fab2(sch_1):page71_i43:a"
				( attribute "PN" "1"
					( Origin gPackager )
				)
				( objectStatus "R3D27.1" )
			)
			( pin "@baseboard_fab2_lib.baseboard_fab2(sch_1):page71_i43:b"
				( attribute "PN" "2"
					( Origin gPackager )
				)
				( objectStatus "R3D27.2" )
			)
			( pin "@baseboard_fab2_lib.baseboard_fab2(sch_1):page71_i49:a"
				( attribute "PN" "1"
					( Origin gPackager )
				)
				( objectStatus "RT8P1.1" )
			)
			( pin "@baseboard_fab2_lib.baseboard_fab2(sch_1):page71_i49:b"
				( attribute "PN" "2"
					( Origin gPackager )
				)
				( objectStatus "RT8P1.2" )
			)
			( pin "@baseboard_fab2_lib.baseboard_fab2(sch_1):page71_i50:vccin(130)"
				( attribute "PN" "BN78"
					( Origin gPackager )
				)
				( objectStatus "U2D1.BN78" )
			)
			( pin "@baseboard_fab2_lib.baseboard_fab2(sch_1):page71_i50:vccin(131)"
				( attribute "PN" "BN76"
					( Origin gPackager )
				)
				( objectStatus "U2D1.BN76" )
			)
			( pin "@baseboard_fab2_lib.baseboard_fab2(sch_1):page71_i50:vccin(132)"
				( attribute "PN" "BN74"
					( Origin gPackager )
				)
				( objectStatus "U2D1.BN74" )
			)
			( pin "@baseboard_fab2_lib.baseboard_fab2(sch_1):page71_i50:vccin(133)"
				( attribute "PN" "BN72"
					( Origin gPackager )
				)
				( objectStatus "U2D1.BN72" )
			)
			( pin "@baseboard_fab2_lib.baseboard_fab2(sch_1):page71_i50:vccin(134)"
				( attribute "PN" "BN70"
					( Origin gPackager )
				)
				( objectStatus "U2D1.BN70" )
			)
			( pin "@baseboard_fab2_lib.baseboard_fab2(sch_1):page71_i50:vccin(135)"
				( attribute "PN" "BN68"
					( Origin gPackager )
				)
				( objectStatus "U2D1.BN68" )
			)
			( pin "@baseboard_fab2_lib.baseboard_fab2(sch_1):page71_i50:vccin(136)"
				( attribute "PN" "BN66"
					( Origin gPackager )
				)
				( objectStatus "U2D1.BN66" )
			)
			( pin "@baseboard_fab2_lib.baseboard_fab2(sch_1):page71_i50:vccin(137)"
				( attribute "PN" "BN64"
					( Origin gPackager )
				)
				( objectStatus "U2D1.BN64" )
			)
			( pin "@baseboard_fab2_lib.baseboard_fab2(sch_1):page71_i50:vccin(138)"
				( attribute "PN" "BN62"
					( Origin gPackager )
				)
				( objectStatus "U2D1.BN62" )
			)
			( pin "@baseboard_fab2_lib.baseboard_fab2(sch_1):page71_i50:vccin(139)"
				( attribute "PN" "BN60"
					( Origin gPackager )
				)
				( objectStatus "U2D1.BN60" )
			)
			( pin "@baseboard_fab2_lib.baseboard_fab2(sch_1):page71_i50:vccin(140)"
				( attribute "PN" "BM83"
					( Origin gPackager )
				)
				( objectStatus "U2D1.BM83" )
			)
			( pin "@baseboard_fab2_lib.baseboard_fab2(sch_1):page71_i50:vccin(141)"
				( attribute "PN" "BM81"
					( Origin gPackager )
				)
				( objectStatus "U2D1.BM81" )
			)
			( pin "@baseboard_fab2_lib.baseboard_fab2(sch_1):page71_i50:vccin(142)"
				( attribute "PN" "BM79"
					( Origin gPackager )
				)
				( objectStatus "U2D1.BM79" )
			)
			( pin "@baseboard_fab2_lib.baseboard_fab2(sch_1):page71_i50:vccin(143)"
				( attribute "PN" "BM77"
					( Origin gPackager )
				)
				( objectStatus "U2D1.BM77" )
			)
			( pin "@baseboard_fab2_lib.baseboard_fab2(sch_1):page71_i50:vccin(144)"
				( attribute "PN" "BM75"
					( Origin gPackager )
				)
				( objectStatus "U2D1.BM75" )
			)
			( pin "@baseboard_fab2_lib.baseboard_fab2(sch_1):page71_i50:vccin(145)"
				( attribute "PN" "BM73"
					( Origin gPackager )
				)
				( objectStatus "U2D1.BM73" )
			)
			( pin "@baseboard_fab2_lib.baseboard_fab2(sch_1):page71_i50:vccin(146)"
				( attribute "PN" "BM71"
					( Origin gPackager )
				)
				( objectStatus "U2D1.BM71" )
			)
			( pin "@baseboard_fab2_lib.baseboard_fab2(sch_1):page71_i50:vccin(147)"
				( attribute "PN" "BM69"
					( Origin gPackager )
				)
				( objectStatus "U2D1.BM69" )
			)
			( pin "@baseboard_fab2_lib.baseboard_fab2(sch_1):page71_i50:vccin(148)"
				( attribute "PN" "BM67"
					( Origin gPackager )
				)
				( objectStatus "U2D1.BM67" )
			)
			( pin "@baseboard_fab2_lib.baseboard_fab2(sch_1):page71_i50:vccin(149)"
				( attribute "PN" "BM65"
					( Origin gPackager )
				)
				( objectStatus "U2D1.BM65" )
			)
			( pin "@baseboard_fab2_lib.baseboard_fab2(sch_1):page71_i50:vccin(150)"
				( attribute "PN" "BM63"
					( Origin gPackager )
				)
				( objectStatus "U2D1.BM63" )
			)
			( pin "@baseboard_fab2_lib.baseboard_fab2(sch_1):page71_i50:vccin(151)"
				( attribute "PN" "BM61"
					( Origin gPackager )
				)
				( objectStatus "U2D1.BM61" )
			)
			( pin "@baseboard_fab2_lib.baseboard_fab2(sch_1):page71_i50:vccin(152)"
				( attribute "PN" "BL84"
					( Origin gPackager )
				)
				( objectStatus "U2D1.BL84" )
			)
			( pin "@baseboard_fab2_lib.baseboard_fab2(sch_1):page71_i50:vccin(153)"
				( attribute "PN" "BL62"
					( Origin gPackager )
				)
				( objectStatus "U2D1.BL62" )
			)
			( pin "@baseboard_fab2_lib.baseboard_fab2(sch_1):page71_i50:vccin(154)"
				( attribute "PN" "BL60"
					( Origin gPackager )
				)
				( objectStatus "U2D1.BL60" )
			)
			( pin "@baseboard_fab2_lib.baseboard_fab2(sch_1):page71_i50:vccin(155)"
				( attribute "PN" "BK83"
					( Origin gPackager )
				)
				( objectStatus "U2D1.BK83" )
			)
			( pin "@baseboard_fab2_lib.baseboard_fab2(sch_1):page71_i50:vccin(156)"
				( attribute "PN" "BK81"
					( Origin gPackager )
				)
				( objectStatus "U2D1.BK81" )
			)
			( pin "@baseboard_fab2_lib.baseboard_fab2(sch_1):page71_i50:vccin(157)"
				( attribute "PN" "BK79"
					( Origin gPackager )
				)
				( objectStatus "U2D1.BK79" )
			)
			( pin "@baseboard_fab2_lib.baseboard_fab2(sch_1):page71_i50:vccin(158)"
				( attribute "PN" "BK77"
					( Origin gPackager )
				)
				( objectStatus "U2D1.BK77" )
			)
			( pin "@baseboard_fab2_lib.baseboard_fab2(sch_1):page71_i50:vccin(159)"
				( attribute "PN" "BK75"
					( Origin gPackager )
				)
				( objectStatus "U2D1.BK75" )
			)
			( pin "@baseboard_fab2_lib.baseboard_fab2(sch_1):page71_i50:vccin(160)"
				( attribute "PN" "BK73"
					( Origin gPackager )
				)
				( objectStatus "U2D1.BK73" )
			)
			( pin "@baseboard_fab2_lib.baseboard_fab2(sch_1):page71_i50:vccin(161)"
				( attribute "PN" "BK71"
					( Origin gPackager )
				)
				( objectStatus "U2D1.BK71" )
			)
			( pin "@baseboard_fab2_lib.baseboard_fab2(sch_1):page71_i50:vccin(162)"
				( attribute "PN" "BK69"
					( Origin gPackager )
				)
				( objectStatus "U2D1.BK69" )
			)
			( pin "@baseboard_fab2_lib.baseboard_fab2(sch_1):page71_i50:vccin(163)"
				( attribute "PN" "BK67"
					( Origin gPackager )
				)
				( objectStatus "U2D1.BK67" )
			)
			( pin "@baseboard_fab2_lib.baseboard_fab2(sch_1):page71_i50:vccin(164)"
				( attribute "PN" "BK65"
					( Origin gPackager )
				)
				( objectStatus "U2D1.BK65" )
			)
			( pin "@baseboard_fab2_lib.baseboard_fab2(sch_1):page71_i50:vccin(165)"
				( attribute "PN" "BK63"
					( Origin gPackager )
				)
				( objectStatus "U2D1.BK63" )
			)
			( pin "@baseboard_fab2_lib.baseboard_fab2(sch_1):page71_i50:vccin(166)"
				( attribute "PN" "BK61"
					( Origin gPackager )
				)
				( objectStatus "U2D1.BK61" )
			)
			( pin "@baseboard_fab2_lib.baseboard_fab2(sch_1):page71_i50:vccin(167)"
				( attribute "PN" "BJ84"
					( Origin gPackager )
				)
				( objectStatus "U2D1.BJ84" )
			)
			( pin "@baseboard_fab2_lib.baseboard_fab2(sch_1):page71_i50:vccin(168)"
				( attribute "PN" "BJ82"
					( Origin gPackager )
				)
				( objectStatus "U2D1.BJ82" )
			)
			( pin "@baseboard_fab2_lib.baseboard_fab2(sch_1):page71_i50:vccin(169)"
				( attribute "PN" "BJ80"
					( Origin gPackager )
				)
				( objectStatus "U2D1.BJ80" )
			)
			( pin "@baseboard_fab2_lib.baseboard_fab2(sch_1):page71_i50:vccin(170)"
				( attribute "PN" "BJ78"
					( Origin gPackager )
				)
				( objectStatus "U2D1.BJ78" )
			)
			( pin "@baseboard_fab2_lib.baseboard_fab2(sch_1):page71_i50:vccin(171)"
				( attribute "PN" "BJ76"
					( Origin gPackager )
				)
				( objectStatus "U2D1.BJ76" )
			)
			( pin "@baseboard_fab2_lib.baseboard_fab2(sch_1):page71_i50:vccin(172)"
				( attribute "PN" "BJ74"
					( Origin gPackager )
				)
				( objectStatus "U2D1.BJ74" )
			)
			( pin "@baseboard_fab2_lib.baseboard_fab2(sch_1):page71_i50:vccin(173)"
				( attribute "PN" "BJ72"
					( Origin gPackager )
				)
				( objectStatus "U2D1.BJ72" )
			)
			( pin "@baseboard_fab2_lib.baseboard_fab2(sch_1):page71_i50:vccin(174)"
				( attribute "PN" "BJ70"
					( Origin gPackager )
				)
				( objectStatus "U2D1.BJ70" )
			)
			( pin "@baseboard_fab2_lib.baseboard_fab2(sch_1):page71_i50:vccin(175)"
				( attribute "PN" "BJ68"
					( Origin gPackager )
				)
				( objectStatus "U2D1.BJ68" )
			)
			( pin "@baseboard_fab2_lib.baseboard_fab2(sch_1):page71_i50:vccin(176)"
				( attribute "PN" "BJ66"
					( Origin gPackager )
				)
				( objectStatus "U2D1.BJ66" )
			)
			( pin "@baseboard_fab2_lib.baseboard_fab2(sch_1):page71_i50:vccin(177)"
				( attribute "PN" "BJ64"
					( Origin gPackager )
				)
				( objectStatus "U2D1.BJ64" )
			)
			( pin "@baseboard_fab2_lib.baseboard_fab2(sch_1):page71_i50:vccin(178)"
				( attribute "PN" "BJ62"
					( Origin gPackager )
				)
				( objectStatus "U2D1.BJ62" )
			)
			( pin "@baseboard_fab2_lib.baseboard_fab2(sch_1):page71_i50:vccin(179)"
				( attribute "PN" "BJ60"
					( Origin gPackager )
				)
				( objectStatus "U2D1.BJ60" )
			)
			( pin "@baseboard_fab2_lib.baseboard_fab2(sch_1):page71_i50:vccin(180)"
				( attribute "PN" "BH83"
					( Origin gPackager )
				)
				( objectStatus "U2D1.BH83" )
			)
			( pin "@baseboard_fab2_lib.baseboard_fab2(sch_1):page71_i50:vccin(181)"
				( attribute "PN" "BH81"
					( Origin gPackager )
				)
				( objectStatus "U2D1.BH81" )
			)
			( pin "@baseboard_fab2_lib.baseboard_fab2(sch_1):page71_i50:vccin(182)"
				( attribute "PN" "BH79"
					( Origin gPackager )
				)
				( objectStatus "U2D1.BH79" )
			)
			( pin "@baseboard_fab2_lib.baseboard_fab2(sch_1):page71_i50:vccin(183)"
				( attribute "PN" "BH77"
					( Origin gPackager )
				)
				( objectStatus "U2D1.BH77" )
			)
			( pin "@baseboard_fab2_lib.baseboard_fab2(sch_1):page71_i50:vccin(184)"
				( attribute "PN" "BH75"
					( Origin gPackager )
				)
				( objectStatus "U2D1.BH75" )
			)
			( pin "@baseboard_fab2_lib.baseboard_fab2(sch_1):page71_i50:vccin(185)"
				( attribute "PN" "BH73"
					( Origin gPackager )
				)
				( objectStatus "U2D1.BH73" )
			)
			( pin "@baseboard_fab2_lib.baseboard_fab2(sch_1):page71_i50:vccin(186)"
				( attribute "PN" "BH71"
					( Origin gPackager )
				)
				( objectStatus "U2D1.BH71" )
			)
			( pin "@baseboard_fab2_lib.baseboard_fab2(sch_1):page71_i50:vccin(187)"
				( attribute "PN" "BH69"
					( Origin gPackager )
				)
				( objectStatus "U2D1.BH69" )
			)
			( pin "@baseboard_fab2_lib.baseboard_fab2(sch_1):page71_i50:vccin(188)"
				( attribute "PN" "BH67"
					( Origin gPackager )
				)
				( objectStatus "U2D1.BH67" )
			)
			( pin "@baseboard_fab2_lib.baseboard_fab2(sch_1):page71_i50:vccin(189)"
				( attribute "PN" "BH65"
					( Origin gPackager )
				)
				( objectStatus "U2D1.BH65" )
			)
			( pin "@baseboard_fab2_lib.baseboard_fab2(sch_1):page71_i50:vccin(190)"
				( attribute "PN" "BH63"
					( Origin gPackager )
				)
				( objectStatus "U2D1.BH63" )
			)
			( pin "@baseboard_fab2_lib.baseboard_fab2(sch_1):page71_i50:vccin(191)"
				( attribute "PN" "BH61"
					( Origin gPackager )
				)
				( objectStatus "U2D1.BH61" )
			)
			( pin "@baseboard_fab2_lib.baseboard_fab2(sch_1):page71_i50:vccin(192)"
				( attribute "PN" "BG84"
					( Origin gPackager )
				)
				( objectStatus "U2D1.BG84" )
			)
			( pin "@baseboard_fab2_lib.baseboard_fab2(sch_1):page71_i50:vccin(193)"
				( attribute "PN" "BG70"
					( Origin gPackager )
				)
				( objectStatus "U2D1.BG70" )
			)
			( pin "@baseboard_fab2_lib.baseboard_fab2(sch_1):page71_i50:vccin(194)"
				( attribute "PN" "BG68"
					( Origin gPackager )
				)
				( objectStatus "U2D1.BG68" )
			)
			( pin "@baseboard_fab2_lib.baseboard_fab2(sch_1):page71_i50:vccin(195)"
				( attribute "PN" "BG66"
					( Origin gPackager )
				)
				( objectStatus "U2D1.BG66" )
			)
			( pin "@baseboard_fab2_lib.baseboard_fab2(sch_1):page71_i50:vccin(196)"
				( attribute "PN" "BG64"
					( Origin gPackager )
				)
				( objectStatus "U2D1.BG64" )
			)
			( pin "@baseboard_fab2_lib.baseboard_fab2(sch_1):page71_i50:vccin(197)"
				( attribute "PN" "BG62"
					( Origin gPackager )
				)
				( objectStatus "U2D1.BG62" )
			)
			( pin "@baseboard_fab2_lib.baseboard_fab2(sch_1):page71_i50:vccin(198)"
				( attribute "PN" "BG60"
					( Origin gPackager )
				)
				( objectStatus "U2D1.BG60" )
			)
			( pin "@baseboard_fab2_lib.baseboard_fab2(sch_1):page71_i50:vccin(199)"
				( attribute "PN" "BF85"
					( Origin gPackager )
				)
				( objectStatus "U2D1.BF85" )
			)
			( pin "@baseboard_fab2_lib.baseboard_fab2(sch_1):page71_i50:vccin(200)"
				( attribute "PN" "BF83"
					( Origin gPackager )
				)
				( objectStatus "U2D1.BF83" )
			)
			( pin "@baseboard_fab2_lib.baseboard_fab2(sch_1):page71_i50:vccin(201)"
				( attribute "PN" "BF81"
					( Origin gPackager )
				)
				( objectStatus "U2D1.BF81" )
			)
			( pin "@baseboard_fab2_lib.baseboard_fab2(sch_1):page71_i50:vccin(202)"
				( attribute "PN" "BF79"
					( Origin gPackager )
				)
				( objectStatus "U2D1.BF79" )
			)
			( pin "@baseboard_fab2_lib.baseboard_fab2(sch_1):page71_i50:vccin(203)"
				( attribute "PN" "BF77"
					( Origin gPackager )
				)
				( objectStatus "U2D1.BF77" )
			)
			( pin "@baseboard_fab2_lib.baseboard_fab2(sch_1):page71_i50:vccin(204)"
				( attribute "PN" "BF75"
					( Origin gPackager )
				)
				( objectStatus "U2D1.BF75" )
			)
			( pin "@baseboard_fab2_lib.baseboard_fab2(sch_1):page71_i50:vccin(205)"
				( attribute "PN" "BF73"
					( Origin gPackager )
				)
				( objectStatus "U2D1.BF73" )
			)
			( pin "@baseboard_fab2_lib.baseboard_fab2(sch_1):page71_i50:vccin(206)"
				( attribute "PN" "BF61"
					( Origin gPackager )
				)
				( objectStatus "U2D1.BF61" )
			)
			( pin "@baseboard_fab2_lib.baseboard_fab2(sch_1):page71_i50:vccin(207)"
				( attribute "PN" "BE84"
					( Origin gPackager )
				)
				( objectStatus "U2D1.BE84" )
			)
			( pin "@baseboard_fab2_lib.baseboard_fab2(sch_1):page71_i50:vccin(208)"
				( attribute "PN" "BE82"
					( Origin gPackager )
				)
				( objectStatus "U2D1.BE82" )
			)
			( pin "@baseboard_fab2_lib.baseboard_fab2(sch_1):page71_i50:vccin(209)"
				( attribute "PN" "BE80"
					( Origin gPackager )
				)
				( objectStatus "U2D1.BE80" )
			)
			( pin "@baseboard_fab2_lib.baseboard_fab2(sch_1):page71_i50:vccin(210)"
				( attribute "PN" "BE78"
					( Origin gPackager )
				)
				( objectStatus "U2D1.BE78" )
			)
			( pin "@baseboard_fab2_lib.baseboard_fab2(sch_1):page71_i50:vccin(211)"
				( attribute "PN" "BE76"
					( Origin gPackager )
				)
				( objectStatus "U2D1.BE76" )
			)
			( pin "@baseboard_fab2_lib.baseboard_fab2(sch_1):page71_i50:vccin(212)"
				( attribute "PN" "BE74"
					( Origin gPackager )
				)
				( objectStatus "U2D1.BE74" )
			)
			( pin "@baseboard_fab2_lib.baseboard_fab2(sch_1):page71_i50:vccin(213)"
				( attribute "PN" "BE72"
					( Origin gPackager )
				)
				( objectStatus "U2D1.BE72" )
			)
			( pin "@baseboard_fab2_lib.baseboard_fab2(sch_1):page71_i50:vccin(214)"
				( attribute "PN" "BE62"
					( Origin gPackager )
				)
				( objectStatus "U2D1.BE62" )
			)
			( pin "@baseboard_fab2_lib.baseboard_fab2(sch_1):page71_i50:vccin(215)"
				( attribute "PN" "BE60"
					( Origin gPackager )
				)
				( objectStatus "U2D1.BE60" )
			)
			( pin "@baseboard_fab2_lib.baseboard_fab2(sch_1):page71_i50:vccin(216)"
				( attribute "PN" "BD85"
					( Origin gPackager )
				)
				( objectStatus "U2D1.BD85" )
			)
			( pin "@baseboard_fab2_lib.baseboard_fab2(sch_1):page71_i50:vccin(217)"
				( attribute "PN" "BD83"
					( Origin gPackager )
				)
				( objectStatus "U2D1.BD83" )
			)
			( pin "@baseboard_fab2_lib.baseboard_fab2(sch_1):page71_i50:vccin(218)"
				( attribute "PN" "BD81"
					( Origin gPackager )
				)
				( objectStatus "U2D1.BD81" )
			)
			( pin "@baseboard_fab2_lib.baseboard_fab2(sch_1):page71_i50:vccin(219)"
				( attribute "PN" "BD79"
					( Origin gPackager )
				)
				( objectStatus "U2D1.BD79" )
			)
			( pin "@baseboard_fab2_lib.baseboard_fab2(sch_1):page71_i50:vccin(220)"
				( attribute "PN" "BD77"
					( Origin gPackager )
				)
				( objectStatus "U2D1.BD77" )
			)
			( pin "@baseboard_fab2_lib.baseboard_fab2(sch_1):page71_i50:vccin(221)"
				( attribute "PN" "BD75"
					( Origin gPackager )
				)
				( objectStatus "U2D1.BD75" )
			)
			( pin "@baseboard_fab2_lib.baseboard_fab2(sch_1):page71_i50:vccin(222)"
				( attribute "PN" "BD73"
					( Origin gPackager )
				)
				( objectStatus "U2D1.BD73" )
			)
			( pin "@baseboard_fab2_lib.baseboard_fab2(sch_1):page71_i50:vccin(223)"
				( attribute "PN" "BD61"
					( Origin gPackager )
				)
				( objectStatus "U2D1.BD61" )
			)
			( pin "@baseboard_fab2_lib.baseboard_fab2(sch_1):page71_i50:vccin(224)"
				( attribute "PN" "BC84"
					( Origin gPackager )
				)
				( objectStatus "U2D1.BC84" )
			)
			( pin "@baseboard_fab2_lib.baseboard_fab2(sch_1):page71_i50:vccin(225)"
				( attribute "PN" "BC62"
					( Origin gPackager )
				)
				( objectStatus "U2D1.BC62" )
			)
			( pin "@baseboard_fab2_lib.baseboard_fab2(sch_1):page71_i50:vccin(226)"
				( attribute "PN" "BC60"
					( Origin gPackager )
				)
				( objectStatus "U2D1.BC60" )
			)
			( pin "@baseboard_fab2_lib.baseboard_fab2(sch_1):page71_i50:vccin(227)"
				( attribute "PN" "BB85"
					( Origin gPackager )
				)
				( objectStatus "U2D1.BB85" )
			)
			( pin "@baseboard_fab2_lib.baseboard_fab2(sch_1):page71_i50:vccin(228)"
				( attribute "PN" "BB61"
					( Origin gPackager )
				)
				( objectStatus "U2D1.BB61" )
			)
			( pin "@baseboard_fab2_lib.baseboard_fab2(sch_1):page71_i50:vccin(229)"
				( attribute "PN" "BA60"
					( Origin gPackager )
				)
				( objectStatus "U2D1.BA60" )
			)
			( pin "@baseboard_fab2_lib.baseboard_fab2(sch_1):page71_i50:vccin(230)"
				( attribute "PN" "AY61"
					( Origin gPackager )
				)
				( objectStatus "U2D1.AY61" )
			)
			( pin "@baseboard_fab2_lib.baseboard_fab2(sch_1):page71_i50:vccin(231)"
				( attribute "PN" "AW60"
					( Origin gPackager )
				)
				( objectStatus "U2D1.AW60" )
			)
			( pin "@baseboard_fab2_lib.baseboard_fab2(sch_1):page71_i50:vccin(232)"
				( attribute "PN" "AV61"
					( Origin gPackager )
				)
				( objectStatus "U2D1.AV61" )
			)
			( pin "@baseboard_fab2_lib.baseboard_fab2(sch_1):page71_i50:vccin(233)"
				( attribute "PN" "AV59"
					( Origin gPackager )
				)
				( objectStatus "U2D1.AV59" )
			)
			( pin "@baseboard_fab2_lib.baseboard_fab2(sch_1):page71_i50:vccin(234)"
				( attribute "PN" "AU60"
					( Origin gPackager )
				)
				( objectStatus "U2D1.AU60" )
			)
			( pin "@baseboard_fab2_lib.baseboard_fab2(sch_1):page71_i50:vccin(235)"
				( attribute "PN" "AU58"
					( Origin gPackager )
				)
				( objectStatus "U2D1.AU58" )
			)
			( pin "@baseboard_fab2_lib.baseboard_fab2(sch_1):page71_i50:vccin(236)"
				( attribute "PN" "AT59"
					( Origin gPackager )
				)
				( objectStatus "U2D1.AT59" )
			)
			( pin "@baseboard_fab2_lib.baseboard_fab2(sch_1):page71_i50:vccin(237)"
				( attribute "PN" "AT57"
					( Origin gPackager )
				)
				( objectStatus "U2D1.AT57" )
			)
			( pin "@baseboard_fab2_lib.baseboard_fab2(sch_1):page71_i50:vccin(238)"
				( attribute "PN" "AR58"
					( Origin gPackager )
				)
				( objectStatus "U2D1.AR58" )
			)
			( pin "@baseboard_fab2_lib.baseboard_fab2(sch_1):page71_i50:vccin(239)"
				( attribute "PN" "AR56"
					( Origin gPackager )
				)
				( objectStatus "U2D1.AR56" )
			)
			( pin "@baseboard_fab2_lib.baseboard_fab2(sch_1):page71_i50:vccin(240)"
				( attribute "PN" "AP57"
					( Origin gPackager )
				)
				( objectStatus "U2D1.AP57" )
			)
			( pin "@baseboard_fab2_lib.baseboard_fab2(sch_1):page71_i50:vccin(241)"
				( attribute "PN" "AP55"
					( Origin gPackager )
				)
				( objectStatus "U2D1.AP55" )
			)
			( pin "@baseboard_fab2_lib.baseboard_fab2(sch_1):page71_i50:vccin(242)"
				( attribute "PN" "AN56"
					( Origin gPackager )
				)
				( objectStatus "U2D1.AN56" )
			)
			( pin "@baseboard_fab2_lib.baseboard_fab2(sch_1):page71_i50:vccin(243)"
				( attribute "PN" "AN54"
					( Origin gPackager )
				)
				( objectStatus "U2D1.AN54" )
			)
			( pin "@baseboard_fab2_lib.baseboard_fab2(sch_1):page71_i50:vccin(244)"
				( attribute "PN" "AN32"
					( Origin gPackager )
				)
				( objectStatus "U2D1.AN32" )
			)
			( pin "@baseboard_fab2_lib.baseboard_fab2(sch_1):page71_i50:vccin(245)"
				( attribute "PN" "AM55"
					( Origin gPackager )
				)
				( objectStatus "U2D1.AM55" )
			)
			( pin "@baseboard_fab2_lib.baseboard_fab2(sch_1):page71_i50:vccin(246)"
				( attribute "PN" "AM53"
					( Origin gPackager )
				)
				( objectStatus "U2D1.AM53" )
			)
			( pin "@baseboard_fab2_lib.baseboard_fab2(sch_1):page71_i50:vccin(247)"
				( attribute "PN" "AM33"
					( Origin gPackager )
				)
				( objectStatus "U2D1.AM33" )
			)
			( pin "@baseboard_fab2_lib.baseboard_fab2(sch_1):page71_i50:vccin(248)"
				( attribute "PN" "AL54"
					( Origin gPackager )
				)
				( objectStatus "U2D1.AL54" )
			)
			( pin "@baseboard_fab2_lib.baseboard_fab2(sch_1):page71_i50:vccin(249)"
				( attribute "PN" "AL52"
					( Origin gPackager )
				)
				( objectStatus "U2D1.AL52" )
			)
			( pin "@baseboard_fab2_lib.baseboard_fab2(sch_1):page71_i50:vccin(250)"
				( attribute "PN" "AL50"
					( Origin gPackager )
				)
				( objectStatus "U2D1.AL50" )
			)
			( pin "@baseboard_fab2_lib.baseboard_fab2(sch_1):page71_i50:vccin(251)"
				( attribute "PN" "AL48"
					( Origin gPackager )
				)
				( objectStatus "U2D1.AL48" )
			)
			( pin "@baseboard_fab2_lib.baseboard_fab2(sch_1):page71_i50:vccin(252)"
				( attribute "PN" "AL46"
					( Origin gPackager )
				)
				( objectStatus "U2D1.AL46" )
			)
			( pin "@baseboard_fab2_lib.baseboard_fab2(sch_1):page71_i50:vccin(253)"
				( attribute "PN" "AL34"
					( Origin gPackager )
				)
				( objectStatus "U2D1.AL34" )
			)
			( pin "@baseboard_fab2_lib.baseboard_fab2(sch_1):page71_i50:vccin(254)"
				( attribute "PN" "AK53"
					( Origin gPackager )
				)
				( objectStatus "U2D1.AK53" )
			)
			( pin "@baseboard_fab2_lib.baseboard_fab2(sch_1):page71_i50:vccin(255)"
				( attribute "PN" "AK51"
					( Origin gPackager )
				)
				( objectStatus "U2D1.AK51" )
			)
			( pin "@baseboard_fab2_lib.baseboard_fab2(sch_1):page71_i50:vccin(256)"
				( attribute "PN" "AK49"
					( Origin gPackager )
				)
				( objectStatus "U2D1.AK49" )
			)
			( pin "@baseboard_fab2_lib.baseboard_fab2(sch_1):page71_i50:vccin(257)"
				( attribute "PN" "AK47"
					( Origin gPackager )
				)
				( objectStatus "U2D1.AK47" )
			)
			( pin "@baseboard_fab2_lib.baseboard_fab2(sch_1):page71_i50:vccin(258)"
				( attribute "PN" "AK45"
					( Origin gPackager )
				)
				( objectStatus "U2D1.AK45" )
			)
			( pin "@baseboard_fab2_lib.baseboard_fab2(sch_1):page71_i50:vccin(259)"
				( attribute "PN" "AK35"
					( Origin gPackager )
				)
				( objectStatus "U2D1.AK35" )
			)
			( pin "@baseboard_fab2_lib.baseboard_fab2(sch_1):page71_i50:vccin(260)"
				( attribute "PN" "AJ36"
					( Origin gPackager )
				)
				( objectStatus "U2D1.AJ36" )
			)
			( pin "@baseboard_fab2_lib.baseboard_fab2(sch_1):page71_i50:vccin(261)"
				( attribute "PN" "AH41"
					( Origin gPackager )
				)
				( objectStatus "U2D1.AH41" )
			)
			( pin "@baseboard_fab2_lib.baseboard_fab2(sch_1):page71_i50:vccin(262)"
				( attribute "PN" "AH39"
					( Origin gPackager )
				)
				( objectStatus "U2D1.AH39" )
			)
			( pin "@baseboard_fab2_lib.baseboard_fab2(sch_1):page71_i50:vccin(263)"
				( attribute "PN" "AH37"
					( Origin gPackager )
				)
				( objectStatus "U2D1.AH37" )
			)
			( pin "@baseboard_fab2_lib.baseboard_fab2(sch_1):page71_i50:vccin(264)"
				( attribute "PN" "AG42"
					( Origin gPackager )
				)
				( objectStatus "U2D1.AG42" )
			)
			( pin "@baseboard_fab2_lib.baseboard_fab2(sch_1):page71_i50:vccin(265)"
				( attribute "PN" "AG40"
					( Origin gPackager )
				)
				( objectStatus "U2D1.AG40" )
			)
			( pin "@baseboard_fab2_lib.baseboard_fab2(sch_1):page71_i50:vccin(266)"
				( attribute "PN" "AG38"
					( Origin gPackager )
				)
				( objectStatus "U2D1.AG38" )
			)
			( pin "@baseboard_fab2_lib.baseboard_fab2(sch_1):page71_i50:vccin(267)"
				( attribute "PN" "AF43"
					( Origin gPackager )
				)
				( objectStatus "U2D1.AF43" )
			)
			( pin "@baseboard_fab2_lib.baseboard_fab2(sch_1):page71_i51:vccin(0)"
				( attribute "PN" "CY49"
					( Origin gPackager )
				)
				( objectStatus "U2D1.CY49" )
			)
			( pin "@baseboard_fab2_lib.baseboard_fab2(sch_1):page71_i51:vccin(1)"
				( attribute "PN" "CY47"
					( Origin gPackager )
				)
				( objectStatus "U2D1.CY47" )
			)
			( pin "@baseboard_fab2_lib.baseboard_fab2(sch_1):page71_i51:vccin(2)"
				( attribute "PN" "CW50"
					( Origin gPackager )
				)
				( objectStatus "U2D1.CW50" )
			)
			( pin "@baseboard_fab2_lib.baseboard_fab2(sch_1):page71_i51:vccin(3)"
				( attribute "PN" "CW48"
					( Origin gPackager )
				)
				( objectStatus "U2D1.CW48" )
			)
			( pin "@baseboard_fab2_lib.baseboard_fab2(sch_1):page71_i51:vccin(4)"
				( attribute "PN" "CW46"
					( Origin gPackager )
				)
				( objectStatus "U2D1.CW46" )
			)
			( pin "@baseboard_fab2_lib.baseboard_fab2(sch_1):page71_i51:vccin(5)"
				( attribute "PN" "CV51"
					( Origin gPackager )
				)
				( objectStatus "U2D1.CV51" )
			)
			( pin "@baseboard_fab2_lib.baseboard_fab2(sch_1):page71_i51:vccin(6)"
				( attribute "PN" "CU54"
					( Origin gPackager )
				)
				( objectStatus "U2D1.CU54" )
			)
			( pin "@baseboard_fab2_lib.baseboard_fab2(sch_1):page71_i51:vccin(7)"
				( attribute "PN" "CU52"
					( Origin gPackager )
				)
				( objectStatus "U2D1.CU52" )
			)
			( pin "@baseboard_fab2_lib.baseboard_fab2(sch_1):page71_i51:vccin(8)"
				( attribute "PN" "CU42"
					( Origin gPackager )
				)
				( objectStatus "U2D1.CU42" )
			)
			( pin "@baseboard_fab2_lib.baseboard_fab2(sch_1):page71_i51:vccin(9)"
				( attribute "PN" "CU40"
					( Origin gPackager )
				)
				( objectStatus "U2D1.CU40" )
			)
			( pin "@baseboard_fab2_lib.baseboard_fab2(sch_1):page71_i51:vccin(10)"
				( attribute "PN" "CU38"
					( Origin gPackager )
				)
				( objectStatus "U2D1.CU38" )
			)
			( pin "@baseboard_fab2_lib.baseboard_fab2(sch_1):page71_i51:vccin(11)"
				( attribute "PN" "CT55"
					( Origin gPackager )
				)
				( objectStatus "U2D1.CT55" )
			)
			( pin "@baseboard_fab2_lib.baseboard_fab2(sch_1):page71_i51:vccin(12)"
				( attribute "PN" "CT53"
					( Origin gPackager )
				)
				( objectStatus "U2D1.CT53" )
			)
			( pin "@baseboard_fab2_lib.baseboard_fab2(sch_1):page71_i51:vccin(13)"
				( attribute "PN" "CT41"
					( Origin gPackager )
				)
				( objectStatus "U2D1.CT41" )
			)
			( pin "@baseboard_fab2_lib.baseboard_fab2(sch_1):page71_i51:vccin(14)"
				( attribute "PN" "CT39"
					( Origin gPackager )
				)
				( objectStatus "U2D1.CT39" )
			)
			( pin "@baseboard_fab2_lib.baseboard_fab2(sch_1):page71_i51:vccin(15)"
				( attribute "PN" "CT37"
					( Origin gPackager )
				)
				( objectStatus "U2D1.CT37" )
			)
			( pin "@baseboard_fab2_lib.baseboard_fab2(sch_1):page71_i51:vccin(16)"
				( attribute "PN" "CR56"
					( Origin gPackager )
				)
				( objectStatus "U2D1.CR56" )
			)
			( pin "@baseboard_fab2_lib.baseboard_fab2(sch_1):page71_i51:vccin(17)"
				( attribute "PN" "CR54"
					( Origin gPackager )
				)
				( objectStatus "U2D1.CR54" )
			)
			( pin "@baseboard_fab2_lib.baseboard_fab2(sch_1):page71_i51:vccin(18)"
				( attribute "PN" "CR34"
					( Origin gPackager )
				)
				( objectStatus "U2D1.CR34" )
			)
			( pin "@baseboard_fab2_lib.baseboard_fab2(sch_1):page71_i51:vccin(19)"
				( attribute "PN" "CP57"
					( Origin gPackager )
				)
				( objectStatus "U2D1.CP57" )
			)
			( pin "@baseboard_fab2_lib.baseboard_fab2(sch_1):page71_i51:vccin(20)"
				( attribute "PN" "CP55"
					( Origin gPackager )
				)
				( objectStatus "U2D1.CP55" )
			)
			( pin "@baseboard_fab2_lib.baseboard_fab2(sch_1):page71_i51:vccin(21)"
				( attribute "PN" "CP33"
					( Origin gPackager )
				)
				( objectStatus "U2D1.CP33" )
			)
			( pin "@baseboard_fab2_lib.baseboard_fab2(sch_1):page71_i51:vccin(22)"
				( attribute "PN" "CN58"
					( Origin gPackager )
				)
				( objectStatus "U2D1.CN58" )
			)
			( pin "@baseboard_fab2_lib.baseboard_fab2(sch_1):page71_i51:vccin(23)"
				( attribute "PN" "CN56"
					( Origin gPackager )
				)
				( objectStatus "U2D1.CN56" )
			)
			( pin "@baseboard_fab2_lib.baseboard_fab2(sch_1):page71_i51:vccin(24)"
				( attribute "PN" "CM59"
					( Origin gPackager )
				)
				( objectStatus "U2D1.CM59" )
			)
			( pin "@baseboard_fab2_lib.baseboard_fab2(sch_1):page71_i51:vccin(25)"
				( attribute "PN" "CM57"
					( Origin gPackager )
				)
				( objectStatus "U2D1.CM57" )
			)
			( pin "@baseboard_fab2_lib.baseboard_fab2(sch_1):page71_i51:vccin(26)"
				( attribute "PN" "CL60"
					( Origin gPackager )
				)
				( objectStatus "U2D1.CL60" )
			)
			( pin "@baseboard_fab2_lib.baseboard_fab2(sch_1):page71_i51:vccin(27)"
				( attribute "PN" "CL58"
					( Origin gPackager )
				)
				( objectStatus "U2D1.CL58" )
			)
			( pin "@baseboard_fab2_lib.baseboard_fab2(sch_1):page71_i51:vccin(28)"
				( attribute "PN" "CK61"
					( Origin gPackager )
				)
				( objectStatus "U2D1.CK61" )
			)
			( pin "@baseboard_fab2_lib.baseboard_fab2(sch_1):page71_i51:vccin(29)"
				( attribute "PN" "CK59"
					( Origin gPackager )
				)
				( objectStatus "U2D1.CK59" )
			)
			( pin "@baseboard_fab2_lib.baseboard_fab2(sch_1):page71_i51:vccin(30)"
				( attribute "PN" "CJ60"
					( Origin gPackager )
				)
				( objectStatus "U2D1.CJ60" )
			)
			( pin "@baseboard_fab2_lib.baseboard_fab2(sch_1):page71_i51:vccin(31)"
				( attribute "PN" "CH85"
					( Origin gPackager )
				)
				( objectStatus "U2D1.CH85" )
			)
			( pin "@baseboard_fab2_lib.baseboard_fab2(sch_1):page71_i51:vccin(32)"
				( attribute "PN" "CH61"
					( Origin gPackager )
				)
				( objectStatus "U2D1.CH61" )
			)
			( pin "@baseboard_fab2_lib.baseboard_fab2(sch_1):page71_i51:vccin(33)"
				( attribute "PN" "CG84"
					( Origin gPackager )
				)
				( objectStatus "U2D1.CG84" )
			)
			( pin "@baseboard_fab2_lib.baseboard_fab2(sch_1):page71_i51:vccin(34)"
				( attribute "PN" "CG60"
					( Origin gPackager )
				)
				( objectStatus "U2D1.CG60" )
			)
			( pin "@baseboard_fab2_lib.baseboard_fab2(sch_1):page71_i51:vccin(35)"
				( attribute "PN" "CF85"
					( Origin gPackager )
				)
				( objectStatus "U2D1.CF85" )
			)
			( pin "@baseboard_fab2_lib.baseboard_fab2(sch_1):page71_i51:vccin(36)"
				( attribute "PN" "CF61"
					( Origin gPackager )
				)
				( objectStatus "U2D1.CF61" )
			)
			( pin "@baseboard_fab2_lib.baseboard_fab2(sch_1):page71_i51:vccin(37)"
				( attribute "PN" "CE84"
					( Origin gPackager )
				)
				( objectStatus "U2D1.CE84" )
			)
			( pin "@baseboard_fab2_lib.baseboard_fab2(sch_1):page71_i51:vccin(38)"
				( attribute "PN" "CE60"
					( Origin gPackager )
				)
				( objectStatus "U2D1.CE60" )
			)
			( pin "@baseboard_fab2_lib.baseboard_fab2(sch_1):page71_i51:vccin(39)"
				( attribute "PN" "CD85"
					( Origin gPackager )
				)
				( objectStatus "U2D1.CD85" )
			)
			( pin "@baseboard_fab2_lib.baseboard_fab2(sch_1):page71_i51:vccin(40)"
				( attribute "PN" "CD83"
					( Origin gPackager )
				)
				( objectStatus "U2D1.CD83" )
			)
			( pin "@baseboard_fab2_lib.baseboard_fab2(sch_1):page71_i51:vccin(41)"
				( attribute "PN" "CD61"
					( Origin gPackager )
				)
				( objectStatus "U2D1.CD61" )
			)
			( pin "@baseboard_fab2_lib.baseboard_fab2(sch_1):page71_i51:vccin(42)"
				( attribute "PN" "CC84"
					( Origin gPackager )
				)
				( objectStatus "U2D1.CC84" )
			)
			( pin "@baseboard_fab2_lib.baseboard_fab2(sch_1):page71_i51:vccin(43)"
				( attribute "PN" "CC62"
					( Origin gPackager )
				)
				( objectStatus "U2D1.CC62" )
			)
			( pin "@baseboard_fab2_lib.baseboard_fab2(sch_1):page71_i51:vccin(44)"
				( attribute "PN" "CC60"
					( Origin gPackager )
				)
				( objectStatus "U2D1.CC60" )
			)
			( pin "@baseboard_fab2_lib.baseboard_fab2(sch_1):page71_i51:vccin(45)"
				( attribute "PN" "CB83"
					( Origin gPackager )
				)
				( objectStatus "U2D1.CB83" )
			)
			( pin "@baseboard_fab2_lib.baseboard_fab2(sch_1):page71_i51:vccin(46)"
				( attribute "PN" "CB81"
					( Origin gPackager )
				)
				( objectStatus "U2D1.CB81" )
			)
			( pin "@baseboard_fab2_lib.baseboard_fab2(sch_1):page71_i51:vccin(47)"
				( attribute "PN" "CB79"
					( Origin gPackager )
				)
				( objectStatus "U2D1.CB79" )
			)
			( pin "@baseboard_fab2_lib.baseboard_fab2(sch_1):page71_i51:vccin(48)"
				( attribute "PN" "CB77"
					( Origin gPackager )
				)
				( objectStatus "U2D1.CB77" )
			)
			( pin "@baseboard_fab2_lib.baseboard_fab2(sch_1):page71_i51:vccin(49)"
				( attribute "PN" "CB75"
					( Origin gPackager )
				)
				( objectStatus "U2D1.CB75" )
			)
			( pin "@baseboard_fab2_lib.baseboard_fab2(sch_1):page71_i51:vccin(50)"
				( attribute "PN" "CB73"
					( Origin gPackager )
				)
				( objectStatus "U2D1.CB73" )
			)
			( pin "@baseboard_fab2_lib.baseboard_fab2(sch_1):page71_i51:vccin(51)"
				( attribute "PN" "CB61"
					( Origin gPackager )
				)
				( objectStatus "U2D1.CB61" )
			)
			( pin "@baseboard_fab2_lib.baseboard_fab2(sch_1):page71_i51:vccin(52)"
				( attribute "PN" "CA84"
					( Origin gPackager )
				)
				( objectStatus "U2D1.CA84" )
			)
			( pin "@baseboard_fab2_lib.baseboard_fab2(sch_1):page71_i51:vccin(53)"
				( attribute "PN" "CA82"
					( Origin gPackager )
				)
				( objectStatus "U2D1.CA82" )
			)
			( pin "@baseboard_fab2_lib.baseboard_fab2(sch_1):page71_i51:vccin(54)"
				( attribute "PN" "CA80"
					( Origin gPackager )
				)
				( objectStatus "U2D1.CA80" )
			)
			( pin "@baseboard_fab2_lib.baseboard_fab2(sch_1):page71_i51:vccin(55)"
				( attribute "PN" "CA78"
					( Origin gPackager )
				)
				( objectStatus "U2D1.CA78" )
			)
			( pin "@baseboard_fab2_lib.baseboard_fab2(sch_1):page71_i51:vccin(56)"
				( attribute "PN" "CA76"
					( Origin gPackager )
				)
				( objectStatus "U2D1.CA76" )
			)
			( pin "@baseboard_fab2_lib.baseboard_fab2(sch_1):page71_i51:vccin(57)"
				( attribute "PN" "CA74"
					( Origin gPackager )
				)
				( objectStatus "U2D1.CA74" )
			)
			( pin "@baseboard_fab2_lib.baseboard_fab2(sch_1):page71_i51:vccin(58)"
				( attribute "PN" "CA72"
					( Origin gPackager )
				)
				( objectStatus "U2D1.CA72" )
			)
			( pin "@baseboard_fab2_lib.baseboard_fab2(sch_1):page71_i51:vccin(59)"
				( attribute "PN" "CA62"
					( Origin gPackager )
				)
				( objectStatus "U2D1.CA62" )
			)
			( pin "@baseboard_fab2_lib.baseboard_fab2(sch_1):page71_i51:vccin(60)"
				( attribute "PN" "CA60"
					( Origin gPackager )
				)
				( objectStatus "U2D1.CA60" )
			)
			( pin "@baseboard_fab2_lib.baseboard_fab2(sch_1):page71_i51:vccin(61)"
				( attribute "PN" "BY83"
					( Origin gPackager )
				)
				( objectStatus "U2D1.BY83" )
			)
			( pin "@baseboard_fab2_lib.baseboard_fab2(sch_1):page71_i51:vccin(62)"
				( attribute "PN" "BY81"
					( Origin gPackager )
				)
				( objectStatus "U2D1.BY81" )
			)
			( pin "@baseboard_fab2_lib.baseboard_fab2(sch_1):page71_i51:vccin(63)"
				( attribute "PN" "BY79"
					( Origin gPackager )
				)
				( objectStatus "U2D1.BY79" )
			)
			( pin "@baseboard_fab2_lib.baseboard_fab2(sch_1):page71_i51:vccin(64)"
				( attribute "PN" "BY77"
					( Origin gPackager )
				)
				( objectStatus "U2D1.BY77" )
			)
			( pin "@baseboard_fab2_lib.baseboard_fab2(sch_1):page71_i51:vccin(65)"
				( attribute "PN" "BY75"
					( Origin gPackager )
				)
				( objectStatus "U2D1.BY75" )
			)
			( pin "@baseboard_fab2_lib.baseboard_fab2(sch_1):page71_i51:vccin(66)"
				( attribute "PN" "BY73"
					( Origin gPackager )
				)
				( objectStatus "U2D1.BY73" )
			)
			( pin "@baseboard_fab2_lib.baseboard_fab2(sch_1):page71_i51:vccin(67)"
				( attribute "PN" "BY61"
					( Origin gPackager )
				)
				( objectStatus "U2D1.BY61" )
			)
			( pin "@baseboard_fab2_lib.baseboard_fab2(sch_1):page71_i51:vccin(68)"
				( attribute "PN" "BW84"
					( Origin gPackager )
				)
				( objectStatus "U2D1.BW84" )
			)
			( pin "@baseboard_fab2_lib.baseboard_fab2(sch_1):page71_i51:vccin(69)"
				( attribute "PN" "BW70"
					( Origin gPackager )
				)
				( objectStatus "U2D1.BW70" )
			)
			( pin "@baseboard_fab2_lib.baseboard_fab2(sch_1):page71_i51:vccin(70)"
				( attribute "PN" "BW68"
					( Origin gPackager )
				)
				( objectStatus "U2D1.BW68" )
			)
			( pin "@baseboard_fab2_lib.baseboard_fab2(sch_1):page71_i51:vccin(71)"
				( attribute "PN" "BW66"
					( Origin gPackager )
				)
				( objectStatus "U2D1.BW66" )
			)
			( pin "@baseboard_fab2_lib.baseboard_fab2(sch_1):page71_i51:vccin(72)"
				( attribute "PN" "BW64"
					( Origin gPackager )
				)
				( objectStatus "U2D1.BW64" )
			)
			( pin "@baseboard_fab2_lib.baseboard_fab2(sch_1):page71_i51:vccin(73)"
				( attribute "PN" "BW62"
					( Origin gPackager )
				)
				( objectStatus "U2D1.BW62" )
			)
			( pin "@baseboard_fab2_lib.baseboard_fab2(sch_1):page71_i51:vccin(74)"
				( attribute "PN" "BW60"
					( Origin gPackager )
				)
				( objectStatus "U2D1.BW60" )
			)
			( pin "@baseboard_fab2_lib.baseboard_fab2(sch_1):page71_i51:vccin(75)"
				( attribute "PN" "BV83"
					( Origin gPackager )
				)
				( objectStatus "U2D1.BV83" )
			)
			( pin "@baseboard_fab2_lib.baseboard_fab2(sch_1):page71_i51:vccin(76)"
				( attribute "PN" "BV81"
					( Origin gPackager )
				)
				( objectStatus "U2D1.BV81" )
			)
			( pin "@baseboard_fab2_lib.baseboard_fab2(sch_1):page71_i51:vccin(77)"
				( attribute "PN" "BV79"
					( Origin gPackager )
				)
				( objectStatus "U2D1.BV79" )
			)
			( pin "@baseboard_fab2_lib.baseboard_fab2(sch_1):page71_i51:vccin(78)"
				( attribute "PN" "BV77"
					( Origin gPackager )
				)
				( objectStatus "U2D1.BV77" )
			)
			( pin "@baseboard_fab2_lib.baseboard_fab2(sch_1):page71_i51:vccin(79)"
				( attribute "PN" "BV75"
					( Origin gPackager )
				)
				( objectStatus "U2D1.BV75" )
			)
			( pin "@baseboard_fab2_lib.baseboard_fab2(sch_1):page71_i51:vccin(80)"
				( attribute "PN" "BV73"
					( Origin gPackager )
				)
				( objectStatus "U2D1.BV73" )
			)
			( pin "@baseboard_fab2_lib.baseboard_fab2(sch_1):page71_i51:vccin(81)"
				( attribute "PN" "BV71"
					( Origin gPackager )
				)
				( objectStatus "U2D1.BV71" )
			)
			( pin "@baseboard_fab2_lib.baseboard_fab2(sch_1):page71_i51:vccin(82)"
				( attribute "PN" "BV69"
					( Origin gPackager )
				)
				( objectStatus "U2D1.BV69" )
			)
			( pin "@baseboard_fab2_lib.baseboard_fab2(sch_1):page71_i51:vccin(83)"
				( attribute "PN" "BV67"
					( Origin gPackager )
				)
				( objectStatus "U2D1.BV67" )
			)
			( pin "@baseboard_fab2_lib.baseboard_fab2(sch_1):page71_i51:vccin(84)"
				( attribute "PN" "BV65"
					( Origin gPackager )
				)
				( objectStatus "U2D1.BV65" )
			)
			( pin "@baseboard_fab2_lib.baseboard_fab2(sch_1):page71_i51:vccin(85)"
				( attribute "PN" "BV63"
					( Origin gPackager )
				)
				( objectStatus "U2D1.BV63" )
			)
			( pin "@baseboard_fab2_lib.baseboard_fab2(sch_1):page71_i51:vccin(86)"
				( attribute "PN" "BV61"
					( Origin gPackager )
				)
				( objectStatus "U2D1.BV61" )
			)
			( pin "@baseboard_fab2_lib.baseboard_fab2(sch_1):page71_i51:vccin(87)"
				( attribute "PN" "BU84"
					( Origin gPackager )
				)
				( objectStatus "U2D1.BU84" )
			)
			( pin "@baseboard_fab2_lib.baseboard_fab2(sch_1):page71_i51:vccin(88)"
				( attribute "PN" "BU82"
					( Origin gPackager )
				)
				( objectStatus "U2D1.BU82" )
			)
			( pin "@baseboard_fab2_lib.baseboard_fab2(sch_1):page71_i51:vccin(89)"
				( attribute "PN" "BU80"
					( Origin gPackager )
				)
				( objectStatus "U2D1.BU80" )
			)
			( pin "@baseboard_fab2_lib.baseboard_fab2(sch_1):page71_i51:vccin(90)"
				( attribute "PN" "BU78"
					( Origin gPackager )
				)
				( objectStatus "U2D1.BU78" )
			)
			( pin "@baseboard_fab2_lib.baseboard_fab2(sch_1):page71_i51:vccin(91)"
				( attribute "PN" "BU76"
					( Origin gPackager )
				)
				( objectStatus "U2D1.BU76" )
			)
			( pin "@baseboard_fab2_lib.baseboard_fab2(sch_1):page71_i51:vccin(92)"
				( attribute "PN" "BU74"
					( Origin gPackager )
				)
				( objectStatus "U2D1.BU74" )
			)
			( pin "@baseboard_fab2_lib.baseboard_fab2(sch_1):page71_i51:vccin(93)"
				( attribute "PN" "BU72"
					( Origin gPackager )
				)
				( objectStatus "U2D1.BU72" )
			)
			( pin "@baseboard_fab2_lib.baseboard_fab2(sch_1):page71_i51:vccin(94)"
				( attribute "PN" "BU70"
					( Origin gPackager )
				)
				( objectStatus "U2D1.BU70" )
			)
			( pin "@baseboard_fab2_lib.baseboard_fab2(sch_1):page71_i51:vccin(95)"
				( attribute "PN" "BU68"
					( Origin gPackager )
				)
				( objectStatus "U2D1.BU68" )
			)
			( pin "@baseboard_fab2_lib.baseboard_fab2(sch_1):page71_i51:vccin(96)"
				( attribute "PN" "BU66"
					( Origin gPackager )
				)
				( objectStatus "U2D1.BU66" )
			)
			( pin "@baseboard_fab2_lib.baseboard_fab2(sch_1):page71_i51:vccin(97)"
				( attribute "PN" "BU64"
					( Origin gPackager )
				)
				( objectStatus "U2D1.BU64" )
			)
			( pin "@baseboard_fab2_lib.baseboard_fab2(sch_1):page71_i51:vccin(98)"
				( attribute "PN" "BU62"
					( Origin gPackager )
				)
				( objectStatus "U2D1.BU62" )
			)
			( pin "@baseboard_fab2_lib.baseboard_fab2(sch_1):page71_i51:vccin(99)"
				( attribute "PN" "BU60"
					( Origin gPackager )
				)
				( objectStatus "U2D1.BU60" )
			)
			( pin "@baseboard_fab2_lib.baseboard_fab2(sch_1):page71_i51:vccin(100)"
				( attribute "PN" "BT83"
					( Origin gPackager )
				)
				( objectStatus "U2D1.BT83" )
			)
			( pin "@baseboard_fab2_lib.baseboard_fab2(sch_1):page71_i51:vccin(101)"
				( attribute "PN" "BT81"
					( Origin gPackager )
				)
				( objectStatus "U2D1.BT81" )
			)
			( pin "@baseboard_fab2_lib.baseboard_fab2(sch_1):page71_i51:vccin(102)"
				( attribute "PN" "BT79"
					( Origin gPackager )
				)
				( objectStatus "U2D1.BT79" )
			)
			( pin "@baseboard_fab2_lib.baseboard_fab2(sch_1):page71_i51:vccin(103)"
				( attribute "PN" "BT77"
					( Origin gPackager )
				)
				( objectStatus "U2D1.BT77" )
			)
			( pin "@baseboard_fab2_lib.baseboard_fab2(sch_1):page71_i51:vccin(104)"
				( attribute "PN" "BT75"
					( Origin gPackager )
				)
				( objectStatus "U2D1.BT75" )
			)
			( pin "@baseboard_fab2_lib.baseboard_fab2(sch_1):page71_i51:vccin(105)"
				( attribute "PN" "BT73"
					( Origin gPackager )
				)
				( objectStatus "U2D1.BT73" )
			)
			( pin "@baseboard_fab2_lib.baseboard_fab2(sch_1):page71_i51:vccin(106)"
				( attribute "PN" "BT71"
					( Origin gPackager )
				)
				( objectStatus "U2D1.BT71" )
			)
			( pin "@baseboard_fab2_lib.baseboard_fab2(sch_1):page71_i51:vccin(107)"
				( attribute "PN" "BT69"
					( Origin gPackager )
				)
				( objectStatus "U2D1.BT69" )
			)
			( pin "@baseboard_fab2_lib.baseboard_fab2(sch_1):page71_i51:vccin(108)"
				( attribute "PN" "BT67"
					( Origin gPackager )
				)
				( objectStatus "U2D1.BT67" )
			)
			( pin "@baseboard_fab2_lib.baseboard_fab2(sch_1):page71_i51:vccin(109)"
				( attribute "PN" "BT65"
					( Origin gPackager )
				)
				( objectStatus "U2D1.BT65" )
			)
			( pin "@baseboard_fab2_lib.baseboard_fab2(sch_1):page71_i51:vccin(110)"
				( attribute "PN" "BT63"
					( Origin gPackager )
				)
				( objectStatus "U2D1.BT63" )
			)
			( pin "@baseboard_fab2_lib.baseboard_fab2(sch_1):page71_i51:vccin(111)"
				( attribute "PN" "BT61"
					( Origin gPackager )
				)
				( objectStatus "U2D1.BT61" )
			)
			( pin "@baseboard_fab2_lib.baseboard_fab2(sch_1):page71_i51:vccin(112)"
				( attribute "PN" "BR84"
					( Origin gPackager )
				)
				( objectStatus "U2D1.BR84" )
			)
			( pin "@baseboard_fab2_lib.baseboard_fab2(sch_1):page71_i51:vccin(113)"
				( attribute "PN" "BR62"
					( Origin gPackager )
				)
				( objectStatus "U2D1.BR62" )
			)
			( pin "@baseboard_fab2_lib.baseboard_fab2(sch_1):page71_i51:vccin(114)"
				( attribute "PN" "BR60"
					( Origin gPackager )
				)
				( objectStatus "U2D1.BR60" )
			)
			( pin "@baseboard_fab2_lib.baseboard_fab2(sch_1):page71_i51:vccin(115)"
				( attribute "PN" "BP83"
					( Origin gPackager )
				)
				( objectStatus "U2D1.BP83" )
			)
			( pin "@baseboard_fab2_lib.baseboard_fab2(sch_1):page71_i51:vccin(116)"
				( attribute "PN" "BP81"
					( Origin gPackager )
				)
				( objectStatus "U2D1.BP81" )
			)
			( pin "@baseboard_fab2_lib.baseboard_fab2(sch_1):page71_i51:vccin(117)"
				( attribute "PN" "BP79"
					( Origin gPackager )
				)
				( objectStatus "U2D1.BP79" )
			)
			( pin "@baseboard_fab2_lib.baseboard_fab2(sch_1):page71_i51:vccin(118)"
				( attribute "PN" "BP77"
					( Origin gPackager )
				)
				( objectStatus "U2D1.BP77" )
			)
			( pin "@baseboard_fab2_lib.baseboard_fab2(sch_1):page71_i51:vccin(119)"
				( attribute "PN" "BP75"
					( Origin gPackager )
				)
				( objectStatus "U2D1.BP75" )
			)
			( pin "@baseboard_fab2_lib.baseboard_fab2(sch_1):page71_i51:vccin(120)"
				( attribute "PN" "BP73"
					( Origin gPackager )
				)
				( objectStatus "U2D1.BP73" )
			)
			( pin "@baseboard_fab2_lib.baseboard_fab2(sch_1):page71_i51:vccin(121)"
				( attribute "PN" "BP71"
					( Origin gPackager )
				)
				( objectStatus "U2D1.BP71" )
			)
			( pin "@baseboard_fab2_lib.baseboard_fab2(sch_1):page71_i51:vccin(122)"
				( attribute "PN" "BP69"
					( Origin gPackager )
				)
				( objectStatus "U2D1.BP69" )
			)
			( pin "@baseboard_fab2_lib.baseboard_fab2(sch_1):page71_i51:vccin(123)"
				( attribute "PN" "BP67"
					( Origin gPackager )
				)
				( objectStatus "U2D1.BP67" )
			)
			( pin "@baseboard_fab2_lib.baseboard_fab2(sch_1):page71_i51:vccin(124)"
				( attribute "PN" "BP65"
					( Origin gPackager )
				)
				( objectStatus "U2D1.BP65" )
			)
			( pin "@baseboard_fab2_lib.baseboard_fab2(sch_1):page71_i51:vccin(125)"
				( attribute "PN" "BP63"
					( Origin gPackager )
				)
				( objectStatus "U2D1.BP63" )
			)
			( pin "@baseboard_fab2_lib.baseboard_fab2(sch_1):page71_i51:vccin(126)"
				( attribute "PN" "BP61"
					( Origin gPackager )
				)
				( objectStatus "U2D1.BP61" )
			)
			( pin "@baseboard_fab2_lib.baseboard_fab2(sch_1):page71_i51:vccin(127)"
				( attribute "PN" "BN84"
					( Origin gPackager )
				)
				( objectStatus "U2D1.BN84" )
			)
			( pin "@baseboard_fab2_lib.baseboard_fab2(sch_1):page71_i51:vccin(128)"
				( attribute "PN" "BN82"
					( Origin gPackager )
				)
				( objectStatus "U2D1.BN82" )
			)
			( pin "@baseboard_fab2_lib.baseboard_fab2(sch_1):page71_i51:vccin(129)"
				( attribute "PN" "BN80"
					( Origin gPackager )
				)
				( objectStatus "U2D1.BN80" )
			)
			( pin "@baseboard_fab2_lib.baseboard_fab2(sch_1):page71_i51:vccin_sense"
				( attribute "PN" "BA86"
					( Origin gPackager )
				)
				( objectStatus "U2D1.BA86" )
			)
			( pin "@baseboard_fab2_lib.baseboard_fab2(sch_1):page71_i51:vccinpmax(0)"
				( attribute "PN" "AW86"
					( Origin gPackager )
				)
				( objectStatus "U2D1.AW86" )
			)
			( pin "@baseboard_fab2_lib.baseboard_fab2(sch_1):page71_i51:vccinpmax(1)"
				( attribute "PN" "AV85"
					( Origin gPackager )
				)
				( objectStatus "U2D1.AV85" )
			)
			( pin "@baseboard_fab2_lib.baseboard_fab2(sch_1):page71_i51:vsensepmax"
				( attribute "PN" "AD41"
					( Origin gPackager )
				)
				( objectStatus "U2D1.AD41" )
			)
			( pin "@baseboard_fab2_lib.baseboard_fab2(sch_1):page71_i51:vss_vccin_sense"
				( attribute "PN" "AY85"
					( Origin gPackager )
				)
				( objectStatus "U2D1.AY85" )
			)
			( pin "@baseboard_fab2_lib.baseboard_fab2(sch_1):page71_i53:a"
				( attribute "PN" "1"
					( Origin gPackager )
				)
				( objectStatus "R3D32.1" )
			)
			( pin "@baseboard_fab2_lib.baseboard_fab2(sch_1):page71_i53:b"
				( attribute "PN" "2"
					( Origin gPackager )
				)
				( objectStatus "R3D32.2" )
			)
			( pin "@baseboard_fab2_lib.baseboard_fab2(sch_1):page72_i25:a"
				( attribute "PN" "1"
					( Origin gPackager )
				)
				( objectStatus "C3D3.1" )
			)
			( pin "@baseboard_fab2_lib.baseboard_fab2(sch_1):page72_i25:b"
				( attribute "PN" "2"
					( Origin gPackager )
				)
				( objectStatus "C3D3.2" )
			)
			( pin "@baseboard_fab2_lib.baseboard_fab2(sch_1):page72_i32:vccd012(0)"
				( attribute "PN" "B49"
					( Origin gPackager )
				)
				( objectStatus "U2D1.B49" )
			)
			( pin "@baseboard_fab2_lib.baseboard_fab2(sch_1):page72_i32:vccd012(1)"
				( attribute "PN" "B53"
					( Origin gPackager )
				)
				( objectStatus "U2D1.B53" )
			)
			( pin "@baseboard_fab2_lib.baseboard_fab2(sch_1):page72_i32:vccd012(2)"
				( attribute "PN" "B59"
					( Origin gPackager )
				)
				( objectStatus "U2D1.B59" )
			)
			( pin "@baseboard_fab2_lib.baseboard_fab2(sch_1):page72_i32:vccd012(3)"
				( attribute "PN" "E46"
					( Origin gPackager )
				)
				( objectStatus "U2D1.E46" )
			)
			( pin "@baseboard_fab2_lib.baseboard_fab2(sch_1):page72_i32:vccd012(4)"
				( attribute "PN" "E48"
					( Origin gPackager )
				)
				( objectStatus "U2D1.E48" )
			)
			( pin "@baseboard_fab2_lib.baseboard_fab2(sch_1):page72_i32:vccd012(5)"
				( attribute "PN" "E50"
					( Origin gPackager )
				)
				( objectStatus "U2D1.E50" )
			)
			( pin "@baseboard_fab2_lib.baseboard_fab2(sch_1):page72_i32:vccd012(6)"
				( attribute "PN" "E52"
					( Origin gPackager )
				)
				( objectStatus "U2D1.E52" )
			)
			( pin "@baseboard_fab2_lib.baseboard_fab2(sch_1):page72_i32:vccd012(7)"
				( attribute "PN" "E54"
					( Origin gPackager )
				)
				( objectStatus "U2D1.E54" )
			)
			( pin "@baseboard_fab2_lib.baseboard_fab2(sch_1):page72_i32:vccd012(8)"
				( attribute "PN" "E56"
					( Origin gPackager )
				)
				( objectStatus "U2D1.E56" )
			)
			( pin "@baseboard_fab2_lib.baseboard_fab2(sch_1):page72_i32:vccd012(9)"
				( attribute "PN" "E58"
					( Origin gPackager )
				)
				( objectStatus "U2D1.E58" )
			)
			( pin "@baseboard_fab2_lib.baseboard_fab2(sch_1):page72_i32:vccd012(10)"
				( attribute "PN" "E60"
					( Origin gPackager )
				)
				( objectStatus "U2D1.E60" )
			)
			( pin "@baseboard_fab2_lib.baseboard_fab2(sch_1):page72_i32:vccd012(11)"
				( attribute "PN" "E62"
					( Origin gPackager )
				)
				( objectStatus "U2D1.E62" )
			)
			( pin "@baseboard_fab2_lib.baseboard_fab2(sch_1):page72_i32:vccd012(12)"
				( attribute "PN" "E64"
					( Origin gPackager )
				)
				( objectStatus "U2D1.E64" )
			)
			( pin "@baseboard_fab2_lib.baseboard_fab2(sch_1):page72_i32:vccd012(13)"
				( attribute "PN" "L46"
					( Origin gPackager )
				)
				( objectStatus "U2D1.L46" )
			)
			( pin "@baseboard_fab2_lib.baseboard_fab2(sch_1):page72_i32:vccd012(14)"
				( attribute "PN" "L48"
					( Origin gPackager )
				)
				( objectStatus "U2D1.L48" )
			)
			( pin "@baseboard_fab2_lib.baseboard_fab2(sch_1):page72_i32:vccd012(15)"
				( attribute "PN" "L50"
					( Origin gPackager )
				)
				( objectStatus "U2D1.L50" )
			)
			( pin "@baseboard_fab2_lib.baseboard_fab2(sch_1):page72_i32:vccd012(16)"
				( attribute "PN" "L52"
					( Origin gPackager )
				)
				( objectStatus "U2D1.L52" )
			)
			( pin "@baseboard_fab2_lib.baseboard_fab2(sch_1):page72_i32:vccd012(17)"
				( attribute "PN" "L54"
					( Origin gPackager )
				)
				( objectStatus "U2D1.L54" )
			)
			( pin "@baseboard_fab2_lib.baseboard_fab2(sch_1):page72_i32:vccd012(18)"
				( attribute "PN" "L56"
					( Origin gPackager )
				)
				( objectStatus "U2D1.L56" )
			)
			( pin "@baseboard_fab2_lib.baseboard_fab2(sch_1):page72_i32:vccd012(19)"
				( attribute "PN" "L58"
					( Origin gPackager )
				)
				( objectStatus "U2D1.L58" )
			)
			( pin "@baseboard_fab2_lib.baseboard_fab2(sch_1):page72_i32:vccd012(20)"
				( attribute "PN" "L60"
					( Origin gPackager )
				)
				( objectStatus "U2D1.L60" )
			)
			( pin "@baseboard_fab2_lib.baseboard_fab2(sch_1):page72_i32:vccd012(21)"
				( attribute "PN" "L62"
					( Origin gPackager )
				)
				( objectStatus "U2D1.L62" )
			)
			( pin "@baseboard_fab2_lib.baseboard_fab2(sch_1):page72_i32:vccd012(22)"
				( attribute "PN" "N64"
					( Origin gPackager )
				)
				( objectStatus "U2D1.N64" )
			)
			( pin "@baseboard_fab2_lib.baseboard_fab2(sch_1):page72_i32:vccd012(23)"
				( attribute "PN" "U46"
					( Origin gPackager )
				)
				( objectStatus "U2D1.U46" )
			)
			( pin "@baseboard_fab2_lib.baseboard_fab2(sch_1):page72_i32:vccd012(24)"
				( attribute "PN" "U48"
					( Origin gPackager )
				)
				( objectStatus "U2D1.U48" )
			)
			( pin "@baseboard_fab2_lib.baseboard_fab2(sch_1):page72_i32:vccd012(25)"
				( attribute "PN" "U50"
					( Origin gPackager )
				)
				( objectStatus "U2D1.U50" )
			)
			( pin "@baseboard_fab2_lib.baseboard_fab2(sch_1):page72_i32:vccd012(26)"
				( attribute "PN" "U52"
					( Origin gPackager )
				)
				( objectStatus "U2D1.U52" )
			)
			( pin "@baseboard_fab2_lib.baseboard_fab2(sch_1):page72_i32:vccd012(27)"
				( attribute "PN" "U54"
					( Origin gPackager )
				)
				( objectStatus "U2D1.U54" )
			)
			( pin "@baseboard_fab2_lib.baseboard_fab2(sch_1):page72_i32:vccd012(28)"
				( attribute "PN" "U56"
					( Origin gPackager )
				)
				( objectStatus "U2D1.U56" )
			)
			( pin "@baseboard_fab2_lib.baseboard_fab2(sch_1):page72_i32:vccd012(29)"
				( attribute "PN" "U58"
					( Origin gPackager )
				)
				( objectStatus "U2D1.U58" )
			)
			( pin "@baseboard_fab2_lib.baseboard_fab2(sch_1):page72_i32:vccd012(30)"
				( attribute "PN" "U60"
					( Origin gPackager )
				)
				( objectStatus "U2D1.U60" )
			)
			( pin "@baseboard_fab2_lib.baseboard_fab2(sch_1):page72_i32:vccd012(31)"
				( attribute "PN" "U62"
					( Origin gPackager )
				)
				( objectStatus "U2D1.U62" )
			)
			( pin "@baseboard_fab2_lib.baseboard_fab2(sch_1):page72_i32:vccd012(32)"
				( attribute "PN" "W64"
					( Origin gPackager )
				)
				( objectStatus "U2D1.W64" )
			)
			( pin "@baseboard_fab2_lib.baseboard_fab2(sch_1):page72_i32:vccd012(33)"
				( attribute "PN" "Y45"
					( Origin gPackager )
				)
				( objectStatus "U2D1.Y45" )
			)
			( pin "@baseboard_fab2_lib.baseboard_fab2(sch_1):page72_i32:vccd012(34)"
				( attribute "PN" "Y47"
					( Origin gPackager )
				)
				( objectStatus "U2D1.Y47" )
			)
			( pin "@baseboard_fab2_lib.baseboard_fab2(sch_1):page72_i32:vccd012(35)"
				( attribute "PN" "Y49"
					( Origin gPackager )
				)
				( objectStatus "U2D1.Y49" )
			)
			( pin "@baseboard_fab2_lib.baseboard_fab2(sch_1):page72_i32:vccd012(36)"
				( attribute "PN" "Y51"
					( Origin gPackager )
				)
				( objectStatus "U2D1.Y51" )
			)
			( pin "@baseboard_fab2_lib.baseboard_fab2(sch_1):page72_i32:vccd012(37)"
				( attribute "PN" "Y53"
					( Origin gPackager )
				)
				( objectStatus "U2D1.Y53" )
			)
			( pin "@baseboard_fab2_lib.baseboard_fab2(sch_1):page72_i32:vccd012(38)"
				( attribute "PN" "Y55"
					( Origin gPackager )
				)
				( objectStatus "U2D1.Y55" )
			)
			( pin "@baseboard_fab2_lib.baseboard_fab2(sch_1):page72_i32:vccd012(39)"
				( attribute "PN" "Y57"
					( Origin gPackager )
				)
				( objectStatus "U2D1.Y57" )
			)
			( pin "@baseboard_fab2_lib.baseboard_fab2(sch_1):page72_i32:vccd012(40)"
				( attribute "PN" "Y59"
					( Origin gPackager )
				)
				( objectStatus "U2D1.Y59" )
			)
			( pin "@baseboard_fab2_lib.baseboard_fab2(sch_1):page72_i32:vccd012(41)"
				( attribute "PN" "Y61"
					( Origin gPackager )
				)
				( objectStatus "U2D1.Y61" )
			)
			( pin "@baseboard_fab2_lib.baseboard_fab2(sch_1):page72_i32:vccd012(42)"
				( attribute "PN" "Y63"
					( Origin gPackager )
				)
				( objectStatus "U2D1.Y63" )
			)
			( pin "@baseboard_fab2_lib.baseboard_fab2(sch_1):page72_i32:vccd012(43)"
				( attribute "PN" "AD45"
					( Origin gPackager )
				)
				( objectStatus "U2D1.AD45" )
			)
			( pin "@baseboard_fab2_lib.baseboard_fab2(sch_1):page72_i32:vccd012(44)"
				( attribute "PN" "AF55"
					( Origin gPackager )
				)
				( objectStatus "U2D1.AF55" )
			)
			( pin "@baseboard_fab2_lib.baseboard_fab2(sch_1):page72_i32:vccd012(45)"
				( attribute "PN" "AF57"
					( Origin gPackager )
				)
				( objectStatus "U2D1.AF57" )
			)
			( pin "@baseboard_fab2_lib.baseboard_fab2(sch_1):page72_i32:vccd012(46)"
				( attribute "PN" "AF59"
					( Origin gPackager )
				)
				( objectStatus "U2D1.AF59" )
			)
			( pin "@baseboard_fab2_lib.baseboard_fab2(sch_1):page72_i32:vccd012(47)"
				( attribute "PN" "AF61"
					( Origin gPackager )
				)
				( objectStatus "U2D1.AF61" )
			)
			( pin "@baseboard_fab2_lib.baseboard_fab2(sch_1):page72_i32:vccd012(48)"
				( attribute "PN" "AF63"
					( Origin gPackager )
				)
				( objectStatus "U2D1.AF63" )
			)
			( pin "@baseboard_fab2_lib.baseboard_fab2(sch_1):page72_i32:vccd012(49)"
				( attribute "PN" "D45"
					( Origin gPackager )
				)
				( objectStatus "U2D1.D45" )
			)
			( pin "@baseboard_fab2_lib.baseboard_fab2(sch_1):page72_i32:vccd012(50)"
				( attribute "PN" "C46"
					( Origin gPackager )
				)
				( objectStatus "U2D1.C46" )
			)
			( pin "@baseboard_fab2_lib.baseboard_fab2(sch_1):page72_i32:vccd012(51)"
				( attribute "PN" "B47"
					( Origin gPackager )
				)
				( objectStatus "U2D1.B47" )
			)
			( pin "@baseboard_fab2_lib.baseboard_fab2(sch_1):page72_i32:vccd345(0)"
				( attribute "PN" "EF59"
					( Origin gPackager )
				)
				( objectStatus "U2D1.EF59" )
			)
			( pin "@baseboard_fab2_lib.baseboard_fab2(sch_1):page72_i32:vccd345(1)"
				( attribute "PN" "EF53"
					( Origin gPackager )
				)
				( objectStatus "U2D1.EF53" )
			)
			( pin "@baseboard_fab2_lib.baseboard_fab2(sch_1):page72_i32:vccd345(2)"
				( attribute "PN" "EF49"
					( Origin gPackager )
				)
				( objectStatus "U2D1.EF49" )
			)
			( pin "@baseboard_fab2_lib.baseboard_fab2(sch_1):page72_i32:vccd345(3)"
				( attribute "PN" "EC62"
					( Origin gPackager )
				)
				( objectStatus "U2D1.EC62" )
			)
			( pin "@baseboard_fab2_lib.baseboard_fab2(sch_1):page72_i32:vccd345(4)"
				( attribute "PN" "EC60"
					( Origin gPackager )
				)
				( objectStatus "U2D1.EC60" )
			)
			( pin "@baseboard_fab2_lib.baseboard_fab2(sch_1):page72_i32:vccd345(5)"
				( attribute "PN" "EC58"
					( Origin gPackager )
				)
				( objectStatus "U2D1.EC58" )
			)
			( pin "@baseboard_fab2_lib.baseboard_fab2(sch_1):page72_i32:vccd345(6)"
				( attribute "PN" "EC56"
					( Origin gPackager )
				)
				( objectStatus "U2D1.EC56" )
			)
			( pin "@baseboard_fab2_lib.baseboard_fab2(sch_1):page72_i32:vccd345(7)"
				( attribute "PN" "EC54"
					( Origin gPackager )
				)
				( objectStatus "U2D1.EC54" )
			)
			( pin "@baseboard_fab2_lib.baseboard_fab2(sch_1):page72_i32:vccd345(8)"
				( attribute "PN" "EC52"
					( Origin gPackager )
				)
				( objectStatus "U2D1.EC52" )
			)
			( pin "@baseboard_fab2_lib.baseboard_fab2(sch_1):page72_i32:vccd345(9)"
				( attribute "PN" "EC50"
					( Origin gPackager )
				)
				( objectStatus "U2D1.EC50" )
			)
			( pin "@baseboard_fab2_lib.baseboard_fab2(sch_1):page72_i32:vccd345(10)"
				( attribute "PN" "EC48"
					( Origin gPackager )
				)
				( objectStatus "U2D1.EC48" )
			)
			( pin "@baseboard_fab2_lib.baseboard_fab2(sch_1):page72_i32:vccd345(11)"
				( attribute "PN" "EC46"
					( Origin gPackager )
				)
				( objectStatus "U2D1.EC46" )
			)
			( pin "@baseboard_fab2_lib.baseboard_fab2(sch_1):page72_i32:vccd345(12)"
				( attribute "PN" "DU64"
					( Origin gPackager )
				)
				( objectStatus "U2D1.DU64" )
			)
			( pin "@baseboard_fab2_lib.baseboard_fab2(sch_1):page72_i32:vccd345(13)"
				( attribute "PN" "DU62"
					( Origin gPackager )
				)
				( objectStatus "U2D1.DU62" )
			)
			( pin "@baseboard_fab2_lib.baseboard_fab2(sch_1):page72_i32:vccd345(14)"
				( attribute "PN" "DU60"
					( Origin gPackager )
				)
				( objectStatus "U2D1.DU60" )
			)
			( pin "@baseboard_fab2_lib.baseboard_fab2(sch_1):page72_i32:vccd345(15)"
				( attribute "PN" "DU58"
					( Origin gPackager )
				)
				( objectStatus "U2D1.DU58" )
			)
			( pin "@baseboard_fab2_lib.baseboard_fab2(sch_1):page72_i32:vccd345(16)"
				( attribute "PN" "DU56"
					( Origin gPackager )
				)
				( objectStatus "U2D1.DU56" )
			)
			( pin "@baseboard_fab2_lib.baseboard_fab2(sch_1):page72_i32:vccd345(17)"
				( attribute "PN" "DU54"
					( Origin gPackager )
				)
				( objectStatus "U2D1.DU54" )
			)
			( pin "@baseboard_fab2_lib.baseboard_fab2(sch_1):page72_i32:vccd345(18)"
				( attribute "PN" "DU52"
					( Origin gPackager )
				)
				( objectStatus "U2D1.DU52" )
			)
			( pin "@baseboard_fab2_lib.baseboard_fab2(sch_1):page72_i32:vccd345(19)"
				( attribute "PN" "DU50"
					( Origin gPackager )
				)
				( objectStatus "U2D1.DU50" )
			)
			( pin "@baseboard_fab2_lib.baseboard_fab2(sch_1):page72_i32:vccd345(20)"
				( attribute "PN" "DU48"
					( Origin gPackager )
				)
				( objectStatus "U2D1.DU48" )
			)
			( pin "@baseboard_fab2_lib.baseboard_fab2(sch_1):page72_i32:vccd345(21)"
				( attribute "PN" "DU46"
					( Origin gPackager )
				)
				( objectStatus "U2D1.DU46" )
			)
			( pin "@baseboard_fab2_lib.baseboard_fab2(sch_1):page72_i32:vccd345(22)"
				( attribute "PN" "DL62"
					( Origin gPackager )
				)
				( objectStatus "U2D1.DL62" )
			)
			( pin "@baseboard_fab2_lib.baseboard_fab2(sch_1):page72_i32:vccd345(23)"
				( attribute "PN" "DL60"
					( Origin gPackager )
				)
				( objectStatus "U2D1.DL60" )
			)
			( pin "@baseboard_fab2_lib.baseboard_fab2(sch_1):page72_i32:vccd345(24)"
				( attribute "PN" "DL58"
					( Origin gPackager )
				)
				( objectStatus "U2D1.DL58" )
			)
			( pin "@baseboard_fab2_lib.baseboard_fab2(sch_1):page72_i32:vccd345(25)"
				( attribute "PN" "DL56"
					( Origin gPackager )
				)
				( objectStatus "U2D1.DL56" )
			)
			( pin "@baseboard_fab2_lib.baseboard_fab2(sch_1):page72_i32:vccd345(26)"
				( attribute "PN" "DL54"
					( Origin gPackager )
				)
				( objectStatus "U2D1.DL54" )
			)
			( pin "@baseboard_fab2_lib.baseboard_fab2(sch_1):page72_i32:vccd345(27)"
				( attribute "PN" "DL52"
					( Origin gPackager )
				)
				( objectStatus "U2D1.DL52" )
			)
			( pin "@baseboard_fab2_lib.baseboard_fab2(sch_1):page72_i32:vccd345(28)"
				( attribute "PN" "DL50"
					( Origin gPackager )
				)
				( objectStatus "U2D1.DL50" )
			)
			( pin "@baseboard_fab2_lib.baseboard_fab2(sch_1):page72_i32:vccd345(29)"
				( attribute "PN" "DL48"
					( Origin gPackager )
				)
				( objectStatus "U2D1.DL48" )
			)
			( pin "@baseboard_fab2_lib.baseboard_fab2(sch_1):page72_i32:vccd345(30)"
				( attribute "PN" "DL46"
					( Origin gPackager )
				)
				( objectStatus "U2D1.DL46" )
			)
			( pin "@baseboard_fab2_lib.baseboard_fab2(sch_1):page72_i32:vccd345(31)"
				( attribute "PN" "DJ64"
					( Origin gPackager )
				)
				( objectStatus "U2D1.DJ64" )
			)
			( pin "@baseboard_fab2_lib.baseboard_fab2(sch_1):page72_i32:vccd345(32)"
				( attribute "PN" "DH63"
					( Origin gPackager )
				)
				( objectStatus "U2D1.DH63" )
			)
			( pin "@baseboard_fab2_lib.baseboard_fab2(sch_1):page72_i32:vccd345(33)"
				( attribute "PN" "DH61"
					( Origin gPackager )
				)
				( objectStatus "U2D1.DH61" )
			)
			( pin "@baseboard_fab2_lib.baseboard_fab2(sch_1):page72_i32:vccd345(34)"
				( attribute "PN" "DH59"
					( Origin gPackager )
				)
				( objectStatus "U2D1.DH59" )
			)
			( pin "@baseboard_fab2_lib.baseboard_fab2(sch_1):page72_i32:vccd345(35)"
				( attribute "PN" "DH57"
					( Origin gPackager )
				)
				( objectStatus "U2D1.DH57" )
			)
			( pin "@baseboard_fab2_lib.baseboard_fab2(sch_1):page72_i32:vccd345(36)"
				( attribute "PN" "DH55"
					( Origin gPackager )
				)
				( objectStatus "U2D1.DH55" )
			)
			( pin "@baseboard_fab2_lib.baseboard_fab2(sch_1):page72_i32:vccd345(37)"
				( attribute "PN" "DH53"
					( Origin gPackager )
				)
				( objectStatus "U2D1.DH53" )
			)
			( pin "@baseboard_fab2_lib.baseboard_fab2(sch_1):page72_i32:vccd345(38)"
				( attribute "PN" "DH51"
					( Origin gPackager )
				)
				( objectStatus "U2D1.DH51" )
			)
			( pin "@baseboard_fab2_lib.baseboard_fab2(sch_1):page72_i32:vccd345(39)"
				( attribute "PN" "DH49"
					( Origin gPackager )
				)
				( objectStatus "U2D1.DH49" )
			)
			( pin "@baseboard_fab2_lib.baseboard_fab2(sch_1):page72_i32:vccd345(40)"
				( attribute "PN" "DH47"
					( Origin gPackager )
				)
				( objectStatus "U2D1.DH47" )
			)
			( pin "@baseboard_fab2_lib.baseboard_fab2(sch_1):page72_i32:vccd345(41)"
				( attribute "PN" "DH45"
					( Origin gPackager )
				)
				( objectStatus "U2D1.DH45" )
			)
			( pin "@baseboard_fab2_lib.baseboard_fab2(sch_1):page72_i32:vccd345(42)"
				( attribute "PN" "DD45"
					( Origin gPackager )
				)
				( objectStatus "U2D1.DD45" )
			)
			( pin "@baseboard_fab2_lib.baseboard_fab2(sch_1):page72_i32:vccd345(43)"
				( attribute "PN" "DB63"
					( Origin gPackager )
				)
				( objectStatus "U2D1.DB63" )
			)
			( pin "@baseboard_fab2_lib.baseboard_fab2(sch_1):page72_i32:vccd345(44)"
				( attribute "PN" "DB61"
					( Origin gPackager )
				)
				( objectStatus "U2D1.DB61" )
			)
			( pin "@baseboard_fab2_lib.baseboard_fab2(sch_1):page72_i32:vccd345(45)"
				( attribute "PN" "DB59"
					( Origin gPackager )
				)
				( objectStatus "U2D1.DB59" )
			)
			( pin "@baseboard_fab2_lib.baseboard_fab2(sch_1):page72_i32:vccd345(46)"
				( attribute "PN" "DB57"
					( Origin gPackager )
				)
				( objectStatus "U2D1.DB57" )
			)
			( pin "@baseboard_fab2_lib.baseboard_fab2(sch_1):page72_i32:vccd345(47)"
				( attribute "PN" "DB55"
					( Origin gPackager )
				)
				( objectStatus "U2D1.DB55" )
			)
			( pin "@baseboard_fab2_lib.baseboard_fab2(sch_1):page72_i32:vccd345(48)"
				( attribute "PN" "DB53"
					( Origin gPackager )
				)
				( objectStatus "U2D1.DB53" )
			)
			( pin "@baseboard_fab2_lib.baseboard_fab2(sch_1):page72_i32:vccd345(49)"
				( attribute "PN" "EF45"
					( Origin gPackager )
				)
				( objectStatus "U2D1.EF45" )
			)
			( pin "@baseboard_fab2_lib.baseboard_fab2(sch_1):page72_i32:vccd345(50)"
				( attribute "PN" "EE44"
					( Origin gPackager )
				)
				( objectStatus "U2D1.EE44" )
			)
			( pin "@baseboard_fab2_lib.baseboard_fab2(sch_1):page72_i33:cd_vcc_core(0)"
				( attribute "PN" "BL14"
					( Origin gPackager )
				)
				( objectStatus "U2D1.BL14" )
			)
			( pin "@baseboard_fab2_lib.baseboard_fab2(sch_1):page72_i33:cd_vcc_core(1)"
				( attribute "PN" "BK15"
					( Origin gPackager )
				)
				( objectStatus "U2D1.BK15" )
			)
			( pin "@baseboard_fab2_lib.baseboard_fab2(sch_1):page72_i33:cd_vcc_core(2)"
				( attribute "PN" "BK13"
					( Origin gPackager )
				)
				( objectStatus "U2D1.BK13" )
			)
			( pin "@baseboard_fab2_lib.baseboard_fab2(sch_1):page72_i33:cd_vcc_core(3)"
				( attribute "PN" "BJ14"
					( Origin gPackager )
				)
				( objectStatus "U2D1.BJ14" )
			)
			( pin "@baseboard_fab2_lib.baseboard_fab2(sch_1):page72_i33:cd_vcc_core(4)"
				( attribute "PN" "BJ12"
					( Origin gPackager )
				)
				( objectStatus "U2D1.BJ12" )
			)
			( pin "@baseboard_fab2_lib.baseboard_fab2(sch_1):page72_i33:cd_vcc_core(5)"
				( attribute "PN" "BH13"
					( Origin gPackager )
				)
				( objectStatus "U2D1.BH13" )
			)
			( pin "@baseboard_fab2_lib.baseboard_fab2(sch_1):page72_i33:cd_vcc_core(6)"
				( attribute "PN" "BG14"
					( Origin gPackager )
				)
				( objectStatus "U2D1.BG14" )
			)
			( pin "@baseboard_fab2_lib.baseboard_fab2(sch_1):page72_i33:cd_vcc_core(7)"
				( attribute "PN" "BG12"
					( Origin gPackager )
				)
				( objectStatus "U2D1.BG12" )
			)
			( pin "@baseboard_fab2_lib.baseboard_fab2(sch_1):page72_i33:cd_vcc_core(8)"
				( attribute "PN" "BF13"
					( Origin gPackager )
				)
				( objectStatus "U2D1.BF13" )
			)
			( pin "@baseboard_fab2_lib.baseboard_fab2(sch_1):page72_i33:cd_vcc_core(9)"
				( attribute "PN" "BF11"
					( Origin gPackager )
				)
				( objectStatus "U2D1.BF11" )
			)
			( pin "@baseboard_fab2_lib.baseboard_fab2(sch_1):page72_i33:cd_vcc_core(10)"
				( attribute "PN" "BE14"
					( Origin gPackager )
				)
				( objectStatus "U2D1.BE14" )
			)
			( pin "@baseboard_fab2_lib.baseboard_fab2(sch_1):page72_i33:cd_vcc_core(11)"
				( attribute "PN" "BE12"
					( Origin gPackager )
				)
				( objectStatus "U2D1.BE12" )
			)
			( pin "@baseboard_fab2_lib.baseboard_fab2(sch_1):page72_i33:cd_vcc_core(12)"
				( attribute "PN" "BD13"
					( Origin gPackager )
				)
				( objectStatus "U2D1.BD13" )
			)
			( pin "@baseboard_fab2_lib.baseboard_fab2(sch_1):page72_i33:cd_vccin(0)"
				( attribute "PN" "BT27"
					( Origin gPackager )
				)
				( objectStatus "U2D1.BT27" )
			)
			( pin "@baseboard_fab2_lib.baseboard_fab2(sch_1):page72_i33:cd_vccin(1)"
				( attribute "PN" "BU26"
					( Origin gPackager )
				)
				( objectStatus "U2D1.BU26" )
			)
			( pin "@baseboard_fab2_lib.baseboard_fab2(sch_1):page72_i33:cd_vccin(2)"
				( attribute "PN" "BV27"
					( Origin gPackager )
				)
				( objectStatus "U2D1.BV27" )
			)
			( pin "@baseboard_fab2_lib.baseboard_fab2(sch_1):page72_i33:cd_vccin(3)"
				( attribute "PN" "BY27"
					( Origin gPackager )
				)
				( objectStatus "U2D1.BY27" )
			)
			( pin "@baseboard_fab2_lib.baseboard_fab2(sch_1):page72_i33:cd_vccp(0)"
				( attribute "PN" "BV15"
					( Origin gPackager )
				)
				( objectStatus "U2D1.BV15" )
			)
			( pin "@baseboard_fab2_lib.baseboard_fab2(sch_1):page72_i33:cd_vccp(1)"
				( attribute "PN" "BV13"
					( Origin gPackager )
				)
				( objectStatus "U2D1.BV13" )
			)
			( pin "@baseboard_fab2_lib.baseboard_fab2(sch_1):page72_i33:cd_vccp(2)"
				( attribute "PN" "BV11"
					( Origin gPackager )
				)
				( objectStatus "U2D1.BV11" )
			)
			( pin "@baseboard_fab2_lib.baseboard_fab2(sch_1):page72_i33:cd_vccp(3)"
				( attribute "PN" "BU14"
					( Origin gPackager )
				)
				( objectStatus "U2D1.BU14" )
			)
			( pin "@baseboard_fab2_lib.baseboard_fab2(sch_1):page72_i33:cd_vccp(4)"
				( attribute "PN" "BU12"
					( Origin gPackager )
				)
				( objectStatus "U2D1.BU12" )
			)
			( pin "@baseboard_fab2_lib.baseboard_fab2(sch_1):page72_i33:cd_vccp(5)"
				( attribute "PN" "BT15"
					( Origin gPackager )
				)
				( objectStatus "U2D1.BT15" )
			)
			( pin "@baseboard_fab2_lib.baseboard_fab2(sch_1):page72_i33:cd_vccp(6)"
				( attribute "PN" "BT13"
					( Origin gPackager )
				)
				( objectStatus "U2D1.BT13" )
			)
			( pin "@baseboard_fab2_lib.baseboard_fab2(sch_1):page72_i33:cd_vccp(7)"
				( attribute "PN" "BT11"
					( Origin gPackager )
				)
				( objectStatus "U2D1.BT11" )
			)
			( pin "@baseboard_fab2_lib.baseboard_fab2(sch_1):page72_i33:cd_vccp(8)"
				( attribute "PN" "BR14"
					( Origin gPackager )
				)
				( objectStatus "U2D1.BR14" )
			)
			( pin "@baseboard_fab2_lib.baseboard_fab2(sch_1):page72_i33:cd_vccp(9)"
				( attribute "PN" "BR12"
					( Origin gPackager )
				)
				( objectStatus "U2D1.BR12" )
			)
			( pin "@baseboard_fab2_lib.baseboard_fab2(sch_1):page72_i33:cd_vccp(10)"
				( attribute "PN" "BP15"
					( Origin gPackager )
				)
				( objectStatus "U2D1.BP15" )
			)
			( pin "@baseboard_fab2_lib.baseboard_fab2(sch_1):page72_i33:cd_vccp(11)"
				( attribute "PN" "BP13"
					( Origin gPackager )
				)
				( objectStatus "U2D1.BP13" )
			)
			( pin "@baseboard_fab2_lib.baseboard_fab2(sch_1):page72_i33:cd_vccp(12)"
				( attribute "PN" "BP11"
					( Origin gPackager )
				)
				( objectStatus "U2D1.BP11" )
			)
			( pin "@baseboard_fab2_lib.baseboard_fab2(sch_1):page72_i33:cd_vccp(13)"
				( attribute "PN" "BN14"
					( Origin gPackager )
				)
				( objectStatus "U2D1.BN14" )
			)
			( pin "@baseboard_fab2_lib.baseboard_fab2(sch_1):page72_i33:cd_vccp(14)"
				( attribute "PN" "BN12"
					( Origin gPackager )
				)
				( objectStatus "U2D1.BN12" )
			)
			( pin "@baseboard_fab2_lib.baseboard_fab2(sch_1):page72_i33:cd_vccp(15)"
				( attribute "PN" "BM11"
					( Origin gPackager )
				)
				( objectStatus "U2D1.BM11" )
			)
			( pin "@baseboard_fab2_lib.baseboard_fab2(sch_1):page72_i33:cd_vpp(0)"
				( attribute "PN" "B11"
					( Origin gPackager )
				)
				( objectStatus "U2D1.B11" )
			)
			( pin "@baseboard_fab2_lib.baseboard_fab2(sch_1):page72_i33:cd_vpp(1)"
				( attribute "PN" "A12"
					( Origin gPackager )
				)
				( objectStatus "U2D1.A12" )
			)
			( pin "@baseboard_fab2_lib.baseboard_fab2(sch_1):page72_i33:cd_vpp(2)"
				( attribute "PN" "A10"
					( Origin gPackager )
				)
				( objectStatus "U2D1.A10" )
			)
			( pin "@baseboard_fab2_lib.baseboard_fab2(sch_1):page72_i33:cd_vpp(3)"
				( attribute "PN" "A8"
					( Origin gPackager )
				)
				( objectStatus "U2D1.A8" )
			)
			( pin "@baseboard_fab2_lib.baseboard_fab2(sch_1):page72_i33:vcc33"
				( attribute "PN" "CY55"
					( Origin gPackager )
				)
				( objectStatus "U2D1.CY55" )
			)
			( pin "@baseboard_fab2_lib.baseboard_fab2(sch_1):page72_i33:vccio(20)"
				( attribute "PN" "CM15"
					( Origin gPackager )
				)
				( objectStatus "U2D1.CM15" )
			)
			( pin "@baseboard_fab2_lib.baseboard_fab2(sch_1):page72_i33:vccio(21)"
				( attribute "PN" "CL12"
					( Origin gPackager )
				)
				( objectStatus "U2D1.CL12" )
			)
			( pin "@baseboard_fab2_lib.baseboard_fab2(sch_1):page72_i33:vccio(22)"
				( attribute "PN" "CK5"
					( Origin gPackager )
				)
				( objectStatus "U2D1.CK5" )
			)
			( pin "@baseboard_fab2_lib.baseboard_fab2(sch_1):page72_i33:vccio(23)"
				( attribute "PN" "CV7"
					( Origin gPackager )
				)
				( objectStatus "U2D1.CV7" )
			)
			( pin "@baseboard_fab2_lib.baseboard_fab2(sch_1):page72_i33:vccio(24)"
				( attribute "PN" "CH9"
					( Origin gPackager )
				)
				( objectStatus "U2D1.CH9" )
			)
			( pin "@baseboard_fab2_lib.baseboard_fab2(sch_1):page72_i33:vccio(25)"
				( attribute "PN" "D7"
					( Origin gPackager )
				)
				( objectStatus "U2D1.D7" )
			)
			( pin "@baseboard_fab2_lib.baseboard_fab2(sch_1):page72_i33:vccio(26)"
				( attribute "PN" "CE18"
					( Origin gPackager )
				)
				( objectStatus "U2D1.CE18" )
			)
			( pin "@baseboard_fab2_lib.baseboard_fab2(sch_1):page72_i33:vccio(27)"
				( attribute "PN" "CD9"
					( Origin gPackager )
				)
				( objectStatus "U2D1.CD9" )
			)
			( pin "@baseboard_fab2_lib.baseboard_fab2(sch_1):page72_i33:vccio(28)"
				( attribute "PN" "CB17"
					( Origin gPackager )
				)
				( objectStatus "U2D1.CB17" )
			)
			( pin "@baseboard_fab2_lib.baseboard_fab2(sch_1):page72_i33:vccio(29)"
				( attribute "PN" "CB13"
					( Origin gPackager )
				)
				( objectStatus "U2D1.CB13" )
			)
			( pin "@baseboard_fab2_lib.baseboard_fab2(sch_1):page72_i33:vccio(30)"
				( attribute "PN" "BP25"
					( Origin gPackager )
				)
				( objectStatus "U2D1.BP25" )
			)
			( pin "@baseboard_fab2_lib.baseboard_fab2(sch_1):page72_i33:vccio(31)"
				( attribute "PN" "BJ24"
					( Origin gPackager )
				)
				( objectStatus "U2D1.BJ24" )
			)
			( pin "@baseboard_fab2_lib.baseboard_fab2(sch_1):page72_i33:vccio(32)"
				( attribute "PN" "BF23"
					( Origin gPackager )
				)
				( objectStatus "U2D1.BF23" )
			)
			( pin "@baseboard_fab2_lib.baseboard_fab2(sch_1):page72_i33:vccio(33)"
				( attribute "PN" "DA14"
					( Origin gPackager )
				)
				( objectStatus "U2D1.DA14" )
			)
			( pin "@baseboard_fab2_lib.baseboard_fab2(sch_1):page72_i33:vccio(34)"
				( attribute "PN" "BB5"
					( Origin gPackager )
				)
				( objectStatus "U2D1.BB5" )
			)
			( pin "@baseboard_fab2_lib.baseboard_fab2(sch_1):page72_i33:vccio(35)"
				( attribute "PN" "BA24"
					( Origin gPackager )
				)
				( objectStatus "U2D1.BA24" )
			)
			( pin "@baseboard_fab2_lib.baseboard_fab2(sch_1):page72_i33:vccio(36)"
				( attribute "PN" "AY11"
					( Origin gPackager )
				)
				( objectStatus "U2D1.AY11" )
			)
			( pin "@baseboard_fab2_lib.baseboard_fab2(sch_1):page72_i33:vccio(37)"
				( attribute "PN" "AW6"
					( Origin gPackager )
				)
				( objectStatus "U2D1.AW6" )
			)
			( pin "@baseboard_fab2_lib.baseboard_fab2(sch_1):page72_i33:vccio(38)"
				( attribute "PN" "AT11"
					( Origin gPackager )
				)
				( objectStatus "U2D1.AT11" )
			)
			( pin "@baseboard_fab2_lib.baseboard_fab2(sch_1):page72_i33:vccio(39)"
				( attribute "PN" "DD7"
					( Origin gPackager )
				)
				( objectStatus "U2D1.DD7" )
			)
			( pin "@baseboard_fab2_lib.baseboard_fab2(sch_1):page72_i33:vccio(40)"
				( attribute "PN" "AN10"
					( Origin gPackager )
				)
				( objectStatus "U2D1.AN10" )
			)
			( pin "@baseboard_fab2_lib.baseboard_fab2(sch_1):page72_i33:vccio(41)"
				( attribute "PN" "DF13"
					( Origin gPackager )
				)
				( objectStatus "U2D1.DF13" )
			)
			( pin "@baseboard_fab2_lib.baseboard_fab2(sch_1):page72_i33:vccio(42)"
				( attribute "PN" "AH9"
					( Origin gPackager )
				)
				( objectStatus "U2D1.AH9" )
			)
			( pin "@baseboard_fab2_lib.baseboard_fab2(sch_1):page72_i33:vccio(43)"
				( attribute "PN" "AC4"
					( Origin gPackager )
				)
				( objectStatus "U2D1.AC4" )
			)
			( pin "@baseboard_fab2_lib.baseboard_fab2(sch_1):page72_i33:vccio(44)"
				( attribute "PN" "AC20"
					( Origin gPackager )
				)
				( objectStatus "U2D1.AC20" )
			)
			( pin "@baseboard_fab2_lib.baseboard_fab2(sch_1):page72_i33:vccio(45)"
				( attribute "PN" "AA10"
					( Origin gPackager )
				)
				( objectStatus "U2D1.AA10" )
			)
			( pin "@baseboard_fab2_lib.baseboard_fab2(sch_1):page72_i33:vccio(46)"
				( attribute "PN" "W6"
					( Origin gPackager )
				)
				( objectStatus "U2D1.W6" )
			)
			( pin "@baseboard_fab2_lib.baseboard_fab2(sch_1):page72_i33:vccio(47)"
				( attribute "PN" "W4"
					( Origin gPackager )
				)
				( objectStatus "U2D1.W4" )
			)
			( pin "@baseboard_fab2_lib.baseboard_fab2(sch_1):page72_i33:vccio(48)"
				( attribute "PN" "DF21"
					( Origin gPackager )
				)
				( objectStatus "U2D1.DF21" )
			)
			( pin "@baseboard_fab2_lib.baseboard_fab2(sch_1):page72_i33:vccio(49)"
				( attribute "PN" "U14"
					( Origin gPackager )
				)
				( objectStatus "U2D1.U14" )
			)
			( pin "@baseboard_fab2_lib.baseboard_fab2(sch_1):page72_i33:vccio(50)"
				( attribute "PN" "T3"
					( Origin gPackager )
				)
				( objectStatus "U2D1.T3" )
			)
			( pin "@baseboard_fab2_lib.baseboard_fab2(sch_1):page72_i33:vccio(51)"
				( attribute "PN" "P5"
					( Origin gPackager )
				)
				( objectStatus "U2D1.P5" )
			)
			( pin "@baseboard_fab2_lib.baseboard_fab2(sch_1):page72_i33:vccio(52)"
				( attribute "PN" "M21"
					( Origin gPackager )
				)
				( objectStatus "U2D1.M21" )
			)
			( pin "@baseboard_fab2_lib.baseboard_fab2(sch_1):page72_i33:vccio(53)"
				( attribute "PN" "M11"
					( Origin gPackager )
				)
				( objectStatus "U2D1.M11" )
			)
			( pin "@baseboard_fab2_lib.baseboard_fab2(sch_1):page72_i33:vccio(54)"
				( attribute "PN" "DG8"
					( Origin gPackager )
				)
				( objectStatus "U2D1.DG8" )
			)
			( pin "@baseboard_fab2_lib.baseboard_fab2(sch_1):page72_i33:vccio(55)"
				( attribute "PN" "DH7"
					( Origin gPackager )
				)
				( objectStatus "U2D1.DH7" )
			)
			( pin "@baseboard_fab2_lib.baseboard_fab2(sch_1):page72_i33:vccio(56)"
				( attribute "PN" "L16"
					( Origin gPackager )
				)
				( objectStatus "U2D1.L16" )
			)
			( pin "@baseboard_fab2_lib.baseboard_fab2(sch_1):page72_i33:vccio(57)"
				( attribute "PN" "L14"
					( Origin gPackager )
				)
				( objectStatus "U2D1.L14" )
			)
			( pin "@baseboard_fab2_lib.baseboard_fab2(sch_1):page72_i33:vccio(58)"
				( attribute "PN" "J10"
					( Origin gPackager )
				)
				( objectStatus "U2D1.J10" )
			)
			( pin "@baseboard_fab2_lib.baseboard_fab2(sch_1):page72_i33:vccio(59)"
				( attribute "PN" "H13"
					( Origin gPackager )
				)
				( objectStatus "U2D1.H13" )
			)
			( pin "@baseboard_fab2_lib.baseboard_fab2(sch_1):page72_i33:vccio(60)"
				( attribute "PN" "DJ16"
					( Origin gPackager )
				)
				( objectStatus "U2D1.DJ16" )
			)
			( pin "@baseboard_fab2_lib.baseboard_fab2(sch_1):page72_i33:vccio(61)"
				( attribute "PN" "DM17"
					( Origin gPackager )
				)
				( objectStatus "U2D1.DM17" )
			)
			( pin "@baseboard_fab2_lib.baseboard_fab2(sch_1):page72_i33:vccio(62)"
				( attribute "PN" "DN8"
					( Origin gPackager )
				)
				( objectStatus "U2D1.DN8" )
			)
			( pin "@baseboard_fab2_lib.baseboard_fab2(sch_1):page72_i33:vccio(63)"
				( attribute "PN" "DP19"
					( Origin gPackager )
				)
				( objectStatus "U2D1.DP19" )
			)
			( pin "@baseboard_fab2_lib.baseboard_fab2(sch_1):page72_i33:vccio(64)"
				( attribute "PN" "DR10"
					( Origin gPackager )
				)
				( objectStatus "U2D1.DR10" )
			)
			( pin "@baseboard_fab2_lib.baseboard_fab2(sch_1):page72_i33:vccio(65)"
				( attribute "PN" "DR2"
					( Origin gPackager )
				)
				( objectStatus "U2D1.DR2" )
			)
			( pin "@baseboard_fab2_lib.baseboard_fab2(sch_1):page72_i33:vccio(66)"
				( attribute "PN" "DU20"
					( Origin gPackager )
				)
				( objectStatus "U2D1.DU20" )
			)
			( pin "@baseboard_fab2_lib.baseboard_fab2(sch_1):page72_i33:vccio(67)"
				( attribute "PN" "EA12"
					( Origin gPackager )
				)
				( objectStatus "U2D1.EA12" )
			)
			( pin "@baseboard_fab2_lib.baseboard_fab2(sch_1):page72_i33:vccio(68)"
				( attribute "PN" "EB15"
					( Origin gPackager )
				)
				( objectStatus "U2D1.EB15" )
			)
			( pin "@baseboard_fab2_lib.baseboard_fab2(sch_1):page72_i33:vccio(69)"
				( attribute "PN" "J2"
					( Origin gPackager )
				)
				( objectStatus "U2D1.J2" )
			)
			( pin "@baseboard_fab2_lib.baseboard_fab2(sch_1):page72_i33:vccio(70)"
				( attribute "PN" "K15"
					( Origin gPackager )
				)
				( objectStatus "U2D1.K15" )
			)
			( pin "@baseboard_fab2_lib.baseboard_fab2(sch_1):page72_i33:vccio(71)"
				( attribute "PN" "M7"
					( Origin gPackager )
				)
				( objectStatus "U2D1.M7" )
			)
			( pin "@baseboard_fab2_lib.baseboard_fab2(sch_1):page72_i33:vccio(72)"
				( attribute "PN" "M9"
					( Origin gPackager )
				)
				( objectStatus "U2D1.M9" )
			)
			( pin "@baseboard_fab2_lib.baseboard_fab2(sch_1):page72_i33:vccio(73)"
				( attribute "PN" "N18"
					( Origin gPackager )
				)
				( objectStatus "U2D1.N18" )
			)
			( pin "@baseboard_fab2_lib.baseboard_fab2(sch_1):page72_i33:vccio(74)"
				( attribute "PN" "W10"
					( Origin gPackager )
				)
				( objectStatus "U2D1.W10" )
			)
			( pin "@baseboard_fab2_lib.baseboard_fab2(sch_1):page72_i33:vccio(75)"
				( attribute "PN" "BC26"
					( Origin gPackager )
				)
				( objectStatus "U2D1.BC26" )
			)
			( pin "@baseboard_fab2_lib.baseboard_fab2(sch_1):page72_i33:vccio(76)"
				( attribute "PN" "BB27"
					( Origin gPackager )
				)
				( objectStatus "U2D1.BB27" )
			)
			( pin "@baseboard_fab2_lib.baseboard_fab2(sch_1):page72_i33:vccio(77)"
				( attribute "PN" "BA26"
					( Origin gPackager )
				)
				( objectStatus "U2D1.BA26" )
			)
			( pin "@baseboard_fab2_lib.baseboard_fab2(sch_1):page72_i33:vccio(78)"
				( attribute "PN" "AY27"
					( Origin gPackager )
				)
				( objectStatus "U2D1.AY27" )
			)
			( pin "@baseboard_fab2_lib.baseboard_fab2(sch_1):page72_i33:vccio(79)"
				( attribute "PN" "AW26"
					( Origin gPackager )
				)
				( objectStatus "U2D1.AW26" )
			)
			( pin "@baseboard_fab2_lib.baseboard_fab2(sch_1):page72_i33:vccio(80)"
				( attribute "PN" "AV27"
					( Origin gPackager )
				)
				( objectStatus "U2D1.AV27" )
			)
			( pin "@baseboard_fab2_lib.baseboard_fab2(sch_1):page72_i33:vccio(81)"
				( attribute "PN" "CF27"
					( Origin gPackager )
				)
				( objectStatus "U2D1.CF27" )
			)
			( pin "@baseboard_fab2_lib.baseboard_fab2(sch_1):page72_i33:vccio(82)"
				( attribute "PN" "CD27"
					( Origin gPackager )
				)
				( objectStatus "U2D1.CD27" )
			)
			( pin "@baseboard_fab2_lib.baseboard_fab2(sch_1):page72_i33:vccio(83)"
				( attribute "PN" "CC26"
					( Origin gPackager )
				)
				( objectStatus "U2D1.CC26" )
			)
			( pin "@baseboard_fab2_lib.baseboard_fab2(sch_1):page72_i33:vccio(84)"
				( attribute "PN" "CJ28"
					( Origin gPackager )
				)
				( objectStatus "U2D1.CJ28" )
			)
			( pin "@baseboard_fab2_lib.baseboard_fab2(sch_1):page72_i33:vccio(85)"
				( attribute "PN" "CH27"
					( Origin gPackager )
				)
				( objectStatus "U2D1.CH27" )
			)
			( pin "@baseboard_fab2_lib.baseboard_fab2(sch_1):page72_i33:vccio(86)"
				( attribute "PN" "BM27"
					( Origin gPackager )
				)
				( objectStatus "U2D1.BM27" )
			)
			( pin "@baseboard_fab2_lib.baseboard_fab2(sch_1):page72_i33:vccio(87)"
				( attribute "PN" "BL26"
					( Origin gPackager )
				)
				( objectStatus "U2D1.BL26" )
			)
			( pin "@baseboard_fab2_lib.baseboard_fab2(sch_1):page72_i33:vccio(88)"
				( attribute "PN" "BK27"
					( Origin gPackager )
				)
				( objectStatus "U2D1.BK27" )
			)
			( pin "@baseboard_fab2_lib.baseboard_fab2(sch_1):page72_i33:vccio(89)"
				( attribute "PN" "BK25"
					( Origin gPackager )
				)
				( objectStatus "U2D1.BK25" )
			)
			( pin "@baseboard_fab2_lib.baseboard_fab2(sch_1):page72_i33:vccio(90)"
				( attribute "PN" "BJ26"
					( Origin gPackager )
				)
				( objectStatus "U2D1.BJ26" )
			)
			( pin "@baseboard_fab2_lib.baseboard_fab2(sch_1):page72_i33:vccio(91)"
				( attribute "PN" "BH27"
					( Origin gPackager )
				)
				( objectStatus "U2D1.BH27" )
			)
			( pin "@baseboard_fab2_lib.baseboard_fab2(sch_1):page72_i33:vccio(92)"
				( attribute "PN" "BH25"
					( Origin gPackager )
				)
				( objectStatus "U2D1.BH25" )
			)
			( pin "@baseboard_fab2_lib.baseboard_fab2(sch_1):page72_i33:vccio(93)"
				( attribute "PN" "BG26"
					( Origin gPackager )
				)
				( objectStatus "U2D1.BG26" )
			)
			( pin "@baseboard_fab2_lib.baseboard_fab2(sch_1):page72_i33:vccio(94)"
				( attribute "PN" "BF27"
					( Origin gPackager )
				)
				( objectStatus "U2D1.BF27" )
			)
			( pin "@baseboard_fab2_lib.baseboard_fab2(sch_1):page72_i33:vccio(95)"
				( attribute "PN" "AE36"
					( Origin gPackager )
				)
				( objectStatus "U2D1.AE36" )
			)
			( pin "@baseboard_fab2_lib.baseboard_fab2(sch_1):page72_i33:vccio(96)"
				( attribute "PN" "AD37"
					( Origin gPackager )
				)
				( objectStatus "U2D1.AD37" )
			)
			( pin "@baseboard_fab2_lib.baseboard_fab2(sch_1):page72_i33:vccio(97)"
				( attribute "PN" "AC36"
					( Origin gPackager )
				)
				( objectStatus "U2D1.AC36" )
			)
			( pin "@baseboard_fab2_lib.baseboard_fab2(sch_1):page72_i33:vccio(98)"
				( attribute "PN" "AF35"
					( Origin gPackager )
				)
				( objectStatus "U2D1.AF35" )
			)
			( pin "@baseboard_fab2_lib.baseboard_fab2(sch_1):page72_i33:vccio(99)"
				( attribute "PN" "AD35"
					( Origin gPackager )
				)
				( objectStatus "U2D1.AD35" )
			)
			( pin "@baseboard_fab2_lib.baseboard_fab2(sch_1):page72_i33:vccio(100)"
				( attribute "PN" "AE34"
					( Origin gPackager )
				)
				( objectStatus "U2D1.AE34" )
			)
			( pin "@baseboard_fab2_lib.baseboard_fab2(sch_1):page72_i33:vccio(101)"
				( attribute "PN" "AG34"
					( Origin gPackager )
				)
				( objectStatus "U2D1.AG34" )
			)
			( pin "@baseboard_fab2_lib.baseboard_fab2(sch_1):page72_i33:vccio(102)"
				( attribute "PN" "AM29"
					( Origin gPackager )
				)
				( objectStatus "U2D1.AM29" )
			)
			( pin "@baseboard_fab2_lib.baseboard_fab2(sch_1):page72_i33:vccio(103)"
				( attribute "PN" "AL28"
					( Origin gPackager )
				)
				( objectStatus "U2D1.AL28" )
			)
			( pin "@baseboard_fab2_lib.baseboard_fab2(sch_1):page72_i33:vccio(104)"
				( attribute "PN" "AR28"
					( Origin gPackager )
				)
				( objectStatus "U2D1.AR28" )
			)
			( pin "@baseboard_fab2_lib.baseboard_fab2(sch_1):page72_i33:vccsa(0)"
				( attribute "PN" "CJ66"
					( Origin gPackager )
				)
				( objectStatus "U2D1.CJ66" )
			)
			( pin "@baseboard_fab2_lib.baseboard_fab2(sch_1):page72_i33:vccsa(1)"
				( attribute "PN" "CJ64"
					( Origin gPackager )
				)
				( objectStatus "U2D1.CJ64" )
			)
			( pin "@baseboard_fab2_lib.baseboard_fab2(sch_1):page72_i33:vccsa(2)"
				( attribute "PN" "CH75"
					( Origin gPackager )
				)
				( objectStatus "U2D1.CH75" )
			)
			( pin "@baseboard_fab2_lib.baseboard_fab2(sch_1):page72_i33:vccsa(3)"
				( attribute "PN" "CH65"
					( Origin gPackager )
				)
				( objectStatus "U2D1.CH65" )
			)
			( pin "@baseboard_fab2_lib.baseboard_fab2(sch_1):page72_i33:vccsa(4)"
				( attribute "PN" "CG74"
					( Origin gPackager )
				)
				( objectStatus "U2D1.CG74" )
			)
			( pin "@baseboard_fab2_lib.baseboard_fab2(sch_1):page72_i33:vccsa(5)"
				( attribute "PN" "CG66"
					( Origin gPackager )
				)
				( objectStatus "U2D1.CG66" )
			)
			( pin "@baseboard_fab2_lib.baseboard_fab2(sch_1):page72_i33:vccsa(6)"
				( attribute "PN" "CG64"
					( Origin gPackager )
				)
				( objectStatus "U2D1.CG64" )
			)
			( pin "@baseboard_fab2_lib.baseboard_fab2(sch_1):page72_i33:vccsa(7)"
				( attribute "PN" "CF75"
					( Origin gPackager )
				)
				( objectStatus "U2D1.CF75" )
			)
			( pin "@baseboard_fab2_lib.baseboard_fab2(sch_1):page72_i33:vccsa(8)"
				( attribute "PN" "CF73"
					( Origin gPackager )
				)
				( objectStatus "U2D1.CF73" )
			)
			( pin "@baseboard_fab2_lib.baseboard_fab2(sch_1):page72_i33:vccsa(9)"
				( attribute "PN" "CF67"
					( Origin gPackager )
				)
				( objectStatus "U2D1.CF67" )
			)
			( pin "@baseboard_fab2_lib.baseboard_fab2(sch_1):page72_i33:vccsa(10)"
				( attribute "PN" "CF65"
					( Origin gPackager )
				)
				( objectStatus "U2D1.CF65" )
			)
			( pin "@baseboard_fab2_lib.baseboard_fab2(sch_1):page72_i33:vccsa(11)"
				( attribute "PN" "CE74"
					( Origin gPackager )
				)
				( objectStatus "U2D1.CE74" )
			)
			( pin "@baseboard_fab2_lib.baseboard_fab2(sch_1):page72_i33:vccsa(12)"
				( attribute "PN" "CE72"
					( Origin gPackager )
				)
				( objectStatus "U2D1.CE72" )
			)
			( pin "@baseboard_fab2_lib.baseboard_fab2(sch_1):page72_i33:vccsa(13)"
				( attribute "PN" "CE68"
					( Origin gPackager )
				)
				( objectStatus "U2D1.CE68" )
			)
			( pin "@baseboard_fab2_lib.baseboard_fab2(sch_1):page72_i33:vccsa(14)"
				( attribute "PN" "CE66"
					( Origin gPackager )
				)
				( objectStatus "U2D1.CE66" )
			)
			( pin "@baseboard_fab2_lib.baseboard_fab2(sch_1):page72_i33:vccsa(15)"
				( attribute "PN" "CE64"
					( Origin gPackager )
				)
				( objectStatus "U2D1.CE64" )
			)
			( pin "@baseboard_fab2_lib.baseboard_fab2(sch_1):page72_i33:vccsa(16)"
				( attribute "PN" "CD71"
					( Origin gPackager )
				)
				( objectStatus "U2D1.CD71" )
			)
			( pin "@baseboard_fab2_lib.baseboard_fab2(sch_1):page72_i33:vccsa(17)"
				( attribute "PN" "CD69"
					( Origin gPackager )
				)
				( objectStatus "U2D1.CD69" )
			)
			( pin "@baseboard_fab2_lib.baseboard_fab2(sch_1):page72_i33:vccsa(18)"
				( attribute "PN" "CD67"
					( Origin gPackager )
				)
				( objectStatus "U2D1.CD67" )
			)
			( pin "@baseboard_fab2_lib.baseboard_fab2(sch_1):page72_i33:vccsa(19)"
				( attribute "PN" "CD65"
					( Origin gPackager )
				)
				( objectStatus "U2D1.CD65" )
			)
			( pin "@baseboard_fab2_lib.baseboard_fab2(sch_1):page72_i33:vccsa(20)"
				( attribute "PN" "CC70"
					( Origin gPackager )
				)
				( objectStatus "U2D1.CC70" )
			)
			( pin "@baseboard_fab2_lib.baseboard_fab2(sch_1):page72_i33:vccsa(21)"
				( attribute "PN" "CC68"
					( Origin gPackager )
				)
				( objectStatus "U2D1.CC68" )
			)
			( pin "@baseboard_fab2_lib.baseboard_fab2(sch_1):page72_i33:vccsa(22)"
				( attribute "PN" "CC66"
					( Origin gPackager )
				)
				( objectStatus "U2D1.CC66" )
			)
			( pin "@baseboard_fab2_lib.baseboard_fab2(sch_1):page72_i33:vccsa(23)"
				( attribute "PN" "CB69"
					( Origin gPackager )
				)
				( objectStatus "U2D1.CB69" )
			)
			( pin "@baseboard_fab2_lib.baseboard_fab2(sch_1):page72_i33:vccsa(24)"
				( attribute "PN" "CB67"
					( Origin gPackager )
				)
				( objectStatus "U2D1.CB67" )
			)
			( pin "@baseboard_fab2_lib.baseboard_fab2(sch_1):page72_i33:vccsa(25)"
				( attribute "PN" "CB65"
					( Origin gPackager )
				)
				( objectStatus "U2D1.CB65" )
			)
			( pin "@baseboard_fab2_lib.baseboard_fab2(sch_1):page73_i107:cd_vcc_core_sense"
				( attribute "PN" "BN16"
					( Origin gPackager )
				)
				( objectStatus "U2D1.BN16" )
			)
			( pin "@baseboard_fab2_lib.baseboard_fab2(sch_1):page73_i107:cd_vccp_sense(0)"
				( attribute "PN" "BU16"
					( Origin gPackager )
				)
				( objectStatus "U2D1.BU16" )
			)
			( pin "@baseboard_fab2_lib.baseboard_fab2(sch_1):page73_i107:cd_vccp_sense(1)"
				( attribute "PN" "BT17"
					( Origin gPackager )
				)
				( objectStatus "U2D1.BT17" )
			)
			( pin "@baseboard_fab2_lib.baseboard_fab2(sch_1):page73_i107:cd_vss_vcc_core_sense"
				( attribute "PN" "BL16"
					( Origin gPackager )
				)
				( objectStatus "U2D1.BL16" )
			)
			( pin "@baseboard_fab2_lib.baseboard_fab2(sch_1):page73_i107:rsvd(0)"
				( attribute "PN" "EF83"
					( Origin gPackager )
				)
				( objectStatus "U2D1.EF83" )
			)
			( pin "@baseboard_fab2_lib.baseboard_fab2(sch_1):page73_i107:rsvd(1)"
				( attribute "PN" "EF81"
					( Origin gPackager )
				)
				( objectStatus "U2D1.EF81" )
			)
			( pin "@baseboard_fab2_lib.baseboard_fab2(sch_1):page73_i107:rsvd(2)"
				( attribute "PN" "EF77"
					( Origin gPackager )
				)
				( objectStatus "U2D1.EF77" )
			)
			( pin "@baseboard_fab2_lib.baseboard_fab2(sch_1):page73_i107:rsvd(3)"
				( attribute "PN" "EF47"
					( Origin gPackager )
				)
				( objectStatus "U2D1.EF47" )
			)
			( pin "@baseboard_fab2_lib.baseboard_fab2(sch_1):page73_i107:rsvd(4)"
				( attribute "PN" "EE84"
					( Origin gPackager )
				)
				( objectStatus "U2D1.EE84" )
			)
			( pin "@baseboard_fab2_lib.baseboard_fab2(sch_1):page73_i107:rsvd(5)"
				( attribute "PN" "EE82"
					( Origin gPackager )
				)
				( objectStatus "U2D1.EE82" )
			)
			( pin "@baseboard_fab2_lib.baseboard_fab2(sch_1):page73_i107:rsvd(6)"
				( attribute "PN" "EE6"
					( Origin gPackager )
				)
				( objectStatus "U2D1.EE6" )
			)
			( pin "@baseboard_fab2_lib.baseboard_fab2(sch_1):page73_i107:rsvd(7)"
				( attribute "PN" "EE46"
					( Origin gPackager )
				)
				( objectStatus "U2D1.EE46" )
			)
			( pin "@baseboard_fab2_lib.baseboard_fab2(sch_1):page73_i107:rsvd(8)"
				( attribute "PN" "EE16"
					( Origin gPackager )
				)
				( objectStatus "U2D1.EE16" )
			)
			( pin "@baseboard_fab2_lib.baseboard_fab2(sch_1):page73_i107:rsvd(9)"
				( attribute "PN" "ED83"
					( Origin gPackager )
				)
				( objectStatus "U2D1.ED83" )
			)
			( pin "@baseboard_fab2_lib.baseboard_fab2(sch_1):page73_i107:rsvd(10)"
				( attribute "PN" "ED5"
					( Origin gPackager )
				)
				( objectStatus "U2D1.ED5" )
			)
			( pin "@baseboard_fab2_lib.baseboard_fab2(sch_1):page73_i107:rsvd(11)"
				( attribute "PN" "ED45"
					( Origin gPackager )
				)
				( objectStatus "U2D1.ED45" )
			)
			( pin "@baseboard_fab2_lib.baseboard_fab2(sch_1):page73_i107:rsvd(12)"
				( attribute "PN" "EC84"
					( Origin gPackager )
				)
				( objectStatus "U2D1.EC84" )
			)
			( pin "@baseboard_fab2_lib.baseboard_fab2(sch_1):page73_i107:rsvd(13)"
				( attribute "PN" "EC44"
					( Origin gPackager )
				)
				( objectStatus "U2D1.EC44" )
			)
			( pin "@baseboard_fab2_lib.baseboard_fab2(sch_1):page73_i107:rsvd(14)"
				( attribute "PN" "EC4"
					( Origin gPackager )
				)
				( objectStatus "U2D1.EC4" )
			)
			( pin "@baseboard_fab2_lib.baseboard_fab2(sch_1):page73_i107:rsvd(15)"
				( attribute "PN" "EC16"
					( Origin gPackager )
				)
				( objectStatus "U2D1.EC16" )
			)
			( pin "@baseboard_fab2_lib.baseboard_fab2(sch_1):page73_i107:rsvd(16)"
				( attribute "PN" "EB85"
					( Origin gPackager )
				)
				( objectStatus "U2D1.EB85" )
			)
			( pin "@baseboard_fab2_lib.baseboard_fab2(sch_1):page73_i107:rsvd(17)"
				( attribute "PN" "EB5"
					( Origin gPackager )
				)
				( objectStatus "U2D1.EB5" )
			)
			( pin "@baseboard_fab2_lib.baseboard_fab2(sch_1):page73_i107:rsvd(18)"
				( attribute "PN" "EB3"
					( Origin gPackager )
				)
				( objectStatus "U2D1.EB3" )
			)
			( pin "@baseboard_fab2_lib.baseboard_fab2(sch_1):page73_i107:rsvd(19)"
				( attribute "PN" "EA44"
					( Origin gPackager )
				)
				( objectStatus "U2D1.EA44" )
			)
			( pin "@baseboard_fab2_lib.baseboard_fab2(sch_1):page73_i107:rsvd(20)"
				( attribute "PN" "EA4"
					( Origin gPackager )
				)
				( objectStatus "U2D1.EA4" )
			)
			( pin "@baseboard_fab2_lib.baseboard_fab2(sch_1):page73_i107:rsvd(21)"
				( attribute "PN" "DY3"
					( Origin gPackager )
				)
				( objectStatus "U2D1.DY3" )
			)
			( pin "@baseboard_fab2_lib.baseboard_fab2(sch_1):page73_i107:rsvd(22)"
				( attribute "PN" "DW46"
					( Origin gPackager )
				)
				( objectStatus "U2D1.DW46" )
			)
			( pin "@baseboard_fab2_lib.baseboard_fab2(sch_1):page73_i107:rsvd(23)"
				( attribute "PN" "DW44"
					( Origin gPackager )
				)
				( objectStatus "U2D1.DW44" )
			)
			( pin "@baseboard_fab2_lib.baseboard_fab2(sch_1):page73_i107:rsvd(24)"
				( attribute "PN" "DV71"
					( Origin gPackager )
				)
				( objectStatus "U2D1.DV71" )
			)
			( pin "@baseboard_fab2_lib.baseboard_fab2(sch_1):page73_i107:rsvd(25)"
				( attribute "PN" "DV61"
					( Origin gPackager )
				)
				( objectStatus "U2D1.DV61" )
			)
			( pin "@baseboard_fab2_lib.baseboard_fab2(sch_1):page73_i107:rsvd(26)"
				( attribute "PN" "DU44"
					( Origin gPackager )
				)
				( objectStatus "U2D1.DU44" )
			)
			( pin "@baseboard_fab2_lib.baseboard_fab2(sch_1):page73_i107:rsvd(27)"
				( attribute "PN" "DT71"
					( Origin gPackager )
				)
				( objectStatus "U2D1.DT71" )
			)
			( pin "@baseboard_fab2_lib.baseboard_fab2(sch_1):page73_i107:rsvd(28)"
				( attribute "PN" "DR44"
					( Origin gPackager )
				)
				( objectStatus "U2D1.DR44" )
			)
			( pin "@baseboard_fab2_lib.baseboard_fab2(sch_1):page73_i107:rsvd(29)"
				( attribute "PN" "DP65"
					( Origin gPackager )
				)
				( objectStatus "U2D1.DP65" )
			)
			( pin "@baseboard_fab2_lib.baseboard_fab2(sch_1):page73_i107:rsvd(30)"
				( attribute "PN" "DP17"
					( Origin gPackager )
				)
				( objectStatus "U2D1.DP17" )
			)
			( pin "@baseboard_fab2_lib.baseboard_fab2(sch_1):page73_i107:rsvd(31)"
				( attribute "PN" "DN66"
					( Origin gPackager )
				)
				( objectStatus "U2D1.DN66" )
			)
			( pin "@baseboard_fab2_lib.baseboard_fab2(sch_1):page73_i107:rsvd(32)"
				( attribute "PN" "DN62"
					( Origin gPackager )
				)
				( objectStatus "U2D1.DN62" )
			)
			( pin "@baseboard_fab2_lib.baseboard_fab2(sch_1):page73_i107:rsvd(33)"
				( attribute "PN" "DM67"
					( Origin gPackager )
				)
				( objectStatus "U2D1.DM67" )
			)
			( pin "@baseboard_fab2_lib.baseboard_fab2(sch_1):page73_i107:rsvd(34)"
				( attribute "PN" "DL66"
					( Origin gPackager )
				)
				( objectStatus "U2D1.DL66" )
			)
			( pin "@baseboard_fab2_lib.baseboard_fab2(sch_1):page73_i107:rsvd(35)"
				( attribute "PN" "DL38"
					( Origin gPackager )
				)
				( objectStatus "U2D1.DL38" )
			)
			( pin "@baseboard_fab2_lib.baseboard_fab2(sch_1):page73_i107:rsvd(36)"
				( attribute "PN" "DK67"
					( Origin gPackager )
				)
				( objectStatus "U2D1.DK67" )
			)
			( pin "@baseboard_fab2_lib.baseboard_fab2(sch_1):page73_i107:rsvd(37)"
				( attribute "PN" "DK65"
					( Origin gPackager )
				)
				( objectStatus "U2D1.DK65" )
			)
			( pin "@baseboard_fab2_lib.baseboard_fab2(sch_1):page73_i107:rsvd(38)"
				( attribute "PN" "DK37"
					( Origin gPackager )
				)
				( objectStatus "U2D1.DK37" )
			)
			( pin "@baseboard_fab2_lib.baseboard_fab2(sch_1):page73_i107:rsvd(39)"
				( attribute "PN" "DK15"
					( Origin gPackager )
				)
				( objectStatus "U2D1.DK15" )
			)
			( pin "@baseboard_fab2_lib.baseboard_fab2(sch_1):page73_i107:rsvd(40)"
				( attribute "PN" "DJ66"
					( Origin gPackager )
				)
				( objectStatus "U2D1.DJ66" )
			)
			( pin "@baseboard_fab2_lib.baseboard_fab2(sch_1):page73_i107:rsvd(41)"
				( attribute "PN" "DJ36"
					( Origin gPackager )
				)
				( objectStatus "U2D1.DJ36" )
			)
			( pin "@baseboard_fab2_lib.baseboard_fab2(sch_1):page73_i107:rsvd(42)"
				( attribute "PN" "DH65"
					( Origin gPackager )
				)
				( objectStatus "U2D1.DH65" )
			)
			( pin "@baseboard_fab2_lib.baseboard_fab2(sch_1):page73_i107:rsvd(43)"
				( attribute "PN" "DG64"
					( Origin gPackager )
				)
				( objectStatus "U2D1.DG64" )
			)
			( pin "@baseboard_fab2_lib.baseboard_fab2(sch_1):page73_i107:rsvd(44)"
				( attribute "PN" "DG36"
					( Origin gPackager )
				)
				( objectStatus "U2D1.DG36" )
			)
			( pin "@baseboard_fab2_lib.baseboard_fab2(sch_1):page73_i107:rsvd(45)"
				( attribute "PN" "DD51"
					( Origin gPackager )
				)
				( objectStatus "U2D1.DD51" )
			)
			( pin "@baseboard_fab2_lib.baseboard_fab2(sch_1):page73_i107:rsvd(46)"
				( attribute "PN" "DC52"
					( Origin gPackager )
				)
				( objectStatus "U2D1.DC52" )
			)
			( pin "@baseboard_fab2_lib.baseboard_fab2(sch_1):page73_i107:rsvd(47)"
				( attribute "PN" "DC46"
					( Origin gPackager )
				)
				( objectStatus "U2D1.DC46" )
			)
			( pin "@baseboard_fab2_lib.baseboard_fab2(sch_1):page73_i107:rsvd(48)"
				( attribute "PN" "DA56"
					( Origin gPackager )
				)
				( objectStatus "U2D1.DA56" )
			)
			( pin "@baseboard_fab2_lib.baseboard_fab2(sch_1):page73_i107:rsvd(49)"
				( attribute "PN" "DA54"
					( Origin gPackager )
				)
				( objectStatus "U2D1.DA54" )
			)
			( pin "@baseboard_fab2_lib.baseboard_fab2(sch_1):page73_i107:rsvd(50)"
				( attribute "PN" "DA52"
					( Origin gPackager )
				)
				( objectStatus "U2D1.DA52" )
			)
			( pin "@baseboard_fab2_lib.baseboard_fab2(sch_1):page73_i107:rsvd(51)"
				( attribute "PN" "DA40"
					( Origin gPackager )
				)
				( objectStatus "U2D1.DA40" )
			)
			( pin "@baseboard_fab2_lib.baseboard_fab2(sch_1):page73_i107:rsvd(52)"
				( attribute "PN" "DA24"
					( Origin gPackager )
				)
				( objectStatus "U2D1.DA24" )
			)
			( pin "@baseboard_fab2_lib.baseboard_fab2(sch_1):page73_i107:rsvd(53)"
				( attribute "PN" "CY73"
					( Origin gPackager )
				)
				( objectStatus "U2D1.CY73" )
			)
			( pin "@baseboard_fab2_lib.baseboard_fab2(sch_1):page73_i107:rsvd(54)"
				( attribute "PN" "CY63"
					( Origin gPackager )
				)
				( objectStatus "U2D1.CY63" )
			)
			( pin "@baseboard_fab2_lib.baseboard_fab2(sch_1):page73_i107:rsvd(55)"
				( attribute "PN" "CY57"
					( Origin gPackager )
				)
				( objectStatus "U2D1.CY57" )
			)
			( pin "@baseboard_fab2_lib.baseboard_fab2(sch_1):page73_i107:rsvd(56)"
				( attribute "PN" "CY53"
					( Origin gPackager )
				)
				( objectStatus "U2D1.CY53" )
			)
			( pin "@baseboard_fab2_lib.baseboard_fab2(sch_1):page73_i107:rsvd(57)"
				( attribute "PN" "CY39"
					( Origin gPackager )
				)
				( objectStatus "U2D1.CY39" )
			)
			( pin "@baseboard_fab2_lib.baseboard_fab2(sch_1):page73_i107:rsvd(58)"
				( attribute "PN" "CY25"
					( Origin gPackager )
				)
				( objectStatus "U2D1.CY25" )
			)
			( pin "@baseboard_fab2_lib.baseboard_fab2(sch_1):page73_i107:rsvd(59)"
				( attribute "PN" "CY23"
					( Origin gPackager )
				)
				( objectStatus "U2D1.CY23" )
			)
			( pin "@baseboard_fab2_lib.baseboard_fab2(sch_1):page73_i107:rsvd(60)"
				( attribute "PN" "CW62"
					( Origin gPackager )
				)
				( objectStatus "U2D1.CW62" )
			)
			( pin "@baseboard_fab2_lib.baseboard_fab2(sch_1):page73_i107:rsvd(61)"
				( attribute "PN" "CW60"
					( Origin gPackager )
				)
				( objectStatus "U2D1.CW60" )
			)
			( pin "@baseboard_fab2_lib.baseboard_fab2(sch_1):page73_i107:rsvd(62)"
				( attribute "PN" "CW24"
					( Origin gPackager )
				)
				( objectStatus "U2D1.CW24" )
			)
			( pin "@baseboard_fab2_lib.baseboard_fab2(sch_1):page73_i107:rsvd(63)"
				( attribute "PN" "CW22"
					( Origin gPackager )
				)
				( objectStatus "U2D1.CW22" )
			)
			( pin "@baseboard_fab2_lib.baseboard_fab2(sch_1):page73_i107:rsvd(64)"
				( attribute "PN" "CV69"
					( Origin gPackager )
				)
				( objectStatus "U2D1.CV69" )
			)
			( pin "@baseboard_fab2_lib.baseboard_fab2(sch_1):page73_i107:rsvd(65)"
				( attribute "PN" "CV23"
					( Origin gPackager )
				)
				( objectStatus "U2D1.CV23" )
			)
			( pin "@baseboard_fab2_lib.baseboard_fab2(sch_1):page73_i107:rsvd(66)"
				( attribute "PN" "CU60"
					( Origin gPackager )
				)
				( objectStatus "U2D1.CU60" )
			)
			( pin "@baseboard_fab2_lib.baseboard_fab2(sch_1):page73_i107:rsvd(67)"
				( attribute "PN" "CU6"
					( Origin gPackager )
				)
				( objectStatus "U2D1.CU6" )
			)
			( pin "@baseboard_fab2_lib.baseboard_fab2(sch_1):page73_i107:rsvd(68)"
				( attribute "PN" "CU24"
					( Origin gPackager )
				)
				( objectStatus "U2D1.CU24" )
			)
			( pin "@baseboard_fab2_lib.baseboard_fab2(sch_1):page73_i107:rsvd(69)"
				( attribute "PN" "CT69"
					( Origin gPackager )
				)
				( objectStatus "U2D1.CT69" )
			)
			( pin "@baseboard_fab2_lib.baseboard_fab2(sch_1):page73_i107:rsvd(70)"
				( attribute "PN" "CT5"
					( Origin gPackager )
				)
				( objectStatus "U2D1.CT5" )
			)
			( pin "@baseboard_fab2_lib.baseboard_fab2(sch_1):page73_i107:rsvd(71)"
				( attribute "PN" "CT23"
					( Origin gPackager )
				)
				( objectStatus "U2D1.CT23" )
			)
			( pin "@baseboard_fab2_lib.baseboard_fab2(sch_1):page73_i107:rsvd(72)"
				( attribute "PN" "CR60"
					( Origin gPackager )
				)
				( objectStatus "U2D1.CR60" )
			)
			( pin "@baseboard_fab2_lib.baseboard_fab2(sch_1):page73_i107:rsvd(73)"
				( attribute "PN" "CP31"
					( Origin gPackager )
				)
				( objectStatus "U2D1.CP31" )
			)
			( pin "@baseboard_fab2_lib.baseboard_fab2(sch_1):page73_i107:rsvd(74)"
				( attribute "PN" "CP23"
					( Origin gPackager )
				)
				( objectStatus "U2D1.CP23" )
			)
			( pin "@baseboard_fab2_lib.baseboard_fab2(sch_1):page73_i107:rsvd(75)"
				( attribute "PN" "CN28"
					( Origin gPackager )
				)
				( objectStatus "U2D1.CN28" )
			)
			( pin "@baseboard_fab2_lib.baseboard_fab2(sch_1):page73_i107:rsvd(76)"
				( attribute "PN" "CN24"
					( Origin gPackager )
				)
				( objectStatus "U2D1.CN24" )
			)
			( pin "@baseboard_fab2_lib.baseboard_fab2(sch_1):page73_i107:rsvd(77)"
				( attribute "PN" "CN22"
					( Origin gPackager )
				)
				( objectStatus "U2D1.CN22" )
			)
			( pin "@baseboard_fab2_lib.baseboard_fab2(sch_1):page73_i107:rsvd(78)"
				( attribute "PN" "CM25"
					( Origin gPackager )
				)
				( objectStatus "U2D1.CM25" )
			)
			( pin "@baseboard_fab2_lib.baseboard_fab2(sch_1):page73_i107:rsvd(79)"
				( attribute "PN" "CM23"
					( Origin gPackager )
				)
				( objectStatus "U2D1.CM23" )
			)
			( pin "@baseboard_fab2_lib.baseboard_fab2(sch_1):page73_i107:rsvd(80)"
				( attribute "PN" "CL26"
					( Origin gPackager )
				)
				( objectStatus "U2D1.CL26" )
			)
			( pin "@baseboard_fab2_lib.baseboard_fab2(sch_1):page73_i107:vccio(0)"
				( attribute "PN" "EE10"
					( Origin gPackager )
				)
				( objectStatus "U2D1.EE10" )
			)
			( pin "@baseboard_fab2_lib.baseboard_fab2(sch_1):page73_i107:vccio(1)"
				( attribute "PN" "AE10"
					( Origin gPackager )
				)
				( objectStatus "U2D1.AE10" )
			)
			( pin "@baseboard_fab2_lib.baseboard_fab2(sch_1):page73_i107:vccio(2)"
				( attribute "PN" "AF5"
					( Origin gPackager )
				)
				( objectStatus "U2D1.AF5" )
			)
			( pin "@baseboard_fab2_lib.baseboard_fab2(sch_1):page73_i107:vccio(3)"
				( attribute "PN" "DV11"
					( Origin gPackager )
				)
				( objectStatus "U2D1.DV11" )
			)
			( pin "@baseboard_fab2_lib.baseboard_fab2(sch_1):page73_i107:vccio(4)"
				( attribute "PN" "AM5"
					( Origin gPackager )
				)
				( objectStatus "U2D1.AM5" )
			)
			( pin "@baseboard_fab2_lib.baseboard_fab2(sch_1):page73_i107:vccio(5)"
				( attribute "PN" "AT5"
					( Origin gPackager )
				)
				( objectStatus "U2D1.AT5" )
			)
			( pin "@baseboard_fab2_lib.baseboard_fab2(sch_1):page73_i107:vccio(6)"
				( attribute "PN" "AT7"
					( Origin gPackager )
				)
				( objectStatus "U2D1.AT7" )
			)
			( pin "@baseboard_fab2_lib.baseboard_fab2(sch_1):page73_i107:vccio(7)"
				( attribute "PN" "BE24"
					( Origin gPackager )
				)
				( objectStatus "U2D1.BE24" )
			)
			( pin "@baseboard_fab2_lib.baseboard_fab2(sch_1):page73_i107:vccio(8)"
				( attribute "PN" "DK21"
					( Origin gPackager )
				)
				( objectStatus "U2D1.DK21" )
			)
			( pin "@baseboard_fab2_lib.baseboard_fab2(sch_1):page73_i107:vccio(9)"
				( attribute "PN" "CF5"
					( Origin gPackager )
				)
				( objectStatus "U2D1.CF5" )
			)
			( pin "@baseboard_fab2_lib.baseboard_fab2(sch_1):page73_i107:vccio(10)"
				( attribute "PN" "CG14"
					( Origin gPackager )
				)
				( objectStatus "U2D1.CG14" )
			)
			( pin "@baseboard_fab2_lib.baseboard_fab2(sch_1):page73_i107:vccio(11)"
				( attribute "PN" "CL20"
					( Origin gPackager )
				)
				( objectStatus "U2D1.CL20" )
			)
			( pin "@baseboard_fab2_lib.baseboard_fab2(sch_1):page73_i107:vccio(12)"
				( attribute "PN" "CP13"
					( Origin gPackager )
				)
				( objectStatus "U2D1.CP13" )
			)
			( pin "@baseboard_fab2_lib.baseboard_fab2(sch_1):page73_i107:vccio(13)"
				( attribute "PN" "DE14"
					( Origin gPackager )
				)
				( objectStatus "U2D1.DE14" )
			)
			( pin "@baseboard_fab2_lib.baseboard_fab2(sch_1):page73_i107:vccio(14)"
				( attribute "PN" "DC18"
					( Origin gPackager )
				)
				( objectStatus "U2D1.DC18" )
			)
			( pin "@baseboard_fab2_lib.baseboard_fab2(sch_1):page73_i107:vccio(15)"
				( attribute "PN" "CY17"
					( Origin gPackager )
				)
				( objectStatus "U2D1.CY17" )
			)
			( pin "@baseboard_fab2_lib.baseboard_fab2(sch_1):page73_i107:vccio(16)"
				( attribute "PN" "CU18"
					( Origin gPackager )
				)
				( objectStatus "U2D1.CU18" )
			)
			( pin "@baseboard_fab2_lib.baseboard_fab2(sch_1):page73_i107:vccio(17)"
				( attribute "PN" "CV21"
					( Origin gPackager )
				)
				( objectStatus "U2D1.CV21" )
			)
			( pin "@baseboard_fab2_lib.baseboard_fab2(sch_1):page73_i107:vccio(18)"
				( attribute "PN" "CU12"
					( Origin gPackager )
				)
				( objectStatus "U2D1.CU12" )
			)
			( pin "@baseboard_fab2_lib.baseboard_fab2(sch_1):page73_i107:vccio(19)"
				( attribute "PN" "CN6"
					( Origin gPackager )
				)
				( objectStatus "U2D1.CN6" )
			)
			( pin "@baseboard_fab2_lib.baseboard_fab2(sch_1):page73_i107:vccio_sense"
				( attribute "PN" "BH5"
					( Origin gPackager )
				)
				( objectStatus "U2D1.BH5" )
			)
			( pin "@baseboard_fab2_lib.baseboard_fab2(sch_1):page73_i107:vccsa_sense"
				( attribute "PN" "CE76"
					( Origin gPackager )
				)
				( objectStatus "U2D1.CE76" )
			)
			( pin "@baseboard_fab2_lib.baseboard_fab2(sch_1):page73_i107:vss_vccio_sense"
				( attribute "PN" "BF5"
					( Origin gPackager )
				)
				( objectStatus "U2D1.BF5" )
			)
			( pin "@baseboard_fab2_lib.baseboard_fab2(sch_1):page73_i107:vss_vccsa_sense"
				( attribute "PN" "CG76"
					( Origin gPackager )
				)
				( objectStatus "U2D1.CG76" )
			)
			( pin "@baseboard_fab2_lib.baseboard_fab2(sch_1):page74_i20:vss(1094)"
				( attribute "PN" "J74"
					( Origin gPackager )
				)
				( objectStatus "U2D1.J74" )
			)
			( pin "@baseboard_fab2_lib.baseboard_fab2(sch_1):page74_i20:vss(1095)"
				( attribute "PN" "J72"
					( Origin gPackager )
				)
				( objectStatus "U2D1.J72" )
			)
			( pin "@baseboard_fab2_lib.baseboard_fab2(sch_1):page74_i20:vss(1096)"
				( attribute "PN" "J40"
					( Origin gPackager )
				)
				( objectStatus "U2D1.J40" )
			)
			( pin "@baseboard_fab2_lib.baseboard_fab2(sch_1):page74_i20:vss(1097)"
				( attribute "PN" "J38"
					( Origin gPackager )
				)
				( objectStatus "U2D1.J38" )
			)
			( pin "@baseboard_fab2_lib.baseboard_fab2(sch_1):page74_i20:vss(1098)"
				( attribute "PN" "J34"
					( Origin gPackager )
				)
				( objectStatus "U2D1.J34" )
			)
			( pin "@baseboard_fab2_lib.baseboard_fab2(sch_1):page74_i20:vss(1099)"
				( attribute "PN" "J32"
					( Origin gPackager )
				)
				( objectStatus "U2D1.J32" )
			)
			( pin "@baseboard_fab2_lib.baseboard_fab2(sch_1):page74_i20:vss(1100)"
				( attribute "PN" "J28"
					( Origin gPackager )
				)
				( objectStatus "U2D1.J28" )
			)
			( pin "@baseboard_fab2_lib.baseboard_fab2(sch_1):page74_i20:vss(1101)"
				( attribute "PN" "J26"
					( Origin gPackager )
				)
				( objectStatus "U2D1.J26" )
			)
			( pin "@baseboard_fab2_lib.baseboard_fab2(sch_1):page74_i20:vss(1102)"
				( attribute "PN" "J22"
					( Origin gPackager )
				)
				( objectStatus "U2D1.J22" )
			)
			( pin "@baseboard_fab2_lib.baseboard_fab2(sch_1):page74_i20:vss(1103)"
				( attribute "PN" "J14"
					( Origin gPackager )
				)
				( objectStatus "U2D1.J14" )
			)
			( pin "@baseboard_fab2_lib.baseboard_fab2(sch_1):page74_i20:vss(1104)"
				( attribute "PN" "J12"
					( Origin gPackager )
				)
				( objectStatus "U2D1.J12" )
			)
			( pin "@baseboard_fab2_lib.baseboard_fab2(sch_1):page74_i20:vss(1105)"
				( attribute "PN" "J4"
					( Origin gPackager )
				)
				( objectStatus "U2D1.J4" )
			)
			( pin "@baseboard_fab2_lib.baseboard_fab2(sch_1):page74_i20:vss(1106)"
				( attribute "PN" "DN44"
					( Origin gPackager )
				)
				( objectStatus "U2D1.DN44" )
			)
			( pin "@baseboard_fab2_lib.baseboard_fab2(sch_1):page74_i20:vss(1107)"
				( attribute "PN" "H75"
					( Origin gPackager )
				)
				( objectStatus "U2D1.H75" )
			)
			( pin "@baseboard_fab2_lib.baseboard_fab2(sch_1):page74_i20:vss(1108)"
				( attribute "PN" "H71"
					( Origin gPackager )
				)
				( objectStatus "U2D1.H71" )
			)
			( pin "@baseboard_fab2_lib.baseboard_fab2(sch_1):page74_i20:vss(1109)"
				( attribute "PN" "H65"
					( Origin gPackager )
				)
				( objectStatus "U2D1.H65" )
			)
			( pin "@baseboard_fab2_lib.baseboard_fab2(sch_1):page74_i20:vss(1110)"
				( attribute "PN" "H41"
					( Origin gPackager )
				)
				( objectStatus "U2D1.H41" )
			)
			( pin "@baseboard_fab2_lib.baseboard_fab2(sch_1):page74_i20:vss(1111)"
				( attribute "PN" "H39"
					( Origin gPackager )
				)
				( objectStatus "U2D1.H39" )
			)
			( pin "@baseboard_fab2_lib.baseboard_fab2(sch_1):page74_i20:vss(1112)"
				( attribute "PN" "H37"
					( Origin gPackager )
				)
				( objectStatus "U2D1.H37" )
			)
			( pin "@baseboard_fab2_lib.baseboard_fab2(sch_1):page74_i20:vss(1113)"
				( attribute "PN" "H35"
					( Origin gPackager )
				)
				( objectStatus "U2D1.H35" )
			)
			( pin "@baseboard_fab2_lib.baseboard_fab2(sch_1):page74_i20:vss(1114)"
				( attribute "PN" "H33"
					( Origin gPackager )
				)
				( objectStatus "U2D1.H33" )
			)
			( pin "@baseboard_fab2_lib.baseboard_fab2(sch_1):page74_i20:vss(1115)"
				( attribute "PN" "H31"
					( Origin gPackager )
				)
				( objectStatus "U2D1.H31" )
			)
			( pin "@baseboard_fab2_lib.baseboard_fab2(sch_1):page74_i20:vss(1116)"
				( attribute "PN" "H29"
					( Origin gPackager )
				)
				( objectStatus "U2D1.H29" )
			)
			( pin "@baseboard_fab2_lib.baseboard_fab2(sch_1):page74_i20:vss(1117)"
				( attribute "PN" "H27"
					( Origin gPackager )
				)
				( objectStatus "U2D1.H27" )
			)
			( pin "@baseboard_fab2_lib.baseboard_fab2(sch_1):page74_i20:vss(1118)"
				( attribute "PN" "H25"
					( Origin gPackager )
				)
				( objectStatus "U2D1.H25" )
			)
			( pin "@baseboard_fab2_lib.baseboard_fab2(sch_1):page74_i20:vss(1119)"
				( attribute "PN" "H11"
					( Origin gPackager )
				)
				( objectStatus "U2D1.H11" )
			)
			( pin "@baseboard_fab2_lib.baseboard_fab2(sch_1):page74_i20:vss(1120)"
				( attribute "PN" "H3"
					( Origin gPackager )
				)
				( objectStatus "U2D1.H3" )
			)
			( pin "@baseboard_fab2_lib.baseboard_fab2(sch_1):page74_i20:vss(1121)"
				( attribute "PN" "G82"
					( Origin gPackager )
				)
				( objectStatus "U2D1.G82" )
			)
			( pin "@baseboard_fab2_lib.baseboard_fab2(sch_1):page74_i20:vss(1122)"
				( attribute "PN" "G80"
					( Origin gPackager )
				)
				( objectStatus "U2D1.G80" )
			)
			( pin "@baseboard_fab2_lib.baseboard_fab2(sch_1):page74_i20:vss(1123)"
				( attribute "PN" "G78"
					( Origin gPackager )
				)
				( objectStatus "U2D1.G78" )
			)
			( pin "@baseboard_fab2_lib.baseboard_fab2(sch_1):page74_i20:vss(1124)"
				( attribute "PN" "G76"
					( Origin gPackager )
				)
				( objectStatus "U2D1.G76" )
			)
			( pin "@baseboard_fab2_lib.baseboard_fab2(sch_1):page74_i20:vss(1125)"
				( attribute "PN" "G70"
					( Origin gPackager )
				)
				( objectStatus "U2D1.G70" )
			)
			( pin "@baseboard_fab2_lib.baseboard_fab2(sch_1):page74_i20:vss(1126)"
				( attribute "PN" "G66"
					( Origin gPackager )
				)
				( objectStatus "U2D1.G66" )
			)
			( pin "@baseboard_fab2_lib.baseboard_fab2(sch_1):page74_i20:vss(1127)"
				( attribute "PN" "G42"
					( Origin gPackager )
				)
				( objectStatus "U2D1.G42" )
			)
			( pin "@baseboard_fab2_lib.baseboard_fab2(sch_1):page74_i20:vss(1128)"
				( attribute "PN" "G38"
					( Origin gPackager )
				)
				( objectStatus "U2D1.G38" )
			)
			( pin "@baseboard_fab2_lib.baseboard_fab2(sch_1):page74_i20:vss(1129)"
				( attribute "PN" "G36"
					( Origin gPackager )
				)
				( objectStatus "U2D1.G36" )
			)
			( pin "@baseboard_fab2_lib.baseboard_fab2(sch_1):page74_i20:vss(1130)"
				( attribute "PN" "G32"
					( Origin gPackager )
				)
				( objectStatus "U2D1.G32" )
			)
			( pin "@baseboard_fab2_lib.baseboard_fab2(sch_1):page74_i20:vss(1131)"
				( attribute "PN" "G30"
					( Origin gPackager )
				)
				( objectStatus "U2D1.G30" )
			)
			( pin "@baseboard_fab2_lib.baseboard_fab2(sch_1):page74_i20:vss(1132)"
				( attribute "PN" "G26"
					( Origin gPackager )
				)
				( objectStatus "U2D1.G26" )
			)
			( pin "@baseboard_fab2_lib.baseboard_fab2(sch_1):page74_i20:vss(1133)"
				( attribute "PN" "G24"
					( Origin gPackager )
				)
				( objectStatus "U2D1.G24" )
			)
			( pin "@baseboard_fab2_lib.baseboard_fab2(sch_1):page74_i20:vss(1134)"
				( attribute "PN" "G22"
					( Origin gPackager )
				)
				( objectStatus "U2D1.G22" )
			)
			( pin "@baseboard_fab2_lib.baseboard_fab2(sch_1):page74_i20:vss(1135)"
				( attribute "PN" "G8"
					( Origin gPackager )
				)
				( objectStatus "U2D1.G8" )
			)
			( pin "@baseboard_fab2_lib.baseboard_fab2(sch_1):page74_i20:vss(1136)"
				( attribute "PN" "G4"
					( Origin gPackager )
				)
				( objectStatus "U2D1.G4" )
			)
			( pin "@baseboard_fab2_lib.baseboard_fab2(sch_1):page74_i20:vss(1137)"
				( attribute "PN" "F69"
					( Origin gPackager )
				)
				( objectStatus "U2D1.F69" )
			)
			( pin "@baseboard_fab2_lib.baseboard_fab2(sch_1):page74_i20:vss(1138)"
				( attribute "PN" "F67"
					( Origin gPackager )
				)
				( objectStatus "U2D1.F67" )
			)
			( pin "@baseboard_fab2_lib.baseboard_fab2(sch_1):page74_i20:vss(1139)"
				( attribute "PN" "F43"
					( Origin gPackager )
				)
				( objectStatus "U2D1.F43" )
			)
			( pin "@baseboard_fab2_lib.baseboard_fab2(sch_1):page74_i20:vss(1140)"
				( attribute "PN" "F37"
					( Origin gPackager )
				)
				( objectStatus "U2D1.F37" )
			)
			( pin "@baseboard_fab2_lib.baseboard_fab2(sch_1):page74_i20:vss(1141)"
				( attribute "PN" "F31"
					( Origin gPackager )
				)
				( objectStatus "U2D1.F31" )
			)
			( pin "@baseboard_fab2_lib.baseboard_fab2(sch_1):page74_i20:vss(1142)"
				( attribute "PN" "F25"
					( Origin gPackager )
				)
				( objectStatus "U2D1.F25" )
			)
			( pin "@baseboard_fab2_lib.baseboard_fab2(sch_1):page74_i20:vss(1143)"
				( attribute "PN" "F19"
					( Origin gPackager )
				)
				( objectStatus "U2D1.F19" )
			)
			( pin "@baseboard_fab2_lib.baseboard_fab2(sch_1):page74_i20:vss(1144)"
				( attribute "PN" "F17"
					( Origin gPackager )
				)
				( objectStatus "U2D1.F17" )
			)
			( pin "@baseboard_fab2_lib.baseboard_fab2(sch_1):page74_i20:vss(1145)"
				( attribute "PN" "F5"
					( Origin gPackager )
				)
				( objectStatus "U2D1.F5" )
			)
			( pin "@baseboard_fab2_lib.baseboard_fab2(sch_1):page74_i20:vss(1146)"
				( attribute "PN" "E76"
					( Origin gPackager )
				)
				( objectStatus "U2D1.E76" )
			)
			( pin "@baseboard_fab2_lib.baseboard_fab2(sch_1):page74_i20:vss(1147)"
				( attribute "PN" "E74"
					( Origin gPackager )
				)
				( objectStatus "U2D1.E74" )
			)
			( pin "@baseboard_fab2_lib.baseboard_fab2(sch_1):page74_i20:vss(1148)"
				( attribute "PN" "E72"
					( Origin gPackager )
				)
				( objectStatus "U2D1.E72" )
			)
			( pin "@baseboard_fab2_lib.baseboard_fab2(sch_1):page74_i20:vss(1149)"
				( attribute "PN" "E22"
					( Origin gPackager )
				)
				( objectStatus "U2D1.E22" )
			)
			( pin "@baseboard_fab2_lib.baseboard_fab2(sch_1):page74_i20:vss(1150)"
				( attribute "PN" "E20"
					( Origin gPackager )
				)
				( objectStatus "U2D1.E20" )
			)
			( pin "@baseboard_fab2_lib.baseboard_fab2(sch_1):page74_i20:vss(1151)"
				( attribute "PN" "E18"
					( Origin gPackager )
				)
				( objectStatus "U2D1.E18" )
			)
			( pin "@baseboard_fab2_lib.baseboard_fab2(sch_1):page74_i20:vss(1152)"
				( attribute "PN" "E16"
					( Origin gPackager )
				)
				( objectStatus "U2D1.E16" )
			)
			( pin "@baseboard_fab2_lib.baseboard_fab2(sch_1):page74_i20:vss(1153)"
				( attribute "PN" "E8"
					( Origin gPackager )
				)
				( objectStatus "U2D1.E8" )
			)
			( pin "@baseboard_fab2_lib.baseboard_fab2(sch_1):page74_i20:vss(1154)"
				( attribute "PN" "E6"
					( Origin gPackager )
				)
				( objectStatus "U2D1.E6" )
			)
			( pin "@baseboard_fab2_lib.baseboard_fab2(sch_1):page74_i20:vss(1155)"
				( attribute "PN" "D77"
					( Origin gPackager )
				)
				( objectStatus "U2D1.D77" )
			)
			( pin "@baseboard_fab2_lib.baseboard_fab2(sch_1):page74_i20:vss(1156)"
				( attribute "PN" "D43"
					( Origin gPackager )
				)
				( objectStatus "U2D1.D43" )
			)
			( pin "@baseboard_fab2_lib.baseboard_fab2(sch_1):page74_i20:vss(1157)"
				( attribute "PN" "D41"
					( Origin gPackager )
				)
				( objectStatus "U2D1.D41" )
			)
			( pin "@baseboard_fab2_lib.baseboard_fab2(sch_1):page74_i20:vss(1158)"
				( attribute "PN" "D39"
					( Origin gPackager )
				)
				( objectStatus "U2D1.D39" )
			)
			( pin "@baseboard_fab2_lib.baseboard_fab2(sch_1):page74_i20:vss(1159)"
				( attribute "PN" "D37"
					( Origin gPackager )
				)
				( objectStatus "U2D1.D37" )
			)
			( pin "@baseboard_fab2_lib.baseboard_fab2(sch_1):page74_i20:vss(1160)"
				( attribute "PN" "D35"
					( Origin gPackager )
				)
				( objectStatus "U2D1.D35" )
			)
			( pin "@baseboard_fab2_lib.baseboard_fab2(sch_1):page74_i20:vss(1161)"
				( attribute "PN" "D33"
					( Origin gPackager )
				)
				( objectStatus "U2D1.D33" )
			)
			( pin "@baseboard_fab2_lib.baseboard_fab2(sch_1):page74_i20:vss(1162)"
				( attribute "PN" "D31"
					( Origin gPackager )
				)
				( objectStatus "U2D1.D31" )
			)
			( pin "@baseboard_fab2_lib.baseboard_fab2(sch_1):page74_i20:vss(1163)"
				( attribute "PN" "D29"
					( Origin gPackager )
				)
				( objectStatus "U2D1.D29" )
			)
			( pin "@baseboard_fab2_lib.baseboard_fab2(sch_1):page74_i20:vss(1164)"
				( attribute "PN" "D27"
					( Origin gPackager )
				)
				( objectStatus "U2D1.D27" )
			)
			( pin "@baseboard_fab2_lib.baseboard_fab2(sch_1):page74_i20:vss(1165)"
				( attribute "PN" "D25"
					( Origin gPackager )
				)
				( objectStatus "U2D1.D25" )
			)
			( pin "@baseboard_fab2_lib.baseboard_fab2(sch_1):page74_i20:vss(1166)"
				( attribute "PN" "D13"
					( Origin gPackager )
				)
				( objectStatus "U2D1.D13" )
			)
			( pin "@baseboard_fab2_lib.baseboard_fab2(sch_1):page74_i20:vss(1167)"
				( attribute "PN" "D11"
					( Origin gPackager )
				)
				( objectStatus "U2D1.D11" )
			)
			( pin "@baseboard_fab2_lib.baseboard_fab2(sch_1):page74_i20:vss(1168)"
				( attribute "PN" "CM27"
					( Origin gPackager )
				)
				( objectStatus "U2D1.CM27" )
			)
			( pin "@baseboard_fab2_lib.baseboard_fab2(sch_1):page74_i20:vss(1169)"
				( attribute "PN" "C78"
					( Origin gPackager )
				)
				( objectStatus "U2D1.C78" )
			)
			( pin "@baseboard_fab2_lib.baseboard_fab2(sch_1):page74_i20:vss(1170)"
				( attribute "PN" "C76"
					( Origin gPackager )
				)
				( objectStatus "U2D1.C76" )
			)
			( pin "@baseboard_fab2_lib.baseboard_fab2(sch_1):page74_i20:vss(1171)"
				( attribute "PN" "C16"
					( Origin gPackager )
				)
				( objectStatus "U2D1.C16" )
			)
			( pin "@baseboard_fab2_lib.baseboard_fab2(sch_1):page74_i20:vss(1172)"
				( attribute "PN" "C14"
					( Origin gPackager )
				)
				( objectStatus "U2D1.C14" )
			)
			( pin "@baseboard_fab2_lib.baseboard_fab2(sch_1):page74_i20:vss(1173)"
				( attribute "PN" "C12"
					( Origin gPackager )
				)
				( objectStatus "U2D1.C12" )
			)
			( pin "@baseboard_fab2_lib.baseboard_fab2(sch_1):page74_i20:vss(1174)"
				( attribute "PN" "C10"
					( Origin gPackager )
				)
				( objectStatus "U2D1.C10" )
			)
			( pin "@baseboard_fab2_lib.baseboard_fab2(sch_1):page74_i20:vss(1175)"
				( attribute "PN" "C8"
					( Origin gPackager )
				)
				( objectStatus "U2D1.C8" )
			)
			( pin "@baseboard_fab2_lib.baseboard_fab2(sch_1):page74_i20:vss(1176)"
				( attribute "PN" "B75"
					( Origin gPackager )
				)
				( objectStatus "U2D1.B75" )
			)
			( pin "@baseboard_fab2_lib.baseboard_fab2(sch_1):page74_i20:vss(1177)"
				( attribute "PN" "B71"
					( Origin gPackager )
				)
				( objectStatus "U2D1.B71" )
			)
			( pin "@baseboard_fab2_lib.baseboard_fab2(sch_1):page74_i20:vss(1178)"
				( attribute "PN" "B37"
					( Origin gPackager )
				)
				( objectStatus "U2D1.B37" )
			)
			( pin "@baseboard_fab2_lib.baseboard_fab2(sch_1):page74_i20:vss(1179)"
				( attribute "PN" "B31"
					( Origin gPackager )
				)
				( objectStatus "U2D1.B31" )
			)
			( pin "@baseboard_fab2_lib.baseboard_fab2(sch_1):page74_i20:vss(1180)"
				( attribute "PN" "B25"
					( Origin gPackager )
				)
				( objectStatus "U2D1.B25" )
			)
			( pin "@baseboard_fab2_lib.baseboard_fab2(sch_1):page74_i20:vss(1181)"
				( attribute "PN" "A38"
					( Origin gPackager )
				)
				( objectStatus "U2D1.A38" )
			)
			( pin "@baseboard_fab2_lib.baseboard_fab2(sch_1):page74_i20:vss(1182)"
				( attribute "PN" "A36"
					( Origin gPackager )
				)
				( objectStatus "U2D1.A36" )
			)
			( pin "@baseboard_fab2_lib.baseboard_fab2(sch_1):page74_i20:vss(1183)"
				( attribute "PN" "A32"
					( Origin gPackager )
				)
				( objectStatus "U2D1.A32" )
			)
			( pin "@baseboard_fab2_lib.baseboard_fab2(sch_1):page74_i20:vss(1184)"
				( attribute "PN" "A30"
					( Origin gPackager )
				)
				( objectStatus "U2D1.A30" )
			)
			( pin "@baseboard_fab2_lib.baseboard_fab2(sch_1):page74_i20:vss(1185)"
				( attribute "PN" "A26"
					( Origin gPackager )
				)
				( objectStatus "U2D1.A26" )
			)
			( pin "@baseboard_fab2_lib.baseboard_fab2(sch_1):page74_i20:vss(1186)"
				( attribute "PN" "AC58"
					( Origin gPackager )
				)
				( objectStatus "U2D1.AC58" )
			)
			( pin "@baseboard_fab2_lib.baseboard_fab2(sch_1):page74_i20:vss(1187)"
				( attribute "PN" "AC60"
					( Origin gPackager )
				)
				( objectStatus "U2D1.AC60" )
			)
			( pin "@baseboard_fab2_lib.baseboard_fab2(sch_1):page74_i20:vss(1188)"
				( attribute "PN" "AC62"
					( Origin gPackager )
				)
				( objectStatus "U2D1.AC62" )
			)
			( pin "@baseboard_fab2_lib.baseboard_fab2(sch_1):page74_i20:vss(1189)"
				( attribute "PN" "AJ4"
					( Origin gPackager )
				)
				( objectStatus "U2D1.AJ4" )
			)
			( pin "@baseboard_fab2_lib.baseboard_fab2(sch_1):page74_i20:vss(1190)"
				( attribute "PN" "AR6"
					( Origin gPackager )
				)
				( objectStatus "U2D1.AR6" )
			)
			( pin "@baseboard_fab2_lib.baseboard_fab2(sch_1):page74_i20:vss(1191)"
				( attribute "PN" "CG6"
					( Origin gPackager )
				)
				( objectStatus "U2D1.CG6" )
			)
			( pin "@baseboard_fab2_lib.baseboard_fab2(sch_1):page74_i20:vss(1192)"
				( attribute "PN" "CW6"
					( Origin gPackager )
				)
				( objectStatus "U2D1.CW6" )
			)
			( pin "@baseboard_fab2_lib.baseboard_fab2(sch_1):page74_i20:vss(1193)"
				( attribute "PN" "DE48"
					( Origin gPackager )
				)
				( objectStatus "U2D1.DE48" )
			)
			( pin "@baseboard_fab2_lib.baseboard_fab2(sch_1):page74_i20:vss(1194)"
				( attribute "PN" "DE50"
					( Origin gPackager )
				)
				( objectStatus "U2D1.DE50" )
			)
			( pin "@baseboard_fab2_lib.baseboard_fab2(sch_1):page74_i20:vss(1195)"
				( attribute "PN" "DE52"
					( Origin gPackager )
				)
				( objectStatus "U2D1.DE52" )
			)
			( pin "@baseboard_fab2_lib.baseboard_fab2(sch_1):page74_i20:vss(1196)"
				( attribute "PN" "DE54"
					( Origin gPackager )
				)
				( objectStatus "U2D1.DE54" )
			)
			( pin "@baseboard_fab2_lib.baseboard_fab2(sch_1):page74_i20:vss(1197)"
				( attribute "PN" "DE56"
					( Origin gPackager )
				)
				( objectStatus "U2D1.DE56" )
			)
			( pin "@baseboard_fab2_lib.baseboard_fab2(sch_1):page74_i20:vss(1198)"
				( attribute "PN" "DE58"
					( Origin gPackager )
				)
				( objectStatus "U2D1.DE58" )
			)
			( pin "@baseboard_fab2_lib.baseboard_fab2(sch_1):page74_i20:vss(1199)"
				( attribute "PN" "DE60"
					( Origin gPackager )
				)
				( objectStatus "U2D1.DE60" )
			)
			( pin "@baseboard_fab2_lib.baseboard_fab2(sch_1):page74_i20:vss(1200)"
				( attribute "PN" "DE62"
					( Origin gPackager )
				)
				( objectStatus "U2D1.DE62" )
			)
			( pin "@baseboard_fab2_lib.baseboard_fab2(sch_1):page74_i20:vss(1201)"
				( attribute "PN" "DL8"
					( Origin gPackager )
				)
				( objectStatus "U2D1.DL8" )
			)
			( pin "@baseboard_fab2_lib.baseboard_fab2(sch_1):page74_i20:vss(1202)"
				( attribute "PN" "DN18"
					( Origin gPackager )
				)
				( objectStatus "U2D1.DN18" )
			)
			( pin "@baseboard_fab2_lib.baseboard_fab2(sch_1):page74_i20:vss(1203)"
				( attribute "PN" "DP45"
					( Origin gPackager )
				)
				( objectStatus "U2D1.DP45" )
			)
			( pin "@baseboard_fab2_lib.baseboard_fab2(sch_1):page74_i20:vss(1204)"
				( attribute "PN" "DP47"
					( Origin gPackager )
				)
				( objectStatus "U2D1.DP47" )
			)
			( pin "@baseboard_fab2_lib.baseboard_fab2(sch_1):page74_i20:vss(1205)"
				( attribute "PN" "DP49"
					( Origin gPackager )
				)
				( objectStatus "U2D1.DP49" )
			)
			( pin "@baseboard_fab2_lib.baseboard_fab2(sch_1):page74_i20:vss(1206)"
				( attribute "PN" "DP51"
					( Origin gPackager )
				)
				( objectStatus "U2D1.DP51" )
			)
			( pin "@baseboard_fab2_lib.baseboard_fab2(sch_1):page74_i20:vss(1207)"
				( attribute "PN" "DP53"
					( Origin gPackager )
				)
				( objectStatus "U2D1.DP53" )
			)
			( pin "@baseboard_fab2_lib.baseboard_fab2(sch_1):page74_i20:vss(1208)"
				( attribute "PN" "DP55"
					( Origin gPackager )
				)
				( objectStatus "U2D1.DP55" )
			)
			( pin "@baseboard_fab2_lib.baseboard_fab2(sch_1):page74_i20:vss(1209)"
				( attribute "PN" "DP57"
					( Origin gPackager )
				)
				( objectStatus "U2D1.DP57" )
			)
			( pin "@baseboard_fab2_lib.baseboard_fab2(sch_1):page74_i20:vss(1210)"
				( attribute "PN" "DP59"
					( Origin gPackager )
				)
				( objectStatus "U2D1.DP59" )
			)
			( pin "@baseboard_fab2_lib.baseboard_fab2(sch_1):page74_i20:vss(1211)"
				( attribute "PN" "DP61"
					( Origin gPackager )
				)
				( objectStatus "U2D1.DP61" )
			)
			( pin "@baseboard_fab2_lib.baseboard_fab2(sch_1):page74_i20:vss(1212)"
				( attribute "PN" "DP63"
					( Origin gPackager )
				)
				( objectStatus "U2D1.DP63" )
			)
			( pin "@baseboard_fab2_lib.baseboard_fab2(sch_1):page74_i20:vss(1213)"
				( attribute "PN" "DP9"
					( Origin gPackager )
				)
				( objectStatus "U2D1.DP9" )
			)
			( pin "@baseboard_fab2_lib.baseboard_fab2(sch_1):page74_i20:vss(1214)"
				( attribute "PN" "DV19"
					( Origin gPackager )
				)
				( objectStatus "U2D1.DV19" )
			)
			( pin "@baseboard_fab2_lib.baseboard_fab2(sch_1):page74_i20:vss(1215)"
				( attribute "PN" "DY45"
					( Origin gPackager )
				)
				( objectStatus "U2D1.DY45" )
			)
			( pin "@baseboard_fab2_lib.baseboard_fab2(sch_1):page74_i20:vss(1216)"
				( attribute "PN" "DY47"
					( Origin gPackager )
				)
				( objectStatus "U2D1.DY47" )
			)
			( pin "@baseboard_fab2_lib.baseboard_fab2(sch_1):page74_i20:vss(1217)"
				( attribute "PN" "DY49"
					( Origin gPackager )
				)
				( objectStatus "U2D1.DY49" )
			)
			( pin "@baseboard_fab2_lib.baseboard_fab2(sch_1):page74_i20:vss(1218)"
				( attribute "PN" "DY51"
					( Origin gPackager )
				)
				( objectStatus "U2D1.DY51" )
			)
			( pin "@baseboard_fab2_lib.baseboard_fab2(sch_1):page74_i20:vss(1219)"
				( attribute "PN" "DY53"
					( Origin gPackager )
				)
				( objectStatus "U2D1.DY53" )
			)
			( pin "@baseboard_fab2_lib.baseboard_fab2(sch_1):page74_i20:vss(1220)"
				( attribute "PN" "DY55"
					( Origin gPackager )
				)
				( objectStatus "U2D1.DY55" )
			)
			( pin "@baseboard_fab2_lib.baseboard_fab2(sch_1):page74_i20:vss(1221)"
				( attribute "PN" "DY57"
					( Origin gPackager )
				)
				( objectStatus "U2D1.DY57" )
			)
			( pin "@baseboard_fab2_lib.baseboard_fab2(sch_1):page74_i20:vss(1222)"
				( attribute "PN" "DY59"
					( Origin gPackager )
				)
				( objectStatus "U2D1.DY59" )
			)
			( pin "@baseboard_fab2_lib.baseboard_fab2(sch_1):page74_i20:vss(1223)"
				( attribute "PN" "DY61"
					( Origin gPackager )
				)
				( objectStatus "U2D1.DY61" )
			)
			( pin "@baseboard_fab2_lib.baseboard_fab2(sch_1):page74_i20:vss(1224)"
				( attribute "PN" "DY63"
					( Origin gPackager )
				)
				( objectStatus "U2D1.DY63" )
			)
			( pin "@baseboard_fab2_lib.baseboard_fab2(sch_1):page74_i20:vss(1225)"
				( attribute "PN" "EA14"
					( Origin gPackager )
				)
				( objectStatus "U2D1.EA14" )
			)
			( pin "@baseboard_fab2_lib.baseboard_fab2(sch_1):page74_i20:vss(1226)"
				( attribute "PN" "L8"
					( Origin gPackager )
				)
				( objectStatus "U2D1.L8" )
			)
			( pin "@baseboard_fab2_lib.baseboard_fab2(sch_1):page74_i20:vss(1227)"
				( attribute "PN" "V11"
					( Origin gPackager )
				)
				( objectStatus "U2D1.V11" )
			)
			( pin "@baseboard_fab2_lib.baseboard_fab2(sch_1):page74_i20:vss(1228)"
				( attribute "PN" "E66"
					( Origin gPackager )
				)
				( objectStatus "U2D1.E66" )
			)
			( pin "@baseboard_fab2_lib.baseboard_fab2(sch_1):page74_i20:vss(1229)"
				( attribute "PN" "ED69"
					( Origin gPackager )
				)
				( objectStatus "U2D1.ED69" )
			)
			( pin "@baseboard_fab2_lib.baseboard_fab2(sch_1):page74_i20:vss(1230)"
				( attribute "PN" "EE80"
					( Origin gPackager )
				)
				( objectStatus "U2D1.EE80" )
			)
			( pin "@baseboard_fab2_lib.baseboard_fab2(sch_1):page74_i20:vss(1231)"
				( attribute "PN" "EE8"
					( Origin gPackager )
				)
				( objectStatus "U2D1.EE8" )
			)
			( pin "@baseboard_fab2_lib.baseboard_fab2(sch_1):page74_i20:vss(1232)"
				( attribute "PN" "EE40"
					( Origin gPackager )
				)
				( objectStatus "U2D1.EE40" )
			)
			( pin "@baseboard_fab2_lib.baseboard_fab2(sch_1):page74_i20:vss(1233)"
				( attribute "PN" "ED81"
					( Origin gPackager )
				)
				( objectStatus "U2D1.ED81" )
			)
			( pin "@baseboard_fab2_lib.baseboard_fab2(sch_1):page74_i20:vss(1234)"
				( attribute "PN" "ED7"
					( Origin gPackager )
				)
				( objectStatus "U2D1.ED7" )
			)
			( pin "@baseboard_fab2_lib.baseboard_fab2(sch_1):page74_i20:vss(1235)"
				( attribute "PN" "ED41"
					( Origin gPackager )
				)
				( objectStatus "U2D1.ED41" )
			)
			( pin "@baseboard_fab2_lib.baseboard_fab2(sch_1):page74_i20:vss(1236)"
				( attribute "PN" "EC82"
					( Origin gPackager )
				)
				( objectStatus "U2D1.EC82" )
			)
			( pin "@baseboard_fab2_lib.baseboard_fab2(sch_1):page74_i20:vss(1237)"
				( attribute "PN" "EC6"
					( Origin gPackager )
				)
				( objectStatus "U2D1.EC6" )
			)
			( pin "@baseboard_fab2_lib.baseboard_fab2(sch_1):page74_i20:vss(1238)"
				( attribute "PN" "EC42"
					( Origin gPackager )
				)
				( objectStatus "U2D1.EC42" )
			)
			( pin "@baseboard_fab2_lib.baseboard_fab2(sch_1):page74_i20:vss(1239)"
				( attribute "PN" "DW2"
					( Origin gPackager )
				)
				( objectStatus "U2D1.DW2" )
			)
			( pin "@baseboard_fab2_lib.baseboard_fab2(sch_1):page74_i20:vss(1240)"
				( attribute "PN" "EB83"
					( Origin gPackager )
				)
				( objectStatus "U2D1.EB83" )
			)
			( pin "@baseboard_fab2_lib.baseboard_fab2(sch_1):page74_i20:vss(1241)"
				( attribute "PN" "EA84"
					( Origin gPackager )
				)
				( objectStatus "U2D1.EA84" )
			)
			( pin "@baseboard_fab2_lib.baseboard_fab2(sch_1):page74_i20:vss(1242)"
				( attribute "PN" "DY85"
					( Origin gPackager )
				)
				( objectStatus "U2D1.DY85" )
			)
			( pin "@baseboard_fab2_lib.baseboard_fab2(sch_1):page74_i20:vss(1243)"
				( attribute "PN" "J86"
					( Origin gPackager )
				)
				( objectStatus "U2D1.J86" )
			)
			( pin "@baseboard_fab2_lib.baseboard_fab2(sch_1):page74_i20:vss(1244)"
				( attribute "PN" "E82"
					( Origin gPackager )
				)
				( objectStatus "U2D1.E82" )
			)
			( pin "@baseboard_fab2_lib.baseboard_fab2(sch_1):page74_i20:vss(1245)"
				( attribute "PN" "D81"
					( Origin gPackager )
				)
				( objectStatus "U2D1.D81" )
			)
			( pin "@baseboard_fab2_lib.baseboard_fab2(sch_1):page74_i20:vss(1246)"
				( attribute "PN" "D3"
					( Origin gPackager )
				)
				( objectStatus "U2D1.D3" )
			)
			( pin "@baseboard_fab2_lib.baseboard_fab2(sch_1):page74_i20:vss(1247)"
				( attribute "PN" "C80"
					( Origin gPackager )
				)
				( objectStatus "U2D1.C80" )
			)
			( pin "@baseboard_fab2_lib.baseboard_fab2(sch_1):page74_i20:vss(1248)"
				( attribute "PN" "C4"
					( Origin gPackager )
				)
				( objectStatus "U2D1.C4" )
			)
			( pin "@baseboard_fab2_lib.baseboard_fab2(sch_1):page74_i20:vss(1249)"
				( attribute "PN" "B79"
					( Origin gPackager )
				)
				( objectStatus "U2D1.B79" )
			)
			( pin "@baseboard_fab2_lib.baseboard_fab2(sch_1):page74_i20:vss(1250)"
				( attribute "PN" "B5"
					( Origin gPackager )
				)
				( objectStatus "U2D1.B5" )
			)
			( pin "@baseboard_fab2_lib.baseboard_fab2(sch_1):page74_i20:vss(1251)"
				( attribute "PN" "B43"
					( Origin gPackager )
				)
				( objectStatus "U2D1.B43" )
			)
			( pin "@baseboard_fab2_lib.baseboard_fab2(sch_1):page74_i20:vss(1252)"
				( attribute "PN" "A42"
					( Origin gPackager )
				)
				( objectStatus "U2D1.A42" )
			)
			( pin "@baseboard_fab2_lib.baseboard_fab2(sch_1):page74_i20:vss(1253)"
				( attribute "PN" "B9"
					( Origin gPackager )
				)
				( objectStatus "U2D1.B9" )
			)
			( pin "@baseboard_fab2_lib.baseboard_fab2(sch_1):page74_i21:vss(934)"
				( attribute "PN" "AA16"
					( Origin gPackager )
				)
				( objectStatus "U2D1.AA16" )
			)
			( pin "@baseboard_fab2_lib.baseboard_fab2(sch_1):page74_i21:vss(935)"
				( attribute "PN" "AA4"
					( Origin gPackager )
				)
				( objectStatus "U2D1.AA4" )
			)
			( pin "@baseboard_fab2_lib.baseboard_fab2(sch_1):page74_i21:vss(936)"
				( attribute "PN" "Y85"
					( Origin gPackager )
				)
				( objectStatus "U2D1.Y85" )
			)
			( pin "@baseboard_fab2_lib.baseboard_fab2(sch_1):page74_i21:vss(937)"
				( attribute "PN" "Y83"
					( Origin gPackager )
				)
				( objectStatus "U2D1.Y83" )
			)
			( pin "@baseboard_fab2_lib.baseboard_fab2(sch_1):page74_i21:vss(938)"
				( attribute "PN" "Y81"
					( Origin gPackager )
				)
				( objectStatus "U2D1.Y81" )
			)
			( pin "@baseboard_fab2_lib.baseboard_fab2(sch_1):page74_i21:vss(939)"
				( attribute "PN" "Y79"
					( Origin gPackager )
				)
				( objectStatus "U2D1.Y79" )
			)
			( pin "@baseboard_fab2_lib.baseboard_fab2(sch_1):page74_i21:vss(940)"
				( attribute "PN" "Y73"
					( Origin gPackager )
				)
				( objectStatus "U2D1.Y73" )
			)
			( pin "@baseboard_fab2_lib.baseboard_fab2(sch_1):page74_i21:vss(941)"
				( attribute "PN" "Y71"
					( Origin gPackager )
				)
				( objectStatus "U2D1.Y71" )
			)
			( pin "@baseboard_fab2_lib.baseboard_fab2(sch_1):page74_i21:vss(942)"
				( attribute "PN" "Y9"
					( Origin gPackager )
				)
				( objectStatus "U2D1.Y9" )
			)
			( pin "@baseboard_fab2_lib.baseboard_fab2(sch_1):page74_i21:vss(943)"
				( attribute "PN" "Y7"
					( Origin gPackager )
				)
				( objectStatus "U2D1.Y7" )
			)
			( pin "@baseboard_fab2_lib.baseboard_fab2(sch_1):page74_i21:vss(944)"
				( attribute "PN" "Y67"
					( Origin gPackager )
				)
				( objectStatus "U2D1.Y67" )
			)
			( pin "@baseboard_fab2_lib.baseboard_fab2(sch_1):page74_i21:vss(945)"
				( attribute "PN" "Y5"
					( Origin gPackager )
				)
				( objectStatus "U2D1.Y5" )
			)
			( pin "@baseboard_fab2_lib.baseboard_fab2(sch_1):page74_i21:vss(946)"
				( attribute "PN" "Y17"
					( Origin gPackager )
				)
				( objectStatus "U2D1.Y17" )
			)
			( pin "@baseboard_fab2_lib.baseboard_fab2(sch_1):page74_i21:vss(947)"
				( attribute "PN" "Y15"
					( Origin gPackager )
				)
				( objectStatus "U2D1.Y15" )
			)
			( pin "@baseboard_fab2_lib.baseboard_fab2(sch_1):page74_i21:vss(948)"
				( attribute "PN" "W82"
					( Origin gPackager )
				)
				( objectStatus "U2D1.W82" )
			)
			( pin "@baseboard_fab2_lib.baseboard_fab2(sch_1):page74_i21:vss(949)"
				( attribute "PN" "W78"
					( Origin gPackager )
				)
				( objectStatus "U2D1.W78" )
			)
			( pin "@baseboard_fab2_lib.baseboard_fab2(sch_1):page74_i21:vss(950)"
				( attribute "PN" "W74"
					( Origin gPackager )
				)
				( objectStatus "U2D1.W74" )
			)
			( pin "@baseboard_fab2_lib.baseboard_fab2(sch_1):page74_i21:vss(951)"
				( attribute "PN" "W68"
					( Origin gPackager )
				)
				( objectStatus "U2D1.W68" )
			)
			( pin "@baseboard_fab2_lib.baseboard_fab2(sch_1):page74_i21:vss(952)"
				( attribute "PN" "W42"
					( Origin gPackager )
				)
				( objectStatus "U2D1.W42" )
			)
			( pin "@baseboard_fab2_lib.baseboard_fab2(sch_1):page74_i21:vss(953)"
				( attribute "PN" "W40"
					( Origin gPackager )
				)
				( objectStatus "U2D1.W40" )
			)
			( pin "@baseboard_fab2_lib.baseboard_fab2(sch_1):page74_i21:vss(954)"
				( attribute "PN" "W38"
					( Origin gPackager )
				)
				( objectStatus "U2D1.W38" )
			)
			( pin "@baseboard_fab2_lib.baseboard_fab2(sch_1):page74_i21:vss(955)"
				( attribute "PN" "W36"
					( Origin gPackager )
				)
				( objectStatus "U2D1.W36" )
			)
			( pin "@baseboard_fab2_lib.baseboard_fab2(sch_1):page74_i21:vss(956)"
				( attribute "PN" "W34"
					( Origin gPackager )
				)
				( objectStatus "U2D1.W34" )
			)
			( pin "@baseboard_fab2_lib.baseboard_fab2(sch_1):page74_i21:vss(957)"
				( attribute "PN" "W32"
					( Origin gPackager )
				)
				( objectStatus "U2D1.W32" )
			)
			( pin "@baseboard_fab2_lib.baseboard_fab2(sch_1):page74_i21:vss(958)"
				( attribute "PN" "W30"
					( Origin gPackager )
				)
				( objectStatus "U2D1.W30" )
			)
			( pin "@baseboard_fab2_lib.baseboard_fab2(sch_1):page74_i21:vss(959)"
				( attribute "PN" "W28"
					( Origin gPackager )
				)
				( objectStatus "U2D1.W28" )
			)
			( pin "@baseboard_fab2_lib.baseboard_fab2(sch_1):page74_i21:vss(960)"
				( attribute "PN" "W26"
					( Origin gPackager )
				)
				( objectStatus "U2D1.W26" )
			)
			( pin "@baseboard_fab2_lib.baseboard_fab2(sch_1):page74_i21:vss(961)"
				( attribute "PN" "W24"
					( Origin gPackager )
				)
				( objectStatus "U2D1.W24" )
			)
			( pin "@baseboard_fab2_lib.baseboard_fab2(sch_1):page74_i21:vss(962)"
				( attribute "PN" "W22"
					( Origin gPackager )
				)
				( objectStatus "U2D1.W22" )
			)
			( pin "@baseboard_fab2_lib.baseboard_fab2(sch_1):page74_i21:vss(963)"
				( attribute "PN" "W12"
					( Origin gPackager )
				)
				( objectStatus "U2D1.W12" )
			)
			( pin "@baseboard_fab2_lib.baseboard_fab2(sch_1):page74_i21:vss(964)"
				( attribute "PN" "AC56"
					( Origin gPackager )
				)
				( objectStatus "U2D1.AC56" )
			)
			( pin "@baseboard_fab2_lib.baseboard_fab2(sch_1):page74_i21:vss(965)"
				( attribute "PN" "W8"
					( Origin gPackager )
				)
				( objectStatus "U2D1.W8" )
			)
			( pin "@baseboard_fab2_lib.baseboard_fab2(sch_1):page74_i21:vss(966)"
				( attribute "PN" "V83"
					( Origin gPackager )
				)
				( objectStatus "U2D1.V83" )
			)
			( pin "@baseboard_fab2_lib.baseboard_fab2(sch_1):page74_i21:vss(967)"
				( attribute "PN" "V77"
					( Origin gPackager )
				)
				( objectStatus "U2D1.V77" )
			)
			( pin "@baseboard_fab2_lib.baseboard_fab2(sch_1):page74_i21:vss(968)"
				( attribute "PN" "V75"
					( Origin gPackager )
				)
				( objectStatus "U2D1.V75" )
			)
			( pin "@baseboard_fab2_lib.baseboard_fab2(sch_1):page74_i21:vss(969)"
				( attribute "PN" "V73"
					( Origin gPackager )
				)
				( objectStatus "U2D1.V73" )
			)
			( pin "@baseboard_fab2_lib.baseboard_fab2(sch_1):page74_i21:vss(970)"
				( attribute "PN" "V43"
					( Origin gPackager )
				)
				( objectStatus "U2D1.V43" )
			)
			( pin "@baseboard_fab2_lib.baseboard_fab2(sch_1):page74_i21:vss(971)"
				( attribute "PN" "V23"
					( Origin gPackager )
				)
				( objectStatus "U2D1.V23" )
			)
			( pin "@baseboard_fab2_lib.baseboard_fab2(sch_1):page74_i21:vss(972)"
				( attribute "PN" "V21"
					( Origin gPackager )
				)
				( objectStatus "U2D1.V21" )
			)
			( pin "@baseboard_fab2_lib.baseboard_fab2(sch_1):page74_i21:vss(973)"
				( attribute "PN" "V15"
					( Origin gPackager )
				)
				( objectStatus "U2D1.V15" )
			)
			( pin "@baseboard_fab2_lib.baseboard_fab2(sch_1):page74_i21:vss(974)"
				( attribute "PN" "V13"
					( Origin gPackager )
				)
				( objectStatus "U2D1.V13" )
			)
			( pin "@baseboard_fab2_lib.baseboard_fab2(sch_1):page74_i21:vss(975)"
				( attribute "PN" "V9"
					( Origin gPackager )
				)
				( objectStatus "U2D1.V9" )
			)
			( pin "@baseboard_fab2_lib.baseboard_fab2(sch_1):page74_i21:vss(976)"
				( attribute "PN" "V5"
					( Origin gPackager )
				)
				( objectStatus "U2D1.V5" )
			)
			( pin "@baseboard_fab2_lib.baseboard_fab2(sch_1):page74_i21:vss(977)"
				( attribute "PN" "V1"
					( Origin gPackager )
				)
				( objectStatus "U2D1.V1" )
			)
			( pin "@baseboard_fab2_lib.baseboard_fab2(sch_1):page74_i21:vss(978)"
				( attribute "PN" "U86"
					( Origin gPackager )
				)
				( objectStatus "U2D1.U86" )
			)
			( pin "@baseboard_fab2_lib.baseboard_fab2(sch_1):page74_i21:vss(979)"
				( attribute "PN" "U80"
					( Origin gPackager )
				)
				( objectStatus "U2D1.U80" )
			)
			( pin "@baseboard_fab2_lib.baseboard_fab2(sch_1):page74_i21:vss(980)"
				( attribute "PN" "U78"
					( Origin gPackager )
				)
				( objectStatus "U2D1.U78" )
			)
			( pin "@baseboard_fab2_lib.baseboard_fab2(sch_1):page74_i21:vss(981)"
				( attribute "PN" "U76"
					( Origin gPackager )
				)
				( objectStatus "U2D1.U76" )
			)
			( pin "@baseboard_fab2_lib.baseboard_fab2(sch_1):page74_i21:vss(982)"
				( attribute "PN" "U74"
					( Origin gPackager )
				)
				( objectStatus "U2D1.U74" )
			)
			( pin "@baseboard_fab2_lib.baseboard_fab2(sch_1):page74_i21:vss(983)"
				( attribute "PN" "U70"
					( Origin gPackager )
				)
				( objectStatus "U2D1.U70" )
			)
			( pin "@baseboard_fab2_lib.baseboard_fab2(sch_1):page74_i21:vss(984)"
				( attribute "PN" "U68"
					( Origin gPackager )
				)
				( objectStatus "U2D1.U68" )
			)
			( pin "@baseboard_fab2_lib.baseboard_fab2(sch_1):page74_i21:vss(985)"
				( attribute "PN" "U42"
					( Origin gPackager )
				)
				( objectStatus "U2D1.U42" )
			)
			( pin "@baseboard_fab2_lib.baseboard_fab2(sch_1):page74_i21:vss(986)"
				( attribute "PN" "U36"
					( Origin gPackager )
				)
				( objectStatus "U2D1.U36" )
			)
			( pin "@baseboard_fab2_lib.baseboard_fab2(sch_1):page74_i21:vss(987)"
				( attribute "PN" "U30"
					( Origin gPackager )
				)
				( objectStatus "U2D1.U30" )
			)
			( pin "@baseboard_fab2_lib.baseboard_fab2(sch_1):page74_i21:vss(988)"
				( attribute "PN" "U24"
					( Origin gPackager )
				)
				( objectStatus "U2D1.U24" )
			)
			( pin "@baseboard_fab2_lib.baseboard_fab2(sch_1):page74_i21:vss(989)"
				( attribute "PN" "U22"
					( Origin gPackager )
				)
				( objectStatus "U2D1.U22" )
			)
			( pin "@baseboard_fab2_lib.baseboard_fab2(sch_1):page74_i21:vss(990)"
				( attribute "PN" "U20"
					( Origin gPackager )
				)
				( objectStatus "U2D1.U20" )
			)
			( pin "@baseboard_fab2_lib.baseboard_fab2(sch_1):page74_i21:vss(991)"
				( attribute "PN" "U6"
					( Origin gPackager )
				)
				( objectStatus "U2D1.U6" )
			)
			( pin "@baseboard_fab2_lib.baseboard_fab2(sch_1):page74_i21:vss(992)"
				( attribute "PN" "U4"
					( Origin gPackager )
				)
				( objectStatus "U2D1.U4" )
			)
			( pin "@baseboard_fab2_lib.baseboard_fab2(sch_1):page74_i21:vss(993)"
				( attribute "PN" "U2"
					( Origin gPackager )
				)
				( objectStatus "U2D1.U2" )
			)
			( pin "@baseboard_fab2_lib.baseboard_fab2(sch_1):page74_i21:vss(994)"
				( attribute "PN" "T85"
					( Origin gPackager )
				)
				( objectStatus "U2D1.T85" )
			)
			( pin "@baseboard_fab2_lib.baseboard_fab2(sch_1):page74_i21:vss(995)"
				( attribute "PN" "T83"
					( Origin gPackager )
				)
				( objectStatus "U2D1.T83" )
			)
			( pin "@baseboard_fab2_lib.baseboard_fab2(sch_1):page74_i21:vss(996)"
				( attribute "PN" "T77"
					( Origin gPackager )
				)
				( objectStatus "U2D1.T77" )
			)
			( pin "@baseboard_fab2_lib.baseboard_fab2(sch_1):page74_i21:vss(997)"
				( attribute "PN" "T73"
					( Origin gPackager )
				)
				( objectStatus "U2D1.T73" )
			)
			( pin "@baseboard_fab2_lib.baseboard_fab2(sch_1):page74_i21:vss(998)"
				( attribute "PN" "T65"
					( Origin gPackager )
				)
				( objectStatus "U2D1.T65" )
			)
			( pin "@baseboard_fab2_lib.baseboard_fab2(sch_1):page74_i21:vss(999)"
				( attribute "PN" "T41"
					( Origin gPackager )
				)
				( objectStatus "U2D1.T41" )
			)
			( pin "@baseboard_fab2_lib.baseboard_fab2(sch_1):page74_i21:vss(1000)"
				( attribute "PN" "T37"
					( Origin gPackager )
				)
				( objectStatus "U2D1.T37" )
			)
			( pin "@baseboard_fab2_lib.baseboard_fab2(sch_1):page74_i21:vss(1001)"
				( attribute "PN" "T35"
					( Origin gPackager )
				)
				( objectStatus "U2D1.T35" )
			)
			( pin "@baseboard_fab2_lib.baseboard_fab2(sch_1):page74_i21:vss(1002)"
				( attribute "PN" "T31"
					( Origin gPackager )
				)
				( objectStatus "U2D1.T31" )
			)
			( pin "@baseboard_fab2_lib.baseboard_fab2(sch_1):page74_i21:vss(1003)"
				( attribute "PN" "T29"
					( Origin gPackager )
				)
				( objectStatus "U2D1.T29" )
			)
			( pin "@baseboard_fab2_lib.baseboard_fab2(sch_1):page74_i21:vss(1004)"
				( attribute "PN" "T25"
					( Origin gPackager )
				)
				( objectStatus "U2D1.T25" )
			)
			( pin "@baseboard_fab2_lib.baseboard_fab2(sch_1):page74_i21:vss(1005)"
				( attribute "PN" "T17"
					( Origin gPackager )
				)
				( objectStatus "U2D1.T17" )
			)
			( pin "@baseboard_fab2_lib.baseboard_fab2(sch_1):page74_i21:vss(1006)"
				( attribute "PN" "T13"
					( Origin gPackager )
				)
				( objectStatus "U2D1.T13" )
			)
			( pin "@baseboard_fab2_lib.baseboard_fab2(sch_1):page74_i21:vss(1007)"
				( attribute "PN" "R86"
					( Origin gPackager )
				)
				( objectStatus "U2D1.R86" )
			)
			( pin "@baseboard_fab2_lib.baseboard_fab2(sch_1):page74_i21:vss(1008)"
				( attribute "PN" "R78"
					( Origin gPackager )
				)
				( objectStatus "U2D1.R78" )
			)
			( pin "@baseboard_fab2_lib.baseboard_fab2(sch_1):page74_i21:vss(1009)"
				( attribute "PN" "R72"
					( Origin gPackager )
				)
				( objectStatus "U2D1.R72" )
			)
			( pin "@baseboard_fab2_lib.baseboard_fab2(sch_1):page74_i21:vss(1010)"
				( attribute "PN" "R68"
					( Origin gPackager )
				)
				( objectStatus "U2D1.R68" )
			)
			( pin "@baseboard_fab2_lib.baseboard_fab2(sch_1):page74_i21:vss(1011)"
				( attribute "PN" "R40"
					( Origin gPackager )
				)
				( objectStatus "U2D1.R40" )
			)
			( pin "@baseboard_fab2_lib.baseboard_fab2(sch_1):page74_i21:vss(1012)"
				( attribute "PN" "R38"
					( Origin gPackager )
				)
				( objectStatus "U2D1.R38" )
			)
			( pin "@baseboard_fab2_lib.baseboard_fab2(sch_1):page74_i21:vss(1013)"
				( attribute "PN" "R34"
					( Origin gPackager )
				)
				( objectStatus "U2D1.R34" )
			)
			( pin "@baseboard_fab2_lib.baseboard_fab2(sch_1):page74_i21:vss(1014)"
				( attribute "PN" "R32"
					( Origin gPackager )
				)
				( objectStatus "U2D1.R32" )
			)
			( pin "@baseboard_fab2_lib.baseboard_fab2(sch_1):page74_i21:vss(1015)"
				( attribute "PN" "R28"
					( Origin gPackager )
				)
				( objectStatus "U2D1.R28" )
			)
			( pin "@baseboard_fab2_lib.baseboard_fab2(sch_1):page74_i21:vss(1016)"
				( attribute "PN" "R26"
					( Origin gPackager )
				)
				( objectStatus "U2D1.R26" )
			)
			( pin "@baseboard_fab2_lib.baseboard_fab2(sch_1):page74_i21:vss(1017)"
				( attribute "PN" "R22"
					( Origin gPackager )
				)
				( objectStatus "U2D1.R22" )
			)
			( pin "@baseboard_fab2_lib.baseboard_fab2(sch_1):page74_i21:vss(1018)"
				( attribute "PN" "R4"
					( Origin gPackager )
				)
				( objectStatus "U2D1.R4" )
			)
			( pin "@baseboard_fab2_lib.baseboard_fab2(sch_1):page74_i21:vss(1019)"
				( attribute "PN" "R2"
					( Origin gPackager )
				)
				( objectStatus "U2D1.R2" )
			)
			( pin "@baseboard_fab2_lib.baseboard_fab2(sch_1):page74_i21:vss(1020)"
				( attribute "PN" "R18"
					( Origin gPackager )
				)
				( objectStatus "U2D1.R18" )
			)
			( pin "@baseboard_fab2_lib.baseboard_fab2(sch_1):page74_i21:vss(1021)"
				( attribute "PN" "R14"
					( Origin gPackager )
				)
				( objectStatus "U2D1.R14" )
			)
			( pin "@baseboard_fab2_lib.baseboard_fab2(sch_1):page74_i21:vss(1022)"
				( attribute "PN" "P83"
					( Origin gPackager )
				)
				( objectStatus "U2D1.P83" )
			)
			( pin "@baseboard_fab2_lib.baseboard_fab2(sch_1):page74_i21:vss(1023)"
				( attribute "PN" "P81"
					( Origin gPackager )
				)
				( objectStatus "U2D1.P81" )
			)
			( pin "@baseboard_fab2_lib.baseboard_fab2(sch_1):page74_i21:vss(1024)"
				( attribute "PN" "P71"
					( Origin gPackager )
				)
				( objectStatus "U2D1.P71" )
			)
			( pin "@baseboard_fab2_lib.baseboard_fab2(sch_1):page74_i21:vss(1025)"
				( attribute "PN" "P69"
					( Origin gPackager )
				)
				( objectStatus "U2D1.P69" )
			)
			( pin "@baseboard_fab2_lib.baseboard_fab2(sch_1):page74_i21:vss(1026)"
				( attribute "PN" "P67"
					( Origin gPackager )
				)
				( objectStatus "U2D1.P67" )
			)
			( pin "@baseboard_fab2_lib.baseboard_fab2(sch_1):page74_i21:vss(1027)"
				( attribute "PN" "P39"
					( Origin gPackager )
				)
				( objectStatus "U2D1.P39" )
			)
			( pin "@baseboard_fab2_lib.baseboard_fab2(sch_1):page74_i21:vss(1028)"
				( attribute "PN" "P33"
					( Origin gPackager )
				)
				( objectStatus "U2D1.P33" )
			)
			( pin "@baseboard_fab2_lib.baseboard_fab2(sch_1):page74_i21:vss(1029)"
				( attribute "PN" "P27"
					( Origin gPackager )
				)
				( objectStatus "U2D1.P27" )
			)
			( pin "@baseboard_fab2_lib.baseboard_fab2(sch_1):page74_i21:vss(1030)"
				( attribute "PN" "P15"
					( Origin gPackager )
				)
				( objectStatus "U2D1.P15" )
			)
			( pin "@baseboard_fab2_lib.baseboard_fab2(sch_1):page74_i21:vss(1031)"
				( attribute "PN" "P11"
					( Origin gPackager )
				)
				( objectStatus "U2D1.P11" )
			)
			( pin "@baseboard_fab2_lib.baseboard_fab2(sch_1):page74_i21:vss(1032)"
				( attribute "PN" "N8"
					( Origin gPackager )
				)
				( objectStatus "U2D1.N8" )
			)
			( pin "@baseboard_fab2_lib.baseboard_fab2(sch_1):page74_i21:vss(1033)"
				( attribute "PN" "N4"
					( Origin gPackager )
				)
				( objectStatus "U2D1.N4" )
			)
			( pin "@baseboard_fab2_lib.baseboard_fab2(sch_1):page74_i21:vss(1034)"
				( attribute "PN" "N78"
					( Origin gPackager )
				)
				( objectStatus "U2D1.N78" )
			)
			( pin "@baseboard_fab2_lib.baseboard_fab2(sch_1):page74_i21:vss(1035)"
				( attribute "PN" "N76"
					( Origin gPackager )
				)
				( objectStatus "U2D1.N76" )
			)
			( pin "@baseboard_fab2_lib.baseboard_fab2(sch_1):page74_i21:vss(1036)"
				( attribute "PN" "N74"
					( Origin gPackager )
				)
				( objectStatus "U2D1.N74" )
			)
			( pin "@baseboard_fab2_lib.baseboard_fab2(sch_1):page74_i21:vss(1037)"
				( attribute "PN" "N72"
					( Origin gPackager )
				)
				( objectStatus "U2D1.N72" )
			)
			( pin "@baseboard_fab2_lib.baseboard_fab2(sch_1):page74_i21:vss(1038)"
				( attribute "PN" "N70"
					( Origin gPackager )
				)
				( objectStatus "U2D1.N70" )
			)
			( pin "@baseboard_fab2_lib.baseboard_fab2(sch_1):page74_i21:vss(1039)"
				( attribute "PN" "N66"
					( Origin gPackager )
				)
				( objectStatus "U2D1.N66" )
			)
			( pin "@baseboard_fab2_lib.baseboard_fab2(sch_1):page74_i21:vss(1040)"
				( attribute "PN" "N6"
					( Origin gPackager )
				)
				( objectStatus "U2D1.N6" )
			)
			( pin "@baseboard_fab2_lib.baseboard_fab2(sch_1):page74_i21:vss(1041)"
				( attribute "PN" "N22"
					( Origin gPackager )
				)
				( objectStatus "U2D1.N22" )
			)
			( pin "@baseboard_fab2_lib.baseboard_fab2(sch_1):page74_i21:vss(1042)"
				( attribute "PN" "N20"
					( Origin gPackager )
				)
				( objectStatus "U2D1.N20" )
			)
			( pin "@baseboard_fab2_lib.baseboard_fab2(sch_1):page74_i21:vss(1043)"
				( attribute "PN" "DM19"
					( Origin gPackager )
				)
				( objectStatus "U2D1.DM19" )
			)
			( pin "@baseboard_fab2_lib.baseboard_fab2(sch_1):page74_i21:vss(1044)"
				( attribute "PN" "M85"
					( Origin gPackager )
				)
				( objectStatus "U2D1.M85" )
			)
			( pin "@baseboard_fab2_lib.baseboard_fab2(sch_1):page74_i21:vss(1045)"
				( attribute "PN" "M83"
					( Origin gPackager )
				)
				( objectStatus "U2D1.M83" )
			)
			( pin "@baseboard_fab2_lib.baseboard_fab2(sch_1):page74_i21:vss(1046)"
				( attribute "PN" "M79"
					( Origin gPackager )
				)
				( objectStatus "U2D1.M79" )
			)
			( pin "@baseboard_fab2_lib.baseboard_fab2(sch_1):page74_i21:vss(1047)"
				( attribute "PN" "M71"
					( Origin gPackager )
				)
				( objectStatus "U2D1.M71" )
			)
			( pin "@baseboard_fab2_lib.baseboard_fab2(sch_1):page74_i21:vss(1048)"
				( attribute "PN" "M65"
					( Origin gPackager )
				)
				( objectStatus "U2D1.M65" )
			)
			( pin "@baseboard_fab2_lib.baseboard_fab2(sch_1):page74_i21:vss(1049)"
				( attribute "PN" "M43"
					( Origin gPackager )
				)
				( objectStatus "U2D1.M43" )
			)
			( pin "@baseboard_fab2_lib.baseboard_fab2(sch_1):page74_i21:vss(1050)"
				( attribute "PN" "M41"
					( Origin gPackager )
				)
				( objectStatus "U2D1.M41" )
			)
			( pin "@baseboard_fab2_lib.baseboard_fab2(sch_1):page74_i21:vss(1051)"
				( attribute "PN" "M39"
					( Origin gPackager )
				)
				( objectStatus "U2D1.M39" )
			)
			( pin "@baseboard_fab2_lib.baseboard_fab2(sch_1):page74_i21:vss(1052)"
				( attribute "PN" "M37"
					( Origin gPackager )
				)
				( objectStatus "U2D1.M37" )
			)
			( pin "@baseboard_fab2_lib.baseboard_fab2(sch_1):page74_i21:vss(1053)"
				( attribute "PN" "M35"
					( Origin gPackager )
				)
				( objectStatus "U2D1.M35" )
			)
			( pin "@baseboard_fab2_lib.baseboard_fab2(sch_1):page74_i21:vss(1054)"
				( attribute "PN" "M33"
					( Origin gPackager )
				)
				( objectStatus "U2D1.M33" )
			)
			( pin "@baseboard_fab2_lib.baseboard_fab2(sch_1):page74_i21:vss(1055)"
				( attribute "PN" "M31"
					( Origin gPackager )
				)
				( objectStatus "U2D1.M31" )
			)
			( pin "@baseboard_fab2_lib.baseboard_fab2(sch_1):page74_i21:vss(1056)"
				( attribute "PN" "M29"
					( Origin gPackager )
				)
				( objectStatus "U2D1.M29" )
			)
			( pin "@baseboard_fab2_lib.baseboard_fab2(sch_1):page74_i21:vss(1057)"
				( attribute "PN" "M27"
					( Origin gPackager )
				)
				( objectStatus "U2D1.M27" )
			)
			( pin "@baseboard_fab2_lib.baseboard_fab2(sch_1):page74_i21:vss(1058)"
				( attribute "PN" "M25"
					( Origin gPackager )
				)
				( objectStatus "U2D1.M25" )
			)
			( pin "@baseboard_fab2_lib.baseboard_fab2(sch_1):page74_i21:vss(1059)"
				( attribute "PN" "M23"
					( Origin gPackager )
				)
				( objectStatus "U2D1.M23" )
			)
			( pin "@baseboard_fab2_lib.baseboard_fab2(sch_1):page74_i21:vss(1060)"
				( attribute "PN" "M19"
					( Origin gPackager )
				)
				( objectStatus "U2D1.M19" )
			)
			( pin "@baseboard_fab2_lib.baseboard_fab2(sch_1):page74_i21:vss(1061)"
				( attribute "PN" "M17"
					( Origin gPackager )
				)
				( objectStatus "U2D1.M17" )
			)
			( pin "@baseboard_fab2_lib.baseboard_fab2(sch_1):page74_i21:vss(1062)"
				( attribute "PN" "M15"
					( Origin gPackager )
				)
				( objectStatus "U2D1.M15" )
			)
			( pin "@baseboard_fab2_lib.baseboard_fab2(sch_1):page74_i21:vss(1063)"
				( attribute "PN" "CT7"
					( Origin gPackager )
				)
				( objectStatus "U2D1.CT7" )
			)
			( pin "@baseboard_fab2_lib.baseboard_fab2(sch_1):page74_i21:vss(1064)"
				( attribute "PN" "BT9"
					( Origin gPackager )
				)
				( objectStatus "U2D1.BT9" )
			)
			( pin "@baseboard_fab2_lib.baseboard_fab2(sch_1):page74_i21:vss(1065)"
				( attribute "PN" "L82"
					( Origin gPackager )
				)
				( objectStatus "U2D1.L82" )
			)
			( pin "@baseboard_fab2_lib.baseboard_fab2(sch_1):page74_i21:vss(1066)"
				( attribute "PN" "L80"
					( Origin gPackager )
				)
				( objectStatus "U2D1.L80" )
			)
			( pin "@baseboard_fab2_lib.baseboard_fab2(sch_1):page74_i21:vss(1067)"
				( attribute "PN" "L78"
					( Origin gPackager )
				)
				( objectStatus "U2D1.L78" )
			)
			( pin "@baseboard_fab2_lib.baseboard_fab2(sch_1):page74_i21:vss(1068)"
				( attribute "PN" "L72"
					( Origin gPackager )
				)
				( objectStatus "U2D1.L72" )
			)
			( pin "@baseboard_fab2_lib.baseboard_fab2(sch_1):page74_i21:vss(1069)"
				( attribute "PN" "L22"
					( Origin gPackager )
				)
				( objectStatus "U2D1.L22" )
			)
			( pin "@baseboard_fab2_lib.baseboard_fab2(sch_1):page74_i21:vss(1070)"
				( attribute "PN" "L20"
					( Origin gPackager )
				)
				( objectStatus "U2D1.L20" )
			)
			( pin "@baseboard_fab2_lib.baseboard_fab2(sch_1):page74_i21:vss(1071)"
				( attribute "PN" "L6"
					( Origin gPackager )
				)
				( objectStatus "U2D1.L6" )
			)
			( pin "@baseboard_fab2_lib.baseboard_fab2(sch_1):page74_i21:vss(1072)"
				( attribute "PN" "L2"
					( Origin gPackager )
				)
				( objectStatus "U2D1.L2" )
			)
			( pin "@baseboard_fab2_lib.baseboard_fab2(sch_1):page74_i21:vss(1073)"
				( attribute "PN" "L10"
					( Origin gPackager )
				)
				( objectStatus "U2D1.L10" )
			)
			( pin "@baseboard_fab2_lib.baseboard_fab2(sch_1):page74_i21:vss(1074)"
				( attribute "PN" "K85"
					( Origin gPackager )
				)
				( objectStatus "U2D1.K85" )
			)
			( pin "@baseboard_fab2_lib.baseboard_fab2(sch_1):page74_i21:vss(1075)"
				( attribute "PN" "K83"
					( Origin gPackager )
				)
				( objectStatus "U2D1.K83" )
			)
			( pin "@baseboard_fab2_lib.baseboard_fab2(sch_1):page74_i21:vss(1076)"
				( attribute "PN" "K81"
					( Origin gPackager )
				)
				( objectStatus "U2D1.K81" )
			)
			( pin "@baseboard_fab2_lib.baseboard_fab2(sch_1):page74_i21:vss(1077)"
				( attribute "PN" "K77"
					( Origin gPackager )
				)
				( objectStatus "U2D1.K77" )
			)
			( pin "@baseboard_fab2_lib.baseboard_fab2(sch_1):page74_i21:vss(1078)"
				( attribute "PN" "K73"
					( Origin gPackager )
				)
				( objectStatus "U2D1.K73" )
			)
			( pin "@baseboard_fab2_lib.baseboard_fab2(sch_1):page74_i21:vss(1079)"
				( attribute "PN" "K71"
					( Origin gPackager )
				)
				( objectStatus "U2D1.K71" )
			)
			( pin "@baseboard_fab2_lib.baseboard_fab2(sch_1):page74_i21:vss(1080)"
				( attribute "PN" "K69"
					( Origin gPackager )
				)
				( objectStatus "U2D1.K69" )
			)
			( pin "@baseboard_fab2_lib.baseboard_fab2(sch_1):page74_i21:vss(1081)"
				( attribute "PN" "K67"
					( Origin gPackager )
				)
				( objectStatus "U2D1.K67" )
			)
			( pin "@baseboard_fab2_lib.baseboard_fab2(sch_1):page74_i21:vss(1082)"
				( attribute "PN" "K65"
					( Origin gPackager )
				)
				( objectStatus "U2D1.K65" )
			)
			( pin "@baseboard_fab2_lib.baseboard_fab2(sch_1):page74_i21:vss(1083)"
				( attribute "PN" "K39"
					( Origin gPackager )
				)
				( objectStatus "U2D1.K39" )
			)
			( pin "@baseboard_fab2_lib.baseboard_fab2(sch_1):page74_i21:vss(1084)"
				( attribute "PN" "K33"
					( Origin gPackager )
				)
				( objectStatus "U2D1.K33" )
			)
			( pin "@baseboard_fab2_lib.baseboard_fab2(sch_1):page74_i21:vss(1085)"
				( attribute "PN" "K27"
					( Origin gPackager )
				)
				( objectStatus "U2D1.K27" )
			)
			( pin "@baseboard_fab2_lib.baseboard_fab2(sch_1):page74_i21:vss(1086)"
				( attribute "PN" "DB7"
					( Origin gPackager )
				)
				( objectStatus "U2D1.DB7" )
			)
			( pin "@baseboard_fab2_lib.baseboard_fab2(sch_1):page74_i21:vss(1087)"
				( attribute "PN" "K17"
					( Origin gPackager )
				)
				( objectStatus "U2D1.K17" )
			)
			( pin "@baseboard_fab2_lib.baseboard_fab2(sch_1):page74_i21:vss(1088)"
				( attribute "PN" "K13"
					( Origin gPackager )
				)
				( objectStatus "U2D1.K13" )
			)
			( pin "@baseboard_fab2_lib.baseboard_fab2(sch_1):page74_i21:vss(1089)"
				( attribute "PN" "K11"
					( Origin gPackager )
				)
				( objectStatus "U2D1.K11" )
			)
			( pin "@baseboard_fab2_lib.baseboard_fab2(sch_1):page74_i21:vss(1090)"
				( attribute "PN" "K1"
					( Origin gPackager )
				)
				( objectStatus "U2D1.K1" )
			)
			( pin "@baseboard_fab2_lib.baseboard_fab2(sch_1):page74_i21:vss(1091)"
				( attribute "PN" "J84"
					( Origin gPackager )
				)
				( objectStatus "U2D1.J84" )
			)
			( pin "@baseboard_fab2_lib.baseboard_fab2(sch_1):page74_i21:vss(1092)"
				( attribute "PN" "J82"
					( Origin gPackager )
				)
				( objectStatus "U2D1.J82" )
			)
			( pin "@baseboard_fab2_lib.baseboard_fab2(sch_1):page74_i21:vss(1093)"
				( attribute "PN" "J76"
					( Origin gPackager )
				)
				( objectStatus "U2D1.J76" )
			)
			( pin "@baseboard_fab2_lib.baseboard_fab2(sch_1):page74_i22:vss(774)"
				( attribute "PN" "AL68"
					( Origin gPackager )
				)
				( objectStatus "U2D1.AL68" )
			)
			( pin "@baseboard_fab2_lib.baseboard_fab2(sch_1):page74_i22:vss(775)"
				( attribute "PN" "AL64"
					( Origin gPackager )
				)
				( objectStatus "U2D1.AL64" )
			)
			( pin "@baseboard_fab2_lib.baseboard_fab2(sch_1):page74_i22:vss(776)"
				( attribute "PN" "AL56"
					( Origin gPackager )
				)
				( objectStatus "U2D1.AL56" )
			)
			( pin "@baseboard_fab2_lib.baseboard_fab2(sch_1):page74_i22:vss(777)"
				( attribute "PN" "AL32"
					( Origin gPackager )
				)
				( objectStatus "U2D1.AL32" )
			)
			( pin "@baseboard_fab2_lib.baseboard_fab2(sch_1):page74_i22:vss(778)"
				( attribute "PN" "AL30"
					( Origin gPackager )
				)
				( objectStatus "U2D1.AL30" )
			)
			( pin "@baseboard_fab2_lib.baseboard_fab2(sch_1):page74_i22:vss(779)"
				( attribute "PN" "AL24"
					( Origin gPackager )
				)
				( objectStatus "U2D1.AL24" )
			)
			( pin "@baseboard_fab2_lib.baseboard_fab2(sch_1):page74_i22:vss(780)"
				( attribute "PN" "AL10"
					( Origin gPackager )
				)
				( objectStatus "U2D1.AL10" )
			)
			( pin "@baseboard_fab2_lib.baseboard_fab2(sch_1):page74_i22:vss(781)"
				( attribute "PN" "AL4"
					( Origin gPackager )
				)
				( objectStatus "U2D1.AL4" )
			)
			( pin "@baseboard_fab2_lib.baseboard_fab2(sch_1):page74_i22:vss(782)"
				( attribute "PN" "AK85"
					( Origin gPackager )
				)
				( objectStatus "U2D1.AK85" )
			)
			( pin "@baseboard_fab2_lib.baseboard_fab2(sch_1):page74_i22:vss(783)"
				( attribute "PN" "AK83"
					( Origin gPackager )
				)
				( objectStatus "U2D1.AK83" )
			)
			( pin "@baseboard_fab2_lib.baseboard_fab2(sch_1):page74_i22:vss(784)"
				( attribute "PN" "AK81"
					( Origin gPackager )
				)
				( objectStatus "U2D1.AK81" )
			)
			( pin "@baseboard_fab2_lib.baseboard_fab2(sch_1):page74_i22:vss(785)"
				( attribute "PN" "AK79"
					( Origin gPackager )
				)
				( objectStatus "U2D1.AK79" )
			)
			( pin "@baseboard_fab2_lib.baseboard_fab2(sch_1):page74_i22:vss(786)"
				( attribute "PN" "AK73"
					( Origin gPackager )
				)
				( objectStatus "U2D1.AK73" )
			)
			( pin "@baseboard_fab2_lib.baseboard_fab2(sch_1):page74_i22:vss(787)"
				( attribute "PN" "AK67"
					( Origin gPackager )
				)
				( objectStatus "U2D1.AK67" )
			)
			( pin "@baseboard_fab2_lib.baseboard_fab2(sch_1):page74_i22:vss(788)"
				( attribute "PN" "AK65"
					( Origin gPackager )
				)
				( objectStatus "U2D1.AK65" )
			)
			( pin "@baseboard_fab2_lib.baseboard_fab2(sch_1):page74_i22:vss(789)"
				( attribute "PN" "AK55"
					( Origin gPackager )
				)
				( objectStatus "U2D1.AK55" )
			)
			( pin "@baseboard_fab2_lib.baseboard_fab2(sch_1):page74_i22:vss(790)"
				( attribute "PN" "AK33"
					( Origin gPackager )
				)
				( objectStatus "U2D1.AK33" )
			)
			( pin "@baseboard_fab2_lib.baseboard_fab2(sch_1):page74_i22:vss(791)"
				( attribute "PN" "AK31"
					( Origin gPackager )
				)
				( objectStatus "U2D1.AK31" )
			)
			( pin "@baseboard_fab2_lib.baseboard_fab2(sch_1):page74_i22:vss(792)"
				( attribute "PN" "AK29"
					( Origin gPackager )
				)
				( objectStatus "U2D1.AK29" )
			)
			( pin "@baseboard_fab2_lib.baseboard_fab2(sch_1):page74_i22:vss(793)"
				( attribute "PN" "AK25"
					( Origin gPackager )
				)
				( objectStatus "U2D1.AK25" )
			)
			( pin "@baseboard_fab2_lib.baseboard_fab2(sch_1):page74_i22:vss(794)"
				( attribute "PN" "AK23"
					( Origin gPackager )
				)
				( objectStatus "U2D1.AK23" )
			)
			( pin "@baseboard_fab2_lib.baseboard_fab2(sch_1):page74_i22:vss(795)"
				( attribute "PN" "AK19"
					( Origin gPackager )
				)
				( objectStatus "U2D1.AK19" )
			)
			( pin "@baseboard_fab2_lib.baseboard_fab2(sch_1):page74_i22:vss(796)"
				( attribute "PN" "AK13"
					( Origin gPackager )
				)
				( objectStatus "U2D1.AK13" )
			)
			( pin "@baseboard_fab2_lib.baseboard_fab2(sch_1):page74_i22:vss(797)"
				( attribute "PN" "AK9"
					( Origin gPackager )
				)
				( objectStatus "U2D1.AK9" )
			)
			( pin "@baseboard_fab2_lib.baseboard_fab2(sch_1):page74_i22:vss(798)"
				( attribute "PN" "AJ86"
					( Origin gPackager )
				)
				( objectStatus "U2D1.AJ86" )
			)
			( pin "@baseboard_fab2_lib.baseboard_fab2(sch_1):page74_i22:vss(799)"
				( attribute "PN" "AJ82"
					( Origin gPackager )
				)
				( objectStatus "U2D1.AJ82" )
			)
			( pin "@baseboard_fab2_lib.baseboard_fab2(sch_1):page74_i22:vss(800)"
				( attribute "PN" "AJ78"
					( Origin gPackager )
				)
				( objectStatus "U2D1.AJ78" )
			)
			( pin "@baseboard_fab2_lib.baseboard_fab2(sch_1):page74_i22:vss(801)"
				( attribute "PN" "AJ74"
					( Origin gPackager )
				)
				( objectStatus "U2D1.AJ74" )
			)
			( pin "@baseboard_fab2_lib.baseboard_fab2(sch_1):page74_i22:vss(802)"
				( attribute "PN" "AJ68"
					( Origin gPackager )
				)
				( objectStatus "U2D1.AJ68" )
			)
			( pin "@baseboard_fab2_lib.baseboard_fab2(sch_1):page74_i22:vss(803)"
				( attribute "PN" "AJ66"
					( Origin gPackager )
				)
				( objectStatus "U2D1.AJ66" )
			)
			( pin "@baseboard_fab2_lib.baseboard_fab2(sch_1):page74_i22:vss(804)"
				( attribute "PN" "AJ54"
					( Origin gPackager )
				)
				( objectStatus "U2D1.AJ54" )
			)
			( pin "@baseboard_fab2_lib.baseboard_fab2(sch_1):page74_i22:vss(805)"
				( attribute "PN" "AJ52"
					( Origin gPackager )
				)
				( objectStatus "U2D1.AJ52" )
			)
			( pin "@baseboard_fab2_lib.baseboard_fab2(sch_1):page74_i22:vss(806)"
				( attribute "PN" "AJ50"
					( Origin gPackager )
				)
				( objectStatus "U2D1.AJ50" )
			)
			( pin "@baseboard_fab2_lib.baseboard_fab2(sch_1):page74_i22:vss(807)"
				( attribute "PN" "AJ48"
					( Origin gPackager )
				)
				( objectStatus "U2D1.AJ48" )
			)
			( pin "@baseboard_fab2_lib.baseboard_fab2(sch_1):page74_i22:vss(808)"
				( attribute "PN" "AJ46"
					( Origin gPackager )
				)
				( objectStatus "U2D1.AJ46" )
			)
			( pin "@baseboard_fab2_lib.baseboard_fab2(sch_1):page74_i22:vss(809)"
				( attribute "PN" "AJ34"
					( Origin gPackager )
				)
				( objectStatus "U2D1.AJ34" )
			)
			( pin "@baseboard_fab2_lib.baseboard_fab2(sch_1):page74_i22:vss(810)"
				( attribute "PN" "AJ32"
					( Origin gPackager )
				)
				( objectStatus "U2D1.AJ32" )
			)
			( pin "@baseboard_fab2_lib.baseboard_fab2(sch_1):page74_i22:vss(811)"
				( attribute "PN" "AJ28"
					( Origin gPackager )
				)
				( objectStatus "U2D1.AJ28" )
			)
			( pin "@baseboard_fab2_lib.baseboard_fab2(sch_1):page74_i22:vss(812)"
				( attribute "PN" "AJ26"
					( Origin gPackager )
				)
				( objectStatus "U2D1.AJ26" )
			)
			( pin "@baseboard_fab2_lib.baseboard_fab2(sch_1):page74_i22:vss(813)"
				( attribute "PN" "AJ22"
					( Origin gPackager )
				)
				( objectStatus "U2D1.AJ22" )
			)
			( pin "@baseboard_fab2_lib.baseboard_fab2(sch_1):page74_i22:vss(814)"
				( attribute "PN" "AJ8"
					( Origin gPackager )
				)
				( objectStatus "U2D1.AJ8" )
			)
			( pin "@baseboard_fab2_lib.baseboard_fab2(sch_1):page74_i22:vss(815)"
				( attribute "PN" "AH83"
					( Origin gPackager )
				)
				( objectStatus "U2D1.AH83" )
			)
			( pin "@baseboard_fab2_lib.baseboard_fab2(sch_1):page74_i22:vss(816)"
				( attribute "PN" "AH77"
					( Origin gPackager )
				)
				( objectStatus "U2D1.AH77" )
			)
			( pin "@baseboard_fab2_lib.baseboard_fab2(sch_1):page74_i22:vss(817)"
				( attribute "PN" "AH75"
					( Origin gPackager )
				)
				( objectStatus "U2D1.AH75" )
			)
			( pin "@baseboard_fab2_lib.baseboard_fab2(sch_1):page74_i22:vss(818)"
				( attribute "PN" "AH69"
					( Origin gPackager )
				)
				( objectStatus "U2D1.AH69" )
			)
			( pin "@baseboard_fab2_lib.baseboard_fab2(sch_1):page74_i22:vss(819)"
				( attribute "PN" "AH65"
					( Origin gPackager )
				)
				( objectStatus "U2D1.AH65" )
			)
			( pin "@baseboard_fab2_lib.baseboard_fab2(sch_1):page74_i22:vss(820)"
				( attribute "PN" "AH61"
					( Origin gPackager )
				)
				( objectStatus "U2D1.AH61" )
			)
			( pin "@baseboard_fab2_lib.baseboard_fab2(sch_1):page74_i22:vss(821)"
				( attribute "PN" "AH59"
					( Origin gPackager )
				)
				( objectStatus "U2D1.AH59" )
			)
			( pin "@baseboard_fab2_lib.baseboard_fab2(sch_1):page74_i22:vss(822)"
				( attribute "PN" "AH53"
					( Origin gPackager )
				)
				( objectStatus "U2D1.AH53" )
			)
			( pin "@baseboard_fab2_lib.baseboard_fab2(sch_1):page74_i22:vss(823)"
				( attribute "PN" "AH51"
					( Origin gPackager )
				)
				( objectStatus "U2D1.AH51" )
			)
			( pin "@baseboard_fab2_lib.baseboard_fab2(sch_1):page74_i22:vss(824)"
				( attribute "PN" "AH49"
					( Origin gPackager )
				)
				( objectStatus "U2D1.AH49" )
			)
			( pin "@baseboard_fab2_lib.baseboard_fab2(sch_1):page74_i22:vss(825)"
				( attribute "PN" "AH47"
					( Origin gPackager )
				)
				( objectStatus "U2D1.AH47" )
			)
			( pin "@baseboard_fab2_lib.baseboard_fab2(sch_1):page74_i22:vss(826)"
				( attribute "PN" "AH45"
					( Origin gPackager )
				)
				( objectStatus "U2D1.AH45" )
			)
			( pin "@baseboard_fab2_lib.baseboard_fab2(sch_1):page74_i22:vss(827)"
				( attribute "PN" "AH35"
					( Origin gPackager )
				)
				( objectStatus "U2D1.AH35" )
			)
			( pin "@baseboard_fab2_lib.baseboard_fab2(sch_1):page74_i22:vss(828)"
				( attribute "PN" "AH33"
					( Origin gPackager )
				)
				( objectStatus "U2D1.AH33" )
			)
			( pin "@baseboard_fab2_lib.baseboard_fab2(sch_1):page74_i22:vss(829)"
				( attribute "PN" "AH27"
					( Origin gPackager )
				)
				( objectStatus "U2D1.AH27" )
			)
			( pin "@baseboard_fab2_lib.baseboard_fab2(sch_1):page74_i22:vss(830)"
				( attribute "PN" "AH21"
					( Origin gPackager )
				)
				( objectStatus "U2D1.AH21" )
			)
			( pin "@baseboard_fab2_lib.baseboard_fab2(sch_1):page74_i22:vss(831)"
				( attribute "PN" "AH5"
					( Origin gPackager )
				)
				( objectStatus "U2D1.AH5" )
			)
			( pin "@baseboard_fab2_lib.baseboard_fab2(sch_1):page74_i22:vss(832)"
				( attribute "PN" "AH1"
					( Origin gPackager )
				)
				( objectStatus "U2D1.AH1" )
			)
			( pin "@baseboard_fab2_lib.baseboard_fab2(sch_1):page74_i22:vss(833)"
				( attribute "PN" "AG80"
					( Origin gPackager )
				)
				( objectStatus "U2D1.AG80" )
			)
			( pin "@baseboard_fab2_lib.baseboard_fab2(sch_1):page74_i22:vss(834)"
				( attribute "PN" "AG78"
					( Origin gPackager )
				)
				( objectStatus "U2D1.AG78" )
			)
			( pin "@baseboard_fab2_lib.baseboard_fab2(sch_1):page74_i22:vss(835)"
				( attribute "PN" "AG76"
					( Origin gPackager )
				)
				( objectStatus "U2D1.AG76" )
			)
			( pin "@baseboard_fab2_lib.baseboard_fab2(sch_1):page74_i22:vss(836)"
				( attribute "PN" "AG74"
					( Origin gPackager )
				)
				( objectStatus "U2D1.AG74" )
			)
			( pin "@baseboard_fab2_lib.baseboard_fab2(sch_1):page74_i22:vss(837)"
				( attribute "PN" "AG70"
					( Origin gPackager )
				)
				( objectStatus "U2D1.AG70" )
			)
			( pin "@baseboard_fab2_lib.baseboard_fab2(sch_1):page74_i22:vss(838)"
				( attribute "PN" "AG64"
					( Origin gPackager )
				)
				( objectStatus "U2D1.AG64" )
			)
			( pin "@baseboard_fab2_lib.baseboard_fab2(sch_1):page74_i22:vss(839)"
				( attribute "PN" "AG36"
					( Origin gPackager )
				)
				( objectStatus "U2D1.AG36" )
			)
			( pin "@baseboard_fab2_lib.baseboard_fab2(sch_1):page74_i22:vss(840)"
				( attribute "PN" "AG18"
					( Origin gPackager )
				)
				( objectStatus "U2D1.AG18" )
			)
			( pin "@baseboard_fab2_lib.baseboard_fab2(sch_1):page74_i22:vss(841)"
				( attribute "PN" "AG14"
					( Origin gPackager )
				)
				( objectStatus "U2D1.AG14" )
			)
			( pin "@baseboard_fab2_lib.baseboard_fab2(sch_1):page74_i22:vss(842)"
				( attribute "PN" "AG12"
					( Origin gPackager )
				)
				( objectStatus "U2D1.AG12" )
			)
			( pin "@baseboard_fab2_lib.baseboard_fab2(sch_1):page74_i22:vss(843)"
				( attribute "PN" "AF85"
					( Origin gPackager )
				)
				( objectStatus "U2D1.AF85" )
			)
			( pin "@baseboard_fab2_lib.baseboard_fab2(sch_1):page74_i22:vss(844)"
				( attribute "PN" "AF83"
					( Origin gPackager )
				)
				( objectStatus "U2D1.AF83" )
			)
			( pin "@baseboard_fab2_lib.baseboard_fab2(sch_1):page74_i22:vss(845)"
				( attribute "PN" "AF77"
					( Origin gPackager )
				)
				( objectStatus "U2D1.AF77" )
			)
			( pin "@baseboard_fab2_lib.baseboard_fab2(sch_1):page74_i22:vss(846)"
				( attribute "PN" "AF73"
					( Origin gPackager )
				)
				( objectStatus "U2D1.AF73" )
			)
			( pin "@baseboard_fab2_lib.baseboard_fab2(sch_1):page74_i22:vss(847)"
				( attribute "PN" "AF41"
					( Origin gPackager )
				)
				( objectStatus "U2D1.AF41" )
			)
			( pin "@baseboard_fab2_lib.baseboard_fab2(sch_1):page74_i22:vss(848)"
				( attribute "PN" "AF39"
					( Origin gPackager )
				)
				( objectStatus "U2D1.AF39" )
			)
			( pin "@baseboard_fab2_lib.baseboard_fab2(sch_1):page74_i22:vss(849)"
				( attribute "PN" "AF37"
					( Origin gPackager )
				)
				( objectStatus "U2D1.AF37" )
			)
			( pin "@baseboard_fab2_lib.baseboard_fab2(sch_1):page74_i22:vss(850)"
				( attribute "PN" "AF33"
					( Origin gPackager )
				)
				( objectStatus "U2D1.AF33" )
			)
			( pin "@baseboard_fab2_lib.baseboard_fab2(sch_1):page74_i22:vss(851)"
				( attribute "PN" "AF31"
					( Origin gPackager )
				)
				( objectStatus "U2D1.AF31" )
			)
			( pin "@baseboard_fab2_lib.baseboard_fab2(sch_1):page74_i22:vss(852)"
				( attribute "PN" "AF29"
					( Origin gPackager )
				)
				( objectStatus "U2D1.AF29" )
			)
			( pin "@baseboard_fab2_lib.baseboard_fab2(sch_1):page74_i22:vss(853)"
				( attribute "PN" "AF27"
					( Origin gPackager )
				)
				( objectStatus "U2D1.AF27" )
			)
			( pin "@baseboard_fab2_lib.baseboard_fab2(sch_1):page74_i22:vss(854)"
				( attribute "PN" "AF25"
					( Origin gPackager )
				)
				( objectStatus "U2D1.AF25" )
			)
			( pin "@baseboard_fab2_lib.baseboard_fab2(sch_1):page74_i22:vss(855)"
				( attribute "PN" "AF23"
					( Origin gPackager )
				)
				( objectStatus "U2D1.AF23" )
			)
			( pin "@baseboard_fab2_lib.baseboard_fab2(sch_1):page74_i22:vss(856)"
				( attribute "PN" "AF21"
					( Origin gPackager )
				)
				( objectStatus "U2D1.AF21" )
			)
			( pin "@baseboard_fab2_lib.baseboard_fab2(sch_1):page74_i22:vss(857)"
				( attribute "PN" "AF9"
					( Origin gPackager )
				)
				( objectStatus "U2D1.AF9" )
			)
			( pin "@baseboard_fab2_lib.baseboard_fab2(sch_1):page74_i22:vss(858)"
				( attribute "PN" "AC52"
					( Origin gPackager )
				)
				( objectStatus "U2D1.AC52" )
			)
			( pin "@baseboard_fab2_lib.baseboard_fab2(sch_1):page74_i22:vss(859)"
				( attribute "PN" "AF1"
					( Origin gPackager )
				)
				( objectStatus "U2D1.AF1" )
			)
			( pin "@baseboard_fab2_lib.baseboard_fab2(sch_1):page74_i22:vss(860)"
				( attribute "PN" "AE78"
					( Origin gPackager )
				)
				( objectStatus "U2D1.AE78" )
			)
			( pin "@baseboard_fab2_lib.baseboard_fab2(sch_1):page74_i22:vss(861)"
				( attribute "PN" "AE70"
					( Origin gPackager )
				)
				( objectStatus "U2D1.AE70" )
			)
			( pin "@baseboard_fab2_lib.baseboard_fab2(sch_1):page74_i22:vss(862)"
				( attribute "PN" "AE68"
					( Origin gPackager )
				)
				( objectStatus "U2D1.AE68" )
			)
			( pin "@baseboard_fab2_lib.baseboard_fab2(sch_1):page74_i22:vss(863)"
				( attribute "PN" "AE66"
					( Origin gPackager )
				)
				( objectStatus "U2D1.AE66" )
			)
			( pin "@baseboard_fab2_lib.baseboard_fab2(sch_1):page74_i22:vss(864)"
				( attribute "PN" "AE64"
					( Origin gPackager )
				)
				( objectStatus "U2D1.AE64" )
			)
			( pin "@baseboard_fab2_lib.baseboard_fab2(sch_1):page74_i22:vss(865)"
				( attribute "PN" "AE42"
					( Origin gPackager )
				)
				( objectStatus "U2D1.AE42" )
			)
			( pin "@baseboard_fab2_lib.baseboard_fab2(sch_1):page74_i22:vss(866)"
				( attribute "PN" "AE40"
					( Origin gPackager )
				)
				( objectStatus "U2D1.AE40" )
			)
			( pin "@baseboard_fab2_lib.baseboard_fab2(sch_1):page74_i22:vss(867)"
				( attribute "PN" "AE38"
					( Origin gPackager )
				)
				( objectStatus "U2D1.AE38" )
			)
			( pin "@baseboard_fab2_lib.baseboard_fab2(sch_1):page74_i22:vss(868)"
				( attribute "PN" "AE16"
					( Origin gPackager )
				)
				( objectStatus "U2D1.AE16" )
			)
			( pin "@baseboard_fab2_lib.baseboard_fab2(sch_1):page74_i22:vss(869)"
				( attribute "PN" "AC54"
					( Origin gPackager )
				)
				( objectStatus "U2D1.AC54" )
			)
			( pin "@baseboard_fab2_lib.baseboard_fab2(sch_1):page74_i22:vss(870)"
				( attribute "PN" "AE8"
					( Origin gPackager )
				)
				( objectStatus "U2D1.AE8" )
			)
			( pin "@baseboard_fab2_lib.baseboard_fab2(sch_1):page74_i22:vss(871)"
				( attribute "PN" "AE4"
					( Origin gPackager )
				)
				( objectStatus "U2D1.AE4" )
			)
			( pin "@baseboard_fab2_lib.baseboard_fab2(sch_1):page74_i22:vss(872)"
				( attribute "PN" "AD85"
					( Origin gPackager )
				)
				( objectStatus "U2D1.AD85" )
			)
			( pin "@baseboard_fab2_lib.baseboard_fab2(sch_1):page74_i22:vss(873)"
				( attribute "PN" "AD83"
					( Origin gPackager )
				)
				( objectStatus "U2D1.AD83" )
			)
			( pin "@baseboard_fab2_lib.baseboard_fab2(sch_1):page74_i22:vss(874)"
				( attribute "PN" "AD81"
					( Origin gPackager )
				)
				( objectStatus "U2D1.AD81" )
			)
			( pin "@baseboard_fab2_lib.baseboard_fab2(sch_1):page74_i22:vss(875)"
				( attribute "PN" "AD75"
					( Origin gPackager )
				)
				( objectStatus "U2D1.AD75" )
			)
			( pin "@baseboard_fab2_lib.baseboard_fab2(sch_1):page74_i22:vss(876)"
				( attribute "PN" "AD73"
					( Origin gPackager )
				)
				( objectStatus "U2D1.AD73" )
			)
			( pin "@baseboard_fab2_lib.baseboard_fab2(sch_1):page74_i22:vss(877)"
				( attribute "PN" "AD71"
					( Origin gPackager )
				)
				( objectStatus "U2D1.AD71" )
			)
			( pin "@baseboard_fab2_lib.baseboard_fab2(sch_1):page74_i22:vss(878)"
				( attribute "PN" "AD43"
					( Origin gPackager )
				)
				( objectStatus "U2D1.AD43" )
			)
			( pin "@baseboard_fab2_lib.baseboard_fab2(sch_1):page74_i22:vss(879)"
				( attribute "PN" "AD39"
					( Origin gPackager )
				)
				( objectStatus "U2D1.AD39" )
			)
			( pin "@baseboard_fab2_lib.baseboard_fab2(sch_1):page74_i22:vss(880)"
				( attribute "PN" "AD33"
					( Origin gPackager )
				)
				( objectStatus "U2D1.AD33" )
			)
			( pin "@baseboard_fab2_lib.baseboard_fab2(sch_1):page74_i22:vss(881)"
				( attribute "PN" "AD27"
					( Origin gPackager )
				)
				( objectStatus "U2D1.AD27" )
			)
			( pin "@baseboard_fab2_lib.baseboard_fab2(sch_1):page74_i22:vss(882)"
				( attribute "PN" "AD21"
					( Origin gPackager )
				)
				( objectStatus "U2D1.AD21" )
			)
			( pin "@baseboard_fab2_lib.baseboard_fab2(sch_1):page74_i22:vss(883)"
				( attribute "PN" "AD19"
					( Origin gPackager )
				)
				( objectStatus "U2D1.AD19" )
			)
			( pin "@baseboard_fab2_lib.baseboard_fab2(sch_1):page74_i22:vss(884)"
				( attribute "PN" "AD15"
					( Origin gPackager )
				)
				( objectStatus "U2D1.AD15" )
			)
			( pin "@baseboard_fab2_lib.baseboard_fab2(sch_1):page74_i22:vss(885)"
				( attribute "PN" "AD13"
					( Origin gPackager )
				)
				( objectStatus "U2D1.AD13" )
			)
			( pin "@baseboard_fab2_lib.baseboard_fab2(sch_1):page74_i22:vss(886)"
				( attribute "PN" "AD11"
					( Origin gPackager )
				)
				( objectStatus "U2D1.AD11" )
			)
			( pin "@baseboard_fab2_lib.baseboard_fab2(sch_1):page74_i22:vss(887)"
				( attribute "PN" "AD9"
					( Origin gPackager )
				)
				( objectStatus "U2D1.AD9" )
			)
			( pin "@baseboard_fab2_lib.baseboard_fab2(sch_1):page74_i22:vss(888)"
				( attribute "PN" "AD7"
					( Origin gPackager )
				)
				( objectStatus "U2D1.AD7" )
			)
			( pin "@baseboard_fab2_lib.baseboard_fab2(sch_1):page74_i22:vss(889)"
				( attribute "PN" "AD3"
					( Origin gPackager )
				)
				( objectStatus "U2D1.AD3" )
			)
			( pin "@baseboard_fab2_lib.baseboard_fab2(sch_1):page74_i22:vss(890)"
				( attribute "PN" "AC86"
					( Origin gPackager )
				)
				( objectStatus "U2D1.AC86" )
			)
			( pin "@baseboard_fab2_lib.baseboard_fab2(sch_1):page74_i22:vss(891)"
				( attribute "PN" "AC84"
					( Origin gPackager )
				)
				( objectStatus "U2D1.AC84" )
			)
			( pin "@baseboard_fab2_lib.baseboard_fab2(sch_1):page74_i22:vss(892)"
				( attribute "PN" "AC78"
					( Origin gPackager )
				)
				( objectStatus "U2D1.AC78" )
			)
			( pin "@baseboard_fab2_lib.baseboard_fab2(sch_1):page74_i22:vss(893)"
				( attribute "PN" "AC72"
					( Origin gPackager )
				)
				( objectStatus "U2D1.AC72" )
			)
			( pin "@baseboard_fab2_lib.baseboard_fab2(sch_1):page74_i22:vss(894)"
				( attribute "PN" "AC70"
					( Origin gPackager )
				)
				( objectStatus "U2D1.AC70" )
			)
			( pin "@baseboard_fab2_lib.baseboard_fab2(sch_1):page74_i22:vss(895)"
				( attribute "PN" "AC64"
					( Origin gPackager )
				)
				( objectStatus "U2D1.AC64" )
			)
			( pin "@baseboard_fab2_lib.baseboard_fab2(sch_1):page74_i22:vss(896)"
				( attribute "PN" "AC40"
					( Origin gPackager )
				)
				( objectStatus "U2D1.AC40" )
			)
			( pin "@baseboard_fab2_lib.baseboard_fab2(sch_1):page74_i22:vss(897)"
				( attribute "PN" "AC38"
					( Origin gPackager )
				)
				( objectStatus "U2D1.AC38" )
			)
			( pin "@baseboard_fab2_lib.baseboard_fab2(sch_1):page74_i22:vss(898)"
				( attribute "PN" "AC34"
					( Origin gPackager )
				)
				( objectStatus "U2D1.AC34" )
			)
			( pin "@baseboard_fab2_lib.baseboard_fab2(sch_1):page74_i22:vss(899)"
				( attribute "PN" "AC32"
					( Origin gPackager )
				)
				( objectStatus "U2D1.AC32" )
			)
			( pin "@baseboard_fab2_lib.baseboard_fab2(sch_1):page74_i22:vss(900)"
				( attribute "PN" "AC28"
					( Origin gPackager )
				)
				( objectStatus "U2D1.AC28" )
			)
			( pin "@baseboard_fab2_lib.baseboard_fab2(sch_1):page74_i22:vss(901)"
				( attribute "PN" "AC26"
					( Origin gPackager )
				)
				( objectStatus "U2D1.AC26" )
			)
			( pin "@baseboard_fab2_lib.baseboard_fab2(sch_1):page74_i22:vss(902)"
				( attribute "PN" "AC22"
					( Origin gPackager )
				)
				( objectStatus "U2D1.AC22" )
			)
			( pin "@baseboard_fab2_lib.baseboard_fab2(sch_1):page74_i22:vss(903)"
				( attribute "PN" "AC18"
					( Origin gPackager )
				)
				( objectStatus "U2D1.AC18" )
			)
			( pin "@baseboard_fab2_lib.baseboard_fab2(sch_1):page74_i22:vss(904)"
				( attribute "PN" "AB85"
					( Origin gPackager )
				)
				( objectStatus "U2D1.AB85" )
			)
			( pin "@baseboard_fab2_lib.baseboard_fab2(sch_1):page74_i22:vss(905)"
				( attribute "PN" "AB83"
					( Origin gPackager )
				)
				( objectStatus "U2D1.AB83" )
			)
			( pin "@baseboard_fab2_lib.baseboard_fab2(sch_1):page74_i22:vss(906)"
				( attribute "PN" "AB79"
					( Origin gPackager )
				)
				( objectStatus "U2D1.AB79" )
			)
			( pin "@baseboard_fab2_lib.baseboard_fab2(sch_1):page74_i22:vss(907)"
				( attribute "PN" "AB73"
					( Origin gPackager )
				)
				( objectStatus "U2D1.AB73" )
			)
			( pin "@baseboard_fab2_lib.baseboard_fab2(sch_1):page74_i22:vss(908)"
				( attribute "PN" "AB69"
					( Origin gPackager )
				)
				( objectStatus "U2D1.AB69" )
			)
			( pin "@baseboard_fab2_lib.baseboard_fab2(sch_1):page74_i22:vss(909)"
				( attribute "PN" "AB65"
					( Origin gPackager )
				)
				( objectStatus "U2D1.AB65" )
			)
			( pin "@baseboard_fab2_lib.baseboard_fab2(sch_1):page74_i22:vss(910)"
				( attribute "PN" "AB41"
					( Origin gPackager )
				)
				( objectStatus "U2D1.AB41" )
			)
			( pin "@baseboard_fab2_lib.baseboard_fab2(sch_1):page74_i22:vss(911)"
				( attribute "PN" "AB37"
					( Origin gPackager )
				)
				( objectStatus "U2D1.AB37" )
			)
			( pin "@baseboard_fab2_lib.baseboard_fab2(sch_1):page74_i22:vss(912)"
				( attribute "PN" "AB35"
					( Origin gPackager )
				)
				( objectStatus "U2D1.AB35" )
			)
			( pin "@baseboard_fab2_lib.baseboard_fab2(sch_1):page74_i22:vss(913)"
				( attribute "PN" "AB31"
					( Origin gPackager )
				)
				( objectStatus "U2D1.AB31" )
			)
			( pin "@baseboard_fab2_lib.baseboard_fab2(sch_1):page74_i22:vss(914)"
				( attribute "PN" "AB29"
					( Origin gPackager )
				)
				( objectStatus "U2D1.AB29" )
			)
			( pin "@baseboard_fab2_lib.baseboard_fab2(sch_1):page74_i22:vss(915)"
				( attribute "PN" "AB25"
					( Origin gPackager )
				)
				( objectStatus "U2D1.AB25" )
			)
			( pin "@baseboard_fab2_lib.baseboard_fab2(sch_1):page74_i22:vss(916)"
				( attribute "PN" "AB23"
					( Origin gPackager )
				)
				( objectStatus "U2D1.AB23" )
			)
			( pin "@baseboard_fab2_lib.baseboard_fab2(sch_1):page74_i22:vss(917)"
				( attribute "PN" "AB21"
					( Origin gPackager )
				)
				( objectStatus "U2D1.AB21" )
			)
			( pin "@baseboard_fab2_lib.baseboard_fab2(sch_1):page74_i22:vss(918)"
				( attribute "PN" "AB11"
					( Origin gPackager )
				)
				( objectStatus "U2D1.AB11" )
			)
			( pin "@baseboard_fab2_lib.baseboard_fab2(sch_1):page74_i22:vss(919)"
				( attribute "PN" "AB5"
					( Origin gPackager )
				)
				( objectStatus "U2D1.AB5" )
			)
			( pin "@baseboard_fab2_lib.baseboard_fab2(sch_1):page74_i22:vss(920)"
				( attribute "PN" "AB1"
					( Origin gPackager )
				)
				( objectStatus "U2D1.AB1" )
			)
			( pin "@baseboard_fab2_lib.baseboard_fab2(sch_1):page74_i22:vss(921)"
				( attribute "PN" "AA82"
					( Origin gPackager )
				)
				( objectStatus "U2D1.AA82" )
			)
			( pin "@baseboard_fab2_lib.baseboard_fab2(sch_1):page74_i22:vss(922)"
				( attribute "PN" "AA80"
					( Origin gPackager )
				)
				( objectStatus "U2D1.AA80" )
			)
			( pin "@baseboard_fab2_lib.baseboard_fab2(sch_1):page74_i22:vss(923)"
				( attribute "PN" "AA78"
					( Origin gPackager )
				)
				( objectStatus "U2D1.AA78" )
			)
			( pin "@baseboard_fab2_lib.baseboard_fab2(sch_1):page74_i22:vss(924)"
				( attribute "PN" "AA76"
					( Origin gPackager )
				)
				( objectStatus "U2D1.AA76" )
			)
			( pin "@baseboard_fab2_lib.baseboard_fab2(sch_1):page74_i22:vss(925)"
				( attribute "PN" "AA68"
					( Origin gPackager )
				)
				( objectStatus "U2D1.AA68" )
			)
			( pin "@baseboard_fab2_lib.baseboard_fab2(sch_1):page74_i22:vss(926)"
				( attribute "PN" "AA66"
					( Origin gPackager )
				)
				( objectStatus "U2D1.AA66" )
			)
			( pin "@baseboard_fab2_lib.baseboard_fab2(sch_1):page74_i22:vss(927)"
				( attribute "PN" "AA64"
					( Origin gPackager )
				)
				( objectStatus "U2D1.AA64" )
			)
			( pin "@baseboard_fab2_lib.baseboard_fab2(sch_1):page74_i22:vss(928)"
				( attribute "PN" "AA42"
					( Origin gPackager )
				)
				( objectStatus "U2D1.AA42" )
			)
			( pin "@baseboard_fab2_lib.baseboard_fab2(sch_1):page74_i22:vss(929)"
				( attribute "PN" "AA36"
					( Origin gPackager )
				)
				( objectStatus "U2D1.AA36" )
			)
			( pin "@baseboard_fab2_lib.baseboard_fab2(sch_1):page74_i22:vss(930)"
				( attribute "PN" "AA30"
					( Origin gPackager )
				)
				( objectStatus "U2D1.AA30" )
			)
			( pin "@baseboard_fab2_lib.baseboard_fab2(sch_1):page74_i22:vss(931)"
				( attribute "PN" "AA24"
					( Origin gPackager )
				)
				( objectStatus "U2D1.AA24" )
			)
			( pin "@baseboard_fab2_lib.baseboard_fab2(sch_1):page74_i22:vss(932)"
				( attribute "PN" "AA22"
					( Origin gPackager )
				)
				( objectStatus "U2D1.AA22" )
			)
			( pin "@baseboard_fab2_lib.baseboard_fab2(sch_1):page74_i22:vss(933)"
				( attribute "PN" "AA18"
					( Origin gPackager )
				)
				( objectStatus "U2D1.AA18" )
			)
			( pin "@baseboard_fab2_lib.baseboard_fab2(sch_1):page74_i23:vss(614)"
				( attribute "PN" "BG72"
					( Origin gPackager )
				)
				( objectStatus "U2D1.BG72" )
			)
			( pin "@baseboard_fab2_lib.baseboard_fab2(sch_1):page74_i23:vss(615)"
				( attribute "PN" "BG24"
					( Origin gPackager )
				)
				( objectStatus "U2D1.BG24" )
			)
			( pin "@baseboard_fab2_lib.baseboard_fab2(sch_1):page74_i23:vss(616)"
				( attribute "PN" "BG22"
					( Origin gPackager )
				)
				( objectStatus "U2D1.BG22" )
			)
			( pin "@baseboard_fab2_lib.baseboard_fab2(sch_1):page74_i23:vss(617)"
				( attribute "PN" "BG10"
					( Origin gPackager )
				)
				( objectStatus "U2D1.BG10" )
			)
			( pin "@baseboard_fab2_lib.baseboard_fab2(sch_1):page74_i23:vss(618)"
				( attribute "PN" "BG8"
					( Origin gPackager )
				)
				( objectStatus "U2D1.BG8" )
			)
			( pin "@baseboard_fab2_lib.baseboard_fab2(sch_1):page74_i23:vss(619)"
				( attribute "PN" "BG6"
					( Origin gPackager )
				)
				( objectStatus "U2D1.BG6" )
			)
			( pin "@baseboard_fab2_lib.baseboard_fab2(sch_1):page74_i23:vss(620)"
				( attribute "PN" "BF71"
					( Origin gPackager )
				)
				( objectStatus "U2D1.BF71" )
			)
			( pin "@baseboard_fab2_lib.baseboard_fab2(sch_1):page74_i23:vss(621)"
				( attribute "PN" "BF69"
					( Origin gPackager )
				)
				( objectStatus "U2D1.BF69" )
			)
			( pin "@baseboard_fab2_lib.baseboard_fab2(sch_1):page74_i23:vss(622)"
				( attribute "PN" "BF67"
					( Origin gPackager )
				)
				( objectStatus "U2D1.BF67" )
			)
			( pin "@baseboard_fab2_lib.baseboard_fab2(sch_1):page74_i23:vss(623)"
				( attribute "PN" "BF65"
					( Origin gPackager )
				)
				( objectStatus "U2D1.BF65" )
			)
			( pin "@baseboard_fab2_lib.baseboard_fab2(sch_1):page74_i23:vss(624)"
				( attribute "PN" "BF63"
					( Origin gPackager )
				)
				( objectStatus "U2D1.BF63" )
			)
			( pin "@baseboard_fab2_lib.baseboard_fab2(sch_1):page74_i23:vss(625)"
				( attribute "PN" "BF25"
					( Origin gPackager )
				)
				( objectStatus "U2D1.BF25" )
			)
			( pin "@baseboard_fab2_lib.baseboard_fab2(sch_1):page74_i23:vss(626)"
				( attribute "PN" "BF19"
					( Origin gPackager )
				)
				( objectStatus "U2D1.BF19" )
			)
			( pin "@baseboard_fab2_lib.baseboard_fab2(sch_1):page74_i23:vss(627)"
				( attribute "PN" "BF17"
					( Origin gPackager )
				)
				( objectStatus "U2D1.BF17" )
			)
			( pin "@baseboard_fab2_lib.baseboard_fab2(sch_1):page74_i23:vss(628)"
				( attribute "PN" "BF15"
					( Origin gPackager )
				)
				( objectStatus "U2D1.BF15" )
			)
			( pin "@baseboard_fab2_lib.baseboard_fab2(sch_1):page74_i23:vss(629)"
				( attribute "PN" "BF9"
					( Origin gPackager )
				)
				( objectStatus "U2D1.BF9" )
			)
			( pin "@baseboard_fab2_lib.baseboard_fab2(sch_1):page74_i23:vss(630)"
				( attribute "PN" "BE70"
					( Origin gPackager )
				)
				( objectStatus "U2D1.BE70" )
			)
			( pin "@baseboard_fab2_lib.baseboard_fab2(sch_1):page74_i23:vss(631)"
				( attribute "PN" "BE68"
					( Origin gPackager )
				)
				( objectStatus "U2D1.BE68" )
			)
			( pin "@baseboard_fab2_lib.baseboard_fab2(sch_1):page74_i23:vss(632)"
				( attribute "PN" "BE66"
					( Origin gPackager )
				)
				( objectStatus "U2D1.BE66" )
			)
			( pin "@baseboard_fab2_lib.baseboard_fab2(sch_1):page74_i23:vss(633)"
				( attribute "PN" "BE64"
					( Origin gPackager )
				)
				( objectStatus "U2D1.BE64" )
			)
			( pin "@baseboard_fab2_lib.baseboard_fab2(sch_1):page74_i23:vss(634)"
				( attribute "PN" "BE26"
					( Origin gPackager )
				)
				( objectStatus "U2D1.BE26" )
			)
			( pin "@baseboard_fab2_lib.baseboard_fab2(sch_1):page74_i23:vss(635)"
				( attribute "PN" "BE10"
					( Origin gPackager )
				)
				( objectStatus "U2D1.BE10" )
			)
			( pin "@baseboard_fab2_lib.baseboard_fab2(sch_1):page74_i23:vss(636)"
				( attribute "PN" "BE8"
					( Origin gPackager )
				)
				( objectStatus "U2D1.BE8" )
			)
			( pin "@baseboard_fab2_lib.baseboard_fab2(sch_1):page74_i23:vss(637)"
				( attribute "PN" "BE6"
					( Origin gPackager )
				)
				( objectStatus "U2D1.BE6" )
			)
			( pin "@baseboard_fab2_lib.baseboard_fab2(sch_1):page74_i23:vss(638)"
				( attribute "PN" "BE4"
					( Origin gPackager )
				)
				( objectStatus "U2D1.BE4" )
			)
			( pin "@baseboard_fab2_lib.baseboard_fab2(sch_1):page74_i23:vss(639)"
				( attribute "PN" "BD71"
					( Origin gPackager )
				)
				( objectStatus "U2D1.BD71" )
			)
			( pin "@baseboard_fab2_lib.baseboard_fab2(sch_1):page74_i23:vss(640)"
				( attribute "PN" "BD63"
					( Origin gPackager )
				)
				( objectStatus "U2D1.BD63" )
			)
			( pin "@baseboard_fab2_lib.baseboard_fab2(sch_1):page74_i23:vss(641)"
				( attribute "PN" "BD27"
					( Origin gPackager )
				)
				( objectStatus "U2D1.BD27" )
			)
			( pin "@baseboard_fab2_lib.baseboard_fab2(sch_1):page74_i23:vss(642)"
				( attribute "PN" "BD21"
					( Origin gPackager )
				)
				( objectStatus "U2D1.BD21" )
			)
			( pin "@baseboard_fab2_lib.baseboard_fab2(sch_1):page74_i23:vss(643)"
				( attribute "PN" "BD15"
					( Origin gPackager )
				)
				( objectStatus "U2D1.BD15" )
			)
			( pin "@baseboard_fab2_lib.baseboard_fab2(sch_1):page74_i23:vss(644)"
				( attribute "PN" "BD11"
					( Origin gPackager )
				)
				( objectStatus "U2D1.BD11" )
			)
			( pin "@baseboard_fab2_lib.baseboard_fab2(sch_1):page74_i23:vss(645)"
				( attribute "PN" "BD5"
					( Origin gPackager )
				)
				( objectStatus "U2D1.BD5" )
			)
			( pin "@baseboard_fab2_lib.baseboard_fab2(sch_1):page74_i23:vss(646)"
				( attribute "PN" "BC82"
					( Origin gPackager )
				)
				( objectStatus "U2D1.BC82" )
			)
			( pin "@baseboard_fab2_lib.baseboard_fab2(sch_1):page74_i23:vss(647)"
				( attribute "PN" "BC80"
					( Origin gPackager )
				)
				( objectStatus "U2D1.BC80" )
			)
			( pin "@baseboard_fab2_lib.baseboard_fab2(sch_1):page74_i23:vss(648)"
				( attribute "PN" "BC78"
					( Origin gPackager )
				)
				( objectStatus "U2D1.BC78" )
			)
			( pin "@baseboard_fab2_lib.baseboard_fab2(sch_1):page74_i23:vss(649)"
				( attribute "PN" "BC76"
					( Origin gPackager )
				)
				( objectStatus "U2D1.BC76" )
			)
			( pin "@baseboard_fab2_lib.baseboard_fab2(sch_1):page74_i23:vss(650)"
				( attribute "PN" "BC74"
					( Origin gPackager )
				)
				( objectStatus "U2D1.BC74" )
			)
			( pin "@baseboard_fab2_lib.baseboard_fab2(sch_1):page74_i23:vss(651)"
				( attribute "PN" "BC72"
					( Origin gPackager )
				)
				( objectStatus "U2D1.BC72" )
			)
			( pin "@baseboard_fab2_lib.baseboard_fab2(sch_1):page74_i23:vss(652)"
				( attribute "PN" "BC70"
					( Origin gPackager )
				)
				( objectStatus "U2D1.BC70" )
			)
			( pin "@baseboard_fab2_lib.baseboard_fab2(sch_1):page74_i23:vss(653)"
				( attribute "PN" "BC16"
					( Origin gPackager )
				)
				( objectStatus "U2D1.BC16" )
			)
			( pin "@baseboard_fab2_lib.baseboard_fab2(sch_1):page74_i23:vss(654)"
				( attribute "PN" "BC12"
					( Origin gPackager )
				)
				( objectStatus "U2D1.BC12" )
			)
			( pin "@baseboard_fab2_lib.baseboard_fab2(sch_1):page74_i23:vss(655)"
				( attribute "PN" "BC8"
					( Origin gPackager )
				)
				( objectStatus "U2D1.BC8" )
			)
			( pin "@baseboard_fab2_lib.baseboard_fab2(sch_1):page74_i23:vss(656)"
				( attribute "PN" "BC4"
					( Origin gPackager )
				)
				( objectStatus "U2D1.BC4" )
			)
			( pin "@baseboard_fab2_lib.baseboard_fab2(sch_1):page74_i23:vss(657)"
				( attribute "PN" "BB83"
					( Origin gPackager )
				)
				( objectStatus "U2D1.BB83" )
			)
			( pin "@baseboard_fab2_lib.baseboard_fab2(sch_1):page74_i23:vss(658)"
				( attribute "PN" "BB81"
					( Origin gPackager )
				)
				( objectStatus "U2D1.BB81" )
			)
			( pin "@baseboard_fab2_lib.baseboard_fab2(sch_1):page74_i23:vss(659)"
				( attribute "PN" "BB79"
					( Origin gPackager )
				)
				( objectStatus "U2D1.BB79" )
			)
			( pin "@baseboard_fab2_lib.baseboard_fab2(sch_1):page74_i23:vss(660)"
				( attribute "PN" "BB77"
					( Origin gPackager )
				)
				( objectStatus "U2D1.BB77" )
			)
			( pin "@baseboard_fab2_lib.baseboard_fab2(sch_1):page74_i23:vss(661)"
				( attribute "PN" "BB75"
					( Origin gPackager )
				)
				( objectStatus "U2D1.BB75" )
			)
			( pin "@baseboard_fab2_lib.baseboard_fab2(sch_1):page74_i23:vss(662)"
				( attribute "PN" "BB73"
					( Origin gPackager )
				)
				( objectStatus "U2D1.BB73" )
			)
			( pin "@baseboard_fab2_lib.baseboard_fab2(sch_1):page74_i23:vss(663)"
				( attribute "PN" "BB69"
					( Origin gPackager )
				)
				( objectStatus "U2D1.BB69" )
			)
			( pin "@baseboard_fab2_lib.baseboard_fab2(sch_1):page74_i23:vss(664)"
				( attribute "PN" "BB63"
					( Origin gPackager )
				)
				( objectStatus "U2D1.BB63" )
			)
			( pin "@baseboard_fab2_lib.baseboard_fab2(sch_1):page74_i23:vss(665)"
				( attribute "PN" "BB23"
					( Origin gPackager )
				)
				( objectStatus "U2D1.BB23" )
			)
			( pin "@baseboard_fab2_lib.baseboard_fab2(sch_1):page74_i23:vss(666)"
				( attribute "PN" "BB19"
					( Origin gPackager )
				)
				( objectStatus "U2D1.BB19" )
			)
			( pin "@baseboard_fab2_lib.baseboard_fab2(sch_1):page74_i23:vss(667)"
				( attribute "PN" "BA84"
					( Origin gPackager )
				)
				( objectStatus "U2D1.BA84" )
			)
			( pin "@baseboard_fab2_lib.baseboard_fab2(sch_1):page74_i23:vss(668)"
				( attribute "PN" "BA80"
					( Origin gPackager )
				)
				( objectStatus "U2D1.BA80" )
			)
			( pin "@baseboard_fab2_lib.baseboard_fab2(sch_1):page74_i23:vss(669)"
				( attribute "PN" "BA74"
					( Origin gPackager )
				)
				( objectStatus "U2D1.BA74" )
			)
			( pin "@baseboard_fab2_lib.baseboard_fab2(sch_1):page74_i23:vss(670)"
				( attribute "PN" "BA68"
					( Origin gPackager )
				)
				( objectStatus "U2D1.BA68" )
			)
			( pin "@baseboard_fab2_lib.baseboard_fab2(sch_1):page74_i23:vss(671)"
				( attribute "PN" "BA62"
					( Origin gPackager )
				)
				( objectStatus "U2D1.BA62" )
			)
			( pin "@baseboard_fab2_lib.baseboard_fab2(sch_1):page74_i23:vss(672)"
				( attribute "PN" "BA12"
					( Origin gPackager )
				)
				( objectStatus "U2D1.BA12" )
			)
			( pin "@baseboard_fab2_lib.baseboard_fab2(sch_1):page74_i23:vss(673)"
				( attribute "PN" "BA6"
					( Origin gPackager )
				)
				( objectStatus "U2D1.BA6" )
			)
			( pin "@baseboard_fab2_lib.baseboard_fab2(sch_1):page74_i23:vss(674)"
				( attribute "PN" "BA2"
					( Origin gPackager )
				)
				( objectStatus "U2D1.BA2" )
			)
			( pin "@baseboard_fab2_lib.baseboard_fab2(sch_1):page74_i23:vss(675)"
				( attribute "PN" "AY81"
					( Origin gPackager )
				)
				( objectStatus "U2D1.AY81" )
			)
			( pin "@baseboard_fab2_lib.baseboard_fab2(sch_1):page74_i23:vss(676)"
				( attribute "PN" "AY79"
					( Origin gPackager )
				)
				( objectStatus "U2D1.AY79" )
			)
			( pin "@baseboard_fab2_lib.baseboard_fab2(sch_1):page74_i23:vss(677)"
				( attribute "PN" "AY63"
					( Origin gPackager )
				)
				( objectStatus "U2D1.AY63" )
			)
			( pin "@baseboard_fab2_lib.baseboard_fab2(sch_1):page74_i23:vss(678)"
				( attribute "PN" "AY25"
					( Origin gPackager )
				)
				( objectStatus "U2D1.AY25" )
			)
			( pin "@baseboard_fab2_lib.baseboard_fab2(sch_1):page74_i23:vss(679)"
				( attribute "PN" "AY23"
					( Origin gPackager )
				)
				( objectStatus "U2D1.AY23" )
			)
			( pin "@baseboard_fab2_lib.baseboard_fab2(sch_1):page74_i23:vss(680)"
				( attribute "PN" "AY21"
					( Origin gPackager )
				)
				( objectStatus "U2D1.AY21" )
			)
			( pin "@baseboard_fab2_lib.baseboard_fab2(sch_1):page74_i23:vss(681)"
				( attribute "PN" "AY17"
					( Origin gPackager )
				)
				( objectStatus "U2D1.AY17" )
			)
			( pin "@baseboard_fab2_lib.baseboard_fab2(sch_1):page74_i23:vss(682)"
				( attribute "PN" "AY15"
					( Origin gPackager )
				)
				( objectStatus "U2D1.AY15" )
			)
			( pin "@baseboard_fab2_lib.baseboard_fab2(sch_1):page74_i23:vss(683)"
				( attribute "PN" "AY5"
					( Origin gPackager )
				)
				( objectStatus "U2D1.AY5" )
			)
			( pin "@baseboard_fab2_lib.baseboard_fab2(sch_1):page74_i23:vss(684)"
				( attribute "PN" "AW84"
					( Origin gPackager )
				)
				( objectStatus "U2D1.AW84" )
			)
			( pin "@baseboard_fab2_lib.baseboard_fab2(sch_1):page74_i23:vss(685)"
				( attribute "PN" "AW82"
					( Origin gPackager )
				)
				( objectStatus "U2D1.AW82" )
			)
			( pin "@baseboard_fab2_lib.baseboard_fab2(sch_1):page74_i23:vss(686)"
				( attribute "PN" "AW78"
					( Origin gPackager )
				)
				( objectStatus "U2D1.AW78" )
			)
			( pin "@baseboard_fab2_lib.baseboard_fab2(sch_1):page74_i23:vss(687)"
				( attribute "PN" "AW74"
					( Origin gPackager )
				)
				( objectStatus "U2D1.AW74" )
			)
			( pin "@baseboard_fab2_lib.baseboard_fab2(sch_1):page74_i23:vss(688)"
				( attribute "PN" "AW72"
					( Origin gPackager )
				)
				( objectStatus "U2D1.AW72" )
			)
			( pin "@baseboard_fab2_lib.baseboard_fab2(sch_1):page74_i23:vss(689)"
				( attribute "PN" "AW70"
					( Origin gPackager )
				)
				( objectStatus "U2D1.AW70" )
			)
			( pin "@baseboard_fab2_lib.baseboard_fab2(sch_1):page74_i23:vss(690)"
				( attribute "PN" "AW68"
					( Origin gPackager )
				)
				( objectStatus "U2D1.AW68" )
			)
			( pin "@baseboard_fab2_lib.baseboard_fab2(sch_1):page74_i23:vss(691)"
				( attribute "PN" "AW66"
					( Origin gPackager )
				)
				( objectStatus "U2D1.AW66" )
			)
			( pin "@baseboard_fab2_lib.baseboard_fab2(sch_1):page74_i23:vss(692)"
				( attribute "PN" "AW62"
					( Origin gPackager )
				)
				( objectStatus "U2D1.AW62" )
			)
			( pin "@baseboard_fab2_lib.baseboard_fab2(sch_1):page74_i23:vss(693)"
				( attribute "PN" "AW10"
					( Origin gPackager )
				)
				( objectStatus "U2D1.AW10" )
			)
			( pin "@baseboard_fab2_lib.baseboard_fab2(sch_1):page74_i23:vss(694)"
				( attribute "PN" "AW2"
					( Origin gPackager )
				)
				( objectStatus "U2D1.AW2" )
			)
			( pin "@baseboard_fab2_lib.baseboard_fab2(sch_1):page74_i23:vss(695)"
				( attribute "PN" "AV83"
					( Origin gPackager )
				)
				( objectStatus "U2D1.AV83" )
			)
			( pin "@baseboard_fab2_lib.baseboard_fab2(sch_1):page74_i23:vss(696)"
				( attribute "PN" "AV75"
					( Origin gPackager )
				)
				( objectStatus "U2D1.AV75" )
			)
			( pin "@baseboard_fab2_lib.baseboard_fab2(sch_1):page74_i23:vss(697)"
				( attribute "PN" "AV67"
					( Origin gPackager )
				)
				( objectStatus "U2D1.AV67" )
			)
			( pin "@baseboard_fab2_lib.baseboard_fab2(sch_1):page74_i23:vss(698)"
				( attribute "PN" "AV65"
					( Origin gPackager )
				)
				( objectStatus "U2D1.AV65" )
			)
			( pin "@baseboard_fab2_lib.baseboard_fab2(sch_1):page74_i23:vss(699)"
				( attribute "PN" "AV63"
					( Origin gPackager )
				)
				( objectStatus "U2D1.AV63" )
			)
			( pin "@baseboard_fab2_lib.baseboard_fab2(sch_1):page74_i23:vss(700)"
				( attribute "PN" "AV25"
					( Origin gPackager )
				)
				( objectStatus "U2D1.AV25" )
			)
			( pin "@baseboard_fab2_lib.baseboard_fab2(sch_1):page74_i23:vss(701)"
				( attribute "PN" "AV23"
					( Origin gPackager )
				)
				( objectStatus "U2D1.AV23" )
			)
			( pin "@baseboard_fab2_lib.baseboard_fab2(sch_1):page74_i23:vss(702)"
				( attribute "PN" "AV19"
					( Origin gPackager )
				)
				( objectStatus "U2D1.AV19" )
			)
			( pin "@baseboard_fab2_lib.baseboard_fab2(sch_1):page74_i23:vss(703)"
				( attribute "PN" "AV13"
					( Origin gPackager )
				)
				( objectStatus "U2D1.AV13" )
			)
			( pin "@baseboard_fab2_lib.baseboard_fab2(sch_1):page74_i23:vss(704)"
				( attribute "PN" "AV11"
					( Origin gPackager )
				)
				( objectStatus "U2D1.AV11" )
			)
			( pin "@baseboard_fab2_lib.baseboard_fab2(sch_1):page74_i23:vss(705)"
				( attribute "PN" "AV7"
					( Origin gPackager )
				)
				( objectStatus "U2D1.AV7" )
			)
			( pin "@baseboard_fab2_lib.baseboard_fab2(sch_1):page74_i23:vss(706)"
				( attribute "PN" "AV3"
					( Origin gPackager )
				)
				( objectStatus "U2D1.AV3" )
			)
			( pin "@baseboard_fab2_lib.baseboard_fab2(sch_1):page74_i23:vss(707)"
				( attribute "PN" "AV1"
					( Origin gPackager )
				)
				( objectStatus "U2D1.AV1" )
			)
			( pin "@baseboard_fab2_lib.baseboard_fab2(sch_1):page74_i23:vss(708)"
				( attribute "PN" "AU86"
					( Origin gPackager )
				)
				( objectStatus "U2D1.AU86" )
			)
			( pin "@baseboard_fab2_lib.baseboard_fab2(sch_1):page74_i23:vss(709)"
				( attribute "PN" "AU84"
					( Origin gPackager )
				)
				( objectStatus "U2D1.AU84" )
			)
			( pin "@baseboard_fab2_lib.baseboard_fab2(sch_1):page74_i23:vss(710)"
				( attribute "PN" "AU80"
					( Origin gPackager )
				)
				( objectStatus "U2D1.AU80" )
			)
			( pin "@baseboard_fab2_lib.baseboard_fab2(sch_1):page74_i23:vss(711)"
				( attribute "PN" "AU78"
					( Origin gPackager )
				)
				( objectStatus "U2D1.AU78" )
			)
			( pin "@baseboard_fab2_lib.baseboard_fab2(sch_1):page74_i23:vss(712)"
				( attribute "PN" "AU76"
					( Origin gPackager )
				)
				( objectStatus "U2D1.AU76" )
			)
			( pin "@baseboard_fab2_lib.baseboard_fab2(sch_1):page74_i23:vss(713)"
				( attribute "PN" "AU74"
					( Origin gPackager )
				)
				( objectStatus "U2D1.AU74" )
			)
			( pin "@baseboard_fab2_lib.baseboard_fab2(sch_1):page74_i23:vss(714)"
				( attribute "PN" "AU68"
					( Origin gPackager )
				)
				( objectStatus "U2D1.AU68" )
			)
			( pin "@baseboard_fab2_lib.baseboard_fab2(sch_1):page74_i23:vss(715)"
				( attribute "PN" "AU64"
					( Origin gPackager )
				)
				( objectStatus "U2D1.AU64" )
			)
			( pin "@baseboard_fab2_lib.baseboard_fab2(sch_1):page74_i23:vss(716)"
				( attribute "PN" "AU62"
					( Origin gPackager )
				)
				( objectStatus "U2D1.AU62" )
			)
			( pin "@baseboard_fab2_lib.baseboard_fab2(sch_1):page74_i23:vss(717)"
				( attribute "PN" "AU28"
					( Origin gPackager )
				)
				( objectStatus "U2D1.AU28" )
			)
			( pin "@baseboard_fab2_lib.baseboard_fab2(sch_1):page74_i23:vss(718)"
				( attribute "PN" "AU26"
					( Origin gPackager )
				)
				( objectStatus "U2D1.AU26" )
			)
			( pin "@baseboard_fab2_lib.baseboard_fab2(sch_1):page74_i23:vss(719)"
				( attribute "PN" "AU6"
					( Origin gPackager )
				)
				( objectStatus "U2D1.AU6" )
			)
			( pin "@baseboard_fab2_lib.baseboard_fab2(sch_1):page74_i23:vss(720)"
				( attribute "PN" "AU2"
					( Origin gPackager )
				)
				( objectStatus "U2D1.AU2" )
			)
			( pin "@baseboard_fab2_lib.baseboard_fab2(sch_1):page74_i23:vss(721)"
				( attribute "PN" "AT85"
					( Origin gPackager )
				)
				( objectStatus "U2D1.AT85" )
			)
			( pin "@baseboard_fab2_lib.baseboard_fab2(sch_1):page74_i23:vss(722)"
				( attribute "PN" "AT83"
					( Origin gPackager )
				)
				( objectStatus "U2D1.AT83" )
			)
			( pin "@baseboard_fab2_lib.baseboard_fab2(sch_1):page74_i23:vss(723)"
				( attribute "PN" "AT77"
					( Origin gPackager )
				)
				( objectStatus "U2D1.AT77" )
			)
			( pin "@baseboard_fab2_lib.baseboard_fab2(sch_1):page74_i23:vss(724)"
				( attribute "PN" "AT73"
					( Origin gPackager )
				)
				( objectStatus "U2D1.AT73" )
			)
			( pin "@baseboard_fab2_lib.baseboard_fab2(sch_1):page74_i23:vss(725)"
				( attribute "PN" "AT69"
					( Origin gPackager )
				)
				( objectStatus "U2D1.AT69" )
			)
			( pin "@baseboard_fab2_lib.baseboard_fab2(sch_1):page74_i23:vss(726)"
				( attribute "PN" "AT63"
					( Origin gPackager )
				)
				( objectStatus "U2D1.AT63" )
			)
			( pin "@baseboard_fab2_lib.baseboard_fab2(sch_1):page74_i23:vss(727)"
				( attribute "PN" "AT61"
					( Origin gPackager )
				)
				( objectStatus "U2D1.AT61" )
			)
			( pin "@baseboard_fab2_lib.baseboard_fab2(sch_1):page74_i23:vss(728)"
				( attribute "PN" "AT27"
					( Origin gPackager )
				)
				( objectStatus "U2D1.AT27" )
			)
			( pin "@baseboard_fab2_lib.baseboard_fab2(sch_1):page74_i23:vss(729)"
				( attribute "PN" "AT21"
					( Origin gPackager )
				)
				( objectStatus "U2D1.AT21" )
			)
			( pin "@baseboard_fab2_lib.baseboard_fab2(sch_1):page74_i23:vss(730)"
				( attribute "PN" "AT17"
					( Origin gPackager )
				)
				( objectStatus "U2D1.AT17" )
			)
			( pin "@baseboard_fab2_lib.baseboard_fab2(sch_1):page74_i23:vss(731)"
				( attribute "PN" "AT15"
					( Origin gPackager )
				)
				( objectStatus "U2D1.AT15" )
			)
			( pin "@baseboard_fab2_lib.baseboard_fab2(sch_1):page74_i23:vss(732)"
				( attribute "PN" "P63"
					( Origin gPackager )
				)
				( objectStatus "U2D1.P63" )
			)
			( pin "@baseboard_fab2_lib.baseboard_fab2(sch_1):page74_i23:vss(733)"
				( attribute "PN" "AC48"
					( Origin gPackager )
				)
				( objectStatus "U2D1.AC48" )
			)
			( pin "@baseboard_fab2_lib.baseboard_fab2(sch_1):page74_i23:vss(734)"
				( attribute "PN" "AR78"
					( Origin gPackager )
				)
				( objectStatus "U2D1.AR78" )
			)
			( pin "@baseboard_fab2_lib.baseboard_fab2(sch_1):page74_i23:vss(735)"
				( attribute "PN" "AR72"
					( Origin gPackager )
				)
				( objectStatus "U2D1.AR72" )
			)
			( pin "@baseboard_fab2_lib.baseboard_fab2(sch_1):page74_i23:vss(736)"
				( attribute "PN" "AR60"
					( Origin gPackager )
				)
				( objectStatus "U2D1.AR60" )
			)
			( pin "@baseboard_fab2_lib.baseboard_fab2(sch_1):page74_i23:vss(737)"
				( attribute "PN" "AR30"
					( Origin gPackager )
				)
				( objectStatus "U2D1.AR30" )
			)
			( pin "@baseboard_fab2_lib.baseboard_fab2(sch_1):page74_i23:vss(738)"
				( attribute "PN" "AR24"
					( Origin gPackager )
				)
				( objectStatus "U2D1.AR24" )
			)
			( pin "@baseboard_fab2_lib.baseboard_fab2(sch_1):page74_i23:vss(739)"
				( attribute "PN" "AR10"
					( Origin gPackager )
				)
				( objectStatus "U2D1.AR10" )
			)
			( pin "@baseboard_fab2_lib.baseboard_fab2(sch_1):page74_i23:vss(740)"
				( attribute "PN" "AP85"
					( Origin gPackager )
				)
				( objectStatus "U2D1.AP85" )
			)
			( pin "@baseboard_fab2_lib.baseboard_fab2(sch_1):page74_i23:vss(741)"
				( attribute "PN" "AP83"
					( Origin gPackager )
				)
				( objectStatus "U2D1.AP83" )
			)
			( pin "@baseboard_fab2_lib.baseboard_fab2(sch_1):page74_i23:vss(742)"
				( attribute "PN" "AP81"
					( Origin gPackager )
				)
				( objectStatus "U2D1.AP81" )
			)
			( pin "@baseboard_fab2_lib.baseboard_fab2(sch_1):page74_i23:vss(743)"
				( attribute "PN" "AP75"
					( Origin gPackager )
				)
				( objectStatus "U2D1.AP75" )
			)
			( pin "@baseboard_fab2_lib.baseboard_fab2(sch_1):page74_i23:vss(744)"
				( attribute "PN" "AP73"
					( Origin gPackager )
				)
				( objectStatus "U2D1.AP73" )
			)
			( pin "@baseboard_fab2_lib.baseboard_fab2(sch_1):page74_i23:vss(745)"
				( attribute "PN" "AP69"
					( Origin gPackager )
				)
				( objectStatus "U2D1.AP69" )
			)
			( pin "@baseboard_fab2_lib.baseboard_fab2(sch_1):page74_i23:vss(746)"
				( attribute "PN" "AP67"
					( Origin gPackager )
				)
				( objectStatus "U2D1.AP67" )
			)
			( pin "@baseboard_fab2_lib.baseboard_fab2(sch_1):page74_i23:vss(747)"
				( attribute "PN" "AP65"
					( Origin gPackager )
				)
				( objectStatus "U2D1.AP65" )
			)
			( pin "@baseboard_fab2_lib.baseboard_fab2(sch_1):page74_i23:vss(748)"
				( attribute "PN" "AP63"
					( Origin gPackager )
				)
				( objectStatus "U2D1.AP63" )
			)
			( pin "@baseboard_fab2_lib.baseboard_fab2(sch_1):page74_i23:vss(749)"
				( attribute "PN" "AP59"
					( Origin gPackager )
				)
				( objectStatus "U2D1.AP59" )
			)
			( pin "@baseboard_fab2_lib.baseboard_fab2(sch_1):page74_i23:vss(750)"
				( attribute "PN" "AP31"
					( Origin gPackager )
				)
				( objectStatus "U2D1.AP31" )
			)
			( pin "@baseboard_fab2_lib.baseboard_fab2(sch_1):page74_i23:vss(751)"
				( attribute "PN" "AP19"
					( Origin gPackager )
				)
				( objectStatus "U2D1.AP19" )
			)
			( pin "@baseboard_fab2_lib.baseboard_fab2(sch_1):page74_i23:vss(752)"
				( attribute "PN" "AP13"
					( Origin gPackager )
				)
				( objectStatus "U2D1.AP13" )
			)
			( pin "@baseboard_fab2_lib.baseboard_fab2(sch_1):page74_i23:vss(753)"
				( attribute "PN" "AP9"
					( Origin gPackager )
				)
				( objectStatus "U2D1.AP9" )
			)
			( pin "@baseboard_fab2_lib.baseboard_fab2(sch_1):page74_i23:vss(754)"
				( attribute "PN" "AP5"
					( Origin gPackager )
				)
				( objectStatus "U2D1.AP5" )
			)
			( pin "@baseboard_fab2_lib.baseboard_fab2(sch_1):page74_i23:vss(755)"
				( attribute "PN" "AN78"
					( Origin gPackager )
				)
				( objectStatus "U2D1.AN78" )
			)
			( pin "@baseboard_fab2_lib.baseboard_fab2(sch_1):page74_i23:vss(756)"
				( attribute "PN" "AN58"
					( Origin gPackager )
				)
				( objectStatus "U2D1.AN58" )
			)
			( pin "@baseboard_fab2_lib.baseboard_fab2(sch_1):page74_i23:vss(757)"
				( attribute "PN" "AN28"
					( Origin gPackager )
				)
				( objectStatus "U2D1.AN28" )
			)
			( pin "@baseboard_fab2_lib.baseboard_fab2(sch_1):page74_i23:vss(758)"
				( attribute "PN" "AN6"
					( Origin gPackager )
				)
				( objectStatus "U2D1.AN6" )
			)
			( pin "@baseboard_fab2_lib.baseboard_fab2(sch_1):page74_i23:vss(759)"
				( attribute "PN" "AN2"
					( Origin gPackager )
				)
				( objectStatus "U2D1.AN2" )
			)
			( pin "@baseboard_fab2_lib.baseboard_fab2(sch_1):page74_i23:vss(760)"
				( attribute "PN" "AM83"
					( Origin gPackager )
				)
				( objectStatus "U2D1.AM83" )
			)
			( pin "@baseboard_fab2_lib.baseboard_fab2(sch_1):page74_i23:vss(761)"
				( attribute "PN" "AM79"
					( Origin gPackager )
				)
				( objectStatus "U2D1.AM79" )
			)
			( pin "@baseboard_fab2_lib.baseboard_fab2(sch_1):page74_i23:vss(762)"
				( attribute "PN" "AM73"
					( Origin gPackager )
				)
				( objectStatus "U2D1.AM73" )
			)
			( pin "@baseboard_fab2_lib.baseboard_fab2(sch_1):page74_i23:vss(763)"
				( attribute "PN" "AM69"
					( Origin gPackager )
				)
				( objectStatus "U2D1.AM69" )
			)
			( pin "@baseboard_fab2_lib.baseboard_fab2(sch_1):page74_i23:vss(764)"
				( attribute "PN" "AM63"
					( Origin gPackager )
				)
				( objectStatus "U2D1.AM63" )
			)
			( pin "@baseboard_fab2_lib.baseboard_fab2(sch_1):page74_i23:vss(765)"
				( attribute "PN" "AM57"
					( Origin gPackager )
				)
				( objectStatus "U2D1.AM57" )
			)
			( pin "@baseboard_fab2_lib.baseboard_fab2(sch_1):page74_i23:vss(766)"
				( attribute "PN" "AM31"
					( Origin gPackager )
				)
				( objectStatus "U2D1.AM31" )
			)
			( pin "@baseboard_fab2_lib.baseboard_fab2(sch_1):page74_i23:vss(767)"
				( attribute "PN" "AC50"
					( Origin gPackager )
				)
				( objectStatus "U2D1.AC50" )
			)
			( pin "@baseboard_fab2_lib.baseboard_fab2(sch_1):page74_i23:vss(768)"
				( attribute "PN" "AM1"
					( Origin gPackager )
				)
				( objectStatus "U2D1.AM1" )
			)
			( pin "@baseboard_fab2_lib.baseboard_fab2(sch_1):page74_i23:vss(769)"
				( attribute "PN" "AL86"
					( Origin gPackager )
				)
				( objectStatus "U2D1.AL86" )
			)
			( pin "@baseboard_fab2_lib.baseboard_fab2(sch_1):page74_i23:vss(770)"
				( attribute "PN" "AL82"
					( Origin gPackager )
				)
				( objectStatus "U2D1.AL82" )
			)
			( pin "@baseboard_fab2_lib.baseboard_fab2(sch_1):page74_i23:vss(771)"
				( attribute "PN" "AL80"
					( Origin gPackager )
				)
				( objectStatus "U2D1.AL80" )
			)
			( pin "@baseboard_fab2_lib.baseboard_fab2(sch_1):page74_i23:vss(772)"
				( attribute "PN" "AL78"
					( Origin gPackager )
				)
				( objectStatus "U2D1.AL78" )
			)
			( pin "@baseboard_fab2_lib.baseboard_fab2(sch_1):page74_i23:vss(773)"
				( attribute "PN" "AL76"
					( Origin gPackager )
				)
				( objectStatus "U2D1.AL76" )
			)
			( pin "@baseboard_fab2_lib.baseboard_fab2(sch_1):page75_i17:vss(454)"
				( attribute "PN" "P49"
					( Origin gPackager )
				)
				( objectStatus "U2D1.P49" )
			)
			( pin "@baseboard_fab2_lib.baseboard_fab2(sch_1):page75_i17:vss(455)"
				( attribute "PN" "CJ12"
					( Origin gPackager )
				)
				( objectStatus "U2D1.CJ12" )
			)
			( pin "@baseboard_fab2_lib.baseboard_fab2(sch_1):page75_i17:vss(456)"
				( attribute "PN" "CJ10"
					( Origin gPackager )
				)
				( objectStatus "U2D1.CJ10" )
			)
			( pin "@baseboard_fab2_lib.baseboard_fab2(sch_1):page75_i17:vss(457)"
				( attribute "PN" "CJ8"
					( Origin gPackager )
				)
				( objectStatus "U2D1.CJ8" )
			)
			( pin "@baseboard_fab2_lib.baseboard_fab2(sch_1):page75_i17:vss(458)"
				( attribute "PN" "CJ6"
					( Origin gPackager )
				)
				( objectStatus "U2D1.CJ6" )
			)
			( pin "@baseboard_fab2_lib.baseboard_fab2(sch_1):page75_i17:vss(459)"
				( attribute "PN" "CJ2"
					( Origin gPackager )
				)
				( objectStatus "U2D1.CJ2" )
			)
			( pin "@baseboard_fab2_lib.baseboard_fab2(sch_1):page75_i17:vss(460)"
				( attribute "PN" "CH83"
					( Origin gPackager )
				)
				( objectStatus "U2D1.CH83" )
			)
			( pin "@baseboard_fab2_lib.baseboard_fab2(sch_1):page75_i17:vss(461)"
				( attribute "PN" "CH81"
					( Origin gPackager )
				)
				( objectStatus "U2D1.CH81" )
			)
			( pin "@baseboard_fab2_lib.baseboard_fab2(sch_1):page75_i17:vss(462)"
				( attribute "PN" "CH79"
					( Origin gPackager )
				)
				( objectStatus "U2D1.CH79" )
			)
			( pin "@baseboard_fab2_lib.baseboard_fab2(sch_1):page75_i17:vss(463)"
				( attribute "PN" "CH73"
					( Origin gPackager )
				)
				( objectStatus "U2D1.CH73" )
			)
			( pin "@baseboard_fab2_lib.baseboard_fab2(sch_1):page75_i17:vss(464)"
				( attribute "PN" "CH67"
					( Origin gPackager )
				)
				( objectStatus "U2D1.CH67" )
			)
			( pin "@baseboard_fab2_lib.baseboard_fab2(sch_1):page75_i17:vss(465)"
				( attribute "PN" "CH63"
					( Origin gPackager )
				)
				( objectStatus "U2D1.CH63" )
			)
			( pin "@baseboard_fab2_lib.baseboard_fab2(sch_1):page75_i17:vss(466)"
				( attribute "PN" "CH19"
					( Origin gPackager )
				)
				( objectStatus "U2D1.CH19" )
			)
			( pin "@baseboard_fab2_lib.baseboard_fab2(sch_1):page75_i17:vss(467)"
				( attribute "PN" "CH15"
					( Origin gPackager )
				)
				( objectStatus "U2D1.CH15" )
			)
			( pin "@baseboard_fab2_lib.baseboard_fab2(sch_1):page75_i17:vss(468)"
				( attribute "PN" "CH3"
					( Origin gPackager )
				)
				( objectStatus "U2D1.CH3" )
			)
			( pin "@baseboard_fab2_lib.baseboard_fab2(sch_1):page75_i17:vss(469)"
				( attribute "PN" "CH1"
					( Origin gPackager )
				)
				( objectStatus "U2D1.CH1" )
			)
			( pin "@baseboard_fab2_lib.baseboard_fab2(sch_1):page75_i17:vss(470)"
				( attribute "PN" "CG80"
					( Origin gPackager )
				)
				( objectStatus "U2D1.CG80" )
			)
			( pin "@baseboard_fab2_lib.baseboard_fab2(sch_1):page75_i17:vss(471)"
				( attribute "PN" "CG72"
					( Origin gPackager )
				)
				( objectStatus "U2D1.CG72" )
			)
			( pin "@baseboard_fab2_lib.baseboard_fab2(sch_1):page75_i17:vss(472)"
				( attribute "PN" "CG68"
					( Origin gPackager )
				)
				( objectStatus "U2D1.CG68" )
			)
			( pin "@baseboard_fab2_lib.baseboard_fab2(sch_1):page75_i17:vss(473)"
				( attribute "PN" "CG62"
					( Origin gPackager )
				)
				( objectStatus "U2D1.CG62" )
			)
			( pin "@baseboard_fab2_lib.baseboard_fab2(sch_1):page75_i17:vss(474)"
				( attribute "PN" "CG22"
					( Origin gPackager )
				)
				( objectStatus "U2D1.CG22" )
			)
			( pin "@baseboard_fab2_lib.baseboard_fab2(sch_1):page75_i17:vss(475)"
				( attribute "PN" "CG18"
					( Origin gPackager )
				)
				( objectStatus "U2D1.CG18" )
			)
			( pin "@baseboard_fab2_lib.baseboard_fab2(sch_1):page75_i17:vss(476)"
				( attribute "PN" "P51"
					( Origin gPackager )
				)
				( objectStatus "U2D1.P51" )
			)
			( pin "@baseboard_fab2_lib.baseboard_fab2(sch_1):page75_i17:vss(477)"
				( attribute "PN" "CF83"
					( Origin gPackager )
				)
				( objectStatus "U2D1.CF83" )
			)
			( pin "@baseboard_fab2_lib.baseboard_fab2(sch_1):page75_i17:vss(478)"
				( attribute "PN" "CF77"
					( Origin gPackager )
				)
				( objectStatus "U2D1.CF77" )
			)
			( pin "@baseboard_fab2_lib.baseboard_fab2(sch_1):page75_i17:vss(479)"
				( attribute "PN" "CF71"
					( Origin gPackager )
				)
				( objectStatus "U2D1.CF71" )
			)
			( pin "@baseboard_fab2_lib.baseboard_fab2(sch_1):page75_i17:vss(480)"
				( attribute "PN" "CF69"
					( Origin gPackager )
				)
				( objectStatus "U2D1.CF69" )
			)
			( pin "@baseboard_fab2_lib.baseboard_fab2(sch_1):page75_i17:vss(481)"
				( attribute "PN" "CF63"
					( Origin gPackager )
				)
				( objectStatus "U2D1.CF63" )
			)
			( pin "@baseboard_fab2_lib.baseboard_fab2(sch_1):page75_i17:vss(482)"
				( attribute "PN" "CF9"
					( Origin gPackager )
				)
				( objectStatus "U2D1.CF9" )
			)
			( pin "@baseboard_fab2_lib.baseboard_fab2(sch_1):page75_i17:vss(483)"
				( attribute "PN" "P53"
					( Origin gPackager )
				)
				( objectStatus "U2D1.P53" )
			)
			( pin "@baseboard_fab2_lib.baseboard_fab2(sch_1):page75_i17:vss(484)"
				( attribute "PN" "CE82"
					( Origin gPackager )
				)
				( objectStatus "U2D1.CE82" )
			)
			( pin "@baseboard_fab2_lib.baseboard_fab2(sch_1):page75_i17:vss(485)"
				( attribute "PN" "CE70"
					( Origin gPackager )
				)
				( objectStatus "U2D1.CE70" )
			)
			( pin "@baseboard_fab2_lib.baseboard_fab2(sch_1):page75_i17:vss(486)"
				( attribute "PN" "CE62"
					( Origin gPackager )
				)
				( objectStatus "U2D1.CE62" )
			)
			( pin "@baseboard_fab2_lib.baseboard_fab2(sch_1):page75_i17:vss(487)"
				( attribute "PN" "CE26"
					( Origin gPackager )
				)
				( objectStatus "U2D1.CE26" )
			)
			( pin "@baseboard_fab2_lib.baseboard_fab2(sch_1):page75_i17:vss(488)"
				( attribute "PN" "CE20"
					( Origin gPackager )
				)
				( objectStatus "U2D1.CE20" )
			)
			( pin "@baseboard_fab2_lib.baseboard_fab2(sch_1):page75_i17:vss(489)"
				( attribute "PN" "CE14"
					( Origin gPackager )
				)
				( objectStatus "U2D1.CE14" )
			)
			( pin "@baseboard_fab2_lib.baseboard_fab2(sch_1):page75_i17:vss(490)"
				( attribute "PN" "CE10"
					( Origin gPackager )
				)
				( objectStatus "U2D1.CE10" )
			)
			( pin "@baseboard_fab2_lib.baseboard_fab2(sch_1):page75_i17:vss(491)"
				( attribute "PN" "CD81"
					( Origin gPackager )
				)
				( objectStatus "U2D1.CD81" )
			)
			( pin "@baseboard_fab2_lib.baseboard_fab2(sch_1):page75_i17:vss(492)"
				( attribute "PN" "CD79"
					( Origin gPackager )
				)
				( objectStatus "U2D1.CD79" )
			)
			( pin "@baseboard_fab2_lib.baseboard_fab2(sch_1):page75_i17:vss(493)"
				( attribute "PN" "CD77"
					( Origin gPackager )
				)
				( objectStatus "U2D1.CD77" )
			)
			( pin "@baseboard_fab2_lib.baseboard_fab2(sch_1):page75_i17:vss(494)"
				( attribute "PN" "CD75"
					( Origin gPackager )
				)
				( objectStatus "U2D1.CD75" )
			)
			( pin "@baseboard_fab2_lib.baseboard_fab2(sch_1):page75_i17:vss(495)"
				( attribute "PN" "CD73"
					( Origin gPackager )
				)
				( objectStatus "U2D1.CD73" )
			)
			( pin "@baseboard_fab2_lib.baseboard_fab2(sch_1):page75_i17:vss(496)"
				( attribute "PN" "CD63"
					( Origin gPackager )
				)
				( objectStatus "U2D1.CD63" )
			)
			( pin "@baseboard_fab2_lib.baseboard_fab2(sch_1):page75_i17:vss(497)"
				( attribute "PN" "CD13"
					( Origin gPackager )
				)
				( objectStatus "U2D1.CD13" )
			)
			( pin "@baseboard_fab2_lib.baseboard_fab2(sch_1):page75_i17:vss(498)"
				( attribute "PN" "CD5"
					( Origin gPackager )
				)
				( objectStatus "U2D1.CD5" )
			)
			( pin "@baseboard_fab2_lib.baseboard_fab2(sch_1):page75_i17:vss(499)"
				( attribute "PN" "CC82"
					( Origin gPackager )
				)
				( objectStatus "U2D1.CC82" )
			)
			( pin "@baseboard_fab2_lib.baseboard_fab2(sch_1):page75_i17:vss(500)"
				( attribute "PN" "CC80"
					( Origin gPackager )
				)
				( objectStatus "U2D1.CC80" )
			)
			( pin "@baseboard_fab2_lib.baseboard_fab2(sch_1):page75_i17:vss(501)"
				( attribute "PN" "CC78"
					( Origin gPackager )
				)
				( objectStatus "U2D1.CC78" )
			)
			( pin "@baseboard_fab2_lib.baseboard_fab2(sch_1):page75_i17:vss(502)"
				( attribute "PN" "CC76"
					( Origin gPackager )
				)
				( objectStatus "U2D1.CC76" )
			)
			( pin "@baseboard_fab2_lib.baseboard_fab2(sch_1):page75_i17:vss(503)"
				( attribute "PN" "CC74"
					( Origin gPackager )
				)
				( objectStatus "U2D1.CC74" )
			)
			( pin "@baseboard_fab2_lib.baseboard_fab2(sch_1):page75_i17:vss(504)"
				( attribute "PN" "CC72"
					( Origin gPackager )
				)
				( objectStatus "U2D1.CC72" )
			)
			( pin "@baseboard_fab2_lib.baseboard_fab2(sch_1):page75_i17:vss(505)"
				( attribute "PN" "CC64"
					( Origin gPackager )
				)
				( objectStatus "U2D1.CC64" )
			)
			( pin "@baseboard_fab2_lib.baseboard_fab2(sch_1):page75_i17:vss(506)"
				( attribute "PN" "CC24"
					( Origin gPackager )
				)
				( objectStatus "U2D1.CC24" )
			)
			( pin "@baseboard_fab2_lib.baseboard_fab2(sch_1):page75_i17:vss(507)"
				( attribute "PN" "CC18"
					( Origin gPackager )
				)
				( objectStatus "U2D1.CC18" )
			)
			( pin "@baseboard_fab2_lib.baseboard_fab2(sch_1):page75_i17:vss(508)"
				( attribute "PN" "CC16"
					( Origin gPackager )
				)
				( objectStatus "U2D1.CC16" )
			)
			( pin "@baseboard_fab2_lib.baseboard_fab2(sch_1):page75_i17:vss(509)"
				( attribute "PN" "CC4"
					( Origin gPackager )
				)
				( objectStatus "U2D1.CC4" )
			)
			( pin "@baseboard_fab2_lib.baseboard_fab2(sch_1):page75_i17:vss(510)"
				( attribute "PN" "CB71"
					( Origin gPackager )
				)
				( objectStatus "U2D1.CB71" )
			)
			( pin "@baseboard_fab2_lib.baseboard_fab2(sch_1):page75_i17:vss(511)"
				( attribute "PN" "CB63"
					( Origin gPackager )
				)
				( objectStatus "U2D1.CB63" )
			)
			( pin "@baseboard_fab2_lib.baseboard_fab2(sch_1):page75_i17:vss(512)"
				( attribute "PN" "CB27"
					( Origin gPackager )
				)
				( objectStatus "U2D1.CB27" )
			)
			( pin "@baseboard_fab2_lib.baseboard_fab2(sch_1):page75_i17:vss(513)"
				( attribute "PN" "CB9"
					( Origin gPackager )
				)
				( objectStatus "U2D1.CB9" )
			)
			( pin "@baseboard_fab2_lib.baseboard_fab2(sch_1):page75_i17:vss(514)"
				( attribute "PN" "CB7"
					( Origin gPackager )
				)
				( objectStatus "U2D1.CB7" )
			)
			( pin "@baseboard_fab2_lib.baseboard_fab2(sch_1):page75_i17:vss(515)"
				( attribute "PN" "CA70"
					( Origin gPackager )
				)
				( objectStatus "U2D1.CA70" )
			)
			( pin "@baseboard_fab2_lib.baseboard_fab2(sch_1):page75_i17:vss(516)"
				( attribute "PN" "CA68"
					( Origin gPackager )
				)
				( objectStatus "U2D1.CA68" )
			)
			( pin "@baseboard_fab2_lib.baseboard_fab2(sch_1):page75_i17:vss(517)"
				( attribute "PN" "CA66"
					( Origin gPackager )
				)
				( objectStatus "U2D1.CA66" )
			)
			( pin "@baseboard_fab2_lib.baseboard_fab2(sch_1):page75_i17:vss(518)"
				( attribute "PN" "CA64"
					( Origin gPackager )
				)
				( objectStatus "U2D1.CA64" )
			)
			( pin "@baseboard_fab2_lib.baseboard_fab2(sch_1):page75_i17:vss(519)"
				( attribute "PN" "CA26"
					( Origin gPackager )
				)
				( objectStatus "U2D1.CA26" )
			)
			( pin "@baseboard_fab2_lib.baseboard_fab2(sch_1):page75_i17:vss(520)"
				( attribute "PN" "CA18"
					( Origin gPackager )
				)
				( objectStatus "U2D1.CA18" )
			)
			( pin "@baseboard_fab2_lib.baseboard_fab2(sch_1):page75_i17:vss(521)"
				( attribute "PN" "CA14"
					( Origin gPackager )
				)
				( objectStatus "U2D1.CA14" )
			)
			( pin "@baseboard_fab2_lib.baseboard_fab2(sch_1):page75_i17:vss(522)"
				( attribute "PN" "CA10"
					( Origin gPackager )
				)
				( objectStatus "U2D1.CA10" )
			)
			( pin "@baseboard_fab2_lib.baseboard_fab2(sch_1):page75_i17:vss(523)"
				( attribute "PN" "CA8"
					( Origin gPackager )
				)
				( objectStatus "U2D1.CA8" )
			)
			( pin "@baseboard_fab2_lib.baseboard_fab2(sch_1):page75_i17:vss(524)"
				( attribute "PN" "CA6"
					( Origin gPackager )
				)
				( objectStatus "U2D1.CA6" )
			)
			( pin "@baseboard_fab2_lib.baseboard_fab2(sch_1):page75_i17:vss(525)"
				( attribute "PN" "CA2"
					( Origin gPackager )
				)
				( objectStatus "U2D1.CA2" )
			)
			( pin "@baseboard_fab2_lib.baseboard_fab2(sch_1):page75_i17:vss(526)"
				( attribute "PN" "BY71"
					( Origin gPackager )
				)
				( objectStatus "U2D1.BY71" )
			)
			( pin "@baseboard_fab2_lib.baseboard_fab2(sch_1):page75_i17:vss(527)"
				( attribute "PN" "BY69"
					( Origin gPackager )
				)
				( objectStatus "U2D1.BY69" )
			)
			( pin "@baseboard_fab2_lib.baseboard_fab2(sch_1):page75_i17:vss(528)"
				( attribute "PN" "BY67"
					( Origin gPackager )
				)
				( objectStatus "U2D1.BY67" )
			)
			( pin "@baseboard_fab2_lib.baseboard_fab2(sch_1):page75_i17:vss(529)"
				( attribute "PN" "BY65"
					( Origin gPackager )
				)
				( objectStatus "U2D1.BY65" )
			)
			( pin "@baseboard_fab2_lib.baseboard_fab2(sch_1):page75_i17:vss(530)"
				( attribute "PN" "BY63"
					( Origin gPackager )
				)
				( objectStatus "U2D1.BY63" )
			)
			( pin "@baseboard_fab2_lib.baseboard_fab2(sch_1):page75_i17:vss(531)"
				( attribute "PN" "BY23"
					( Origin gPackager )
				)
				( objectStatus "U2D1.BY23" )
			)
			( pin "@baseboard_fab2_lib.baseboard_fab2(sch_1):page75_i17:vss(532)"
				( attribute "PN" "BY13"
					( Origin gPackager )
				)
				( objectStatus "U2D1.BY13" )
			)
			( pin "@baseboard_fab2_lib.baseboard_fab2(sch_1):page75_i17:vss(533)"
				( attribute "PN" "BY11"
					( Origin gPackager )
				)
				( objectStatus "U2D1.BY11" )
			)
			( pin "@baseboard_fab2_lib.baseboard_fab2(sch_1):page75_i17:vss(534)"
				( attribute "PN" "BW82"
					( Origin gPackager )
				)
				( objectStatus "U2D1.BW82" )
			)
			( pin "@baseboard_fab2_lib.baseboard_fab2(sch_1):page75_i17:vss(535)"
				( attribute "PN" "BW80"
					( Origin gPackager )
				)
				( objectStatus "U2D1.BW80" )
			)
			( pin "@baseboard_fab2_lib.baseboard_fab2(sch_1):page75_i17:vss(536)"
				( attribute "PN" "BW78"
					( Origin gPackager )
				)
				( objectStatus "U2D1.BW78" )
			)
			( pin "@baseboard_fab2_lib.baseboard_fab2(sch_1):page75_i17:vss(537)"
				( attribute "PN" "BW76"
					( Origin gPackager )
				)
				( objectStatus "U2D1.BW76" )
			)
			( pin "@baseboard_fab2_lib.baseboard_fab2(sch_1):page75_i17:vss(538)"
				( attribute "PN" "BW74"
					( Origin gPackager )
				)
				( objectStatus "U2D1.BW74" )
			)
			( pin "@baseboard_fab2_lib.baseboard_fab2(sch_1):page75_i17:vss(539)"
				( attribute "PN" "BW72"
					( Origin gPackager )
				)
				( objectStatus "U2D1.BW72" )
			)
			( pin "@baseboard_fab2_lib.baseboard_fab2(sch_1):page75_i17:vss(540)"
				( attribute "PN" "BW26"
					( Origin gPackager )
				)
				( objectStatus "U2D1.BW26" )
			)
			( pin "@baseboard_fab2_lib.baseboard_fab2(sch_1):page75_i17:vss(541)"
				( attribute "PN" "BW18"
					( Origin gPackager )
				)
				( objectStatus "U2D1.BW18" )
			)
			( pin "@baseboard_fab2_lib.baseboard_fab2(sch_1):page75_i17:vss(542)"
				( attribute "PN" "BW16"
					( Origin gPackager )
				)
				( objectStatus "U2D1.BW16" )
			)
			( pin "@baseboard_fab2_lib.baseboard_fab2(sch_1):page75_i17:vss(543)"
				( attribute "PN" "BW14"
					( Origin gPackager )
				)
				( objectStatus "U2D1.BW14" )
			)
			( pin "@baseboard_fab2_lib.baseboard_fab2(sch_1):page75_i17:vss(544)"
				( attribute "PN" "BW12"
					( Origin gPackager )
				)
				( objectStatus "U2D1.BW12" )
			)
			( pin "@baseboard_fab2_lib.baseboard_fab2(sch_1):page75_i17:vss(545)"
				( attribute "PN" "P55"
					( Origin gPackager )
				)
				( objectStatus "U2D1.P55" )
			)
			( pin "@baseboard_fab2_lib.baseboard_fab2(sch_1):page75_i17:vss(546)"
				( attribute "PN" "BW6"
					( Origin gPackager )
				)
				( objectStatus "U2D1.BW6" )
			)
			( pin "@baseboard_fab2_lib.baseboard_fab2(sch_1):page75_i17:vss(547)"
				( attribute "PN" "BV25"
					( Origin gPackager )
				)
				( objectStatus "U2D1.BV25" )
			)
			( pin "@baseboard_fab2_lib.baseboard_fab2(sch_1):page75_i17:vss(548)"
				( attribute "PN" "BV17"
					( Origin gPackager )
				)
				( objectStatus "U2D1.BV17" )
			)
			( pin "@baseboard_fab2_lib.baseboard_fab2(sch_1):page75_i17:vss(549)"
				( attribute "PN" "BU10"
					( Origin gPackager )
				)
				( objectStatus "U2D1.BU10" )
			)
			( pin "@baseboard_fab2_lib.baseboard_fab2(sch_1):page75_i17:vss(550)"
				( attribute "PN" "BV5"
					( Origin gPackager )
				)
				( objectStatus "U2D1.BV5" )
			)
			( pin "@baseboard_fab2_lib.baseboard_fab2(sch_1):page75_i17:vss(551)"
				( attribute "PN" "BU8"
					( Origin gPackager )
				)
				( objectStatus "U2D1.BU8" )
			)
			( pin "@baseboard_fab2_lib.baseboard_fab2(sch_1):page75_i17:vss(552)"
				( attribute "PN" "BT25"
					( Origin gPackager )
				)
				( objectStatus "U2D1.BT25" )
			)
			( pin "@baseboard_fab2_lib.baseboard_fab2(sch_1):page75_i17:vss(553)"
				( attribute "PN" "BT23"
					( Origin gPackager )
				)
				( objectStatus "U2D1.BT23" )
			)
			( pin "@baseboard_fab2_lib.baseboard_fab2(sch_1):page75_i17:vss(554)"
				( attribute "PN" "BT21"
					( Origin gPackager )
				)
				( objectStatus "U2D1.BT21" )
			)
			( pin "@baseboard_fab2_lib.baseboard_fab2(sch_1):page75_i17:vss(555)"
				( attribute "PN" "BT5"
					( Origin gPackager )
				)
				( objectStatus "U2D1.BT5" )
			)
			( pin "@baseboard_fab2_lib.baseboard_fab2(sch_1):page75_i17:vss(556)"
				( attribute "PN" "BT3"
					( Origin gPackager )
				)
				( objectStatus "U2D1.BT3" )
			)
			( pin "@baseboard_fab2_lib.baseboard_fab2(sch_1):page75_i17:vss(557)"
				( attribute "PN" "BR82"
					( Origin gPackager )
				)
				( objectStatus "U2D1.BR82" )
			)
			( pin "@baseboard_fab2_lib.baseboard_fab2(sch_1):page75_i17:vss(558)"
				( attribute "PN" "BR80"
					( Origin gPackager )
				)
				( objectStatus "U2D1.BR80" )
			)
			( pin "@baseboard_fab2_lib.baseboard_fab2(sch_1):page75_i17:vss(559)"
				( attribute "PN" "BR78"
					( Origin gPackager )
				)
				( objectStatus "U2D1.BR78" )
			)
			( pin "@baseboard_fab2_lib.baseboard_fab2(sch_1):page75_i17:vss(560)"
				( attribute "PN" "BR76"
					( Origin gPackager )
				)
				( objectStatus "U2D1.BR76" )
			)
			( pin "@baseboard_fab2_lib.baseboard_fab2(sch_1):page75_i17:vss(561)"
				( attribute "PN" "BR74"
					( Origin gPackager )
				)
				( objectStatus "U2D1.BR74" )
			)
			( pin "@baseboard_fab2_lib.baseboard_fab2(sch_1):page75_i17:vss(562)"
				( attribute "PN" "BR72"
					( Origin gPackager )
				)
				( objectStatus "U2D1.BR72" )
			)
			( pin "@baseboard_fab2_lib.baseboard_fab2(sch_1):page75_i17:vss(563)"
				( attribute "PN" "BR70"
					( Origin gPackager )
				)
				( objectStatus "U2D1.BR70" )
			)
			( pin "@baseboard_fab2_lib.baseboard_fab2(sch_1):page75_i17:vss(564)"
				( attribute "PN" "BR68"
					( Origin gPackager )
				)
				( objectStatus "U2D1.BR68" )
			)
			( pin "@baseboard_fab2_lib.baseboard_fab2(sch_1):page75_i17:vss(565)"
				( attribute "PN" "BR66"
					( Origin gPackager )
				)
				( objectStatus "U2D1.BR66" )
			)
			( pin "@baseboard_fab2_lib.baseboard_fab2(sch_1):page75_i17:vss(566)"
				( attribute "PN" "BR64"
					( Origin gPackager )
				)
				( objectStatus "U2D1.BR64" )
			)
			( pin "@baseboard_fab2_lib.baseboard_fab2(sch_1):page75_i17:vss(567)"
				( attribute "PN" "P57"
					( Origin gPackager )
				)
				( objectStatus "U2D1.P57" )
			)
			( pin "@baseboard_fab2_lib.baseboard_fab2(sch_1):page75_i17:vss(568)"
				( attribute "PN" "BR16"
					( Origin gPackager )
				)
				( objectStatus "U2D1.BR16" )
			)
			( pin "@baseboard_fab2_lib.baseboard_fab2(sch_1):page75_i17:vss(569)"
				( attribute "PN" "BR10"
					( Origin gPackager )
				)
				( objectStatus "U2D1.BR10" )
			)
			( pin "@baseboard_fab2_lib.baseboard_fab2(sch_1):page75_i17:vss(570)"
				( attribute "PN" "BR6"
					( Origin gPackager )
				)
				( objectStatus "U2D1.BR6" )
			)
			( pin "@baseboard_fab2_lib.baseboard_fab2(sch_1):page75_i17:vss(571)"
				( attribute "PN" "BP27"
					( Origin gPackager )
				)
				( objectStatus "U2D1.BP27" )
			)
			( pin "@baseboard_fab2_lib.baseboard_fab2(sch_1):page75_i17:vss(572)"
				( attribute "PN" "BP3"
					( Origin gPackager )
				)
				( objectStatus "U2D1.BP3" )
			)
			( pin "@baseboard_fab2_lib.baseboard_fab2(sch_1):page75_i17:vss(573)"
				( attribute "PN" "BN26"
					( Origin gPackager )
				)
				( objectStatus "U2D1.BN26" )
			)
			( pin "@baseboard_fab2_lib.baseboard_fab2(sch_1):page75_i17:vss(574)"
				( attribute "PN" "BN20"
					( Origin gPackager )
				)
				( objectStatus "U2D1.BN20" )
			)
			( pin "@baseboard_fab2_lib.baseboard_fab2(sch_1):page75_i17:vss(575)"
				( attribute "PN" "BN10"
					( Origin gPackager )
				)
				( objectStatus "U2D1.BN10" )
			)
			( pin "@baseboard_fab2_lib.baseboard_fab2(sch_1):page75_i17:vss(576)"
				( attribute "PN" "BN6"
					( Origin gPackager )
				)
				( objectStatus "U2D1.BN6" )
			)
			( pin "@baseboard_fab2_lib.baseboard_fab2(sch_1):page75_i17:vss(577)"
				( attribute "PN" "BM25"
					( Origin gPackager )
				)
				( objectStatus "U2D1.BM25" )
			)
			( pin "@baseboard_fab2_lib.baseboard_fab2(sch_1):page75_i17:vss(578)"
				( attribute "PN" "P59"
					( Origin gPackager )
				)
				( objectStatus "U2D1.P59" )
			)
			( pin "@baseboard_fab2_lib.baseboard_fab2(sch_1):page75_i17:vss(579)"
				( attribute "PN" "BM15"
					( Origin gPackager )
				)
				( objectStatus "U2D1.BM15" )
			)
			( pin "@baseboard_fab2_lib.baseboard_fab2(sch_1):page75_i17:vss(580)"
				( attribute "PN" "BM13"
					( Origin gPackager )
				)
				( objectStatus "U2D1.BM13" )
			)
			( pin "@baseboard_fab2_lib.baseboard_fab2(sch_1):page75_i17:vss(581)"
				( attribute "PN" "BM9"
					( Origin gPackager )
				)
				( objectStatus "U2D1.BM9" )
			)
			( pin "@baseboard_fab2_lib.baseboard_fab2(sch_1):page75_i17:vss(582)"
				( attribute "PN" "BL82"
					( Origin gPackager )
				)
				( objectStatus "U2D1.BL82" )
			)
			( pin "@baseboard_fab2_lib.baseboard_fab2(sch_1):page75_i17:vss(583)"
				( attribute "PN" "BL80"
					( Origin gPackager )
				)
				( objectStatus "U2D1.BL80" )
			)
			( pin "@baseboard_fab2_lib.baseboard_fab2(sch_1):page75_i17:vss(584)"
				( attribute "PN" "BL78"
					( Origin gPackager )
				)
				( objectStatus "U2D1.BL78" )
			)
			( pin "@baseboard_fab2_lib.baseboard_fab2(sch_1):page75_i17:vss(585)"
				( attribute "PN" "BL76"
					( Origin gPackager )
				)
				( objectStatus "U2D1.BL76" )
			)
			( pin "@baseboard_fab2_lib.baseboard_fab2(sch_1):page75_i17:vss(586)"
				( attribute "PN" "BL74"
					( Origin gPackager )
				)
				( objectStatus "U2D1.BL74" )
			)
			( pin "@baseboard_fab2_lib.baseboard_fab2(sch_1):page75_i17:vss(587)"
				( attribute "PN" "BL72"
					( Origin gPackager )
				)
				( objectStatus "U2D1.BL72" )
			)
			( pin "@baseboard_fab2_lib.baseboard_fab2(sch_1):page75_i17:vss(588)"
				( attribute "PN" "BL70"
					( Origin gPackager )
				)
				( objectStatus "U2D1.BL70" )
			)
			( pin "@baseboard_fab2_lib.baseboard_fab2(sch_1):page75_i17:vss(589)"
				( attribute "PN" "BL68"
					( Origin gPackager )
				)
				( objectStatus "U2D1.BL68" )
			)
			( pin "@baseboard_fab2_lib.baseboard_fab2(sch_1):page75_i17:vss(590)"
				( attribute "PN" "BL66"
					( Origin gPackager )
				)
				( objectStatus "U2D1.BL66" )
			)
			( pin "@baseboard_fab2_lib.baseboard_fab2(sch_1):page75_i17:vss(591)"
				( attribute "PN" "BL64"
					( Origin gPackager )
				)
				( objectStatus "U2D1.BL64" )
			)
			( pin "@baseboard_fab2_lib.baseboard_fab2(sch_1):page75_i17:vss(592)"
				( attribute "PN" "BL24"
					( Origin gPackager )
				)
				( objectStatus "U2D1.BL24" )
			)
			( pin "@baseboard_fab2_lib.baseboard_fab2(sch_1):page75_i17:vss(593)"
				( attribute "PN" "BL22"
					( Origin gPackager )
				)
				( objectStatus "U2D1.BL22" )
			)
			( pin "@baseboard_fab2_lib.baseboard_fab2(sch_1):page75_i17:vss(594)"
				( attribute "PN" "P61"
					( Origin gPackager )
				)
				( objectStatus "U2D1.P61" )
			)
			( pin "@baseboard_fab2_lib.baseboard_fab2(sch_1):page75_i17:vss(595)"
				( attribute "PN" "BL12"
					( Origin gPackager )
				)
				( objectStatus "U2D1.BL12" )
			)
			( pin "@baseboard_fab2_lib.baseboard_fab2(sch_1):page75_i17:vss(596)"
				( attribute "PN" "BL10"
					( Origin gPackager )
				)
				( objectStatus "U2D1.BL10" )
			)
			( pin "@baseboard_fab2_lib.baseboard_fab2(sch_1):page75_i17:vss(597)"
				( attribute "PN" "BL6"
					( Origin gPackager )
				)
				( objectStatus "U2D1.BL6" )
			)
			( pin "@baseboard_fab2_lib.baseboard_fab2(sch_1):page75_i17:vss(598)"
				( attribute "PN" "BK19"
					( Origin gPackager )
				)
				( objectStatus "U2D1.BK19" )
			)
			( pin "@baseboard_fab2_lib.baseboard_fab2(sch_1):page75_i17:vss(599)"
				( attribute "PN" "BK11"
					( Origin gPackager )
				)
				( objectStatus "U2D1.BK11" )
			)
			( pin "@baseboard_fab2_lib.baseboard_fab2(sch_1):page75_i17:vss(600)"
				( attribute "PN" "BK7"
					( Origin gPackager )
				)
				( objectStatus "U2D1.BK7" )
			)
			( pin "@baseboard_fab2_lib.baseboard_fab2(sch_1):page75_i17:vss(601)"
				( attribute "PN" "BK3"
					( Origin gPackager )
				)
				( objectStatus "U2D1.BK3" )
			)
			( pin "@baseboard_fab2_lib.baseboard_fab2(sch_1):page75_i17:vss(602)"
				( attribute "PN" "BJ6"
					( Origin gPackager )
				)
				( objectStatus "U2D1.BJ6" )
			)
			( pin "@baseboard_fab2_lib.baseboard_fab2(sch_1):page75_i17:vss(603)"
				( attribute "PN" "BJ4"
					( Origin gPackager )
				)
				( objectStatus "U2D1.BJ4" )
			)
			( pin "@baseboard_fab2_lib.baseboard_fab2(sch_1):page75_i17:vss(604)"
				( attribute "PN" "BH21"
					( Origin gPackager )
				)
				( objectStatus "U2D1.BH21" )
			)
			( pin "@baseboard_fab2_lib.baseboard_fab2(sch_1):page75_i17:vss(605)"
				( attribute "PN" "BH15"
					( Origin gPackager )
				)
				( objectStatus "U2D1.BH15" )
			)
			( pin "@baseboard_fab2_lib.baseboard_fab2(sch_1):page75_i17:vss(606)"
				( attribute "PN" "BH11"
					( Origin gPackager )
				)
				( objectStatus "U2D1.BH11" )
			)
			( pin "@baseboard_fab2_lib.baseboard_fab2(sch_1):page75_i17:vss(607)"
				( attribute "PN" "BH9"
					( Origin gPackager )
				)
				( objectStatus "U2D1.BH9" )
			)
			( pin "@baseboard_fab2_lib.baseboard_fab2(sch_1):page75_i17:vss(608)"
				( attribute "PN" "BH7"
					( Origin gPackager )
				)
				( objectStatus "U2D1.BH7" )
			)
			( pin "@baseboard_fab2_lib.baseboard_fab2(sch_1):page75_i17:vss(609)"
				( attribute "PN" "BG82"
					( Origin gPackager )
				)
				( objectStatus "U2D1.BG82" )
			)
			( pin "@baseboard_fab2_lib.baseboard_fab2(sch_1):page75_i17:vss(610)"
				( attribute "PN" "BG80"
					( Origin gPackager )
				)
				( objectStatus "U2D1.BG80" )
			)
			( pin "@baseboard_fab2_lib.baseboard_fab2(sch_1):page75_i17:vss(611)"
				( attribute "PN" "BG78"
					( Origin gPackager )
				)
				( objectStatus "U2D1.BG78" )
			)
			( pin "@baseboard_fab2_lib.baseboard_fab2(sch_1):page75_i17:vss(612)"
				( attribute "PN" "BG76"
					( Origin gPackager )
				)
				( objectStatus "U2D1.BG76" )
			)
			( pin "@baseboard_fab2_lib.baseboard_fab2(sch_1):page75_i17:vss(613)"
				( attribute "PN" "BG74"
					( Origin gPackager )
				)
				( objectStatus "U2D1.BG74" )
			)
			( pin "@baseboard_fab2_lib.baseboard_fab2(sch_1):page75_i18:vss(294)"
				( attribute "PN" "DA46"
					( Origin gPackager )
				)
				( objectStatus "U2D1.DA46" )
			)
			( pin "@baseboard_fab2_lib.baseboard_fab2(sch_1):page75_i18:vss(295)"
				( attribute "PN" "DA44"
					( Origin gPackager )
				)
				( objectStatus "U2D1.DA44" )
			)
			( pin "@baseboard_fab2_lib.baseboard_fab2(sch_1):page75_i18:vss(296)"
				( attribute "PN" "DA38"
					( Origin gPackager )
				)
				( objectStatus "U2D1.DA38" )
			)
			( pin "@baseboard_fab2_lib.baseboard_fab2(sch_1):page75_i18:vss(297)"
				( attribute "PN" "DA36"
					( Origin gPackager )
				)
				( objectStatus "U2D1.DA36" )
			)
			( pin "@baseboard_fab2_lib.baseboard_fab2(sch_1):page75_i18:vss(298)"
				( attribute "PN" "DA34"
					( Origin gPackager )
				)
				( objectStatus "U2D1.DA34" )
			)
			( pin "@baseboard_fab2_lib.baseboard_fab2(sch_1):page75_i18:vss(299)"
				( attribute "PN" "DA32"
					( Origin gPackager )
				)
				( objectStatus "U2D1.DA32" )
			)
			( pin "@baseboard_fab2_lib.baseboard_fab2(sch_1):page75_i18:vss(300)"
				( attribute "PN" "DA30"
					( Origin gPackager )
				)
				( objectStatus "U2D1.DA30" )
			)
			( pin "@baseboard_fab2_lib.baseboard_fab2(sch_1):page75_i18:vss(301)"
				( attribute "PN" "DA28"
					( Origin gPackager )
				)
				( objectStatus "U2D1.DA28" )
			)
			( pin "@baseboard_fab2_lib.baseboard_fab2(sch_1):page75_i18:vss(302)"
				( attribute "PN" "DA26"
					( Origin gPackager )
				)
				( objectStatus "U2D1.DA26" )
			)
			( pin "@baseboard_fab2_lib.baseboard_fab2(sch_1):page75_i18:vss(303)"
				( attribute "PN" "DA18"
					( Origin gPackager )
				)
				( objectStatus "U2D1.DA18" )
			)
			( pin "@baseboard_fab2_lib.baseboard_fab2(sch_1):page75_i18:vss(304)"
				( attribute "PN" "H53"
					( Origin gPackager )
				)
				( objectStatus "U2D1.H53" )
			)
			( pin "@baseboard_fab2_lib.baseboard_fab2(sch_1):page75_i18:vss(305)"
				( attribute "PN" "DA6"
					( Origin gPackager )
				)
				( objectStatus "U2D1.DA6" )
			)
			( pin "@baseboard_fab2_lib.baseboard_fab2(sch_1):page75_i18:vss(306)"
				( attribute "PN" "CY85"
					( Origin gPackager )
				)
				( objectStatus "U2D1.CY85" )
			)
			( pin "@baseboard_fab2_lib.baseboard_fab2(sch_1):page75_i18:vss(307)"
				( attribute "PN" "CY83"
					( Origin gPackager )
				)
				( objectStatus "U2D1.CY83" )
			)
			( pin "@baseboard_fab2_lib.baseboard_fab2(sch_1):page75_i18:vss(308)"
				( attribute "PN" "CY77"
					( Origin gPackager )
				)
				( objectStatus "U2D1.CY77" )
			)
			( pin "@baseboard_fab2_lib.baseboard_fab2(sch_1):page75_i18:vss(309)"
				( attribute "PN" "CY75"
					( Origin gPackager )
				)
				( objectStatus "U2D1.CY75" )
			)
			( pin "@baseboard_fab2_lib.baseboard_fab2(sch_1):page75_i18:vss(310)"
				( attribute "PN" "CY69"
					( Origin gPackager )
				)
				( objectStatus "U2D1.CY69" )
			)
			( pin "@baseboard_fab2_lib.baseboard_fab2(sch_1):page75_i18:vss(311)"
				( attribute "PN" "CY65"
					( Origin gPackager )
				)
				( objectStatus "U2D1.CY65" )
			)
			( pin "@baseboard_fab2_lib.baseboard_fab2(sch_1):page75_i18:vss(312)"
				( attribute "PN" "CY61"
					( Origin gPackager )
				)
				( objectStatus "U2D1.CY61" )
			)
			( pin "@baseboard_fab2_lib.baseboard_fab2(sch_1):page75_i18:vss(313)"
				( attribute "PN" "CY59"
					( Origin gPackager )
				)
				( objectStatus "U2D1.CY59" )
			)
			( pin "@baseboard_fab2_lib.baseboard_fab2(sch_1):page75_i18:vss(314)"
				( attribute "PN" "CY51"
					( Origin gPackager )
				)
				( objectStatus "U2D1.CY51" )
			)
			( pin "@baseboard_fab2_lib.baseboard_fab2(sch_1):page75_i18:vss(315)"
				( attribute "PN" "CY45"
					( Origin gPackager )
				)
				( objectStatus "U2D1.CY45" )
			)
			( pin "@baseboard_fab2_lib.baseboard_fab2(sch_1):page75_i18:vss(316)"
				( attribute "PN" "CY41"
					( Origin gPackager )
				)
				( objectStatus "U2D1.CY41" )
			)
			( pin "@baseboard_fab2_lib.baseboard_fab2(sch_1):page75_i18:vss(317)"
				( attribute "PN" "CY21"
					( Origin gPackager )
				)
				( objectStatus "U2D1.CY21" )
			)
			( pin "@baseboard_fab2_lib.baseboard_fab2(sch_1):page75_i18:vss(318)"
				( attribute "PN" "CY15"
					( Origin gPackager )
				)
				( objectStatus "U2D1.CY15" )
			)
			( pin "@baseboard_fab2_lib.baseboard_fab2(sch_1):page75_i18:vss(319)"
				( attribute "PN" "CY13"
					( Origin gPackager )
				)
				( objectStatus "U2D1.CY13" )
			)
			( pin "@baseboard_fab2_lib.baseboard_fab2(sch_1):page75_i18:vss(320)"
				( attribute "PN" "CY9"
					( Origin gPackager )
				)
				( objectStatus "U2D1.CY9" )
			)
			( pin "@baseboard_fab2_lib.baseboard_fab2(sch_1):page75_i18:vss(321)"
				( attribute "PN" "CY1"
					( Origin gPackager )
				)
				( objectStatus "U2D1.CY1" )
			)
			( pin "@baseboard_fab2_lib.baseboard_fab2(sch_1):page75_i18:vss(322)"
				( attribute "PN" "CW82"
					( Origin gPackager )
				)
				( objectStatus "U2D1.CW82" )
			)
			( pin "@baseboard_fab2_lib.baseboard_fab2(sch_1):page75_i18:vss(323)"
				( attribute "PN" "CW78"
					( Origin gPackager )
				)
				( objectStatus "U2D1.CW78" )
			)
			( pin "@baseboard_fab2_lib.baseboard_fab2(sch_1):page75_i18:vss(324)"
				( attribute "PN" "CW74"
					( Origin gPackager )
				)
				( objectStatus "U2D1.CW74" )
			)
			( pin "@baseboard_fab2_lib.baseboard_fab2(sch_1):page75_i18:vss(325)"
				( attribute "PN" "CW68"
					( Origin gPackager )
				)
				( objectStatus "U2D1.CW68" )
			)
			( pin "@baseboard_fab2_lib.baseboard_fab2(sch_1):page75_i18:vss(326)"
				( attribute "PN" "CW66"
					( Origin gPackager )
				)
				( objectStatus "U2D1.CW66" )
			)
			( pin "@baseboard_fab2_lib.baseboard_fab2(sch_1):page75_i18:vss(327)"
				( attribute "PN" "CW64"
					( Origin gPackager )
				)
				( objectStatus "U2D1.CW64" )
			)
			( pin "@baseboard_fab2_lib.baseboard_fab2(sch_1):page75_i18:vss(328)"
				( attribute "PN" "CW54"
					( Origin gPackager )
				)
				( objectStatus "U2D1.CW54" )
			)
			( pin "@baseboard_fab2_lib.baseboard_fab2(sch_1):page75_i18:vss(329)"
				( attribute "PN" "CW52"
					( Origin gPackager )
				)
				( objectStatus "U2D1.CW52" )
			)
			( pin "@baseboard_fab2_lib.baseboard_fab2(sch_1):page75_i18:vss(330)"
				( attribute "PN" "CW42"
					( Origin gPackager )
				)
				( objectStatus "U2D1.CW42" )
			)
			( pin "@baseboard_fab2_lib.baseboard_fab2(sch_1):page75_i18:vss(331)"
				( attribute "PN" "CW40"
					( Origin gPackager )
				)
				( objectStatus "U2D1.CW40" )
			)
			( pin "@baseboard_fab2_lib.baseboard_fab2(sch_1):page75_i18:vss(332)"
				( attribute "PN" "CW38"
					( Origin gPackager )
				)
				( objectStatus "U2D1.CW38" )
			)
			( pin "@baseboard_fab2_lib.baseboard_fab2(sch_1):page75_i18:vss(333)"
				( attribute "PN" "CW32"
					( Origin gPackager )
				)
				( objectStatus "U2D1.CW32" )
			)
			( pin "@baseboard_fab2_lib.baseboard_fab2(sch_1):page75_i18:vss(334)"
				( attribute "PN" "CW26"
					( Origin gPackager )
				)
				( objectStatus "U2D1.CW26" )
			)
			( pin "@baseboard_fab2_lib.baseboard_fab2(sch_1):page75_i18:vss(335)"
				( attribute "PN" "CW12"
					( Origin gPackager )
				)
				( objectStatus "U2D1.CW12" )
			)
			( pin "@baseboard_fab2_lib.baseboard_fab2(sch_1):page75_i18:vss(336)"
				( attribute "PN" "CV83"
					( Origin gPackager )
				)
				( objectStatus "U2D1.CV83" )
			)
			( pin "@baseboard_fab2_lib.baseboard_fab2(sch_1):page75_i18:vss(337)"
				( attribute "PN" "CV81"
					( Origin gPackager )
				)
				( objectStatus "U2D1.CV81" )
			)
			( pin "@baseboard_fab2_lib.baseboard_fab2(sch_1):page75_i18:vss(338)"
				( attribute "PN" "CV79"
					( Origin gPackager )
				)
				( objectStatus "U2D1.CV79" )
			)
			( pin "@baseboard_fab2_lib.baseboard_fab2(sch_1):page75_i18:vss(339)"
				( attribute "PN" "CV73"
					( Origin gPackager )
				)
				( objectStatus "U2D1.CV73" )
			)
			( pin "@baseboard_fab2_lib.baseboard_fab2(sch_1):page75_i18:vss(340)"
				( attribute "PN" "CV67"
					( Origin gPackager )
				)
				( objectStatus "U2D1.CV67" )
			)
			( pin "@baseboard_fab2_lib.baseboard_fab2(sch_1):page75_i18:vss(341)"
				( attribute "PN" "CV63"
					( Origin gPackager )
				)
				( objectStatus "U2D1.CV63" )
			)
			( pin "@baseboard_fab2_lib.baseboard_fab2(sch_1):page75_i18:vss(342)"
				( attribute "PN" "CV55"
					( Origin gPackager )
				)
				( objectStatus "U2D1.CV55" )
			)
			( pin "@baseboard_fab2_lib.baseboard_fab2(sch_1):page75_i18:vss(343)"
				( attribute "PN" "CV53"
					( Origin gPackager )
				)
				( objectStatus "U2D1.CV53" )
			)
			( pin "@baseboard_fab2_lib.baseboard_fab2(sch_1):page75_i18:vss(344)"
				( attribute "PN" "CV41"
					( Origin gPackager )
				)
				( objectStatus "U2D1.CV41" )
			)
			( pin "@baseboard_fab2_lib.baseboard_fab2(sch_1):page75_i18:vss(345)"
				( attribute "PN" "CV39"
					( Origin gPackager )
				)
				( objectStatus "U2D1.CV39" )
			)
			( pin "@baseboard_fab2_lib.baseboard_fab2(sch_1):page75_i18:vss(346)"
				( attribute "PN" "CV37"
					( Origin gPackager )
				)
				( objectStatus "U2D1.CV37" )
			)
			( pin "@baseboard_fab2_lib.baseboard_fab2(sch_1):page75_i18:vss(347)"
				( attribute "PN" "CV33"
					( Origin gPackager )
				)
				( objectStatus "U2D1.CV33" )
			)
			( pin "@baseboard_fab2_lib.baseboard_fab2(sch_1):page75_i18:vss(348)"
				( attribute "PN" "CV31"
					( Origin gPackager )
				)
				( objectStatus "U2D1.CV31" )
			)
			( pin "@baseboard_fab2_lib.baseboard_fab2(sch_1):page75_i18:vss(349)"
				( attribute "PN" "CV27"
					( Origin gPackager )
				)
				( objectStatus "U2D1.CV27" )
			)
			( pin "@baseboard_fab2_lib.baseboard_fab2(sch_1):page75_i18:vss(350)"
				( attribute "PN" "CV25"
					( Origin gPackager )
				)
				( objectStatus "U2D1.CV25" )
			)
			( pin "@baseboard_fab2_lib.baseboard_fab2(sch_1):page75_i18:vss(351)"
				( attribute "PN" "CV17"
					( Origin gPackager )
				)
				( objectStatus "U2D1.CV17" )
			)
			( pin "@baseboard_fab2_lib.baseboard_fab2(sch_1):page75_i18:vss(352)"
				( attribute "PN" "H55"
					( Origin gPackager )
				)
				( objectStatus "U2D1.H55" )
			)
			( pin "@baseboard_fab2_lib.baseboard_fab2(sch_1):page75_i18:vss(353)"
				( attribute "PN" "CV1"
					( Origin gPackager )
				)
				( objectStatus "U2D1.CV1" )
			)
			( pin "@baseboard_fab2_lib.baseboard_fab2(sch_1):page75_i18:vss(354)"
				( attribute "PN" "CU86"
					( Origin gPackager )
				)
				( objectStatus "U2D1.CU86" )
			)
			( pin "@baseboard_fab2_lib.baseboard_fab2(sch_1):page75_i18:vss(355)"
				( attribute "PN" "CU82"
					( Origin gPackager )
				)
				( objectStatus "U2D1.CU82" )
			)
			( pin "@baseboard_fab2_lib.baseboard_fab2(sch_1):page75_i18:vss(356)"
				( attribute "PN" "CU80"
					( Origin gPackager )
				)
				( objectStatus "U2D1.CU80" )
			)
			( pin "@baseboard_fab2_lib.baseboard_fab2(sch_1):page75_i18:vss(357)"
				( attribute "PN" "CU78"
					( Origin gPackager )
				)
				( objectStatus "U2D1.CU78" )
			)
			( pin "@baseboard_fab2_lib.baseboard_fab2(sch_1):page75_i18:vss(358)"
				( attribute "PN" "CU76"
					( Origin gPackager )
				)
				( objectStatus "U2D1.CU76" )
			)
			( pin "@baseboard_fab2_lib.baseboard_fab2(sch_1):page75_i18:vss(359)"
				( attribute "PN" "CU68"
					( Origin gPackager )
				)
				( objectStatus "U2D1.CU68" )
			)
			( pin "@baseboard_fab2_lib.baseboard_fab2(sch_1):page75_i18:vss(360)"
				( attribute "PN" "CU62"
					( Origin gPackager )
				)
				( objectStatus "U2D1.CU62" )
			)
			( pin "@baseboard_fab2_lib.baseboard_fab2(sch_1):page75_i18:vss(361)"
				( attribute "PN" "CU56"
					( Origin gPackager )
				)
				( objectStatus "U2D1.CU56" )
			)
			( pin "@baseboard_fab2_lib.baseboard_fab2(sch_1):page75_i18:vss(362)"
				( attribute "PN" "CU36"
					( Origin gPackager )
				)
				( objectStatus "U2D1.CU36" )
			)
			( pin "@baseboard_fab2_lib.baseboard_fab2(sch_1):page75_i18:vss(363)"
				( attribute "PN" "CU34"
					( Origin gPackager )
				)
				( objectStatus "U2D1.CU34" )
			)
			( pin "@baseboard_fab2_lib.baseboard_fab2(sch_1):page75_i18:vss(364)"
				( attribute "PN" "CU30"
					( Origin gPackager )
				)
				( objectStatus "U2D1.CU30" )
			)
			( pin "@baseboard_fab2_lib.baseboard_fab2(sch_1):page75_i18:vss(365)"
				( attribute "PN" "CU28"
					( Origin gPackager )
				)
				( objectStatus "U2D1.CU28" )
			)
			( pin "@baseboard_fab2_lib.baseboard_fab2(sch_1):page75_i18:vss(366)"
				( attribute "PN" "CU22"
					( Origin gPackager )
				)
				( objectStatus "U2D1.CU22" )
			)
			( pin "@baseboard_fab2_lib.baseboard_fab2(sch_1):page75_i18:vss(367)"
				( attribute "PN" "CU4"
					( Origin gPackager )
				)
				( objectStatus "U2D1.CU4" )
			)
			( pin "@baseboard_fab2_lib.baseboard_fab2(sch_1):page75_i18:vss(368)"
				( attribute "PN" "CT85"
					( Origin gPackager )
				)
				( objectStatus "U2D1.CT85" )
			)
			( pin "@baseboard_fab2_lib.baseboard_fab2(sch_1):page75_i18:vss(369)"
				( attribute "PN" "CT83"
					( Origin gPackager )
				)
				( objectStatus "U2D1.CT83" )
			)
			( pin "@baseboard_fab2_lib.baseboard_fab2(sch_1):page75_i18:vss(370)"
				( attribute "PN" "CT79"
					( Origin gPackager )
				)
				( objectStatus "U2D1.CT79" )
			)
			( pin "@baseboard_fab2_lib.baseboard_fab2(sch_1):page75_i18:vss(371)"
				( attribute "PN" "CT73"
					( Origin gPackager )
				)
				( objectStatus "U2D1.CT73" )
			)
			( pin "@baseboard_fab2_lib.baseboard_fab2(sch_1):page75_i18:vss(372)"
				( attribute "PN" "CT57"
					( Origin gPackager )
				)
				( objectStatus "U2D1.CT57" )
			)
			( pin "@baseboard_fab2_lib.baseboard_fab2(sch_1):page75_i18:vss(373)"
				( attribute "PN" "CT35"
					( Origin gPackager )
				)
				( objectStatus "U2D1.CT35" )
			)
			( pin "@baseboard_fab2_lib.baseboard_fab2(sch_1):page75_i18:vss(374)"
				( attribute "PN" "CT33"
					( Origin gPackager )
				)
				( objectStatus "U2D1.CT33" )
			)
			( pin "@baseboard_fab2_lib.baseboard_fab2(sch_1):page75_i18:vss(375)"
				( attribute "PN" "CT29"
					( Origin gPackager )
				)
				( objectStatus "U2D1.CT29" )
			)
			( pin "@baseboard_fab2_lib.baseboard_fab2(sch_1):page75_i18:vss(376)"
				( attribute "PN" "CT27"
					( Origin gPackager )
				)
				( objectStatus "U2D1.CT27" )
			)
			( pin "@baseboard_fab2_lib.baseboard_fab2(sch_1):page75_i18:vss(377)"
				( attribute "PN" "CT19"
					( Origin gPackager )
				)
				( objectStatus "U2D1.CT19" )
			)
			( pin "@baseboard_fab2_lib.baseboard_fab2(sch_1):page75_i18:vss(378)"
				( attribute "PN" "CT13"
					( Origin gPackager )
				)
				( objectStatus "U2D1.CT13" )
			)
			( pin "@baseboard_fab2_lib.baseboard_fab2(sch_1):page75_i18:vss(379)"
				( attribute "PN" "H57"
					( Origin gPackager )
				)
				( objectStatus "U2D1.H57" )
			)
			( pin "@baseboard_fab2_lib.baseboard_fab2(sch_1):page75_i18:vss(380)"
				( attribute "PN" "CR86"
					( Origin gPackager )
				)
				( objectStatus "U2D1.CR86" )
			)
			( pin "@baseboard_fab2_lib.baseboard_fab2(sch_1):page75_i18:vss(381)"
				( attribute "PN" "CR78"
					( Origin gPackager )
				)
				( objectStatus "U2D1.CR78" )
			)
			( pin "@baseboard_fab2_lib.baseboard_fab2(sch_1):page75_i18:vss(382)"
				( attribute "PN" "CR68"
					( Origin gPackager )
				)
				( objectStatus "U2D1.CR68" )
			)
			( pin "@baseboard_fab2_lib.baseboard_fab2(sch_1):page75_i18:vss(383)"
				( attribute "PN" "CR66"
					( Origin gPackager )
				)
				( objectStatus "U2D1.CR66" )
			)
			( pin "@baseboard_fab2_lib.baseboard_fab2(sch_1):page75_i18:vss(384)"
				( attribute "PN" "CR64"
					( Origin gPackager )
				)
				( objectStatus "U2D1.CR64" )
			)
			( pin "@baseboard_fab2_lib.baseboard_fab2(sch_1):page75_i18:vss(385)"
				( attribute "PN" "CR62"
					( Origin gPackager )
				)
				( objectStatus "U2D1.CR62" )
			)
			( pin "@baseboard_fab2_lib.baseboard_fab2(sch_1):page75_i18:vss(386)"
				( attribute "PN" "CR58"
					( Origin gPackager )
				)
				( objectStatus "U2D1.CR58" )
			)
			( pin "@baseboard_fab2_lib.baseboard_fab2(sch_1):page75_i18:vss(387)"
				( attribute "PN" "CR32"
					( Origin gPackager )
				)
				( objectStatus "U2D1.CR32" )
			)
			( pin "@baseboard_fab2_lib.baseboard_fab2(sch_1):page75_i18:vss(388)"
				( attribute "PN" "CR24"
					( Origin gPackager )
				)
				( objectStatus "U2D1.CR24" )
			)
			( pin "@baseboard_fab2_lib.baseboard_fab2(sch_1):page75_i18:vss(389)"
				( attribute "PN" "CR22"
					( Origin gPackager )
				)
				( objectStatus "U2D1.CR22" )
			)
			( pin "@baseboard_fab2_lib.baseboard_fab2(sch_1):page75_i18:vss(390)"
				( attribute "PN" "CR10"
					( Origin gPackager )
				)
				( objectStatus "U2D1.CR10" )
			)
			( pin "@baseboard_fab2_lib.baseboard_fab2(sch_1):page75_i18:vss(391)"
				( attribute "PN" "CR6"
					( Origin gPackager )
				)
				( objectStatus "U2D1.CR6" )
			)
			( pin "@baseboard_fab2_lib.baseboard_fab2(sch_1):page75_i18:vss(392)"
				( attribute "PN" "CP83"
					( Origin gPackager )
				)
				( objectStatus "U2D1.CP83" )
			)
			( pin "@baseboard_fab2_lib.baseboard_fab2(sch_1):page75_i18:vss(393)"
				( attribute "PN" "CP81"
					( Origin gPackager )
				)
				( objectStatus "U2D1.CP81" )
			)
			( pin "@baseboard_fab2_lib.baseboard_fab2(sch_1):page75_i18:vss(394)"
				( attribute "PN" "CP75"
					( Origin gPackager )
				)
				( objectStatus "U2D1.CP75" )
			)
			( pin "@baseboard_fab2_lib.baseboard_fab2(sch_1):page75_i18:vss(395)"
				( attribute "PN" "CP73"
					( Origin gPackager )
				)
				( objectStatus "U2D1.CP73" )
			)
			( pin "@baseboard_fab2_lib.baseboard_fab2(sch_1):page75_i18:vss(396)"
				( attribute "PN" "CP69"
					( Origin gPackager )
				)
				( objectStatus "U2D1.CP69" )
			)
			( pin "@baseboard_fab2_lib.baseboard_fab2(sch_1):page75_i18:vss(397)"
				( attribute "PN" "CP59"
					( Origin gPackager )
				)
				( objectStatus "U2D1.CP59" )
			)
			( pin "@baseboard_fab2_lib.baseboard_fab2(sch_1):page75_i18:vss(398)"
				( attribute "PN" "CP25"
					( Origin gPackager )
				)
				( objectStatus "U2D1.CP25" )
			)
			( pin "@baseboard_fab2_lib.baseboard_fab2(sch_1):page75_i18:vss(399)"
				( attribute "PN" "H59"
					( Origin gPackager )
				)
				( objectStatus "U2D1.H59" )
			)
			( pin "@baseboard_fab2_lib.baseboard_fab2(sch_1):page75_i18:vss(400)"
				( attribute "PN" "CP1"
					( Origin gPackager )
				)
				( objectStatus "U2D1.CP1" )
			)
			( pin "@baseboard_fab2_lib.baseboard_fab2(sch_1):page75_i18:vss(401)"
				( attribute "PN" "CN78"
					( Origin gPackager )
				)
				( objectStatus "U2D1.CN78" )
			)
			( pin "@baseboard_fab2_lib.baseboard_fab2(sch_1):page75_i18:vss(402)"
				( attribute "PN" "CN68"
					( Origin gPackager )
				)
				( objectStatus "U2D1.CN68" )
			)
			( pin "@baseboard_fab2_lib.baseboard_fab2(sch_1):page75_i18:vss(403)"
				( attribute "PN" "CN62"
					( Origin gPackager )
				)
				( objectStatus "U2D1.CN62" )
			)
			( pin "@baseboard_fab2_lib.baseboard_fab2(sch_1):page75_i18:vss(404)"
				( attribute "PN" "CN60"
					( Origin gPackager )
				)
				( objectStatus "U2D1.CN60" )
			)
			( pin "@baseboard_fab2_lib.baseboard_fab2(sch_1):page75_i18:vss(405)"
				( attribute "PN" "CN32"
					( Origin gPackager )
				)
				( objectStatus "U2D1.CN32" )
			)
			( pin "@baseboard_fab2_lib.baseboard_fab2(sch_1):page75_i18:vss(406)"
				( attribute "PN" "CN26"
					( Origin gPackager )
				)
				( objectStatus "U2D1.CN26" )
			)
			( pin "@baseboard_fab2_lib.baseboard_fab2(sch_1):page75_i18:vss(407)"
				( attribute "PN" "H61"
					( Origin gPackager )
				)
				( objectStatus "U2D1.H61" )
			)
			( pin "@baseboard_fab2_lib.baseboard_fab2(sch_1):page75_i18:vss(408)"
				( attribute "PN" "CN12"
					( Origin gPackager )
				)
				( objectStatus "U2D1.CN12" )
			)
			( pin "@baseboard_fab2_lib.baseboard_fab2(sch_1):page75_i18:vss(409)"
				( attribute "PN" "CN2"
					( Origin gPackager )
				)
				( objectStatus "U2D1.CN2" )
			)
			( pin "@baseboard_fab2_lib.baseboard_fab2(sch_1):page75_i18:vss(410)"
				( attribute "PN" "CM85"
					( Origin gPackager )
				)
				( objectStatus "U2D1.CM85" )
			)
			( pin "@baseboard_fab2_lib.baseboard_fab2(sch_1):page75_i18:vss(411)"
				( attribute "PN" "CM83"
					( Origin gPackager )
				)
				( objectStatus "U2D1.CM83" )
			)
			( pin "@baseboard_fab2_lib.baseboard_fab2(sch_1):page75_i18:vss(412)"
				( attribute "PN" "CM77"
					( Origin gPackager )
				)
				( objectStatus "U2D1.CM77" )
			)
			( pin "@baseboard_fab2_lib.baseboard_fab2(sch_1):page75_i18:vss(413)"
				( attribute "PN" "CM73"
					( Origin gPackager )
				)
				( objectStatus "U2D1.CM73" )
			)
			( pin "@baseboard_fab2_lib.baseboard_fab2(sch_1):page75_i18:vss(414)"
				( attribute "PN" "CM67"
					( Origin gPackager )
				)
				( objectStatus "U2D1.CM67" )
			)
			( pin "@baseboard_fab2_lib.baseboard_fab2(sch_1):page75_i18:vss(415)"
				( attribute "PN" "CM63"
					( Origin gPackager )
				)
				( objectStatus "U2D1.CM63" )
			)
			( pin "@baseboard_fab2_lib.baseboard_fab2(sch_1):page75_i18:vss(416)"
				( attribute "PN" "CM61"
					( Origin gPackager )
				)
				( objectStatus "U2D1.CM61" )
			)
			( pin "@baseboard_fab2_lib.baseboard_fab2(sch_1):page75_i18:vss(417)"
				( attribute "PN" "CM31"
					( Origin gPackager )
				)
				( objectStatus "U2D1.CM31" )
			)
			( pin "@baseboard_fab2_lib.baseboard_fab2(sch_1):page75_i18:vss(418)"
				( attribute "PN" "CM5"
					( Origin gPackager )
				)
				( objectStatus "U2D1.CM5" )
			)
			( pin "@baseboard_fab2_lib.baseboard_fab2(sch_1):page75_i18:vss(419)"
				( attribute "PN" "CM29"
					( Origin gPackager )
				)
				( objectStatus "U2D1.CM29" )
			)
			( pin "@baseboard_fab2_lib.baseboard_fab2(sch_1):page75_i18:vss(420)"
				( attribute "PN" "CM19"
					( Origin gPackager )
				)
				( objectStatus "U2D1.CM19" )
			)
			( pin "@baseboard_fab2_lib.baseboard_fab2(sch_1):page75_i18:vss(421)"
				( attribute "PN" "CL80"
					( Origin gPackager )
				)
				( objectStatus "U2D1.CL80" )
			)
			( pin "@baseboard_fab2_lib.baseboard_fab2(sch_1):page75_i18:vss(422)"
				( attribute "PN" "CL78"
					( Origin gPackager )
				)
				( objectStatus "U2D1.CL78" )
			)
			( pin "@baseboard_fab2_lib.baseboard_fab2(sch_1):page75_i18:vss(423)"
				( attribute "PN" "CL76"
					( Origin gPackager )
				)
				( objectStatus "U2D1.CL76" )
			)
			( pin "@baseboard_fab2_lib.baseboard_fab2(sch_1):page75_i18:vss(424)"
				( attribute "PN" "CL74"
					( Origin gPackager )
				)
				( objectStatus "U2D1.CL74" )
			)
			( pin "@baseboard_fab2_lib.baseboard_fab2(sch_1):page75_i18:vss(425)"
				( attribute "PN" "CL66"
					( Origin gPackager )
				)
				( objectStatus "U2D1.CL66" )
			)
			( pin "@baseboard_fab2_lib.baseboard_fab2(sch_1):page75_i18:vss(426)"
				( attribute "PN" "CL64"
					( Origin gPackager )
				)
				( objectStatus "U2D1.CL64" )
			)
			( pin "@baseboard_fab2_lib.baseboard_fab2(sch_1):page75_i18:vss(427)"
				( attribute "PN" "CL62"
					( Origin gPackager )
				)
				( objectStatus "U2D1.CL62" )
			)
			( pin "@baseboard_fab2_lib.baseboard_fab2(sch_1):page75_i18:vss(428)"
				( attribute "PN" "H63"
					( Origin gPackager )
				)
				( objectStatus "U2D1.H63" )
			)
			( pin "@baseboard_fab2_lib.baseboard_fab2(sch_1):page75_i18:vss(429)"
				( attribute "PN" "P45"
					( Origin gPackager )
				)
				( objectStatus "U2D1.P45" )
			)
			( pin "@baseboard_fab2_lib.baseboard_fab2(sch_1):page75_i18:vss(430)"
				( attribute "PN" "CL18"
					( Origin gPackager )
				)
				( objectStatus "U2D1.CL18" )
			)
			( pin "@baseboard_fab2_lib.baseboard_fab2(sch_1):page75_i18:vss(431)"
				( attribute "PN" "CL14"
					( Origin gPackager )
				)
				( objectStatus "U2D1.CL14" )
			)
			( pin "@baseboard_fab2_lib.baseboard_fab2(sch_1):page75_i18:vss(432)"
				( attribute "PN" "CL8"
					( Origin gPackager )
				)
				( objectStatus "U2D1.CL8" )
			)
			( pin "@baseboard_fab2_lib.baseboard_fab2(sch_1):page75_i18:vss(433)"
				( attribute "PN" "CK85"
					( Origin gPackager )
				)
				( objectStatus "U2D1.CK85" )
			)
			( pin "@baseboard_fab2_lib.baseboard_fab2(sch_1):page75_i18:vss(434)"
				( attribute "PN" "CK83"
					( Origin gPackager )
				)
				( objectStatus "U2D1.CK83" )
			)
			( pin "@baseboard_fab2_lib.baseboard_fab2(sch_1):page75_i18:vss(435)"
				( attribute "PN" "CK75"
					( Origin gPackager )
				)
				( objectStatus "U2D1.CK75" )
			)
			( pin "@baseboard_fab2_lib.baseboard_fab2(sch_1):page75_i18:vss(436)"
				( attribute "PN" "CK73"
					( Origin gPackager )
				)
				( objectStatus "U2D1.CK73" )
			)
			( pin "@baseboard_fab2_lib.baseboard_fab2(sch_1):page75_i18:vss(437)"
				( attribute "PN" "CK71"
					( Origin gPackager )
				)
				( objectStatus "U2D1.CK71" )
			)
			( pin "@baseboard_fab2_lib.baseboard_fab2(sch_1):page75_i18:vss(438)"
				( attribute "PN" "CK69"
					( Origin gPackager )
				)
				( objectStatus "U2D1.CK69" )
			)
			( pin "@baseboard_fab2_lib.baseboard_fab2(sch_1):page75_i18:vss(439)"
				( attribute "PN" "CK67"
					( Origin gPackager )
				)
				( objectStatus "U2D1.CK67" )
			)
			( pin "@baseboard_fab2_lib.baseboard_fab2(sch_1):page75_i18:vss(440)"
				( attribute "PN" "CK65"
					( Origin gPackager )
				)
				( objectStatus "U2D1.CK65" )
			)
			( pin "@baseboard_fab2_lib.baseboard_fab2(sch_1):page75_i18:vss(441)"
				( attribute "PN" "CK63"
					( Origin gPackager )
				)
				( objectStatus "U2D1.CK63" )
			)
			( pin "@baseboard_fab2_lib.baseboard_fab2(sch_1):page75_i18:vss(442)"
				( attribute "PN" "CK27"
					( Origin gPackager )
				)
				( objectStatus "U2D1.CK27" )
			)
			( pin "@baseboard_fab2_lib.baseboard_fab2(sch_1):page75_i18:vss(443)"
				( attribute "PN" "CK21"
					( Origin gPackager )
				)
				( objectStatus "U2D1.CK21" )
			)
			( pin "@baseboard_fab2_lib.baseboard_fab2(sch_1):page75_i18:vss(444)"
				( attribute "PN" "CK15"
					( Origin gPackager )
				)
				( objectStatus "U2D1.CK15" )
			)
			( pin "@baseboard_fab2_lib.baseboard_fab2(sch_1):page75_i18:vss(445)"
				( attribute "PN" "CK11"
					( Origin gPackager )
				)
				( objectStatus "U2D1.CK11" )
			)
			( pin "@baseboard_fab2_lib.baseboard_fab2(sch_1):page75_i18:vss(446)"
				( attribute "PN" "CJ86"
					( Origin gPackager )
				)
				( objectStatus "U2D1.CJ86" )
			)
			( pin "@baseboard_fab2_lib.baseboard_fab2(sch_1):page75_i18:vss(447)"
				( attribute "PN" "CJ84"
					( Origin gPackager )
				)
				( objectStatus "U2D1.CJ84" )
			)
			( pin "@baseboard_fab2_lib.baseboard_fab2(sch_1):page75_i18:vss(448)"
				( attribute "PN" "CJ82"
					( Origin gPackager )
				)
				( objectStatus "U2D1.CJ82" )
			)
			( pin "@baseboard_fab2_lib.baseboard_fab2(sch_1):page75_i18:vss(449)"
				( attribute "PN" "CJ78"
					( Origin gPackager )
				)
				( objectStatus "U2D1.CJ78" )
			)
			( pin "@baseboard_fab2_lib.baseboard_fab2(sch_1):page75_i18:vss(450)"
				( attribute "PN" "CJ76"
					( Origin gPackager )
				)
				( objectStatus "U2D1.CJ76" )
			)
			( pin "@baseboard_fab2_lib.baseboard_fab2(sch_1):page75_i18:vss(451)"
				( attribute "PN" "CJ74"
					( Origin gPackager )
				)
				( objectStatus "U2D1.CJ74" )
			)
			( pin "@baseboard_fab2_lib.baseboard_fab2(sch_1):page75_i18:vss(452)"
				( attribute "PN" "CJ62"
					( Origin gPackager )
				)
				( objectStatus "U2D1.CJ62" )
			)
			( pin "@baseboard_fab2_lib.baseboard_fab2(sch_1):page75_i18:vss(453)"
				( attribute "PN" "P47"
					( Origin gPackager )
				)
				( objectStatus "U2D1.P47" )
			)
			( pin "@baseboard_fab2_lib.baseboard_fab2(sch_1):page75_i19:vss(134)"
				( attribute "PN" "DN72"
					( Origin gPackager )
				)
				( objectStatus "U2D1.DN72" )
			)
			( pin "@baseboard_fab2_lib.baseboard_fab2(sch_1):page75_i19:vss(135)"
				( attribute "PN" "DN68"
					( Origin gPackager )
				)
				( objectStatus "U2D1.DN68" )
			)
			( pin "@baseboard_fab2_lib.baseboard_fab2(sch_1):page75_i19:vss(136)"
				( attribute "PN" "DN38"
					( Origin gPackager )
				)
				( objectStatus "U2D1.DN38" )
			)
			( pin "@baseboard_fab2_lib.baseboard_fab2(sch_1):page75_i19:vss(137)"
				( attribute "PN" "DN32"
					( Origin gPackager )
				)
				( objectStatus "U2D1.DN32" )
			)
			( pin "@baseboard_fab2_lib.baseboard_fab2(sch_1):page75_i19:vss(138)"
				( attribute "PN" "DN26"
					( Origin gPackager )
				)
				( objectStatus "U2D1.DN26" )
			)
			( pin "@baseboard_fab2_lib.baseboard_fab2(sch_1):page75_i19:vss(139)"
				( attribute "PN" "DN22"
					( Origin gPackager )
				)
				( objectStatus "U2D1.DN22" )
			)
			( pin "@baseboard_fab2_lib.baseboard_fab2(sch_1):page75_i19:vss(140)"
				( attribute "PN" "DN12"
					( Origin gPackager )
				)
				( objectStatus "U2D1.DN12" )
			)
			( pin "@baseboard_fab2_lib.baseboard_fab2(sch_1):page75_i19:vss(141)"
				( attribute "PN" "BH17"
					( Origin gPackager )
				)
				( objectStatus "U2D1.BH17" )
			)
			( pin "@baseboard_fab2_lib.baseboard_fab2(sch_1):page75_i19:vss(142)"
				( attribute "PN" "DN2"
					( Origin gPackager )
				)
				( objectStatus "U2D1.DN2" )
			)
			( pin "@baseboard_fab2_lib.baseboard_fab2(sch_1):page75_i19:vss(143)"
				( attribute "PN" "DM83"
					( Origin gPackager )
				)
				( objectStatus "U2D1.DM83" )
			)
			( pin "@baseboard_fab2_lib.baseboard_fab2(sch_1):page75_i19:vss(144)"
				( attribute "PN" "DM77"
					( Origin gPackager )
				)
				( objectStatus "U2D1.DM77" )
			)
			( pin "@baseboard_fab2_lib.baseboard_fab2(sch_1):page75_i19:vss(145)"
				( attribute "PN" "DM73"
					( Origin gPackager )
				)
				( objectStatus "U2D1.DM73" )
			)
			( pin "@baseboard_fab2_lib.baseboard_fab2(sch_1):page75_i19:vss(146)"
				( attribute "PN" "DM65"
					( Origin gPackager )
				)
				( objectStatus "U2D1.DM65" )
			)
			( pin "@baseboard_fab2_lib.baseboard_fab2(sch_1):page75_i19:vss(147)"
				( attribute "PN" "DM39"
					( Origin gPackager )
				)
				( objectStatus "U2D1.DM39" )
			)
			( pin "@baseboard_fab2_lib.baseboard_fab2(sch_1):page75_i19:vss(148)"
				( attribute "PN" "DM37"
					( Origin gPackager )
				)
				( objectStatus "U2D1.DM37" )
			)
			( pin "@baseboard_fab2_lib.baseboard_fab2(sch_1):page75_i19:vss(149)"
				( attribute "PN" "DM33"
					( Origin gPackager )
				)
				( objectStatus "U2D1.DM33" )
			)
			( pin "@baseboard_fab2_lib.baseboard_fab2(sch_1):page75_i19:vss(150)"
				( attribute "PN" "DM31"
					( Origin gPackager )
				)
				( objectStatus "U2D1.DM31" )
			)
			( pin "@baseboard_fab2_lib.baseboard_fab2(sch_1):page75_i19:vss(151)"
				( attribute "PN" "DM27"
					( Origin gPackager )
				)
				( objectStatus "U2D1.DM27" )
			)
			( pin "@baseboard_fab2_lib.baseboard_fab2(sch_1):page75_i19:vss(152)"
				( attribute "PN" "DM25"
					( Origin gPackager )
				)
				( objectStatus "U2D1.DM25" )
			)
			( pin "@baseboard_fab2_lib.baseboard_fab2(sch_1):page75_i19:vss(153)"
				( attribute "PN" "H45"
					( Origin gPackager )
				)
				( objectStatus "U2D1.H45" )
			)
			( pin "@baseboard_fab2_lib.baseboard_fab2(sch_1):page75_i19:vss(154)"
				( attribute "PN" "DM15"
					( Origin gPackager )
				)
				( objectStatus "U2D1.DM15" )
			)
			( pin "@baseboard_fab2_lib.baseboard_fab2(sch_1):page75_i19:vss(155)"
				( attribute "PN" "DL80"
					( Origin gPackager )
				)
				( objectStatus "U2D1.DL80" )
			)
			( pin "@baseboard_fab2_lib.baseboard_fab2(sch_1):page75_i19:vss(156)"
				( attribute "PN" "DL78"
					( Origin gPackager )
				)
				( objectStatus "U2D1.DL78" )
			)
			( pin "@baseboard_fab2_lib.baseboard_fab2(sch_1):page75_i19:vss(157)"
				( attribute "PN" "DL76"
					( Origin gPackager )
				)
				( objectStatus "U2D1.DL76" )
			)
			( pin "@baseboard_fab2_lib.baseboard_fab2(sch_1):page75_i19:vss(158)"
				( attribute "PN" "DL74"
					( Origin gPackager )
				)
				( objectStatus "U2D1.DL74" )
			)
			( pin "@baseboard_fab2_lib.baseboard_fab2(sch_1):page75_i19:vss(159)"
				( attribute "PN" "DL70"
					( Origin gPackager )
				)
				( objectStatus "U2D1.DL70" )
			)
			( pin "@baseboard_fab2_lib.baseboard_fab2(sch_1):page75_i19:vss(160)"
				( attribute "PN" "DL68"
					( Origin gPackager )
				)
				( objectStatus "U2D1.DL68" )
			)
			( pin "@baseboard_fab2_lib.baseboard_fab2(sch_1):page75_i19:vss(161)"
				( attribute "PN" "DL40"
					( Origin gPackager )
				)
				( objectStatus "U2D1.DL40" )
			)
			( pin "@baseboard_fab2_lib.baseboard_fab2(sch_1):page75_i19:vss(162)"
				( attribute "PN" "DL36"
					( Origin gPackager )
				)
				( objectStatus "U2D1.DL36" )
			)
			( pin "@baseboard_fab2_lib.baseboard_fab2(sch_1):page75_i19:vss(163)"
				( attribute "PN" "DL34"
					( Origin gPackager )
				)
				( objectStatus "U2D1.DL34" )
			)
			( pin "@baseboard_fab2_lib.baseboard_fab2(sch_1):page75_i19:vss(164)"
				( attribute "PN" "DL30"
					( Origin gPackager )
				)
				( objectStatus "U2D1.DL30" )
			)
			( pin "@baseboard_fab2_lib.baseboard_fab2(sch_1):page75_i19:vss(165)"
				( attribute "PN" "DL28"
					( Origin gPackager )
				)
				( objectStatus "U2D1.DL28" )
			)
			( pin "@baseboard_fab2_lib.baseboard_fab2(sch_1):page75_i19:vss(166)"
				( attribute "PN" "DL24"
					( Origin gPackager )
				)
				( objectStatus "U2D1.DL24" )
			)
			( pin "@baseboard_fab2_lib.baseboard_fab2(sch_1):page75_i19:vss(167)"
				( attribute "PN" "DL22"
					( Origin gPackager )
				)
				( objectStatus "U2D1.DL22" )
			)
			( pin "@baseboard_fab2_lib.baseboard_fab2(sch_1):page75_i19:vss(168)"
				( attribute "PN" "DL4"
					( Origin gPackager )
				)
				( objectStatus "U2D1.DL4" )
			)
			( pin "@baseboard_fab2_lib.baseboard_fab2(sch_1):page75_i19:vss(169)"
				( attribute "PN" "DL18"
					( Origin gPackager )
				)
				( objectStatus "U2D1.DL18" )
			)
			( pin "@baseboard_fab2_lib.baseboard_fab2(sch_1):page75_i19:vss(170)"
				( attribute "PN" "DL16"
					( Origin gPackager )
				)
				( objectStatus "U2D1.DL16" )
			)
			( pin "@baseboard_fab2_lib.baseboard_fab2(sch_1):page75_i19:vss(171)"
				( attribute "PN" "DK85"
					( Origin gPackager )
				)
				( objectStatus "U2D1.DK85" )
			)
			( pin "@baseboard_fab2_lib.baseboard_fab2(sch_1):page75_i19:vss(172)"
				( attribute "PN" "DK83"
					( Origin gPackager )
				)
				( objectStatus "U2D1.DK83" )
			)
			( pin "@baseboard_fab2_lib.baseboard_fab2(sch_1):page75_i19:vss(173)"
				( attribute "PN" "DK77"
					( Origin gPackager )
				)
				( objectStatus "U2D1.DK77" )
			)
			( pin "@baseboard_fab2_lib.baseboard_fab2(sch_1):page75_i19:vss(174)"
				( attribute "PN" "DK75"
					( Origin gPackager )
				)
				( objectStatus "U2D1.DK75" )
			)
			( pin "@baseboard_fab2_lib.baseboard_fab2(sch_1):page75_i19:vss(175)"
				( attribute "PN" "DK73"
					( Origin gPackager )
				)
				( objectStatus "U2D1.DK73" )
			)
			( pin "@baseboard_fab2_lib.baseboard_fab2(sch_1):page75_i19:vss(176)"
				( attribute "PN" "DK41"
					( Origin gPackager )
				)
				( objectStatus "U2D1.DK41" )
			)
			( pin "@baseboard_fab2_lib.baseboard_fab2(sch_1):page75_i19:vss(177)"
				( attribute "PN" "DK39"
					( Origin gPackager )
				)
				( objectStatus "U2D1.DK39" )
			)
			( pin "@baseboard_fab2_lib.baseboard_fab2(sch_1):page75_i19:vss(178)"
				( attribute "PN" "DK35"
					( Origin gPackager )
				)
				( objectStatus "U2D1.DK35" )
			)
			( pin "@baseboard_fab2_lib.baseboard_fab2(sch_1):page75_i19:vss(179)"
				( attribute "PN" "DK29"
					( Origin gPackager )
				)
				( objectStatus "U2D1.DK29" )
			)
			( pin "@baseboard_fab2_lib.baseboard_fab2(sch_1):page75_i19:vss(180)"
				( attribute "PN" "DK23"
					( Origin gPackager )
				)
				( objectStatus "U2D1.DK23" )
			)
			( pin "@baseboard_fab2_lib.baseboard_fab2(sch_1):page75_i19:vss(181)"
				( attribute "PN" "DK7"
					( Origin gPackager )
				)
				( objectStatus "U2D1.DK7" )
			)
			( pin "@baseboard_fab2_lib.baseboard_fab2(sch_1):page75_i19:vss(182)"
				( attribute "PN" "DJ84"
					( Origin gPackager )
				)
				( objectStatus "U2D1.DJ84" )
			)
			( pin "@baseboard_fab2_lib.baseboard_fab2(sch_1):page75_i19:vss(183)"
				( attribute "PN" "DJ82"
					( Origin gPackager )
				)
				( objectStatus "U2D1.DJ82" )
			)
			( pin "@baseboard_fab2_lib.baseboard_fab2(sch_1):page75_i19:vss(184)"
				( attribute "PN" "DJ78"
					( Origin gPackager )
				)
				( objectStatus "U2D1.DJ78" )
			)
			( pin "@baseboard_fab2_lib.baseboard_fab2(sch_1):page75_i19:vss(185)"
				( attribute "PN" "DJ74"
					( Origin gPackager )
				)
				( objectStatus "U2D1.DJ74" )
			)
			( pin "@baseboard_fab2_lib.baseboard_fab2(sch_1):page75_i19:vss(186)"
				( attribute "PN" "DJ68"
					( Origin gPackager )
				)
				( objectStatus "U2D1.DJ68" )
			)
			( pin "@baseboard_fab2_lib.baseboard_fab2(sch_1):page75_i19:vss(187)"
				( attribute "PN" "DJ42"
					( Origin gPackager )
				)
				( objectStatus "U2D1.DJ42" )
			)
			( pin "@baseboard_fab2_lib.baseboard_fab2(sch_1):page75_i19:vss(188)"
				( attribute "PN" "DJ38"
					( Origin gPackager )
				)
				( objectStatus "U2D1.DJ38" )
			)
			( pin "@baseboard_fab2_lib.baseboard_fab2(sch_1):page75_i19:vss(189)"
				( attribute "PN" "DJ22"
					( Origin gPackager )
				)
				( objectStatus "U2D1.DJ22" )
			)
			( pin "@baseboard_fab2_lib.baseboard_fab2(sch_1):page75_i19:vss(190)"
				( attribute "PN" "H47"
					( Origin gPackager )
				)
				( objectStatus "U2D1.H47" )
			)
			( pin "@baseboard_fab2_lib.baseboard_fab2(sch_1):page75_i19:vss(191)"
				( attribute "PN" "DJ10"
					( Origin gPackager )
				)
				( objectStatus "U2D1.DJ10" )
			)
			( pin "@baseboard_fab2_lib.baseboard_fab2(sch_1):page75_i19:vss(192)"
				( attribute "PN" "DJ2"
					( Origin gPackager )
				)
				( objectStatus "U2D1.DJ2" )
			)
			( pin "@baseboard_fab2_lib.baseboard_fab2(sch_1):page75_i19:vss(193)"
				( attribute "PN" "DH83"
					( Origin gPackager )
				)
				( objectStatus "U2D1.DH83" )
			)
			( pin "@baseboard_fab2_lib.baseboard_fab2(sch_1):page75_i19:vss(194)"
				( attribute "PN" "DH81"
					( Origin gPackager )
				)
				( objectStatus "U2D1.DH81" )
			)
			( pin "@baseboard_fab2_lib.baseboard_fab2(sch_1):page75_i19:vss(195)"
				( attribute "PN" "DH79"
					( Origin gPackager )
				)
				( objectStatus "U2D1.DH79" )
			)
			( pin "@baseboard_fab2_lib.baseboard_fab2(sch_1):page75_i19:vss(196)"
				( attribute "PN" "DH73"
					( Origin gPackager )
				)
				( objectStatus "U2D1.DH73" )
			)
			( pin "@baseboard_fab2_lib.baseboard_fab2(sch_1):page75_i19:vss(197)"
				( attribute "PN" "DH71"
					( Origin gPackager )
				)
				( objectStatus "U2D1.DH71" )
			)
			( pin "@baseboard_fab2_lib.baseboard_fab2(sch_1):page75_i19:vss(198)"
				( attribute "PN" "DH67"
					( Origin gPackager )
				)
				( objectStatus "U2D1.DH67" )
			)
			( pin "@baseboard_fab2_lib.baseboard_fab2(sch_1):page75_i19:vss(199)"
				( attribute "PN" "DH41"
					( Origin gPackager )
				)
				( objectStatus "U2D1.DH41" )
			)
			( pin "@baseboard_fab2_lib.baseboard_fab2(sch_1):page75_i19:vss(200)"
				( attribute "PN" "DH37"
					( Origin gPackager )
				)
				( objectStatus "U2D1.DH37" )
			)
			( pin "@baseboard_fab2_lib.baseboard_fab2(sch_1):page75_i19:vss(201)"
				( attribute "PN" "DH35"
					( Origin gPackager )
				)
				( objectStatus "U2D1.DH35" )
			)
			( pin "@baseboard_fab2_lib.baseboard_fab2(sch_1):page75_i19:vss(202)"
				( attribute "PN" "DH33"
					( Origin gPackager )
				)
				( objectStatus "U2D1.DH33" )
			)
			( pin "@baseboard_fab2_lib.baseboard_fab2(sch_1):page75_i19:vss(203)"
				( attribute "PN" "DH31"
					( Origin gPackager )
				)
				( objectStatus "U2D1.DH31" )
			)
			( pin "@baseboard_fab2_lib.baseboard_fab2(sch_1):page75_i19:vss(204)"
				( attribute "PN" "DH29"
					( Origin gPackager )
				)
				( objectStatus "U2D1.DH29" )
			)
			( pin "@baseboard_fab2_lib.baseboard_fab2(sch_1):page75_i19:vss(205)"
				( attribute "PN" "DH27"
					( Origin gPackager )
				)
				( objectStatus "U2D1.DH27" )
			)
			( pin "@baseboard_fab2_lib.baseboard_fab2(sch_1):page75_i19:vss(206)"
				( attribute "PN" "DH25"
					( Origin gPackager )
				)
				( objectStatus "U2D1.DH25" )
			)
			( pin "@baseboard_fab2_lib.baseboard_fab2(sch_1):page75_i19:vss(207)"
				( attribute "PN" "DH23"
					( Origin gPackager )
				)
				( objectStatus "U2D1.DH23" )
			)
			( pin "@baseboard_fab2_lib.baseboard_fab2(sch_1):page75_i19:vss(208)"
				( attribute "PN" "DH15"
					( Origin gPackager )
				)
				( objectStatus "U2D1.DH15" )
			)
			( pin "@baseboard_fab2_lib.baseboard_fab2(sch_1):page75_i19:vss(209)"
				( attribute "PN" "DH13"
					( Origin gPackager )
				)
				( objectStatus "U2D1.DH13" )
			)
			( pin "@baseboard_fab2_lib.baseboard_fab2(sch_1):page75_i19:vss(210)"
				( attribute "PN" "DG82"
					( Origin gPackager )
				)
				( objectStatus "U2D1.DG82" )
			)
			( pin "@baseboard_fab2_lib.baseboard_fab2(sch_1):page75_i19:vss(211)"
				( attribute "PN" "DG80"
					( Origin gPackager )
				)
				( objectStatus "U2D1.DG80" )
			)
			( pin "@baseboard_fab2_lib.baseboard_fab2(sch_1):page75_i19:vss(212)"
				( attribute "PN" "DG78"
					( Origin gPackager )
				)
				( objectStatus "U2D1.DG78" )
			)
			( pin "@baseboard_fab2_lib.baseboard_fab2(sch_1):page75_i19:vss(213)"
				( attribute "PN" "DG76"
					( Origin gPackager )
				)
				( objectStatus "U2D1.DG76" )
			)
			( pin "@baseboard_fab2_lib.baseboard_fab2(sch_1):page75_i19:vss(214)"
				( attribute "PN" "DG68"
					( Origin gPackager )
				)
				( objectStatus "U2D1.DG68" )
			)
			( pin "@baseboard_fab2_lib.baseboard_fab2(sch_1):page75_i19:vss(215)"
				( attribute "PN" "DG66"
					( Origin gPackager )
				)
				( objectStatus "U2D1.DG66" )
			)
			( pin "@baseboard_fab2_lib.baseboard_fab2(sch_1):page75_i19:vss(216)"
				( attribute "PN" "DG24"
					( Origin gPackager )
				)
				( objectStatus "U2D1.DG24" )
			)
			( pin "@baseboard_fab2_lib.baseboard_fab2(sch_1):page75_i19:vss(217)"
				( attribute "PN" "DG16"
					( Origin gPackager )
				)
				( objectStatus "U2D1.DG16" )
			)
			( pin "@baseboard_fab2_lib.baseboard_fab2(sch_1):page75_i19:vss(218)"
				( attribute "PN" "DG14"
					( Origin gPackager )
				)
				( objectStatus "U2D1.DG14" )
			)
			( pin "@baseboard_fab2_lib.baseboard_fab2(sch_1):page75_i19:vss(219)"
				( attribute "PN" "H49"
					( Origin gPackager )
				)
				( objectStatus "U2D1.H49" )
			)
			( pin "@baseboard_fab2_lib.baseboard_fab2(sch_1):page75_i19:vss(220)"
				( attribute "PN" "DG2"
					( Origin gPackager )
				)
				( objectStatus "U2D1.DG2" )
			)
			( pin "@baseboard_fab2_lib.baseboard_fab2(sch_1):page75_i19:vss(221)"
				( attribute "PN" "DF85"
					( Origin gPackager )
				)
				( objectStatus "U2D1.DF85" )
			)
			( pin "@baseboard_fab2_lib.baseboard_fab2(sch_1):page75_i19:vss(222)"
				( attribute "PN" "DF83"
					( Origin gPackager )
				)
				( objectStatus "U2D1.DF83" )
			)
			( pin "@baseboard_fab2_lib.baseboard_fab2(sch_1):page75_i19:vss(223)"
				( attribute "PN" "DF79"
					( Origin gPackager )
				)
				( objectStatus "U2D1.DF79" )
			)
			( pin "@baseboard_fab2_lib.baseboard_fab2(sch_1):page75_i19:vss(224)"
				( attribute "PN" "DF73"
					( Origin gPackager )
				)
				( objectStatus "U2D1.DF73" )
			)
			( pin "@baseboard_fab2_lib.baseboard_fab2(sch_1):page75_i19:vss(225)"
				( attribute "PN" "DF69"
					( Origin gPackager )
				)
				( objectStatus "U2D1.DF69" )
			)
			( pin "@baseboard_fab2_lib.baseboard_fab2(sch_1):page75_i19:vss(226)"
				( attribute "PN" "DF65"
					( Origin gPackager )
				)
				( objectStatus "U2D1.DF65" )
			)
			( pin "@baseboard_fab2_lib.baseboard_fab2(sch_1):page75_i19:vss(227)"
				( attribute "PN" "DF41"
					( Origin gPackager )
				)
				( objectStatus "U2D1.DF41" )
			)
			( pin "@baseboard_fab2_lib.baseboard_fab2(sch_1):page75_i19:vss(228)"
				( attribute "PN" "DF39"
					( Origin gPackager )
				)
				( objectStatus "U2D1.DF39" )
			)
			( pin "@baseboard_fab2_lib.baseboard_fab2(sch_1):page75_i19:vss(229)"
				( attribute "PN" "DF37"
					( Origin gPackager )
				)
				( objectStatus "U2D1.DF37" )
			)
			( pin "@baseboard_fab2_lib.baseboard_fab2(sch_1):page75_i19:vss(230)"
				( attribute "PN" "DF35"
					( Origin gPackager )
				)
				( objectStatus "U2D1.DF35" )
			)
			( pin "@baseboard_fab2_lib.baseboard_fab2(sch_1):page75_i19:vss(231)"
				( attribute "PN" "DF29"
					( Origin gPackager )
				)
				( objectStatus "U2D1.DF29" )
			)
			( pin "@baseboard_fab2_lib.baseboard_fab2(sch_1):page75_i19:vss(232)"
				( attribute "PN" "DF19"
					( Origin gPackager )
				)
				( objectStatus "U2D1.DF19" )
			)
			( pin "@baseboard_fab2_lib.baseboard_fab2(sch_1):page75_i19:vss(233)"
				( attribute "PN" "H51"
					( Origin gPackager )
				)
				( objectStatus "U2D1.H51" )
			)
			( pin "@baseboard_fab2_lib.baseboard_fab2(sch_1):page75_i19:vss(234)"
				( attribute "PN" "DF7"
					( Origin gPackager )
				)
				( objectStatus "U2D1.DF7" )
			)
			( pin "@baseboard_fab2_lib.baseboard_fab2(sch_1):page75_i19:vss(235)"
				( attribute "PN" "DF5"
					( Origin gPackager )
				)
				( objectStatus "U2D1.DF5" )
			)
			( pin "@baseboard_fab2_lib.baseboard_fab2(sch_1):page75_i19:vss(236)"
				( attribute "PN" "DE78"
					( Origin gPackager )
				)
				( objectStatus "U2D1.DE78" )
			)
			( pin "@baseboard_fab2_lib.baseboard_fab2(sch_1):page75_i19:vss(237)"
				( attribute "PN" "DE72"
					( Origin gPackager )
				)
				( objectStatus "U2D1.DE72" )
			)
			( pin "@baseboard_fab2_lib.baseboard_fab2(sch_1):page75_i19:vss(238)"
				( attribute "PN" "DE70"
					( Origin gPackager )
				)
				( objectStatus "U2D1.DE70" )
			)
			( pin "@baseboard_fab2_lib.baseboard_fab2(sch_1):page75_i19:vss(239)"
				( attribute "PN" "DE64"
					( Origin gPackager )
				)
				( objectStatus "U2D1.DE64" )
			)
			( pin "@baseboard_fab2_lib.baseboard_fab2(sch_1):page75_i19:vss(240)"
				( attribute "PN" "DE36"
					( Origin gPackager )
				)
				( objectStatus "U2D1.DE36" )
			)
			( pin "@baseboard_fab2_lib.baseboard_fab2(sch_1):page75_i19:vss(241)"
				( attribute "PN" "DE34"
					( Origin gPackager )
				)
				( objectStatus "U2D1.DE34" )
			)
			( pin "@baseboard_fab2_lib.baseboard_fab2(sch_1):page75_i19:vss(242)"
				( attribute "PN" "DE30"
					( Origin gPackager )
				)
				( objectStatus "U2D1.DE30" )
			)
			( pin "@baseboard_fab2_lib.baseboard_fab2(sch_1):page75_i19:vss(243)"
				( attribute "PN" "DE28"
					( Origin gPackager )
				)
				( objectStatus "U2D1.DE28" )
			)
			( pin "@baseboard_fab2_lib.baseboard_fab2(sch_1):page75_i19:vss(244)"
				( attribute "PN" "DE24"
					( Origin gPackager )
				)
				( objectStatus "U2D1.DE24" )
			)
			( pin "@baseboard_fab2_lib.baseboard_fab2(sch_1):page75_i19:vss(245)"
				( attribute "PN" "DE20"
					( Origin gPackager )
				)
				( objectStatus "U2D1.DE20" )
			)
			( pin "@baseboard_fab2_lib.baseboard_fab2(sch_1):page75_i19:vss(246)"
				( attribute "PN" "DE18"
					( Origin gPackager )
				)
				( objectStatus "U2D1.DE18" )
			)
			( pin "@baseboard_fab2_lib.baseboard_fab2(sch_1):page75_i19:vss(247)"
				( attribute "PN" "DE8"
					( Origin gPackager )
				)
				( objectStatus "U2D1.DE8" )
			)
			( pin "@baseboard_fab2_lib.baseboard_fab2(sch_1):page75_i19:vss(248)"
				( attribute "PN" "DE6"
					( Origin gPackager )
				)
				( objectStatus "U2D1.DE6" )
			)
			( pin "@baseboard_fab2_lib.baseboard_fab2(sch_1):page75_i19:vss(249)"
				( attribute "PN" "DD83"
					( Origin gPackager )
				)
				( objectStatus "U2D1.DD83" )
			)
			( pin "@baseboard_fab2_lib.baseboard_fab2(sch_1):page75_i19:vss(250)"
				( attribute "PN" "DD81"
					( Origin gPackager )
				)
				( objectStatus "U2D1.DD81" )
			)
			( pin "@baseboard_fab2_lib.baseboard_fab2(sch_1):page75_i19:vss(251)"
				( attribute "PN" "DD75"
					( Origin gPackager )
				)
				( objectStatus "U2D1.DD75" )
			)
			( pin "@baseboard_fab2_lib.baseboard_fab2(sch_1):page75_i19:vss(252)"
				( attribute "PN" "DD73"
					( Origin gPackager )
				)
				( objectStatus "U2D1.DD73" )
			)
			( pin "@baseboard_fab2_lib.baseboard_fab2(sch_1):page75_i19:vss(253)"
				( attribute "PN" "DD71"
					( Origin gPackager )
				)
				( objectStatus "U2D1.DD71" )
			)
			( pin "@baseboard_fab2_lib.baseboard_fab2(sch_1):page75_i19:vss(254)"
				( attribute "PN" "DD37"
					( Origin gPackager )
				)
				( objectStatus "U2D1.DD37" )
			)
			( pin "@baseboard_fab2_lib.baseboard_fab2(sch_1):page75_i19:vss(255)"
				( attribute "PN" "DD33"
					( Origin gPackager )
				)
				( objectStatus "U2D1.DD33" )
			)
			( pin "@baseboard_fab2_lib.baseboard_fab2(sch_1):page75_i19:vss(256)"
				( attribute "PN" "DD31"
					( Origin gPackager )
				)
				( objectStatus "U2D1.DD31" )
			)
			( pin "@baseboard_fab2_lib.baseboard_fab2(sch_1):page75_i19:vss(257)"
				( attribute "PN" "DD27"
					( Origin gPackager )
				)
				( objectStatus "U2D1.DD27" )
			)
			( pin "@baseboard_fab2_lib.baseboard_fab2(sch_1):page75_i19:vss(258)"
				( attribute "PN" "DD23"
					( Origin gPackager )
				)
				( objectStatus "U2D1.DD23" )
			)
			( pin "@baseboard_fab2_lib.baseboard_fab2(sch_1):page75_i19:vss(259)"
				( attribute "PN" "DD11"
					( Origin gPackager )
				)
				( objectStatus "U2D1.DD11" )
			)
			( pin "@baseboard_fab2_lib.baseboard_fab2(sch_1):page75_i19:vss(260)"
				( attribute "PN" "DC86"
					( Origin gPackager )
				)
				( objectStatus "U2D1.DC86" )
			)
			( pin "@baseboard_fab2_lib.baseboard_fab2(sch_1):page75_i19:vss(261)"
				( attribute "PN" "DC84"
					( Origin gPackager )
				)
				( objectStatus "U2D1.DC84" )
			)
			( pin "@baseboard_fab2_lib.baseboard_fab2(sch_1):page75_i19:vss(262)"
				( attribute "PN" "DC78"
					( Origin gPackager )
				)
				( objectStatus "U2D1.DC78" )
			)
			( pin "@baseboard_fab2_lib.baseboard_fab2(sch_1):page75_i19:vss(263)"
				( attribute "PN" "DC70"
					( Origin gPackager )
				)
				( objectStatus "U2D1.DC70" )
			)
			( pin "@baseboard_fab2_lib.baseboard_fab2(sch_1):page75_i19:vss(264)"
				( attribute "PN" "DC68"
					( Origin gPackager )
				)
				( objectStatus "U2D1.DC68" )
			)
			( pin "@baseboard_fab2_lib.baseboard_fab2(sch_1):page75_i19:vss(265)"
				( attribute "PN" "DC66"
					( Origin gPackager )
				)
				( objectStatus "U2D1.DC66" )
			)
			( pin "@baseboard_fab2_lib.baseboard_fab2(sch_1):page75_i19:vss(266)"
				( attribute "PN" "DC64"
					( Origin gPackager )
				)
				( objectStatus "U2D1.DC64" )
			)
			( pin "@baseboard_fab2_lib.baseboard_fab2(sch_1):page75_i19:vss(267)"
				( attribute "PN" "DC42"
					( Origin gPackager )
				)
				( objectStatus "U2D1.DC42" )
			)
			( pin "@baseboard_fab2_lib.baseboard_fab2(sch_1):page75_i19:vss(268)"
				( attribute "PN" "DC38"
					( Origin gPackager )
				)
				( objectStatus "U2D1.DC38" )
			)
			( pin "@baseboard_fab2_lib.baseboard_fab2(sch_1):page75_i19:vss(269)"
				( attribute "PN" "DC32"
					( Origin gPackager )
				)
				( objectStatus "U2D1.DC32" )
			)
			( pin "@baseboard_fab2_lib.baseboard_fab2(sch_1):page75_i19:vss(270)"
				( attribute "PN" "DC26"
					( Origin gPackager )
				)
				( objectStatus "U2D1.DC26" )
			)
			( pin "@baseboard_fab2_lib.baseboard_fab2(sch_1):page75_i19:vss(271)"
				( attribute "PN" "DC24"
					( Origin gPackager )
				)
				( objectStatus "U2D1.DC24" )
			)
			( pin "@baseboard_fab2_lib.baseboard_fab2(sch_1):page75_i19:vss(272)"
				( attribute "PN" "DC14"
					( Origin gPackager )
				)
				( objectStatus "U2D1.DC14" )
			)
			( pin "@baseboard_fab2_lib.baseboard_fab2(sch_1):page75_i19:vss(273)"
				( attribute "PN" "DB85"
					( Origin gPackager )
				)
				( objectStatus "U2D1.DB85" )
			)
			( pin "@baseboard_fab2_lib.baseboard_fab2(sch_1):page75_i19:vss(274)"
				( attribute "PN" "DB83"
					( Origin gPackager )
				)
				( objectStatus "U2D1.DB83" )
			)
			( pin "@baseboard_fab2_lib.baseboard_fab2(sch_1):page75_i19:vss(275)"
				( attribute "PN" "DB77"
					( Origin gPackager )
				)
				( objectStatus "U2D1.DB77" )
			)
			( pin "@baseboard_fab2_lib.baseboard_fab2(sch_1):page75_i19:vss(276)"
				( attribute "PN" "DB73"
					( Origin gPackager )
				)
				( objectStatus "U2D1.DB73" )
			)
			( pin "@baseboard_fab2_lib.baseboard_fab2(sch_1):page75_i19:vss(277)"
				( attribute "PN" "DB49"
					( Origin gPackager )
				)
				( objectStatus "U2D1.DB49" )
			)
			( pin "@baseboard_fab2_lib.baseboard_fab2(sch_1):page75_i19:vss(278)"
				( attribute "PN" "DB47"
					( Origin gPackager )
				)
				( objectStatus "U2D1.DB47" )
			)
			( pin "@baseboard_fab2_lib.baseboard_fab2(sch_1):page75_i19:vss(279)"
				( attribute "PN" "DB41"
					( Origin gPackager )
				)
				( objectStatus "U2D1.DB41" )
			)
			( pin "@baseboard_fab2_lib.baseboard_fab2(sch_1):page75_i19:vss(280)"
				( attribute "PN" "DB39"
					( Origin gPackager )
				)
				( objectStatus "U2D1.DB39" )
			)
			( pin "@baseboard_fab2_lib.baseboard_fab2(sch_1):page75_i19:vss(281)"
				( attribute "PN" "DB25"
					( Origin gPackager )
				)
				( objectStatus "U2D1.DB25" )
			)
			( pin "@baseboard_fab2_lib.baseboard_fab2(sch_1):page75_i19:vss(282)"
				( attribute "PN" "DB23"
					( Origin gPackager )
				)
				( objectStatus "U2D1.DB23" )
			)
			( pin "@baseboard_fab2_lib.baseboard_fab2(sch_1):page75_i19:vss(283)"
				( attribute "PN" "DB17"
					( Origin gPackager )
				)
				( objectStatus "U2D1.DB17" )
			)
			( pin "@baseboard_fab2_lib.baseboard_fab2(sch_1):page75_i19:vss(284)"
				( attribute "PN" "DB13"
					( Origin gPackager )
				)
				( objectStatus "U2D1.DB13" )
			)
			( pin "@baseboard_fab2_lib.baseboard_fab2(sch_1):page75_i19:vss(285)"
				( attribute "PN" "DB3"
					( Origin gPackager )
				)
				( objectStatus "U2D1.DB3" )
			)
			( pin "@baseboard_fab2_lib.baseboard_fab2(sch_1):page75_i19:vss(286)"
				( attribute "PN" "DA80"
					( Origin gPackager )
				)
				( objectStatus "U2D1.DA80" )
			)
			( pin "@baseboard_fab2_lib.baseboard_fab2(sch_1):page75_i19:vss(287)"
				( attribute "PN" "DA78"
					( Origin gPackager )
				)
				( objectStatus "U2D1.DA78" )
			)
			( pin "@baseboard_fab2_lib.baseboard_fab2(sch_1):page75_i19:vss(288)"
				( attribute "PN" "DA76"
					( Origin gPackager )
				)
				( objectStatus "U2D1.DA76" )
			)
			( pin "@baseboard_fab2_lib.baseboard_fab2(sch_1):page75_i19:vss(289)"
				( attribute "PN" "DA74"
					( Origin gPackager )
				)
				( objectStatus "U2D1.DA74" )
			)
			( pin "@baseboard_fab2_lib.baseboard_fab2(sch_1):page75_i19:vss(290)"
				( attribute "PN" "DA70"
					( Origin gPackager )
				)
				( objectStatus "U2D1.DA70" )
			)
			( pin "@baseboard_fab2_lib.baseboard_fab2(sch_1):page75_i19:vss(291)"
				( attribute "PN" "DA64"
					( Origin gPackager )
				)
				( objectStatus "U2D1.DA64" )
			)
			( pin "@baseboard_fab2_lib.baseboard_fab2(sch_1):page75_i19:vss(292)"
				( attribute "PN" "DA50"
					( Origin gPackager )
				)
				( objectStatus "U2D1.DA50" )
			)
			( pin "@baseboard_fab2_lib.baseboard_fab2(sch_1):page75_i19:vss(293)"
				( attribute "PN" "DA48"
					( Origin gPackager )
				)
				( objectStatus "U2D1.DA48" )
			)
			( pin "@baseboard_fab2_lib.baseboard_fab2(sch_1):page75_i20:vss(0)"
				( attribute "PN" "EF79"
					( Origin gPackager )
				)
				( objectStatus "U2D1.EF79" )
			)
			( pin "@baseboard_fab2_lib.baseboard_fab2(sch_1):page75_i20:vss(1)"
				( attribute "PN" "EF75"
					( Origin gPackager )
				)
				( objectStatus "U2D1.EF75" )
			)
			( pin "@baseboard_fab2_lib.baseboard_fab2(sch_1):page75_i20:vss(2)"
				( attribute "PN" "EF71"
					( Origin gPackager )
				)
				( objectStatus "U2D1.EF71" )
			)
			( pin "@baseboard_fab2_lib.baseboard_fab2(sch_1):page75_i20:vss(3)"
				( attribute "PN" "EE78"
					( Origin gPackager )
				)
				( objectStatus "U2D1.EE78" )
			)
			( pin "@baseboard_fab2_lib.baseboard_fab2(sch_1):page75_i20:vss(4)"
				( attribute "PN" "EE76"
					( Origin gPackager )
				)
				( objectStatus "U2D1.EE76" )
			)
			( pin "@baseboard_fab2_lib.baseboard_fab2(sch_1):page75_i20:vss(5)"
				( attribute "PN" "EE70"
					( Origin gPackager )
				)
				( objectStatus "U2D1.EE70" )
			)
			( pin "@baseboard_fab2_lib.baseboard_fab2(sch_1):page75_i20:vss(6)"
				( attribute "PN" "EE36"
					( Origin gPackager )
				)
				( objectStatus "U2D1.EE36" )
			)
			( pin "@baseboard_fab2_lib.baseboard_fab2(sch_1):page75_i20:vss(7)"
				( attribute "PN" "EE34"
					( Origin gPackager )
				)
				( objectStatus "U2D1.EE34" )
			)
			( pin "@baseboard_fab2_lib.baseboard_fab2(sch_1):page75_i20:vss(8)"
				( attribute "PN" "EE30"
					( Origin gPackager )
				)
				( objectStatus "U2D1.EE30" )
			)
			( pin "@baseboard_fab2_lib.baseboard_fab2(sch_1):page75_i20:vss(9)"
				( attribute "PN" "EE28"
					( Origin gPackager )
				)
				( objectStatus "U2D1.EE28" )
			)
			( pin "@baseboard_fab2_lib.baseboard_fab2(sch_1):page75_i20:vss(10)"
				( attribute "PN" "EE24"
					( Origin gPackager )
				)
				( objectStatus "U2D1.EE24" )
			)
			( pin "@baseboard_fab2_lib.baseboard_fab2(sch_1):page75_i20:vss(11)"
				( attribute "PN" "ED77"
					( Origin gPackager )
				)
				( objectStatus "U2D1.ED77" )
			)
			( pin "@baseboard_fab2_lib.baseboard_fab2(sch_1):page75_i20:vss(12)"
				( attribute "PN" "ED35"
					( Origin gPackager )
				)
				( objectStatus "U2D1.ED35" )
			)
			( pin "@baseboard_fab2_lib.baseboard_fab2(sch_1):page75_i20:vss(13)"
				( attribute "PN" "ED29"
					( Origin gPackager )
				)
				( objectStatus "U2D1.ED29" )
			)
			( pin "@baseboard_fab2_lib.baseboard_fab2(sch_1):page75_i20:vss(14)"
				( attribute "PN" "ED23"
					( Origin gPackager )
				)
				( objectStatus "U2D1.ED23" )
			)
			( pin "@baseboard_fab2_lib.baseboard_fab2(sch_1):page75_i20:vss(15)"
				( attribute "PN" "ED15"
					( Origin gPackager )
				)
				( objectStatus "U2D1.ED15" )
			)
			( pin "@baseboard_fab2_lib.baseboard_fab2(sch_1):page75_i20:vss(16)"
				( attribute "PN" "ED11"
					( Origin gPackager )
				)
				( objectStatus "U2D1.ED11" )
			)
			( pin "@baseboard_fab2_lib.baseboard_fab2(sch_1):page75_i20:vss(17)"
				( attribute "PN" "EC76"
					( Origin gPackager )
				)
				( objectStatus "U2D1.EC76" )
			)
			( pin "@baseboard_fab2_lib.baseboard_fab2(sch_1):page75_i20:vss(18)"
				( attribute "PN" "EC74"
					( Origin gPackager )
				)
				( objectStatus "U2D1.EC74" )
			)
			( pin "@baseboard_fab2_lib.baseboard_fab2(sch_1):page75_i20:vss(19)"
				( attribute "PN" "EC72"
					( Origin gPackager )
				)
				( objectStatus "U2D1.EC72" )
			)
			( pin "@baseboard_fab2_lib.baseboard_fab2(sch_1):page75_i20:vss(20)"
				( attribute "PN" "EC70"
					( Origin gPackager )
				)
				( objectStatus "U2D1.EC70" )
			)
			( pin "@baseboard_fab2_lib.baseboard_fab2(sch_1):page75_i20:vss(21)"
				( attribute "PN" "EC10"
					( Origin gPackager )
				)
				( objectStatus "U2D1.EC10" )
			)
			( pin "@baseboard_fab2_lib.baseboard_fab2(sch_1):page75_i20:vss(22)"
				( attribute "PN" "EB69"
					( Origin gPackager )
				)
				( objectStatus "U2D1.EB69" )
			)
			( pin "@baseboard_fab2_lib.baseboard_fab2(sch_1):page75_i20:vss(23)"
				( attribute "PN" "EB65"
					( Origin gPackager )
				)
				( objectStatus "U2D1.EB65" )
			)
			( pin "@baseboard_fab2_lib.baseboard_fab2(sch_1):page75_i20:vss(24)"
				( attribute "PN" "EB41"
					( Origin gPackager )
				)
				( objectStatus "U2D1.EB41" )
			)
			( pin "@baseboard_fab2_lib.baseboard_fab2(sch_1):page75_i20:vss(25)"
				( attribute "PN" "EB39"
					( Origin gPackager )
				)
				( objectStatus "U2D1.EB39" )
			)
			( pin "@baseboard_fab2_lib.baseboard_fab2(sch_1):page75_i20:vss(26)"
				( attribute "PN" "EB37"
					( Origin gPackager )
				)
				( objectStatus "U2D1.EB37" )
			)
			( pin "@baseboard_fab2_lib.baseboard_fab2(sch_1):page75_i20:vss(27)"
				( attribute "PN" "EB35"
					( Origin gPackager )
				)
				( objectStatus "U2D1.EB35" )
			)
			( pin "@baseboard_fab2_lib.baseboard_fab2(sch_1):page75_i20:vss(28)"
				( attribute "PN" "EB33"
					( Origin gPackager )
				)
				( objectStatus "U2D1.EB33" )
			)
			( pin "@baseboard_fab2_lib.baseboard_fab2(sch_1):page75_i20:vss(29)"
				( attribute "PN" "EB31"
					( Origin gPackager )
				)
				( objectStatus "U2D1.EB31" )
			)
			( pin "@baseboard_fab2_lib.baseboard_fab2(sch_1):page75_i20:vss(30)"
				( attribute "PN" "EB29"
					( Origin gPackager )
				)
				( objectStatus "U2D1.EB29" )
			)
			( pin "@baseboard_fab2_lib.baseboard_fab2(sch_1):page75_i20:vss(31)"
				( attribute "PN" "EB27"
					( Origin gPackager )
				)
				( objectStatus "U2D1.EB27" )
			)
			( pin "@baseboard_fab2_lib.baseboard_fab2(sch_1):page75_i20:vss(32)"
				( attribute "PN" "EB25"
					( Origin gPackager )
				)
				( objectStatus "U2D1.EB25" )
			)
			( pin "@baseboard_fab2_lib.baseboard_fab2(sch_1):page75_i20:vss(33)"
				( attribute "PN" "EB23"
					( Origin gPackager )
				)
				( objectStatus "U2D1.EB23" )
			)
			( pin "@baseboard_fab2_lib.baseboard_fab2(sch_1):page75_i20:vss(34)"
				( attribute "PN" "BR18"
					( Origin gPackager )
				)
				( objectStatus "U2D1.BR18" )
			)
			( pin "@baseboard_fab2_lib.baseboard_fab2(sch_1):page75_i20:vss(35)"
				( attribute "PN" "EB13"
					( Origin gPackager )
				)
				( objectStatus "U2D1.EB13" )
			)
			( pin "@baseboard_fab2_lib.baseboard_fab2(sch_1):page75_i20:vss(36)"
				( attribute "PN" "EA82"
					( Origin gPackager )
				)
				( objectStatus "U2D1.EA82" )
			)
			( pin "@baseboard_fab2_lib.baseboard_fab2(sch_1):page75_i20:vss(37)"
				( attribute "PN" "EA80"
					( Origin gPackager )
				)
				( objectStatus "U2D1.EA80" )
			)
			( pin "@baseboard_fab2_lib.baseboard_fab2(sch_1):page75_i20:vss(38)"
				( attribute "PN" "EA78"
					( Origin gPackager )
				)
				( objectStatus "U2D1.EA78" )
			)
			( pin "@baseboard_fab2_lib.baseboard_fab2(sch_1):page75_i20:vss(39)"
				( attribute "PN" "EA76"
					( Origin gPackager )
				)
				( objectStatus "U2D1.EA76" )
			)
			( pin "@baseboard_fab2_lib.baseboard_fab2(sch_1):page75_i20:vss(40)"
				( attribute "PN" "EA70"
					( Origin gPackager )
				)
				( objectStatus "U2D1.EA70" )
			)
			( pin "@baseboard_fab2_lib.baseboard_fab2(sch_1):page75_i20:vss(41)"
				( attribute "PN" "EA64"
					( Origin gPackager )
				)
				( objectStatus "U2D1.EA64" )
			)
			( pin "@baseboard_fab2_lib.baseboard_fab2(sch_1):page75_i20:vss(42)"
				( attribute "PN" "EA42"
					( Origin gPackager )
				)
				( objectStatus "U2D1.EA42" )
			)
			( pin "@baseboard_fab2_lib.baseboard_fab2(sch_1):page75_i20:vss(43)"
				( attribute "PN" "EA22"
					( Origin gPackager )
				)
				( objectStatus "U2D1.EA22" )
			)
			( pin "@baseboard_fab2_lib.baseboard_fab2(sch_1):page75_i20:vss(44)"
				( attribute "PN" "EA20"
					( Origin gPackager )
				)
				( objectStatus "U2D1.EA20" )
			)
			( pin "@baseboard_fab2_lib.baseboard_fab2(sch_1):page75_i20:vss(45)"
				( attribute "PN" "EA16"
					( Origin gPackager )
				)
				( objectStatus "U2D1.EA16" )
			)
			( pin "@baseboard_fab2_lib.baseboard_fab2(sch_1):page75_i20:vss(46)"
				( attribute "PN" "J16"
					( Origin gPackager )
				)
				( objectStatus "U2D1.J16" )
			)
			( pin "@baseboard_fab2_lib.baseboard_fab2(sch_1):page75_i20:vss(47)"
				( attribute "PN" "EA6"
					( Origin gPackager )
				)
				( objectStatus "U2D1.EA6" )
			)
			( pin "@baseboard_fab2_lib.baseboard_fab2(sch_1):page75_i20:vss(48)"
				( attribute "PN" "DY75"
					( Origin gPackager )
				)
				( objectStatus "U2D1.DY75" )
			)
			( pin "@baseboard_fab2_lib.baseboard_fab2(sch_1):page75_i20:vss(49)"
				( attribute "PN" "DY71"
					( Origin gPackager )
				)
				( objectStatus "U2D1.DY71" )
			)
			( pin "@baseboard_fab2_lib.baseboard_fab2(sch_1):page75_i20:vss(50)"
				( attribute "PN" "DY41"
					( Origin gPackager )
				)
				( objectStatus "U2D1.DY41" )
			)
			( pin "@baseboard_fab2_lib.baseboard_fab2(sch_1):page75_i20:vss(51)"
				( attribute "PN" "DY35"
					( Origin gPackager )
				)
				( objectStatus "U2D1.DY35" )
			)
			( pin "@baseboard_fab2_lib.baseboard_fab2(sch_1):page75_i20:vss(52)"
				( attribute "PN" "DY29"
					( Origin gPackager )
				)
				( objectStatus "U2D1.DY29" )
			)
			( pin "@baseboard_fab2_lib.baseboard_fab2(sch_1):page75_i20:vss(53)"
				( attribute "PN" "DY23"
					( Origin gPackager )
				)
				( objectStatus "U2D1.DY23" )
			)
			( pin "@baseboard_fab2_lib.baseboard_fab2(sch_1):page75_i20:vss(54)"
				( attribute "PN" "DY19"
					( Origin gPackager )
				)
				( objectStatus "U2D1.DY19" )
			)
			( pin "@baseboard_fab2_lib.baseboard_fab2(sch_1):page75_i20:vss(55)"
				( attribute "PN" "DY5"
					( Origin gPackager )
				)
				( objectStatus "U2D1.DY5" )
			)
			( pin "@baseboard_fab2_lib.baseboard_fab2(sch_1):page75_i20:vss(56)"
				( attribute "PN" "DW84"
					( Origin gPackager )
				)
				( objectStatus "U2D1.DW84" )
			)
			( pin "@baseboard_fab2_lib.baseboard_fab2(sch_1):page75_i20:vss(57)"
				( attribute "PN" "DW82"
					( Origin gPackager )
				)
				( objectStatus "U2D1.DW82" )
			)
			( pin "@baseboard_fab2_lib.baseboard_fab2(sch_1):page75_i20:vss(58)"
				( attribute "PN" "DW8"
					( Origin gPackager )
				)
				( objectStatus "U2D1.DW8" )
			)
			( pin "@baseboard_fab2_lib.baseboard_fab2(sch_1):page75_i20:vss(59)"
				( attribute "PN" "DW76"
					( Origin gPackager )
				)
				( objectStatus "U2D1.DW76" )
			)
			( pin "@baseboard_fab2_lib.baseboard_fab2(sch_1):page75_i20:vss(60)"
				( attribute "PN" "DW74"
					( Origin gPackager )
				)
				( objectStatus "U2D1.DW74" )
			)
			( pin "@baseboard_fab2_lib.baseboard_fab2(sch_1):page75_i20:vss(61)"
				( attribute "PN" "DW72"
					( Origin gPackager )
				)
				( objectStatus "U2D1.DW72" )
			)
			( pin "@baseboard_fab2_lib.baseboard_fab2(sch_1):page75_i20:vss(62)"
				( attribute "PN" "DW70"
					( Origin gPackager )
				)
				( objectStatus "U2D1.DW70" )
			)
			( pin "@baseboard_fab2_lib.baseboard_fab2(sch_1):page75_i20:vss(63)"
				( attribute "PN" "DW68"
					( Origin gPackager )
				)
				( objectStatus "U2D1.DW68" )
			)
			( pin "@baseboard_fab2_lib.baseboard_fab2(sch_1):page75_i20:vss(64)"
				( attribute "PN" "DW66"
					( Origin gPackager )
				)
				( objectStatus "U2D1.DW66" )
			)
			( pin "@baseboard_fab2_lib.baseboard_fab2(sch_1):page75_i20:vss(65)"
				( attribute "PN" "DW64"
					( Origin gPackager )
				)
				( objectStatus "U2D1.DW64" )
			)
			( pin "@baseboard_fab2_lib.baseboard_fab2(sch_1):page75_i20:vss(66)"
				( attribute "PN" "DW40"
					( Origin gPackager )
				)
				( objectStatus "U2D1.DW40" )
			)
			( pin "@baseboard_fab2_lib.baseboard_fab2(sch_1):page75_i20:vss(67)"
				( attribute "PN" "DW36"
					( Origin gPackager )
				)
				( objectStatus "U2D1.DW36" )
			)
			( pin "@baseboard_fab2_lib.baseboard_fab2(sch_1):page75_i20:vss(68)"
				( attribute "PN" "DW34"
					( Origin gPackager )
				)
				( objectStatus "U2D1.DW34" )
			)
			( pin "@baseboard_fab2_lib.baseboard_fab2(sch_1):page75_i20:vss(69)"
				( attribute "PN" "DW30"
					( Origin gPackager )
				)
				( objectStatus "U2D1.DW30" )
			)
			( pin "@baseboard_fab2_lib.baseboard_fab2(sch_1):page75_i20:vss(70)"
				( attribute "PN" "DW28"
					( Origin gPackager )
				)
				( objectStatus "U2D1.DW28" )
			)
			( pin "@baseboard_fab2_lib.baseboard_fab2(sch_1):page75_i20:vss(71)"
				( attribute "PN" "DW24"
					( Origin gPackager )
				)
				( objectStatus "U2D1.DW24" )
			)
			( pin "@baseboard_fab2_lib.baseboard_fab2(sch_1):page75_i20:vss(72)"
				( attribute "PN" "DW20"
					( Origin gPackager )
				)
				( objectStatus "U2D1.DW20" )
			)
			( pin "@baseboard_fab2_lib.baseboard_fab2(sch_1):page75_i20:vss(73)"
				( attribute "PN" "DW12"
					( Origin gPackager )
				)
				( objectStatus "U2D1.DW12" )
			)
			( pin "@baseboard_fab2_lib.baseboard_fab2(sch_1):page75_i20:vss(74)"
				( attribute "PN" "DV81"
					( Origin gPackager )
				)
				( objectStatus "U2D1.DV81" )
			)
			( pin "@baseboard_fab2_lib.baseboard_fab2(sch_1):page75_i20:vss(75)"
				( attribute "PN" "DV77"
					( Origin gPackager )
				)
				( objectStatus "U2D1.DV77" )
			)
			( pin "@baseboard_fab2_lib.baseboard_fab2(sch_1):page75_i20:vss(76)"
				( attribute "PN" "DV73"
					( Origin gPackager )
				)
				( objectStatus "U2D1.DV73" )
			)
			( pin "@baseboard_fab2_lib.baseboard_fab2(sch_1):page75_i20:vss(77)"
				( attribute "PN" "DV39"
					( Origin gPackager )
				)
				( objectStatus "U2D1.DV39" )
			)
			( pin "@baseboard_fab2_lib.baseboard_fab2(sch_1):page75_i20:vss(78)"
				( attribute "PN" "DV37"
					( Origin gPackager )
				)
				( objectStatus "U2D1.DV37" )
			)
			( pin "@baseboard_fab2_lib.baseboard_fab2(sch_1):page75_i20:vss(79)"
				( attribute "PN" "DV33"
					( Origin gPackager )
				)
				( objectStatus "U2D1.DV33" )
			)
			( pin "@baseboard_fab2_lib.baseboard_fab2(sch_1):page75_i20:vss(80)"
				( attribute "PN" "DV31"
					( Origin gPackager )
				)
				( objectStatus "U2D1.DV31" )
			)
			( pin "@baseboard_fab2_lib.baseboard_fab2(sch_1):page75_i20:vss(81)"
				( attribute "PN" "DV27"
					( Origin gPackager )
				)
				( objectStatus "U2D1.DV27" )
			)
			( pin "@baseboard_fab2_lib.baseboard_fab2(sch_1):page75_i20:vss(82)"
				( attribute "PN" "DV25"
					( Origin gPackager )
				)
				( objectStatus "U2D1.DV25" )
			)
			( pin "@baseboard_fab2_lib.baseboard_fab2(sch_1):page75_i20:vss(83)"
				( attribute "PN" "DV21"
					( Origin gPackager )
				)
				( objectStatus "U2D1.DV21" )
			)
			( pin "@baseboard_fab2_lib.baseboard_fab2(sch_1):page75_i20:vss(84)"
				( attribute "PN" "DU84"
					( Origin gPackager )
				)
				( objectStatus "U2D1.DU84" )
			)
			( pin "@baseboard_fab2_lib.baseboard_fab2(sch_1):page75_i20:vss(85)"
				( attribute "PN" "DU82"
					( Origin gPackager )
				)
				( objectStatus "U2D1.DU82" )
			)
			( pin "@baseboard_fab2_lib.baseboard_fab2(sch_1):page75_i20:vss(86)"
				( attribute "PN" "DU80"
					( Origin gPackager )
				)
				( objectStatus "U2D1.DU80" )
			)
			( pin "@baseboard_fab2_lib.baseboard_fab2(sch_1):page75_i20:vss(87)"
				( attribute "PN" "DU78"
					( Origin gPackager )
				)
				( objectStatus "U2D1.DU78" )
			)
			( pin "@baseboard_fab2_lib.baseboard_fab2(sch_1):page75_i20:vss(88)"
				( attribute "PN" "DU72"
					( Origin gPackager )
				)
				( objectStatus "U2D1.DU72" )
			)
			( pin "@baseboard_fab2_lib.baseboard_fab2(sch_1):page75_i20:vss(89)"
				( attribute "PN" "DU70"
					( Origin gPackager )
				)
				( objectStatus "U2D1.DU70" )
			)
			( pin "@baseboard_fab2_lib.baseboard_fab2(sch_1):page75_i20:vss(90)"
				( attribute "PN" "DU38"
					( Origin gPackager )
				)
				( objectStatus "U2D1.DU38" )
			)
			( pin "@baseboard_fab2_lib.baseboard_fab2(sch_1):page75_i20:vss(91)"
				( attribute "PN" "DU32"
					( Origin gPackager )
				)
				( objectStatus "U2D1.DU32" )
			)
			( pin "@baseboard_fab2_lib.baseboard_fab2(sch_1):page75_i20:vss(92)"
				( attribute "PN" "DU26"
					( Origin gPackager )
				)
				( objectStatus "U2D1.DU26" )
			)
			( pin "@baseboard_fab2_lib.baseboard_fab2(sch_1):page75_i20:vss(93)"
				( attribute "PN" "DU22"
					( Origin gPackager )
				)
				( objectStatus "U2D1.DU22" )
			)
			( pin "@baseboard_fab2_lib.baseboard_fab2(sch_1):page75_i20:vss(94)"
				( attribute "PN" "CN14"
					( Origin gPackager )
				)
				( objectStatus "U2D1.CN14" )
			)
			( pin "@baseboard_fab2_lib.baseboard_fab2(sch_1):page75_i20:vss(95)"
				( attribute "PN" "DU14"
					( Origin gPackager )
				)
				( objectStatus "U2D1.DU14" )
			)
			( pin "@baseboard_fab2_lib.baseboard_fab2(sch_1):page75_i20:vss(96)"
				( attribute "PN" "DU10"
					( Origin gPackager )
				)
				( objectStatus "U2D1.DU10" )
			)
			( pin "@baseboard_fab2_lib.baseboard_fab2(sch_1):page75_i20:vss(97)"
				( attribute "PN" "DT85"
					( Origin gPackager )
				)
				( objectStatus "U2D1.DT85" )
			)
			( pin "@baseboard_fab2_lib.baseboard_fab2(sch_1):page75_i20:vss(98)"
				( attribute "PN" "DT83"
					( Origin gPackager )
				)
				( objectStatus "U2D1.DT83" )
			)
			( pin "@baseboard_fab2_lib.baseboard_fab2(sch_1):page75_i20:vss(99)"
				( attribute "PN" "DT79"
					( Origin gPackager )
				)
				( objectStatus "U2D1.DT79" )
			)
			( pin "@baseboard_fab2_lib.baseboard_fab2(sch_1):page75_i20:vss(100)"
				( attribute "PN" "DT69"
					( Origin gPackager )
				)
				( objectStatus "U2D1.DT69" )
			)
			( pin "@baseboard_fab2_lib.baseboard_fab2(sch_1):page75_i20:vss(101)"
				( attribute "PN" "DT65"
					( Origin gPackager )
				)
				( objectStatus "U2D1.DT65" )
			)
			( pin "@baseboard_fab2_lib.baseboard_fab2(sch_1):page75_i20:vss(102)"
				( attribute "PN" "DH21"
					( Origin gPackager )
				)
				( objectStatus "U2D1.DH21" )
			)
			( pin "@baseboard_fab2_lib.baseboard_fab2(sch_1):page75_i20:vss(103)"
				( attribute "PN" "DT17"
					( Origin gPackager )
				)
				( objectStatus "U2D1.DT17" )
			)
			( pin "@baseboard_fab2_lib.baseboard_fab2(sch_1):page75_i20:vss(104)"
				( attribute "PN" "DT3"
					( Origin gPackager )
				)
				( objectStatus "U2D1.DT3" )
			)
			( pin "@baseboard_fab2_lib.baseboard_fab2(sch_1):page75_i20:vss(105)"
				( attribute "PN" "DR78"
					( Origin gPackager )
				)
				( objectStatus "U2D1.DR78" )
			)
			( pin "@baseboard_fab2_lib.baseboard_fab2(sch_1):page75_i20:vss(106)"
				( attribute "PN" "DR76"
					( Origin gPackager )
				)
				( objectStatus "U2D1.DR76" )
			)
			( pin "@baseboard_fab2_lib.baseboard_fab2(sch_1):page75_i20:vss(107)"
				( attribute "PN" "DR74"
					( Origin gPackager )
				)
				( objectStatus "U2D1.DR74" )
			)
			( pin "@baseboard_fab2_lib.baseboard_fab2(sch_1):page75_i20:vss(108)"
				( attribute "PN" "DR72"
					( Origin gPackager )
				)
				( objectStatus "U2D1.DR72" )
			)
			( pin "@baseboard_fab2_lib.baseboard_fab2(sch_1):page75_i20:vss(109)"
				( attribute "PN" "DR70"
					( Origin gPackager )
				)
				( objectStatus "U2D1.DR70" )
			)
			( pin "@baseboard_fab2_lib.baseboard_fab2(sch_1):page75_i20:vss(110)"
				( attribute "PN" "DR68"
					( Origin gPackager )
				)
				( objectStatus "U2D1.DR68" )
			)
			( pin "@baseboard_fab2_lib.baseboard_fab2(sch_1):page75_i20:vss(111)"
				( attribute "PN" "DR66"
					( Origin gPackager )
				)
				( objectStatus "U2D1.DR66" )
			)
			( pin "@baseboard_fab2_lib.baseboard_fab2(sch_1):page75_i20:vss(112)"
				( attribute "PN" "DR42"
					( Origin gPackager )
				)
				( objectStatus "U2D1.DR42" )
			)
			( pin "@baseboard_fab2_lib.baseboard_fab2(sch_1):page75_i20:vss(113)"
				( attribute "PN" "DR40"
					( Origin gPackager )
				)
				( objectStatus "U2D1.DR40" )
			)
			( pin "@baseboard_fab2_lib.baseboard_fab2(sch_1):page75_i20:vss(114)"
				( attribute "PN" "DR38"
					( Origin gPackager )
				)
				( objectStatus "U2D1.DR38" )
			)
			( pin "@baseboard_fab2_lib.baseboard_fab2(sch_1):page75_i20:vss(115)"
				( attribute "PN" "DR36"
					( Origin gPackager )
				)
				( objectStatus "U2D1.DR36" )
			)
			( pin "@baseboard_fab2_lib.baseboard_fab2(sch_1):page75_i20:vss(116)"
				( attribute "PN" "DR34"
					( Origin gPackager )
				)
				( objectStatus "U2D1.DR34" )
			)
			( pin "@baseboard_fab2_lib.baseboard_fab2(sch_1):page75_i20:vss(117)"
				( attribute "PN" "DR32"
					( Origin gPackager )
				)
				( objectStatus "U2D1.DR32" )
			)
			( pin "@baseboard_fab2_lib.baseboard_fab2(sch_1):page75_i20:vss(118)"
				( attribute "PN" "DR30"
					( Origin gPackager )
				)
				( objectStatus "U2D1.DR30" )
			)
			( pin "@baseboard_fab2_lib.baseboard_fab2(sch_1):page75_i20:vss(119)"
				( attribute "PN" "DR28"
					( Origin gPackager )
				)
				( objectStatus "U2D1.DR28" )
			)
			( pin "@baseboard_fab2_lib.baseboard_fab2(sch_1):page75_i20:vss(120)"
				( attribute "PN" "DR26"
					( Origin gPackager )
				)
				( objectStatus "U2D1.DR26" )
			)
			( pin "@baseboard_fab2_lib.baseboard_fab2(sch_1):page75_i20:vss(121)"
				( attribute "PN" "DR24"
					( Origin gPackager )
				)
				( objectStatus "U2D1.DR24" )
			)
			( pin "@baseboard_fab2_lib.baseboard_fab2(sch_1):page75_i20:vss(122)"
				( attribute "PN" "DR22"
					( Origin gPackager )
				)
				( objectStatus "U2D1.DR22" )
			)
			( pin "@baseboard_fab2_lib.baseboard_fab2(sch_1):page75_i20:vss(123)"
				( attribute "PN" "DR20"
					( Origin gPackager )
				)
				( objectStatus "U2D1.DR20" )
			)
			( pin "@baseboard_fab2_lib.baseboard_fab2(sch_1):page75_i20:vss(124)"
				( attribute "PN" "CL22"
					( Origin gPackager )
				)
				( objectStatus "U2D1.CL22" )
			)
			( pin "@baseboard_fab2_lib.baseboard_fab2(sch_1):page75_i20:vss(125)"
				( attribute "PN" "CA20"
					( Origin gPackager )
				)
				( objectStatus "U2D1.CA20" )
			)
			( pin "@baseboard_fab2_lib.baseboard_fab2(sch_1):page75_i20:vss(126)"
				( attribute "PN" "DR6"
					( Origin gPackager )
				)
				( objectStatus "U2D1.DR6" )
			)
			( pin "@baseboard_fab2_lib.baseboard_fab2(sch_1):page75_i20:vss(127)"
				( attribute "PN" "BR26"
					( Origin gPackager )
				)
				( objectStatus "U2D1.BR26" )
			)
			( pin "@baseboard_fab2_lib.baseboard_fab2(sch_1):page75_i20:vss(128)"
				( attribute "PN" "DP83"
					( Origin gPackager )
				)
				( objectStatus "U2D1.DP83" )
			)
			( pin "@baseboard_fab2_lib.baseboard_fab2(sch_1):page75_i20:vss(129)"
				( attribute "PN" "DP81"
					( Origin gPackager )
				)
				( objectStatus "U2D1.DP81" )
			)
			( pin "@baseboard_fab2_lib.baseboard_fab2(sch_1):page75_i20:vss(130)"
				( attribute "PN" "DP71"
					( Origin gPackager )
				)
				( objectStatus "U2D1.DP71" )
			)
			( pin "@baseboard_fab2_lib.baseboard_fab2(sch_1):page75_i20:vss(131)"
				( attribute "PN" "DP69"
					( Origin gPackager )
				)
				( objectStatus "U2D1.DP69" )
			)
			( pin "@baseboard_fab2_lib.baseboard_fab2(sch_1):page75_i20:vss(132)"
				( attribute "PN" "DP67"
					( Origin gPackager )
				)
				( objectStatus "U2D1.DP67" )
			)
			( pin "@baseboard_fab2_lib.baseboard_fab2(sch_1):page75_i20:vss(133)"
				( attribute "PN" "DN78"
					( Origin gPackager )
				)
				( objectStatus "U2D1.DN78" )
			)
			( pin "@baseboard_fab2_lib.baseboard_fab2(sch_1):page76_i1:a"
				( attribute "PN" "1"
					( Origin gPackager )
				)
				( objectStatus "C3D21.1" )
			)
			( pin "@baseboard_fab2_lib.baseboard_fab2(sch_1):page76_i1:b"
				( attribute "PN" "2"
					( Origin gPackager )
				)
				( objectStatus "C3D21.2" )
			)
			( pin "@baseboard_fab2_lib.baseboard_fab2(sch_1):page76_i3:a"
				( attribute "PN" "1"
					( Origin gPackager )
				)
				( objectStatus "C3D5.1" )
			)
			( pin "@baseboard_fab2_lib.baseboard_fab2(sch_1):page76_i3:b"
				( attribute "PN" "2"
					( Origin gPackager )
				)
				( objectStatus "C3D5.2" )
			)
			( pin "@baseboard_fab2_lib.baseboard_fab2(sch_1):page76_i4:a"
				( attribute "PN" "1"
					( Origin gPackager )
				)
				( objectStatus "C3D12.1" )
			)
			( pin "@baseboard_fab2_lib.baseboard_fab2(sch_1):page76_i4:b"
				( attribute "PN" "2"
					( Origin gPackager )
				)
				( objectStatus "C3D12.2" )
			)
			( pin "@baseboard_fab2_lib.baseboard_fab2(sch_1):page76_i5:a"
				( attribute "PN" "1"
					( Origin gPackager )
				)
				( objectStatus "C3D4.1" )
			)
			( pin "@baseboard_fab2_lib.baseboard_fab2(sch_1):page76_i5:b"
				( attribute "PN" "2"
					( Origin gPackager )
				)
				( objectStatus "C3D4.2" )
			)
			( pin "@baseboard_fab2_lib.baseboard_fab2(sch_1):page76_i7:a"
				( attribute "PN" "1"
					( Origin gPackager )
				)
				( objectStatus "C3D11.1" )
			)
			( pin "@baseboard_fab2_lib.baseboard_fab2(sch_1):page76_i7:b"
				( attribute "PN" "2"
					( Origin gPackager )
				)
				( objectStatus "C3D11.2" )
			)
			( pin "@baseboard_fab2_lib.baseboard_fab2(sch_1):page76_i8:a"
				( attribute "PN" "1"
					( Origin gPackager )
				)
				( objectStatus "C3D13.1" )
			)
			( pin "@baseboard_fab2_lib.baseboard_fab2(sch_1):page76_i8:b"
				( attribute "PN" "2"
					( Origin gPackager )
				)
				( objectStatus "C3D13.2" )
			)
			( pin "@baseboard_fab2_lib.baseboard_fab2(sch_1):page76_i10:a"
				( attribute "PN" "1"
					( Origin gPackager )
				)
				( objectStatus "C2D40.1" )
			)
			( pin "@baseboard_fab2_lib.baseboard_fab2(sch_1):page76_i10:b"
				( attribute "PN" "2"
					( Origin gPackager )
				)
				( objectStatus "C2D40.2" )
			)
			( pin "@baseboard_fab2_lib.baseboard_fab2(sch_1):page76_i15:a"
				( attribute "PN" "1"
					( Origin gPackager )
				)
				( objectStatus "C3D9.1" )
			)
			( pin "@baseboard_fab2_lib.baseboard_fab2(sch_1):page76_i15:b"
				( attribute "PN" "2"
					( Origin gPackager )
				)
				( objectStatus "C3D9.2" )
			)
			( pin "@baseboard_fab2_lib.baseboard_fab2(sch_1):page76_i18:a"
				( attribute "PN" "1"
					( Origin gPackager )
				)
				( objectStatus "C3D8.1" )
			)
			( pin "@baseboard_fab2_lib.baseboard_fab2(sch_1):page76_i18:b"
				( attribute "PN" "2"
					( Origin gPackager )
				)
				( objectStatus "C3D8.2" )
			)
			( pin "@baseboard_fab2_lib.baseboard_fab2(sch_1):page76_i271:a"
				( attribute "PN" "1"
					( Origin gPackager )
				)
				( objectStatus "C7P4.1" )
			)
			( pin "@baseboard_fab2_lib.baseboard_fab2(sch_1):page76_i271:b"
				( attribute "PN" "2"
					( Origin gPackager )
				)
				( objectStatus "C7P4.2" )
			)
			( pin "@baseboard_fab2_lib.baseboard_fab2(sch_1):page76_i270:a"
				( attribute "PN" "1"
					( Origin gPackager )
				)
				( objectStatus "C8P15.1" )
			)
			( pin "@baseboard_fab2_lib.baseboard_fab2(sch_1):page76_i270:b"
				( attribute "PN" "2"
					( Origin gPackager )
				)
				( objectStatus "C8P15.2" )
			)
			( pin "@baseboard_fab2_lib.baseboard_fab2(sch_1):page76_i269:a"
				( attribute "PN" "1"
					( Origin gPackager )
				)
				( objectStatus "C7P13.1" )
			)
			( pin "@baseboard_fab2_lib.baseboard_fab2(sch_1):page76_i269:b"
				( attribute "PN" "2"
					( Origin gPackager )
				)
				( objectStatus "C7P13.2" )
			)
			( pin "@baseboard_fab2_lib.baseboard_fab2(sch_1):page76_i29:a"
				( attribute "PN" "1"
					( Origin gPackager )
				)
				( objectStatus "C7P17.1" )
			)
			( pin "@baseboard_fab2_lib.baseboard_fab2(sch_1):page76_i29:b"
				( attribute "PN" "2"
					( Origin gPackager )
				)
				( objectStatus "C7P17.2" )
			)
			( pin "@baseboard_fab2_lib.baseboard_fab2(sch_1):page76_i33:a"
				( attribute "PN" "1"
					( Origin gPackager )
				)
				( objectStatus "C2D8.1" )
			)
			( pin "@baseboard_fab2_lib.baseboard_fab2(sch_1):page76_i33:b"
				( attribute "PN" "2"
					( Origin gPackager )
				)
				( objectStatus "C2D8.2" )
			)
			( pin "@baseboard_fab2_lib.baseboard_fab2(sch_1):page76_i37:a"
				( attribute "PN" "1"
					( Origin gPackager )
				)
				( objectStatus "C2D10.1" )
			)
			( pin "@baseboard_fab2_lib.baseboard_fab2(sch_1):page76_i37:b"
				( attribute "PN" "2"
					( Origin gPackager )
				)
				( objectStatus "C2D10.2" )
			)
			( pin "@baseboard_fab2_lib.baseboard_fab2(sch_1):page76_i42:a"
				( attribute "PN" "1"
					( Origin gPackager )
				)
				( objectStatus "C2D11.1" )
			)
			( pin "@baseboard_fab2_lib.baseboard_fab2(sch_1):page76_i42:b"
				( attribute "PN" "2"
					( Origin gPackager )
				)
				( objectStatus "C2D11.2" )
			)
			( pin "@baseboard_fab2_lib.baseboard_fab2(sch_1):page76_i43:a"
				( attribute "PN" "1"
					( Origin gPackager )
				)
				( objectStatus "C2D9.1" )
			)
			( pin "@baseboard_fab2_lib.baseboard_fab2(sch_1):page76_i43:b"
				( attribute "PN" "2"
					( Origin gPackager )
				)
				( objectStatus "C2D9.2" )
			)
			( pin "@baseboard_fab2_lib.baseboard_fab2(sch_1):page76_i265:a"
				( attribute "PN" "1"
					( Origin gPackager )
				)
				( objectStatus "C7P8.1" )
			)
			( pin "@baseboard_fab2_lib.baseboard_fab2(sch_1):page76_i265:b"
				( attribute "PN" "2"
					( Origin gPackager )
				)
				( objectStatus "C7P8.2" )
			)
			( pin "@baseboard_fab2_lib.baseboard_fab2(sch_1):page76_i263:a"
				( attribute "PN" "1"
					( Origin gPackager )
				)
				( objectStatus "C7P15.1" )
			)
			( pin "@baseboard_fab2_lib.baseboard_fab2(sch_1):page76_i263:b"
				( attribute "PN" "2"
					( Origin gPackager )
				)
				( objectStatus "C7P15.2" )
			)
			( pin "@baseboard_fab2_lib.baseboard_fab2(sch_1):page76_i262:a"
				( attribute "PN" "1"
					( Origin gPackager )
				)
				( objectStatus "C7P11.1" )
			)
			( pin "@baseboard_fab2_lib.baseboard_fab2(sch_1):page76_i262:b"
				( attribute "PN" "2"
					( Origin gPackager )
				)
				( objectStatus "C7P11.2" )
			)
			( pin "@baseboard_fab2_lib.baseboard_fab2(sch_1):page76_i251:a"
				( attribute "PN" "1"
					( Origin gPackager )
				)
				( objectStatus "C8P25.1" )
			)
			( pin "@baseboard_fab2_lib.baseboard_fab2(sch_1):page76_i251:b"
				( attribute "PN" "2"
					( Origin gPackager )
				)
				( objectStatus "C8P25.2" )
			)
			( pin "@baseboard_fab2_lib.baseboard_fab2(sch_1):page76_i51:a"
				( attribute "PN" "1"
					( Origin gPackager )
				)
				( objectStatus "C7P18.1" )
			)
			( pin "@baseboard_fab2_lib.baseboard_fab2(sch_1):page76_i51:b"
				( attribute "PN" "2"
					( Origin gPackager )
				)
				( objectStatus "C7P18.2" )
			)
			( pin "@baseboard_fab2_lib.baseboard_fab2(sch_1):page76_i52:a"
				( attribute "PN" "1"
					( Origin gPackager )
				)
				( objectStatus "C7P3.1" )
			)
			( pin "@baseboard_fab2_lib.baseboard_fab2(sch_1):page76_i52:b"
				( attribute "PN" "2"
					( Origin gPackager )
				)
				( objectStatus "C7P3.2" )
			)
			( pin "@baseboard_fab2_lib.baseboard_fab2(sch_1):page76_i250:a"
				( attribute "PN" "1"
					( Origin gPackager )
				)
				( objectStatus "C8P27.1" )
			)
			( pin "@baseboard_fab2_lib.baseboard_fab2(sch_1):page76_i250:b"
				( attribute "PN" "2"
					( Origin gPackager )
				)
				( objectStatus "C8P27.2" )
			)
			( pin "@baseboard_fab2_lib.baseboard_fab2(sch_1):page76_i249:a"
				( attribute "PN" "1"
					( Origin gPackager )
				)
				( objectStatus "C8P21.1" )
			)
			( pin "@baseboard_fab2_lib.baseboard_fab2(sch_1):page76_i249:b"
				( attribute "PN" "2"
					( Origin gPackager )
				)
				( objectStatus "C8P21.2" )
			)
			( pin "@baseboard_fab2_lib.baseboard_fab2(sch_1):page76_i59:a"
				( attribute "PN" "1"
					( Origin gPackager )
				)
				( objectStatus "C2D12.1" )
			)
			( pin "@baseboard_fab2_lib.baseboard_fab2(sch_1):page76_i59:b"
				( attribute "PN" "2"
					( Origin gPackager )
				)
				( objectStatus "C2D12.2" )
			)
			( pin "@baseboard_fab2_lib.baseboard_fab2(sch_1):page76_i61:a"
				( attribute "PN" "1"
					( Origin gPackager )
				)
				( objectStatus "C2D22.1" )
			)
			( pin "@baseboard_fab2_lib.baseboard_fab2(sch_1):page76_i61:b"
				( attribute "PN" "2"
					( Origin gPackager )
				)
				( objectStatus "C2D22.2" )
			)
			( pin "@baseboard_fab2_lib.baseboard_fab2(sch_1):page76_i63:a"
				( attribute "PN" "1"
					( Origin gPackager )
				)
				( objectStatus "C2D31.1" )
			)
			( pin "@baseboard_fab2_lib.baseboard_fab2(sch_1):page76_i63:b"
				( attribute "PN" "2"
					( Origin gPackager )
				)
				( objectStatus "C2D31.2" )
			)
			( pin "@baseboard_fab2_lib.baseboard_fab2(sch_1):page76_i65:a"
				( attribute "PN" "1"
					( Origin gPackager )
				)
				( objectStatus "C2D21.1" )
			)
			( pin "@baseboard_fab2_lib.baseboard_fab2(sch_1):page76_i65:b"
				( attribute "PN" "2"
					( Origin gPackager )
				)
				( objectStatus "C2D21.2" )
			)
			( pin "@baseboard_fab2_lib.baseboard_fab2(sch_1):page76_i66:a"
				( attribute "PN" "1"
					( Origin gPackager )
				)
				( objectStatus "C2D27.1" )
			)
			( pin "@baseboard_fab2_lib.baseboard_fab2(sch_1):page76_i66:b"
				( attribute "PN" "2"
					( Origin gPackager )
				)
				( objectStatus "C2D27.2" )
			)
			( pin "@baseboard_fab2_lib.baseboard_fab2(sch_1):page76_i69:a"
				( attribute "PN" "1"
					( Origin gPackager )
				)
				( objectStatus "C3D2.1" )
			)
			( pin "@baseboard_fab2_lib.baseboard_fab2(sch_1):page76_i69:b"
				( attribute "PN" "2"
					( Origin gPackager )
				)
				( objectStatus "C3D2.2" )
			)
			( pin "@baseboard_fab2_lib.baseboard_fab2(sch_1):page76_i70:a"
				( attribute "PN" "1"
					( Origin gPackager )
				)
				( objectStatus "C2D36.1" )
			)
			( pin "@baseboard_fab2_lib.baseboard_fab2(sch_1):page76_i70:b"
				( attribute "PN" "2"
					( Origin gPackager )
				)
				( objectStatus "C2D36.2" )
			)
			( pin "@baseboard_fab2_lib.baseboard_fab2(sch_1):page76_i73:a"
				( attribute "PN" "1"
					( Origin gPackager )
				)
				( objectStatus "C2D13.1" )
			)
			( pin "@baseboard_fab2_lib.baseboard_fab2(sch_1):page76_i73:b"
				( attribute "PN" "2"
					( Origin gPackager )
				)
				( objectStatus "C2D13.2" )
			)
			( pin "@baseboard_fab2_lib.baseboard_fab2(sch_1):page76_i75:a"
				( attribute "PN" "1"
					( Origin gPackager )
				)
				( objectStatus "C2D19.1" )
			)
			( pin "@baseboard_fab2_lib.baseboard_fab2(sch_1):page76_i75:b"
				( attribute "PN" "2"
					( Origin gPackager )
				)
				( objectStatus "C2D19.2" )
			)
			( pin "@baseboard_fab2_lib.baseboard_fab2(sch_1):page76_i76:a"
				( attribute "PN" "1"
					( Origin gPackager )
				)
				( objectStatus "C2D14.1" )
			)
			( pin "@baseboard_fab2_lib.baseboard_fab2(sch_1):page76_i76:b"
				( attribute "PN" "2"
					( Origin gPackager )
				)
				( objectStatus "C2D14.2" )
			)
			( pin "@baseboard_fab2_lib.baseboard_fab2(sch_1):page76_i79:a"
				( attribute "PN" "1"
					( Origin gPackager )
				)
				( objectStatus "C2D20.1" )
			)
			( pin "@baseboard_fab2_lib.baseboard_fab2(sch_1):page76_i79:b"
				( attribute "PN" "2"
					( Origin gPackager )
				)
				( objectStatus "C2D20.2" )
			)
			( pin "@baseboard_fab2_lib.baseboard_fab2(sch_1):page76_i80:a"
				( attribute "PN" "1"
					( Origin gPackager )
				)
				( objectStatus "C2D24.1" )
			)
			( pin "@baseboard_fab2_lib.baseboard_fab2(sch_1):page76_i80:b"
				( attribute "PN" "2"
					( Origin gPackager )
				)
				( objectStatus "C2D24.2" )
			)
			( pin "@baseboard_fab2_lib.baseboard_fab2(sch_1):page76_i82:a"
				( attribute "PN" "1"
					( Origin gPackager )
				)
				( objectStatus "C2D25.1" )
			)
			( pin "@baseboard_fab2_lib.baseboard_fab2(sch_1):page76_i82:b"
				( attribute "PN" "2"
					( Origin gPackager )
				)
				( objectStatus "C2D25.2" )
			)
			( pin "@baseboard_fab2_lib.baseboard_fab2(sch_1):page76_i83:a"
				( attribute "PN" "1"
					( Origin gPackager )
				)
				( objectStatus "C2D30.1" )
			)
			( pin "@baseboard_fab2_lib.baseboard_fab2(sch_1):page76_i83:b"
				( attribute "PN" "2"
					( Origin gPackager )
				)
				( objectStatus "C2D30.2" )
			)
			( pin "@baseboard_fab2_lib.baseboard_fab2(sch_1):page76_i85:a"
				( attribute "PN" "1"
					( Origin gPackager )
				)
				( objectStatus "C2D33.1" )
			)
			( pin "@baseboard_fab2_lib.baseboard_fab2(sch_1):page76_i85:b"
				( attribute "PN" "2"
					( Origin gPackager )
				)
				( objectStatus "C2D33.2" )
			)
			( pin "@baseboard_fab2_lib.baseboard_fab2(sch_1):page76_i89:a"
				( attribute "PN" "1"
					( Origin gPackager )
				)
				( objectStatus "C8P20.1" )
			)
			( pin "@baseboard_fab2_lib.baseboard_fab2(sch_1):page76_i89:b"
				( attribute "PN" "2"
					( Origin gPackager )
				)
				( objectStatus "C8P20.2" )
			)
			( pin "@baseboard_fab2_lib.baseboard_fab2(sch_1):page76_i90:a"
				( attribute "PN" "1"
					( Origin gPackager )
				)
				( objectStatus "C2D32.1" )
			)
			( pin "@baseboard_fab2_lib.baseboard_fab2(sch_1):page76_i90:b"
				( attribute "PN" "2"
					( Origin gPackager )
				)
				( objectStatus "C2D32.2" )
			)
			( pin "@baseboard_fab2_lib.baseboard_fab2(sch_1):page76_i92:a"
				( attribute "PN" "1"
					( Origin gPackager )
				)
				( objectStatus "C8P18.1" )
			)
			( pin "@baseboard_fab2_lib.baseboard_fab2(sch_1):page76_i92:b"
				( attribute "PN" "2"
					( Origin gPackager )
				)
				( objectStatus "C8P18.2" )
			)
			( pin "@baseboard_fab2_lib.baseboard_fab2(sch_1):page76_i103:a"
				( attribute "PN" "1"
					( Origin gPackager )
				)
				( objectStatus "C8P19.1" )
			)
			( pin "@baseboard_fab2_lib.baseboard_fab2(sch_1):page76_i103:b"
				( attribute "PN" "2"
					( Origin gPackager )
				)
				( objectStatus "C8P19.2" )
			)
			( pin "@baseboard_fab2_lib.baseboard_fab2(sch_1):page166_i34:a"
				( attribute "PN" "4"
					( Origin gPackager )
				)
				( objectStatus "U7W1.4" )
			)
			( pin "@baseboard_fab2_lib.baseboard_fab2(sch_1):page166_i34:b0"
				( attribute "PN" "3"
					( Origin gPackager )
				)
				( objectStatus "U7W1.3" )
			)
			( pin "@baseboard_fab2_lib.baseboard_fab2(sch_1):page166_i34:b1"
				( attribute "PN" "1"
					( Origin gPackager )
				)
				( objectStatus "U7W1.1" )
			)
			( pin "@baseboard_fab2_lib.baseboard_fab2(sch_1):page166_i34:gnd"
				( attribute "PN" "2"
					( Origin gPackager )
				)
				( objectStatus "U7W1.2" )
			)
			( pin "@baseboard_fab2_lib.baseboard_fab2(sch_1):page166_i34:s"
				( attribute "PN" "6"
					( Origin gPackager )
				)
				( objectStatus "U7W1.6" )
			)
			( pin "@baseboard_fab2_lib.baseboard_fab2(sch_1):page166_i34:vcc"
				( attribute "PN" "5"
					( Origin gPackager )
				)
				( objectStatus "U7W1.5" )
			)
			( pin "@baseboard_fab2_lib.baseboard_fab2(sch_1):page76_i107:a"
				( attribute "PN" "1"
					( Origin gPackager )
				)
				( objectStatus "C8P12.1" )
			)
			( pin "@baseboard_fab2_lib.baseboard_fab2(sch_1):page76_i107:b"
				( attribute "PN" "2"
					( Origin gPackager )
				)
				( objectStatus "C8P12.2" )
			)
			( pin "@baseboard_fab2_lib.baseboard_fab2(sch_1):page76_i108:a"
				( attribute "PN" "1"
					( Origin gPackager )
				)
				( objectStatus "C2D26.1" )
			)
			( pin "@baseboard_fab2_lib.baseboard_fab2(sch_1):page76_i108:b"
				( attribute "PN" "2"
					( Origin gPackager )
				)
				( objectStatus "C2D26.2" )
			)
			( pin "@baseboard_fab2_lib.baseboard_fab2(sch_1):page76_i112:a"
				( attribute "PN" "1"
					( Origin gPackager )
				)
				( objectStatus "C2D23.1" )
			)
			( pin "@baseboard_fab2_lib.baseboard_fab2(sch_1):page76_i112:b"
				( attribute "PN" "2"
					( Origin gPackager )
				)
				( objectStatus "C2D23.2" )
			)
			( pin "@baseboard_fab2_lib.baseboard_fab2(sch_1):page76_i114:a"
				( attribute "PN" "1"
					( Origin gPackager )
				)
				( objectStatus "C2D17.1" )
			)
			( pin "@baseboard_fab2_lib.baseboard_fab2(sch_1):page76_i114:b"
				( attribute "PN" "2"
					( Origin gPackager )
				)
				( objectStatus "C2D17.2" )
			)
			( pin "@baseboard_fab2_lib.baseboard_fab2(sch_1):page228_i257:a"
				( attribute "PN" "1"
					( Origin gPackager )
				)
				( objectStatus "C2D2.1" )
			)
			( pin "@baseboard_fab2_lib.baseboard_fab2(sch_1):page228_i257:b"
				( attribute "PN" "2"
					( Origin gPackager )
				)
				( objectStatus "C2D2.2" )
			)
			( pin "@baseboard_fab2_lib.baseboard_fab2(sch_1):page76_i118:a"
				( attribute "PN" "1"
					( Origin gPackager )
				)
				( objectStatus "C8P26.1" )
			)
			( pin "@baseboard_fab2_lib.baseboard_fab2(sch_1):page76_i118:b"
				( attribute "PN" "2"
					( Origin gPackager )
				)
				( objectStatus "C8P26.2" )
			)
			( pin "@baseboard_fab2_lib.baseboard_fab2(sch_1):page76_i119:a"
				( attribute "PN" "1"
					( Origin gPackager )
				)
				( objectStatus "C2D37.1" )
			)
			( pin "@baseboard_fab2_lib.baseboard_fab2(sch_1):page76_i119:b"
				( attribute "PN" "2"
					( Origin gPackager )
				)
				( objectStatus "C2D37.2" )
			)
			( pin "@baseboard_fab2_lib.baseboard_fab2(sch_1):page76_i122:a"
				( attribute "PN" "1"
					( Origin gPackager )
				)
				( objectStatus "C2D34.1" )
			)
			( pin "@baseboard_fab2_lib.baseboard_fab2(sch_1):page76_i122:b"
				( attribute "PN" "2"
					( Origin gPackager )
				)
				( objectStatus "C2D34.2" )
			)
			( pin "@baseboard_fab2_lib.baseboard_fab2(sch_1):page228_i258:a"
				( attribute "PN" "1"
					( Origin gPackager )
				)
				( objectStatus "C2D1.1" )
			)
			( pin "@baseboard_fab2_lib.baseboard_fab2(sch_1):page228_i258:b"
				( attribute "PN" "2"
					( Origin gPackager )
				)
				( objectStatus "C2D1.2" )
			)
			( pin "@baseboard_fab2_lib.baseboard_fab2(sch_1):page76_i124:a"
				( attribute "PN" "1"
					( Origin gPackager )
				)
				( objectStatus "C2D16.1" )
			)
			( pin "@baseboard_fab2_lib.baseboard_fab2(sch_1):page76_i124:b"
				( attribute "PN" "2"
					( Origin gPackager )
				)
				( objectStatus "C2D16.2" )
			)
			( pin "@baseboard_fab2_lib.baseboard_fab2(sch_1):page76_i125:a"
				( attribute "PN" "1"
					( Origin gPackager )
				)
				( objectStatus "C8P29.1" )
			)
			( pin "@baseboard_fab2_lib.baseboard_fab2(sch_1):page76_i125:b"
				( attribute "PN" "2"
					( Origin gPackager )
				)
				( objectStatus "C8P29.2" )
			)
			( pin "@baseboard_fab2_lib.baseboard_fab2(sch_1):page76_i127:a"
				( attribute "PN" "1"
					( Origin gPackager )
				)
				( objectStatus "C8P10.1" )
			)
			( pin "@baseboard_fab2_lib.baseboard_fab2(sch_1):page76_i127:b"
				( attribute "PN" "2"
					( Origin gPackager )
				)
				( objectStatus "C8P10.2" )
			)
			( pin "@baseboard_fab2_lib.baseboard_fab2(sch_1):page76_i129:a"
				( attribute "PN" "1"
					( Origin gPackager )
				)
				( objectStatus "C8P16.1" )
			)
			( pin "@baseboard_fab2_lib.baseboard_fab2(sch_1):page76_i129:b"
				( attribute "PN" "2"
					( Origin gPackager )
				)
				( objectStatus "C8P16.2" )
			)
			( pin "@baseboard_fab2_lib.baseboard_fab2(sch_1):page166_i36:a"
				( attribute "PN" "1"
					( Origin gPackager )
				)
				( objectStatus "C7W1.1" )
			)
			( pin "@baseboard_fab2_lib.baseboard_fab2(sch_1):page166_i36:b"
				( attribute "PN" "2"
					( Origin gPackager )
				)
				( objectStatus "C7W1.2" )
			)
			( pin "@baseboard_fab2_lib.baseboard_fab2(sch_1):page76_i132:a"
				( attribute "PN" "1"
					( Origin gPackager )
				)
				( objectStatus "C8P13.1" )
			)
			( pin "@baseboard_fab2_lib.baseboard_fab2(sch_1):page76_i132:b"
				( attribute "PN" "2"
					( Origin gPackager )
				)
				( objectStatus "C8P13.2" )
			)
			( pin "@baseboard_fab2_lib.baseboard_fab2(sch_1):page76_i137:a"
				( attribute "PN" "1"
					( Origin gPackager )
				)
				( objectStatus "C8P28.1" )
			)
			( pin "@baseboard_fab2_lib.baseboard_fab2(sch_1):page76_i137:b"
				( attribute "PN" "2"
					( Origin gPackager )
				)
				( objectStatus "C8P28.2" )
			)
			( pin "@baseboard_fab2_lib.baseboard_fab2(sch_1):page76_i139:a"
				( attribute "PN" "1"
					( Origin gPackager )
				)
				( objectStatus "C8P11.1" )
			)
			( pin "@baseboard_fab2_lib.baseboard_fab2(sch_1):page76_i139:b"
				( attribute "PN" "2"
					( Origin gPackager )
				)
				( objectStatus "C8P11.2" )
			)
			( pin "@baseboard_fab2_lib.baseboard_fab2(sch_1):page196_i130:a"
				( attribute "PN" "1"
					( Origin gPackager )
				)
				( objectStatus "R8D40.1" )
			)
			( pin "@baseboard_fab2_lib.baseboard_fab2(sch_1):page196_i130:b"
				( attribute "PN" "2"
					( Origin gPackager )
				)
				( objectStatus "R8D40.2" )
			)
			( pin "@baseboard_fab2_lib.baseboard_fab2(sch_1):page76_i159:a"
				( attribute "PN" "1"
					( Origin gPackager )
				)
				( objectStatus "C2D15.1" )
			)
			( pin "@baseboard_fab2_lib.baseboard_fab2(sch_1):page76_i159:b"
				( attribute "PN" "2"
					( Origin gPackager )
				)
				( objectStatus "C2D15.2" )
			)
			( pin "@baseboard_fab2_lib.baseboard_fab2(sch_1):page76_i160:a"
				( attribute "PN" "1"
					( Origin gPackager )
				)
				( objectStatus "C2D38.1" )
			)
			( pin "@baseboard_fab2_lib.baseboard_fab2(sch_1):page76_i160:b"
				( attribute "PN" "2"
					( Origin gPackager )
				)
				( objectStatus "C2D38.2" )
			)
			( pin "@baseboard_fab2_lib.baseboard_fab2(sch_1):page76_i161:a"
				( attribute "PN" "1"
					( Origin gPackager )
				)
				( objectStatus "C2D35.1" )
			)
			( pin "@baseboard_fab2_lib.baseboard_fab2(sch_1):page76_i161:b"
				( attribute "PN" "2"
					( Origin gPackager )
				)
				( objectStatus "C2D35.2" )
			)
			( pin "@baseboard_fab2_lib.baseboard_fab2(sch_1):page76_i164:a"
				( attribute "PN" "1"
					( Origin gPackager )
				)
				( objectStatus "C3D7.1" )
			)
			( pin "@baseboard_fab2_lib.baseboard_fab2(sch_1):page76_i164:b"
				( attribute "PN" "2"
					( Origin gPackager )
				)
				( objectStatus "C3D7.2" )
			)
			( pin "@baseboard_fab2_lib.baseboard_fab2(sch_1):page76_i165:a"
				( attribute "PN" "1"
					( Origin gPackager )
				)
				( objectStatus "C2D39.1" )
			)
			( pin "@baseboard_fab2_lib.baseboard_fab2(sch_1):page76_i165:b"
				( attribute "PN" "2"
					( Origin gPackager )
				)
				( objectStatus "C2D39.2" )
			)
			( pin "@baseboard_fab2_lib.baseboard_fab2(sch_1):page76_i166:a"
				( attribute "PN" "1"
					( Origin gPackager )
				)
				( objectStatus "C3D17.1" )
			)
			( pin "@baseboard_fab2_lib.baseboard_fab2(sch_1):page76_i166:b"
				( attribute "PN" "2"
					( Origin gPackager )
				)
				( objectStatus "C3D17.2" )
			)
			( pin "@baseboard_fab2_lib.baseboard_fab2(sch_1):page76_i169:a"
				( attribute "PN" "1"
					( Origin gPackager )
				)
				( objectStatus "C3D18.1" )
			)
			( pin "@baseboard_fab2_lib.baseboard_fab2(sch_1):page76_i169:b"
				( attribute "PN" "2"
					( Origin gPackager )
				)
				( objectStatus "C3D18.2" )
			)
			( pin "@baseboard_fab2_lib.baseboard_fab2(sch_1):page76_i170:a"
				( attribute "PN" "1"
					( Origin gPackager )
				)
				( objectStatus "C3D6.1" )
			)
			( pin "@baseboard_fab2_lib.baseboard_fab2(sch_1):page76_i170:b"
				( attribute "PN" "2"
					( Origin gPackager )
				)
				( objectStatus "C3D6.2" )
			)
			( pin "@baseboard_fab2_lib.baseboard_fab2(sch_1):page76_i171:a"
				( attribute "PN" "1"
					( Origin gPackager )
				)
				( objectStatus "C3D14.1" )
			)
			( pin "@baseboard_fab2_lib.baseboard_fab2(sch_1):page76_i171:b"
				( attribute "PN" "2"
					( Origin gPackager )
				)
				( objectStatus "C3D14.2" )
			)
			( pin "@baseboard_fab2_lib.baseboard_fab2(sch_1):page76_i172:a"
				( attribute "PN" "1"
					( Origin gPackager )
				)
				( objectStatus "C3D23.1" )
			)
			( pin "@baseboard_fab2_lib.baseboard_fab2(sch_1):page76_i172:b"
				( attribute "PN" "2"
					( Origin gPackager )
				)
				( objectStatus "C3D23.2" )
			)
			( pin "@baseboard_fab2_lib.baseboard_fab2(sch_1):page76_i174:a"
				( attribute "PN" "1"
					( Origin gPackager )
				)
				( objectStatus "C3D15.1" )
			)
			( pin "@baseboard_fab2_lib.baseboard_fab2(sch_1):page76_i174:b"
				( attribute "PN" "2"
					( Origin gPackager )
				)
				( objectStatus "C3D15.2" )
			)
			( pin "@baseboard_fab2_lib.baseboard_fab2(sch_1):page76_i175:a"
				( attribute "PN" "1"
					( Origin gPackager )
				)
				( objectStatus "C3D24.1" )
			)
			( pin "@baseboard_fab2_lib.baseboard_fab2(sch_1):page76_i175:b"
				( attribute "PN" "2"
					( Origin gPackager )
				)
				( objectStatus "C3D24.2" )
			)
			( pin "@baseboard_fab2_lib.baseboard_fab2(sch_1):page76_i176:a"
				( attribute "PN" "1"
					( Origin gPackager )
				)
				( objectStatus "C3D16.1" )
			)
			( pin "@baseboard_fab2_lib.baseboard_fab2(sch_1):page76_i176:b"
				( attribute "PN" "2"
					( Origin gPackager )
				)
				( objectStatus "C3D16.2" )
			)
			( pin "@baseboard_fab2_lib.baseboard_fab2(sch_1):page76_i179:a"
				( attribute "PN" "1"
					( Origin gPackager )
				)
				( objectStatus "C7P12.1" )
			)
			( pin "@baseboard_fab2_lib.baseboard_fab2(sch_1):page76_i179:b"
				( attribute "PN" "2"
					( Origin gPackager )
				)
				( objectStatus "C7P12.2" )
			)
			( pin "@baseboard_fab2_lib.baseboard_fab2(sch_1):page76_i261:a"
				( attribute "PN" "1"
					( Origin gPackager )
				)
				( objectStatus "C7P14.1" )
			)
			( pin "@baseboard_fab2_lib.baseboard_fab2(sch_1):page76_i261:b"
				( attribute "PN" "2"
					( Origin gPackager )
				)
				( objectStatus "C7P14.2" )
			)
			( pin "@baseboard_fab2_lib.baseboard_fab2(sch_1):page76_i260:a"
				( attribute "PN" "1"
					( Origin gPackager )
				)
				( objectStatus "C8P23.1" )
			)
			( pin "@baseboard_fab2_lib.baseboard_fab2(sch_1):page76_i260:b"
				( attribute "PN" "2"
					( Origin gPackager )
				)
				( objectStatus "C8P23.2" )
			)
			( pin "@baseboard_fab2_lib.baseboard_fab2(sch_1):page76_i264:a"
				( attribute "PN" "1"
					( Origin gPackager )
				)
				( objectStatus "C8P22.1" )
			)
			( pin "@baseboard_fab2_lib.baseboard_fab2(sch_1):page76_i264:b"
				( attribute "PN" "2"
					( Origin gPackager )
				)
				( objectStatus "C8P22.2" )
			)
			( pin "@baseboard_fab2_lib.baseboard_fab2(sch_1):page76_i268:a"
				( attribute "PN" "1"
					( Origin gPackager )
				)
				( objectStatus "C7P6.1" )
			)
			( pin "@baseboard_fab2_lib.baseboard_fab2(sch_1):page76_i268:b"
				( attribute "PN" "2"
					( Origin gPackager )
				)
				( objectStatus "C7P6.2" )
			)
			( pin "@baseboard_fab2_lib.baseboard_fab2(sch_1):page76_i196:a"
				( attribute "PN" "1"
					( Origin gPackager )
				)
				( objectStatus "C3D10.1" )
			)
			( pin "@baseboard_fab2_lib.baseboard_fab2(sch_1):page76_i196:b"
				( attribute "PN" "2"
					( Origin gPackager )
				)
				( objectStatus "C3D10.2" )
			)
			( pin "@baseboard_fab2_lib.baseboard_fab2(sch_1):page76_i197:a"
				( attribute "PN" "1"
					( Origin gPackager )
				)
				( objectStatus "C2D18.1" )
			)
			( pin "@baseboard_fab2_lib.baseboard_fab2(sch_1):page76_i197:b"
				( attribute "PN" "2"
					( Origin gPackager )
				)
				( objectStatus "C2D18.2" )
			)
			( pin "@baseboard_fab2_lib.baseboard_fab2(sch_1):page76_i198:a"
				( attribute "PN" "1"
					( Origin gPackager )
				)
				( objectStatus "C2D28.1" )
			)
			( pin "@baseboard_fab2_lib.baseboard_fab2(sch_1):page76_i198:b"
				( attribute "PN" "2"
					( Origin gPackager )
				)
				( objectStatus "C2D28.2" )
			)
			( pin "@baseboard_fab2_lib.baseboard_fab2(sch_1):page76_i199:a"
				( attribute "PN" "1"
					( Origin gPackager )
				)
				( objectStatus "C2D29.1" )
			)
			( pin "@baseboard_fab2_lib.baseboard_fab2(sch_1):page76_i199:b"
				( attribute "PN" "2"
					( Origin gPackager )
				)
				( objectStatus "C2D29.2" )
			)
			( pin "@baseboard_fab2_lib.baseboard_fab2(sch_1):page42_i211:a"
				( attribute "PN" "1"
					( Origin gPackager )
				)
				( objectStatus "C8W3.1" )
			)
			( pin "@baseboard_fab2_lib.baseboard_fab2(sch_1):page42_i211:b"
				( attribute "PN" "2"
					( Origin gPackager )
				)
				( objectStatus "C8W3.2" )
			)
			( pin "@baseboard_fab2_lib.baseboard_fab2(sch_1):page217_i316:a"
				( attribute "PN" "1"
					( Origin gPackager )
				)
				( objectStatus "C5U1.1" )
			)
			( pin "@baseboard_fab2_lib.baseboard_fab2(sch_1):page217_i316:b"
				( attribute "PN" "2"
					( Origin gPackager )
				)
				( objectStatus "C5U1.2" )
			)
			( pin "@baseboard_fab2_lib.baseboard_fab2(sch_1):page225_i264:a"
				( attribute "PN" "1"
					( Origin gPackager )
				)
				( objectStatus "C2D46.1" )
			)
			( pin "@baseboard_fab2_lib.baseboard_fab2(sch_1):page225_i264:b"
				( attribute "PN" "2"
					( Origin gPackager )
				)
				( objectStatus "C2D46.2" )
			)
			( pin "@baseboard_fab2_lib.baseboard_fab2(sch_1):page225_i263:a"
				( attribute "PN" "1"
					( Origin gPackager )
				)
				( objectStatus "C2D47.1" )
			)
			( pin "@baseboard_fab2_lib.baseboard_fab2(sch_1):page225_i263:b"
				( attribute "PN" "2"
					( Origin gPackager )
				)
				( objectStatus "C2D47.2" )
			)
			( pin "@baseboard_fab2_lib.baseboard_fab2(sch_1):page225_i262:a"
				( attribute "PN" "1"
					( Origin gPackager )
				)
				( objectStatus "C3D25.1" )
			)
			( pin "@baseboard_fab2_lib.baseboard_fab2(sch_1):page225_i262:b"
				( attribute "PN" "2"
					( Origin gPackager )
				)
				( objectStatus "C3D25.2" )
			)
			( pin "@baseboard_fab2_lib.baseboard_fab2(sch_1):page76_i206:a"
				( attribute "PN" "1"
					( Origin gPackager )
				)
				( objectStatus "C7P16.1" )
			)
			( pin "@baseboard_fab2_lib.baseboard_fab2(sch_1):page76_i206:b"
				( attribute "PN" "2"
					( Origin gPackager )
				)
				( objectStatus "C7P16.2" )
			)
			( pin "@baseboard_fab2_lib.baseboard_fab2(sch_1):page76_i207:a"
				( attribute "PN" "1"
					( Origin gPackager )
				)
				( objectStatus "C3D20.1" )
			)
			( pin "@baseboard_fab2_lib.baseboard_fab2(sch_1):page76_i207:b"
				( attribute "PN" "2"
					( Origin gPackager )
				)
				( objectStatus "C3D20.2" )
			)
			( pin "@baseboard_fab2_lib.baseboard_fab2(sch_1):page76_i208:a"
				( attribute "PN" "1"
					( Origin gPackager )
				)
				( objectStatus "C3D19.1" )
			)
			( pin "@baseboard_fab2_lib.baseboard_fab2(sch_1):page76_i208:b"
				( attribute "PN" "2"
					( Origin gPackager )
				)
				( objectStatus "C3D19.2" )
			)
			( pin "@baseboard_fab2_lib.baseboard_fab2(sch_1):page76_i215:a"
				( attribute "PN" "1"
					( Origin gPackager )
				)
				( objectStatus "C7P19.1" )
			)
			( pin "@baseboard_fab2_lib.baseboard_fab2(sch_1):page76_i215:b"
				( attribute "PN" "2"
					( Origin gPackager )
				)
				( objectStatus "C7P19.2" )
			)
			( pin "@baseboard_fab2_lib.baseboard_fab2(sch_1):page76_i217:a"
				( attribute "PN" "1"
					( Origin gPackager )
				)
				( objectStatus "C8P24.1" )
			)
			( pin "@baseboard_fab2_lib.baseboard_fab2(sch_1):page76_i217:b"
				( attribute "PN" "2"
					( Origin gPackager )
				)
				( objectStatus "C8P24.2" )
			)
			( pin "@baseboard_fab2_lib.baseboard_fab2(sch_1):page77_i43:vss(0)"
				( attribute "PN" "283"
					( Origin gPackager )
				)
				( objectStatus "J1G1.283" )
			)
			( pin "@baseboard_fab2_lib.baseboard_fab2(sch_1):page77_i43:vss(1)"
				( attribute "PN" "281"
					( Origin gPackager )
				)
				( objectStatus "J1G1.281" )
			)
			( pin "@baseboard_fab2_lib.baseboard_fab2(sch_1):page77_i43:vss(2)"
				( attribute "PN" "279"
					( Origin gPackager )
				)
				( objectStatus "J1G1.279" )
			)
			( pin "@baseboard_fab2_lib.baseboard_fab2(sch_1):page77_i43:vss(3)"
				( attribute "PN" "276"
					( Origin gPackager )
				)
				( objectStatus "J1G1.276" )
			)
			( pin "@baseboard_fab2_lib.baseboard_fab2(sch_1):page77_i43:vss(4)"
				( attribute "PN" "274"
					( Origin gPackager )
				)
				( objectStatus "J1G1.274" )
			)
			( pin "@baseboard_fab2_lib.baseboard_fab2(sch_1):page77_i43:vss(5)"
				( attribute "PN" "272"
					( Origin gPackager )
				)
				( objectStatus "J1G1.272" )
			)
			( pin "@baseboard_fab2_lib.baseboard_fab2(sch_1):page77_i43:vss(6)"
				( attribute "PN" "270"
					( Origin gPackager )
				)
				( objectStatus "J1G1.270" )
			)
			( pin "@baseboard_fab2_lib.baseboard_fab2(sch_1):page77_i43:vss(7)"
				( attribute "PN" "268"
					( Origin gPackager )
				)
				( objectStatus "J1G1.268" )
			)
			( pin "@baseboard_fab2_lib.baseboard_fab2(sch_1):page77_i43:vss(8)"
				( attribute "PN" "265"
					( Origin gPackager )
				)
				( objectStatus "J1G1.265" )
			)
			( pin "@baseboard_fab2_lib.baseboard_fab2(sch_1):page77_i43:vss(9)"
				( attribute "PN" "263"
					( Origin gPackager )
				)
				( objectStatus "J1G1.263" )
			)
			( pin "@baseboard_fab2_lib.baseboard_fab2(sch_1):page77_i43:vss(10)"
				( attribute "PN" "261"
					( Origin gPackager )
				)
				( objectStatus "J1G1.261" )
			)
			( pin "@baseboard_fab2_lib.baseboard_fab2(sch_1):page77_i43:vss(11)"
				( attribute "PN" "259"
					( Origin gPackager )
				)
				( objectStatus "J1G1.259" )
			)
			( pin "@baseboard_fab2_lib.baseboard_fab2(sch_1):page77_i43:vss(12)"
				( attribute "PN" "257"
					( Origin gPackager )
				)
				( objectStatus "J1G1.257" )
			)
			( pin "@baseboard_fab2_lib.baseboard_fab2(sch_1):page77_i43:vss(13)"
				( attribute "PN" "254"
					( Origin gPackager )
				)
				( objectStatus "J1G1.254" )
			)
			( pin "@baseboard_fab2_lib.baseboard_fab2(sch_1):page77_i43:vss(14)"
				( attribute "PN" "252"
					( Origin gPackager )
				)
				( objectStatus "J1G1.252" )
			)
			( pin "@baseboard_fab2_lib.baseboard_fab2(sch_1):page77_i43:vss(15)"
				( attribute "PN" "250"
					( Origin gPackager )
				)
				( objectStatus "J1G1.250" )
			)
			( pin "@baseboard_fab2_lib.baseboard_fab2(sch_1):page77_i43:vss(16)"
				( attribute "PN" "248"
					( Origin gPackager )
				)
				( objectStatus "J1G1.248" )
			)
			( pin "@baseboard_fab2_lib.baseboard_fab2(sch_1):page77_i43:vss(17)"
				( attribute "PN" "246"
					( Origin gPackager )
				)
				( objectStatus "J1G1.246" )
			)
			( pin "@baseboard_fab2_lib.baseboard_fab2(sch_1):page77_i43:vss(18)"
				( attribute "PN" "243"
					( Origin gPackager )
				)
				( objectStatus "J1G1.243" )
			)
			( pin "@baseboard_fab2_lib.baseboard_fab2(sch_1):page77_i43:vss(19)"
				( attribute "PN" "241"
					( Origin gPackager )
				)
				( objectStatus "J1G1.241" )
			)
			( pin "@baseboard_fab2_lib.baseboard_fab2(sch_1):page77_i43:vss(20)"
				( attribute "PN" "239"
					( Origin gPackager )
				)
				( objectStatus "J1G1.239" )
			)
			( pin "@baseboard_fab2_lib.baseboard_fab2(sch_1):page77_i43:vss(21)"
				( attribute "PN" "202"
					( Origin gPackager )
				)
				( objectStatus "J1G1.202" )
			)
			( pin "@baseboard_fab2_lib.baseboard_fab2(sch_1):page77_i43:vss(22)"
				( attribute "PN" "200"
					( Origin gPackager )
				)
				( objectStatus "J1G1.200" )
			)
			( pin "@baseboard_fab2_lib.baseboard_fab2(sch_1):page77_i43:vss(23)"
				( attribute "PN" "198"
					( Origin gPackager )
				)
				( objectStatus "J1G1.198" )
			)
			( pin "@baseboard_fab2_lib.baseboard_fab2(sch_1):page77_i43:vss(24)"
				( attribute "PN" "195"
					( Origin gPackager )
				)
				( objectStatus "J1G1.195" )
			)
			( pin "@baseboard_fab2_lib.baseboard_fab2(sch_1):page77_i43:vss(25)"
				( attribute "PN" "193"
					( Origin gPackager )
				)
				( objectStatus "J1G1.193" )
			)
			( pin "@baseboard_fab2_lib.baseboard_fab2(sch_1):page77_i43:vss(26)"
				( attribute "PN" "191"
					( Origin gPackager )
				)
				( objectStatus "J1G1.191" )
			)
			( pin "@baseboard_fab2_lib.baseboard_fab2(sch_1):page77_i43:vss(27)"
				( attribute "PN" "189"
					( Origin gPackager )
				)
				( objectStatus "J1G1.189" )
			)
			( pin "@baseboard_fab2_lib.baseboard_fab2(sch_1):page77_i43:vss(28)"
				( attribute "PN" "187"
					( Origin gPackager )
				)
				( objectStatus "J1G1.187" )
			)
			( pin "@baseboard_fab2_lib.baseboard_fab2(sch_1):page77_i43:vss(29)"
				( attribute "PN" "184"
					( Origin gPackager )
				)
				( objectStatus "J1G1.184" )
			)
			( pin "@baseboard_fab2_lib.baseboard_fab2(sch_1):page77_i43:vss(30)"
				( attribute "PN" "182"
					( Origin gPackager )
				)
				( objectStatus "J1G1.182" )
			)
			( pin "@baseboard_fab2_lib.baseboard_fab2(sch_1):page77_i43:vss(31)"
				( attribute "PN" "180"
					( Origin gPackager )
				)
				( objectStatus "J1G1.180" )
			)
			( pin "@baseboard_fab2_lib.baseboard_fab2(sch_1):page77_i43:vss(32)"
				( attribute "PN" "178"
					( Origin gPackager )
				)
				( objectStatus "J1G1.178" )
			)
			( pin "@baseboard_fab2_lib.baseboard_fab2(sch_1):page77_i43:vss(33)"
				( attribute "PN" "176"
					( Origin gPackager )
				)
				( objectStatus "J1G1.176" )
			)
			( pin "@baseboard_fab2_lib.baseboard_fab2(sch_1):page77_i43:vss(34)"
				( attribute "PN" "173"
					( Origin gPackager )
				)
				( objectStatus "J1G1.173" )
			)
			( pin "@baseboard_fab2_lib.baseboard_fab2(sch_1):page77_i43:vss(35)"
				( attribute "PN" "171"
					( Origin gPackager )
				)
				( objectStatus "J1G1.171" )
			)
			( pin "@baseboard_fab2_lib.baseboard_fab2(sch_1):page77_i43:vss(36)"
				( attribute "PN" "169"
					( Origin gPackager )
				)
				( objectStatus "J1G1.169" )
			)
			( pin "@baseboard_fab2_lib.baseboard_fab2(sch_1):page77_i43:vss(37)"
				( attribute "PN" "167"
					( Origin gPackager )
				)
				( objectStatus "J1G1.167" )
			)
			( pin "@baseboard_fab2_lib.baseboard_fab2(sch_1):page77_i43:vss(38)"
				( attribute "PN" "165"
					( Origin gPackager )
				)
				( objectStatus "J1G1.165" )
			)
			( pin "@baseboard_fab2_lib.baseboard_fab2(sch_1):page77_i43:vss(39)"
				( attribute "PN" "162"
					( Origin gPackager )
				)
				( objectStatus "J1G1.162" )
			)
			( pin "@baseboard_fab2_lib.baseboard_fab2(sch_1):page77_i43:vss(40)"
				( attribute "PN" "160"
					( Origin gPackager )
				)
				( objectStatus "J1G1.160" )
			)
			( pin "@baseboard_fab2_lib.baseboard_fab2(sch_1):page77_i43:vss(41)"
				( attribute "PN" "158"
					( Origin gPackager )
				)
				( objectStatus "J1G1.158" )
			)
			( pin "@baseboard_fab2_lib.baseboard_fab2(sch_1):page77_i43:vss(42)"
				( attribute "PN" "156"
					( Origin gPackager )
				)
				( objectStatus "J1G1.156" )
			)
			( pin "@baseboard_fab2_lib.baseboard_fab2(sch_1):page77_i43:vss(43)"
				( attribute "PN" "154"
					( Origin gPackager )
				)
				( objectStatus "J1G1.154" )
			)
			( pin "@baseboard_fab2_lib.baseboard_fab2(sch_1):page77_i43:vss(44)"
				( attribute "PN" "151"
					( Origin gPackager )
				)
				( objectStatus "J1G1.151" )
			)
			( pin "@baseboard_fab2_lib.baseboard_fab2(sch_1):page77_i43:vss(45)"
				( attribute "PN" "149"
					( Origin gPackager )
				)
				( objectStatus "J1G1.149" )
			)
			( pin "@baseboard_fab2_lib.baseboard_fab2(sch_1):page77_i43:vss(46)"
				( attribute "PN" "147"
					( Origin gPackager )
				)
				( objectStatus "J1G1.147" )
			)
			( pin "@baseboard_fab2_lib.baseboard_fab2(sch_1):page77_i43:vss(47)"
				( attribute "PN" "138"
					( Origin gPackager )
				)
				( objectStatus "J1G1.138" )
			)
			( pin "@baseboard_fab2_lib.baseboard_fab2(sch_1):page77_i43:vss(48)"
				( attribute "PN" "136"
					( Origin gPackager )
				)
				( objectStatus "J1G1.136" )
			)
			( pin "@baseboard_fab2_lib.baseboard_fab2(sch_1):page77_i43:vss(49)"
				( attribute "PN" "134"
					( Origin gPackager )
				)
				( objectStatus "J1G1.134" )
			)
			( pin "@baseboard_fab2_lib.baseboard_fab2(sch_1):page77_i43:vss(50)"
				( attribute "PN" "131"
					( Origin gPackager )
				)
				( objectStatus "J1G1.131" )
			)
			( pin "@baseboard_fab2_lib.baseboard_fab2(sch_1):page77_i43:vss(51)"
				( attribute "PN" "129"
					( Origin gPackager )
				)
				( objectStatus "J1G1.129" )
			)
			( pin "@baseboard_fab2_lib.baseboard_fab2(sch_1):page77_i43:vss(52)"
				( attribute "PN" "127"
					( Origin gPackager )
				)
				( objectStatus "J1G1.127" )
			)
			( pin "@baseboard_fab2_lib.baseboard_fab2(sch_1):page77_i43:vss(53)"
				( attribute "PN" "125"
					( Origin gPackager )
				)
				( objectStatus "J1G1.125" )
			)
			( pin "@baseboard_fab2_lib.baseboard_fab2(sch_1):page77_i43:vss(54)"
				( attribute "PN" "123"
					( Origin gPackager )
				)
				( objectStatus "J1G1.123" )
			)
			( pin "@baseboard_fab2_lib.baseboard_fab2(sch_1):page77_i43:vss(55)"
				( attribute "PN" "120"
					( Origin gPackager )
				)
				( objectStatus "J1G1.120" )
			)
			( pin "@baseboard_fab2_lib.baseboard_fab2(sch_1):page77_i43:vss(56)"
				( attribute "PN" "118"
					( Origin gPackager )
				)
				( objectStatus "J1G1.118" )
			)
			( pin "@baseboard_fab2_lib.baseboard_fab2(sch_1):page77_i43:vss(57)"
				( attribute "PN" "116"
					( Origin gPackager )
				)
				( objectStatus "J1G1.116" )
			)
			( pin "@baseboard_fab2_lib.baseboard_fab2(sch_1):page77_i43:vss(58)"
				( attribute "PN" "114"
					( Origin gPackager )
				)
				( objectStatus "J1G1.114" )
			)
			( pin "@baseboard_fab2_lib.baseboard_fab2(sch_1):page77_i43:vss(59)"
				( attribute "PN" "112"
					( Origin gPackager )
				)
				( objectStatus "J1G1.112" )
			)
			( pin "@baseboard_fab2_lib.baseboard_fab2(sch_1):page77_i43:vss(60)"
				( attribute "PN" "109"
					( Origin gPackager )
				)
				( objectStatus "J1G1.109" )
			)
			( pin "@baseboard_fab2_lib.baseboard_fab2(sch_1):page77_i43:vss(61)"
				( attribute "PN" "107"
					( Origin gPackager )
				)
				( objectStatus "J1G1.107" )
			)
			( pin "@baseboard_fab2_lib.baseboard_fab2(sch_1):page77_i43:vss(62)"
				( attribute "PN" "105"
					( Origin gPackager )
				)
				( objectStatus "J1G1.105" )
			)
			( pin "@baseboard_fab2_lib.baseboard_fab2(sch_1):page77_i43:vss(63)"
				( attribute "PN" "103"
					( Origin gPackager )
				)
				( objectStatus "J1G1.103" )
			)
			( pin "@baseboard_fab2_lib.baseboard_fab2(sch_1):page77_i43:vss(64)"
				( attribute "PN" "101"
					( Origin gPackager )
				)
				( objectStatus "J1G1.101" )
			)
			( pin "@baseboard_fab2_lib.baseboard_fab2(sch_1):page77_i43:vss(65)"
				( attribute "PN" "98"
					( Origin gPackager )
				)
				( objectStatus "J1G1.98" )
			)
			( pin "@baseboard_fab2_lib.baseboard_fab2(sch_1):page77_i43:vss(66)"
				( attribute "PN" "96"
					( Origin gPackager )
				)
				( objectStatus "J1G1.96" )
			)
			( pin "@baseboard_fab2_lib.baseboard_fab2(sch_1):page77_i43:vss(67)"
				( attribute "PN" "94"
					( Origin gPackager )
				)
				( objectStatus "J1G1.94" )
			)
			( pin "@baseboard_fab2_lib.baseboard_fab2(sch_1):page77_i43:vss(68)"
				( attribute "PN" "57"
					( Origin gPackager )
				)
				( objectStatus "J1G1.57" )
			)
			( pin "@baseboard_fab2_lib.baseboard_fab2(sch_1):page77_i43:vss(69)"
				( attribute "PN" "55"
					( Origin gPackager )
				)
				( objectStatus "J1G1.55" )
			)
			( pin "@baseboard_fab2_lib.baseboard_fab2(sch_1):page77_i43:vss(70)"
				( attribute "PN" "53"
					( Origin gPackager )
				)
				( objectStatus "J1G1.53" )
			)
			( pin "@baseboard_fab2_lib.baseboard_fab2(sch_1):page77_i43:vss(71)"
				( attribute "PN" "50"
					( Origin gPackager )
				)
				( objectStatus "J1G1.50" )
			)
			( pin "@baseboard_fab2_lib.baseboard_fab2(sch_1):page77_i43:vss(72)"
				( attribute "PN" "48"
					( Origin gPackager )
				)
				( objectStatus "J1G1.48" )
			)
			( pin "@baseboard_fab2_lib.baseboard_fab2(sch_1):page77_i43:vss(73)"
				( attribute "PN" "46"
					( Origin gPackager )
				)
				( objectStatus "J1G1.46" )
			)
			( pin "@baseboard_fab2_lib.baseboard_fab2(sch_1):page77_i43:vss(74)"
				( attribute "PN" "44"
					( Origin gPackager )
				)
				( objectStatus "J1G1.44" )
			)
			( pin "@baseboard_fab2_lib.baseboard_fab2(sch_1):page77_i43:vss(75)"
				( attribute "PN" "42"
					( Origin gPackager )
				)
				( objectStatus "J1G1.42" )
			)
			( pin "@baseboard_fab2_lib.baseboard_fab2(sch_1):page77_i43:vss(76)"
				( attribute "PN" "39"
					( Origin gPackager )
				)
				( objectStatus "J1G1.39" )
			)
			( pin "@baseboard_fab2_lib.baseboard_fab2(sch_1):page77_i43:vss(77)"
				( attribute "PN" "37"
					( Origin gPackager )
				)
				( objectStatus "J1G1.37" )
			)
			( pin "@baseboard_fab2_lib.baseboard_fab2(sch_1):page77_i43:vss(78)"
				( attribute "PN" "35"
					( Origin gPackager )
				)
				( objectStatus "J1G1.35" )
			)
			( pin "@baseboard_fab2_lib.baseboard_fab2(sch_1):page77_i43:vss(79)"
				( attribute "PN" "33"
					( Origin gPackager )
				)
				( objectStatus "J1G1.33" )
			)
			( pin "@baseboard_fab2_lib.baseboard_fab2(sch_1):page77_i43:vss(80)"
				( attribute "PN" "31"
					( Origin gPackager )
				)
				( objectStatus "J1G1.31" )
			)
			( pin "@baseboard_fab2_lib.baseboard_fab2(sch_1):page77_i43:vss(81)"
				( attribute "PN" "28"
					( Origin gPackager )
				)
				( objectStatus "J1G1.28" )
			)
			( pin "@baseboard_fab2_lib.baseboard_fab2(sch_1):page77_i43:vss(82)"
				( attribute "PN" "26"
					( Origin gPackager )
				)
				( objectStatus "J1G1.26" )
			)
			( pin "@baseboard_fab2_lib.baseboard_fab2(sch_1):page77_i43:vss(83)"
				( attribute "PN" "24"
					( Origin gPackager )
				)
				( objectStatus "J1G1.24" )
			)
			( pin "@baseboard_fab2_lib.baseboard_fab2(sch_1):page77_i43:vss(84)"
				( attribute "PN" "22"
					( Origin gPackager )
				)
				( objectStatus "J1G1.22" )
			)
			( pin "@baseboard_fab2_lib.baseboard_fab2(sch_1):page77_i43:vss(85)"
				( attribute "PN" "20"
					( Origin gPackager )
				)
				( objectStatus "J1G1.20" )
			)
			( pin "@baseboard_fab2_lib.baseboard_fab2(sch_1):page77_i43:vss(86)"
				( attribute "PN" "17"
					( Origin gPackager )
				)
				( objectStatus "J1G1.17" )
			)
			( pin "@baseboard_fab2_lib.baseboard_fab2(sch_1):page77_i43:vss(87)"
				( attribute "PN" "15"
					( Origin gPackager )
				)
				( objectStatus "J1G1.15" )
			)
			( pin "@baseboard_fab2_lib.baseboard_fab2(sch_1):page77_i43:vss(88)"
				( attribute "PN" "13"
					( Origin gPackager )
				)
				( objectStatus "J1G1.13" )
			)
			( pin "@baseboard_fab2_lib.baseboard_fab2(sch_1):page77_i43:vss(89)"
				( attribute "PN" "11"
					( Origin gPackager )
				)
				( objectStatus "J1G1.11" )
			)
			( pin "@baseboard_fab2_lib.baseboard_fab2(sch_1):page77_i43:vss(90)"
				( attribute "PN" "9"
					( Origin gPackager )
				)
				( objectStatus "J1G1.9" )
			)
			( pin "@baseboard_fab2_lib.baseboard_fab2(sch_1):page77_i43:vss(91)"
				( attribute "PN" "6"
					( Origin gPackager )
				)
				( objectStatus "J1G1.6" )
			)
			( pin "@baseboard_fab2_lib.baseboard_fab2(sch_1):page77_i43:vss(92)"
				( attribute "PN" "4"
					( Origin gPackager )
				)
				( objectStatus "J1G1.4" )
			)
			( pin "@baseboard_fab2_lib.baseboard_fab2(sch_1):page77_i43:vss(93)"
				( attribute "PN" "2"
					( Origin gPackager )
				)
				( objectStatus "J1G1.2" )
			)
			( pin "@baseboard_fab2_lib.baseboard_fab2(sch_1):page77_i66:dqs0n"
				( attribute "PN" "152"
					( Origin gPackager )
				)
				( objectStatus "J1G1.152" )
			)
			( pin "@baseboard_fab2_lib.baseboard_fab2(sch_1):page77_i66:dqs0p"
				( attribute "PN" "153"
					( Origin gPackager )
				)
				( objectStatus "J1G1.153" )
			)
			( pin "@baseboard_fab2_lib.baseboard_fab2(sch_1):page77_i66:dqs1n"
				( attribute "PN" "163"
					( Origin gPackager )
				)
				( objectStatus "J1G1.163" )
			)
			( pin "@baseboard_fab2_lib.baseboard_fab2(sch_1):page77_i66:dqs1p"
				( attribute "PN" "164"
					( Origin gPackager )
				)
				( objectStatus "J1G1.164" )
			)
			( pin "@baseboard_fab2_lib.baseboard_fab2(sch_1):page77_i66:dqs2n"
				( attribute "PN" "174"
					( Origin gPackager )
				)
				( objectStatus "J1G1.174" )
			)
			( pin "@baseboard_fab2_lib.baseboard_fab2(sch_1):page77_i66:dqs2p"
				( attribute "PN" "175"
					( Origin gPackager )
				)
				( objectStatus "J1G1.175" )
			)
			( pin "@baseboard_fab2_lib.baseboard_fab2(sch_1):page77_i66:dqs3n"
				( attribute "PN" "185"
					( Origin gPackager )
				)
				( objectStatus "J1G1.185" )
			)
			( pin "@baseboard_fab2_lib.baseboard_fab2(sch_1):page77_i66:dqs3p"
				( attribute "PN" "186"
					( Origin gPackager )
				)
				( objectStatus "J1G1.186" )
			)
			( pin "@baseboard_fab2_lib.baseboard_fab2(sch_1):page77_i66:dqs4n"
				( attribute "PN" "244"
					( Origin gPackager )
				)
				( objectStatus "J1G1.244" )
			)
			( pin "@baseboard_fab2_lib.baseboard_fab2(sch_1):page77_i66:dqs4p"
				( attribute "PN" "245"
					( Origin gPackager )
				)
				( objectStatus "J1G1.245" )
			)
			( pin "@baseboard_fab2_lib.baseboard_fab2(sch_1):page77_i66:dqs5n"
				( attribute "PN" "255"
					( Origin gPackager )
				)
				( objectStatus "J1G1.255" )
			)
			( pin "@baseboard_fab2_lib.baseboard_fab2(sch_1):page77_i66:dqs5p"
				( attribute "PN" "256"
					( Origin gPackager )
				)
				( objectStatus "J1G1.256" )
			)
			( pin "@baseboard_fab2_lib.baseboard_fab2(sch_1):page77_i66:dqs6n"
				( attribute "PN" "266"
					( Origin gPackager )
				)
				( objectStatus "J1G1.266" )
			)
			( pin "@baseboard_fab2_lib.baseboard_fab2(sch_1):page77_i66:dqs6p"
				( attribute "PN" "267"
					( Origin gPackager )
				)
				( objectStatus "J1G1.267" )
			)
			( pin "@baseboard_fab2_lib.baseboard_fab2(sch_1):page77_i66:dqs7n"
				( attribute "PN" "277"
					( Origin gPackager )
				)
				( objectStatus "J1G1.277" )
			)
			( pin "@baseboard_fab2_lib.baseboard_fab2(sch_1):page77_i66:dqs7p"
				( attribute "PN" "278"
					( Origin gPackager )
				)
				( objectStatus "J1G1.278" )
			)
			( pin "@baseboard_fab2_lib.baseboard_fab2(sch_1):page77_i66:dqs8n"
				( attribute "PN" "196"
					( Origin gPackager )
				)
				( objectStatus "J1G1.196" )
			)
			( pin "@baseboard_fab2_lib.baseboard_fab2(sch_1):page77_i66:dqs8p"
				( attribute "PN" "197"
					( Origin gPackager )
				)
				( objectStatus "J1G1.197" )
			)
			( pin "@baseboard_fab2_lib.baseboard_fab2(sch_1):page77_i66:dqs9n"
				( attribute "PN" "8"
					( Origin gPackager )
				)
				( objectStatus "J1G1.8" )
			)
			( pin "@baseboard_fab2_lib.baseboard_fab2(sch_1):page77_i66:dqs9p"
				( attribute "PN" "7"
					( Origin gPackager )
				)
				( objectStatus "J1G1.7" )
			)
			( pin "@baseboard_fab2_lib.baseboard_fab2(sch_1):page77_i66:dqs10n"
				( attribute "PN" "19"
					( Origin gPackager )
				)
				( objectStatus "J1G1.19" )
			)
			( pin "@baseboard_fab2_lib.baseboard_fab2(sch_1):page77_i66:dqs10p"
				( attribute "PN" "18"
					( Origin gPackager )
				)
				( objectStatus "J1G1.18" )
			)
			( pin "@baseboard_fab2_lib.baseboard_fab2(sch_1):page77_i66:dqs11n"
				( attribute "PN" "30"
					( Origin gPackager )
				)
				( objectStatus "J1G1.30" )
			)
			( pin "@baseboard_fab2_lib.baseboard_fab2(sch_1):page77_i66:dqs11p"
				( attribute "PN" "29"
					( Origin gPackager )
				)
				( objectStatus "J1G1.29" )
			)
			( pin "@baseboard_fab2_lib.baseboard_fab2(sch_1):page77_i66:dqs12n"
				( attribute "PN" "41"
					( Origin gPackager )
				)
				( objectStatus "J1G1.41" )
			)
			( pin "@baseboard_fab2_lib.baseboard_fab2(sch_1):page77_i66:dqs12p"
				( attribute "PN" "40"
					( Origin gPackager )
				)
				( objectStatus "J1G1.40" )
			)
			( pin "@baseboard_fab2_lib.baseboard_fab2(sch_1):page77_i66:dqs13n"
				( attribute "PN" "100"
					( Origin gPackager )
				)
				( objectStatus "J1G1.100" )
			)
			( pin "@baseboard_fab2_lib.baseboard_fab2(sch_1):page77_i66:dqs13p"
				( attribute "PN" "99"
					( Origin gPackager )
				)
				( objectStatus "J1G1.99" )
			)
			( pin "@baseboard_fab2_lib.baseboard_fab2(sch_1):page77_i66:dqs14n"
				( attribute "PN" "111"
					( Origin gPackager )
				)
				( objectStatus "J1G1.111" )
			)
			( pin "@baseboard_fab2_lib.baseboard_fab2(sch_1):page77_i66:dqs14p"
				( attribute "PN" "110"
					( Origin gPackager )
				)
				( objectStatus "J1G1.110" )
			)
			( pin "@baseboard_fab2_lib.baseboard_fab2(sch_1):page77_i66:dqs15n"
				( attribute "PN" "122"
					( Origin gPackager )
				)
				( objectStatus "J1G1.122" )
			)
			( pin "@baseboard_fab2_lib.baseboard_fab2(sch_1):page77_i66:dqs15p"
				( attribute "PN" "121"
					( Origin gPackager )
				)
				( objectStatus "J1G1.121" )
			)
			( pin "@baseboard_fab2_lib.baseboard_fab2(sch_1):page77_i66:dqs16n"
				( attribute "PN" "133"
					( Origin gPackager )
				)
				( objectStatus "J1G1.133" )
			)
			( pin "@baseboard_fab2_lib.baseboard_fab2(sch_1):page77_i66:dqs16p"
				( attribute "PN" "132"
					( Origin gPackager )
				)
				( objectStatus "J1G1.132" )
			)
			( pin "@baseboard_fab2_lib.baseboard_fab2(sch_1):page77_i66:dqs17n"
				( attribute "PN" "52"
					( Origin gPackager )
				)
				( objectStatus "J1G1.52" )
			)
			( pin "@baseboard_fab2_lib.baseboard_fab2(sch_1):page77_i66:dqs17p"
				( attribute "PN" "51"
					( Origin gPackager )
				)
				( objectStatus "J1G1.51" )
			)
			( pin "@baseboard_fab2_lib.baseboard_fab2(sch_1):page77_i111:a0"
				( attribute "PN" "79"
					( Origin gPackager )
				)
				( objectStatus "J1G1.79" )
			)
			( pin "@baseboard_fab2_lib.baseboard_fab2(sch_1):page77_i111:a1"
				( attribute "PN" "72"
					( Origin gPackager )
				)
				( objectStatus "J1G1.72" )
			)
			( pin "@baseboard_fab2_lib.baseboard_fab2(sch_1):page77_i111:a2"
				( attribute "PN" "216"
					( Origin gPackager )
				)
				( objectStatus "J1G1.216" )
			)
			( pin "@baseboard_fab2_lib.baseboard_fab2(sch_1):page77_i111:a3"
				( attribute "PN" "71"
					( Origin gPackager )
				)
				( objectStatus "J1G1.71" )
			)
			( pin "@baseboard_fab2_lib.baseboard_fab2(sch_1):page77_i111:a4"
				( attribute "PN" "214"
					( Origin gPackager )
				)
				( objectStatus "J1G1.214" )
			)
			( pin "@baseboard_fab2_lib.baseboard_fab2(sch_1):page77_i111:a5"
				( attribute "PN" "213"
					( Origin gPackager )
				)
				( objectStatus "J1G1.213" )
			)
			( pin "@baseboard_fab2_lib.baseboard_fab2(sch_1):page77_i111:a6"
				( attribute "PN" "69"
					( Origin gPackager )
				)
				( objectStatus "J1G1.69" )
			)
			( pin "@baseboard_fab2_lib.baseboard_fab2(sch_1):page77_i111:a7"
				( attribute "PN" "211"
					( Origin gPackager )
				)
				( objectStatus "J1G1.211" )
			)
			( pin "@baseboard_fab2_lib.baseboard_fab2(sch_1):page77_i111:a8"
				( attribute "PN" "68"
					( Origin gPackager )
				)
				( objectStatus "J1G1.68" )
			)
			( pin "@baseboard_fab2_lib.baseboard_fab2(sch_1):page77_i111:a9"
				( attribute "PN" "66"
					( Origin gPackager )
				)
				( objectStatus "J1G1.66" )
			)
			( pin "@baseboard_fab2_lib.baseboard_fab2(sch_1):page77_i111:a10"
				( attribute "PN" "225"
					( Origin gPackager )
				)
				( objectStatus "J1G1.225" )
			)
			( pin "@baseboard_fab2_lib.baseboard_fab2(sch_1):page77_i111:a11"
				( attribute "PN" "210"
					( Origin gPackager )
				)
				( objectStatus "J1G1.210" )
			)
			( pin "@baseboard_fab2_lib.baseboard_fab2(sch_1):page77_i111:a12"
				( attribute "PN" "65"
					( Origin gPackager )
				)
				( objectStatus "J1G1.65" )
			)
			( pin "@baseboard_fab2_lib.baseboard_fab2(sch_1):page77_i111:a13"
				( attribute "PN" "232"
					( Origin gPackager )
				)
				( objectStatus "J1G1.232" )
			)
			( pin "@baseboard_fab2_lib.baseboard_fab2(sch_1):page77_i111:a14_we_n"
				( attribute "PN" "228"
					( Origin gPackager )
				)
				( objectStatus "J1G1.228" )
			)
			( pin "@baseboard_fab2_lib.baseboard_fab2(sch_1):page77_i111:a15_cas_n"
				( attribute "PN" "86"
					( Origin gPackager )
				)
				( objectStatus "J1G1.86" )
			)
			( pin "@baseboard_fab2_lib.baseboard_fab2(sch_1):page77_i111:a16_ras_n"
				( attribute "PN" "82"
					( Origin gPackager )
				)
				( objectStatus "J1G1.82" )
			)
			( pin "@baseboard_fab2_lib.baseboard_fab2(sch_1):page77_i111:a17"
				( attribute "PN" "234"
					( Origin gPackager )
				)
				( objectStatus "J1G1.234" )
			)
			( pin "@baseboard_fab2_lib.baseboard_fab2(sch_1):page77_i111:act_n"
				( attribute "PN" "62"
					( Origin gPackager )
				)
				( objectStatus "J1G1.62" )
			)
			( pin "@baseboard_fab2_lib.baseboard_fab2(sch_1):page77_i111:alert_n"
				( attribute "PN" "208"
					( Origin gPackager )
				)
				( objectStatus "J1G1.208" )
			)
			( pin "@baseboard_fab2_lib.baseboard_fab2(sch_1):page77_i111:ba(0)"
				( attribute "PN" "81"
					( Origin gPackager )
				)
				( objectStatus "J1G1.81" )
			)
			( pin "@baseboard_fab2_lib.baseboard_fab2(sch_1):page77_i111:ba(1)"
				( attribute "PN" "224"
					( Origin gPackager )
				)
				( objectStatus "J1G1.224" )
			)
			( pin "@baseboard_fab2_lib.baseboard_fab2(sch_1):page77_i111:bg(0)"
				( attribute "PN" "63"
					( Origin gPackager )
				)
				( objectStatus "J1G1.63" )
			)
			( pin "@baseboard_fab2_lib.baseboard_fab2(sch_1):page77_i111:bg(1)"
				( attribute "PN" "207"
					( Origin gPackager )
				)
				( objectStatus "J1G1.207" )
			)
			( pin "@baseboard_fab2_lib.baseboard_fab2(sch_1):page77_i111:c(2)"
				( attribute "PN" "235"
					( Origin gPackager )
				)
				( objectStatus "J1G1.235" )
			)
			( pin "@baseboard_fab2_lib.baseboard_fab2(sch_1):page77_i111:cb(0)"
				( attribute "PN" "49"
					( Origin gPackager )
				)
				( objectStatus "J1G1.49" )
			)
			( pin "@baseboard_fab2_lib.baseboard_fab2(sch_1):page77_i111:cb(1)"
				( attribute "PN" "194"
					( Origin gPackager )
				)
				( objectStatus "J1G1.194" )
			)
			( pin "@baseboard_fab2_lib.baseboard_fab2(sch_1):page77_i111:cb(2)"
				( attribute "PN" "56"
					( Origin gPackager )
				)
				( objectStatus "J1G1.56" )
			)
			( pin "@baseboard_fab2_lib.baseboard_fab2(sch_1):page77_i111:cb(3)"
				( attribute "PN" "201"
					( Origin gPackager )
				)
				( objectStatus "J1G1.201" )
			)
			( pin "@baseboard_fab2_lib.baseboard_fab2(sch_1):page77_i111:cb(4)"
				( attribute "PN" "47"
					( Origin gPackager )
				)
				( objectStatus "J1G1.47" )
			)
			( pin "@baseboard_fab2_lib.baseboard_fab2(sch_1):page77_i111:cb(5)"
				( attribute "PN" "192"
					( Origin gPackager )
				)
				( objectStatus "J1G1.192" )
			)
			( pin "@baseboard_fab2_lib.baseboard_fab2(sch_1):page77_i111:cb(6)"
				( attribute "PN" "54"
					( Origin gPackager )
				)
				( objectStatus "J1G1.54" )
			)
			( pin "@baseboard_fab2_lib.baseboard_fab2(sch_1):page77_i111:cb(7)"
				( attribute "PN" "199"
					( Origin gPackager )
				)
				( objectStatus "J1G1.199" )
			)
			( pin "@baseboard_fab2_lib.baseboard_fab2(sch_1):page77_i111:ck0n"
				( attribute "PN" "75"
					( Origin gPackager )
				)
				( objectStatus "J1G1.75" )
			)
			( pin "@baseboard_fab2_lib.baseboard_fab2(sch_1):page77_i111:ck0p"
				( attribute "PN" "74"
					( Origin gPackager )
				)
				( objectStatus "J1G1.74" )
			)
			( pin "@baseboard_fab2_lib.baseboard_fab2(sch_1):page77_i111:ck1n"
				( attribute "PN" "219"
					( Origin gPackager )
				)
				( objectStatus "J1G1.219" )
			)
			( pin "@baseboard_fab2_lib.baseboard_fab2(sch_1):page77_i111:ck1p"
				( attribute "PN" "218"
					( Origin gPackager )
				)
				( objectStatus "J1G1.218" )
			)
			( pin "@baseboard_fab2_lib.baseboard_fab2(sch_1):page77_i111:cke(0)"
				( attribute "PN" "60"
					( Origin gPackager )
				)
				( objectStatus "J1G1.60" )
			)
			( pin "@baseboard_fab2_lib.baseboard_fab2(sch_1):page77_i111:cke(1)"
				( attribute "PN" "203"
					( Origin gPackager )
				)
				( objectStatus "J1G1.203" )
			)
			( pin "@baseboard_fab2_lib.baseboard_fab2(sch_1):page77_i111:dq(0)"
				( attribute "PN" "5"
					( Origin gPackager )
				)
				( objectStatus "J1G1.5" )
			)
			( pin "@baseboard_fab2_lib.baseboard_fab2(sch_1):page77_i111:dq(1)"
				( attribute "PN" "150"
					( Origin gPackager )
				)
				( objectStatus "J1G1.150" )
			)
			( pin "@baseboard_fab2_lib.baseboard_fab2(sch_1):page77_i111:dq(2)"
				( attribute "PN" "12"
					( Origin gPackager )
				)
				( objectStatus "J1G1.12" )
			)
			( pin "@baseboard_fab2_lib.baseboard_fab2(sch_1):page77_i111:dq(3)"
				( attribute "PN" "157"
					( Origin gPackager )
				)
				( objectStatus "J1G1.157" )
			)
			( pin "@baseboard_fab2_lib.baseboard_fab2(sch_1):page77_i111:dq(4)"
				( attribute "PN" "3"
					( Origin gPackager )
				)
				( objectStatus "J1G1.3" )
			)
			( pin "@baseboard_fab2_lib.baseboard_fab2(sch_1):page77_i111:dq(5)"
				( attribute "PN" "148"
					( Origin gPackager )
				)
				( objectStatus "J1G1.148" )
			)
			( pin "@baseboard_fab2_lib.baseboard_fab2(sch_1):page77_i111:dq(6)"
				( attribute "PN" "10"
					( Origin gPackager )
				)
				( objectStatus "J1G1.10" )
			)
			( pin "@baseboard_fab2_lib.baseboard_fab2(sch_1):page77_i111:dq(7)"
				( attribute "PN" "155"
					( Origin gPackager )
				)
				( objectStatus "J1G1.155" )
			)
			( pin "@baseboard_fab2_lib.baseboard_fab2(sch_1):page77_i111:dq(8)"
				( attribute "PN" "16"
					( Origin gPackager )
				)
				( objectStatus "J1G1.16" )
			)
			( pin "@baseboard_fab2_lib.baseboard_fab2(sch_1):page77_i111:dq(9)"
				( attribute "PN" "161"
					( Origin gPackager )
				)
				( objectStatus "J1G1.161" )
			)
			( pin "@baseboard_fab2_lib.baseboard_fab2(sch_1):page77_i111:dq(10)"
				( attribute "PN" "23"
					( Origin gPackager )
				)
				( objectStatus "J1G1.23" )
			)
			( pin "@baseboard_fab2_lib.baseboard_fab2(sch_1):page77_i111:dq(11)"
				( attribute "PN" "168"
					( Origin gPackager )
				)
				( objectStatus "J1G1.168" )
			)
			( pin "@baseboard_fab2_lib.baseboard_fab2(sch_1):page77_i111:dq(12)"
				( attribute "PN" "14"
					( Origin gPackager )
				)
				( objectStatus "J1G1.14" )
			)
			( pin "@baseboard_fab2_lib.baseboard_fab2(sch_1):page77_i111:dq(13)"
				( attribute "PN" "159"
					( Origin gPackager )
				)
				( objectStatus "J1G1.159" )
			)
			( pin "@baseboard_fab2_lib.baseboard_fab2(sch_1):page77_i111:dq(14)"
				( attribute "PN" "21"
					( Origin gPackager )
				)
				( objectStatus "J1G1.21" )
			)
			( pin "@baseboard_fab2_lib.baseboard_fab2(sch_1):page77_i111:dq(15)"
				( attribute "PN" "166"
					( Origin gPackager )
				)
				( objectStatus "J1G1.166" )
			)
			( pin "@baseboard_fab2_lib.baseboard_fab2(sch_1):page77_i111:dq(16)"
				( attribute "PN" "27"
					( Origin gPackager )
				)
				( objectStatus "J1G1.27" )
			)
			( pin "@baseboard_fab2_lib.baseboard_fab2(sch_1):page77_i111:dq(17)"
				( attribute "PN" "172"
					( Origin gPackager )
				)
				( objectStatus "J1G1.172" )
			)
			( pin "@baseboard_fab2_lib.baseboard_fab2(sch_1):page77_i111:dq(18)"
				( attribute "PN" "34"
					( Origin gPackager )
				)
				( objectStatus "J1G1.34" )
			)
			( pin "@baseboard_fab2_lib.baseboard_fab2(sch_1):page77_i111:dq(19)"
				( attribute "PN" "179"
					( Origin gPackager )
				)
				( objectStatus "J1G1.179" )
			)
			( pin "@baseboard_fab2_lib.baseboard_fab2(sch_1):page77_i111:dq(20)"
				( attribute "PN" "25"
					( Origin gPackager )
				)
				( objectStatus "J1G1.25" )
			)
			( pin "@baseboard_fab2_lib.baseboard_fab2(sch_1):page77_i111:dq(21)"
				( attribute "PN" "170"
					( Origin gPackager )
				)
				( objectStatus "J1G1.170" )
			)
			( pin "@baseboard_fab2_lib.baseboard_fab2(sch_1):page77_i111:dq(22)"
				( attribute "PN" "32"
					( Origin gPackager )
				)
				( objectStatus "J1G1.32" )
			)
			( pin "@baseboard_fab2_lib.baseboard_fab2(sch_1):page77_i111:dq(23)"
				( attribute "PN" "177"
					( Origin gPackager )
				)
				( objectStatus "J1G1.177" )
			)
			( pin "@baseboard_fab2_lib.baseboard_fab2(sch_1):page77_i111:dq(24)"
				( attribute "PN" "38"
					( Origin gPackager )
				)
				( objectStatus "J1G1.38" )
			)
			( pin "@baseboard_fab2_lib.baseboard_fab2(sch_1):page77_i111:dq(25)"
				( attribute "PN" "183"
					( Origin gPackager )
				)
				( objectStatus "J1G1.183" )
			)
			( pin "@baseboard_fab2_lib.baseboard_fab2(sch_1):page77_i111:dq(26)"
				( attribute "PN" "45"
					( Origin gPackager )
				)
				( objectStatus "J1G1.45" )
			)
			( pin "@baseboard_fab2_lib.baseboard_fab2(sch_1):page77_i111:dq(27)"
				( attribute "PN" "190"
					( Origin gPackager )
				)
				( objectStatus "J1G1.190" )
			)
			( pin "@baseboard_fab2_lib.baseboard_fab2(sch_1):page77_i111:dq(28)"
				( attribute "PN" "36"
					( Origin gPackager )
				)
				( objectStatus "J1G1.36" )
			)
			( pin "@baseboard_fab2_lib.baseboard_fab2(sch_1):page77_i111:dq(29)"
				( attribute "PN" "181"
					( Origin gPackager )
				)
				( objectStatus "J1G1.181" )
			)
			( pin "@baseboard_fab2_lib.baseboard_fab2(sch_1):page77_i111:dq(30)"
				( attribute "PN" "43"
					( Origin gPackager )
				)
				( objectStatus "J1G1.43" )
			)
			( pin "@baseboard_fab2_lib.baseboard_fab2(sch_1):page77_i111:dq(31)"
				( attribute "PN" "188"
					( Origin gPackager )
				)
				( objectStatus "J1G1.188" )
			)
			( pin "@baseboard_fab2_lib.baseboard_fab2(sch_1):page77_i111:dq(32)"
				( attribute "PN" "97"
					( Origin gPackager )
				)
				( objectStatus "J1G1.97" )
			)
			( pin "@baseboard_fab2_lib.baseboard_fab2(sch_1):page77_i111:dq(33)"
				( attribute "PN" "242"
					( Origin gPackager )
				)
				( objectStatus "J1G1.242" )
			)
			( pin "@baseboard_fab2_lib.baseboard_fab2(sch_1):page77_i111:dq(34)"
				( attribute "PN" "104"
					( Origin gPackager )
				)
				( objectStatus "J1G1.104" )
			)
			( pin "@baseboard_fab2_lib.baseboard_fab2(sch_1):page77_i111:dq(35)"
				( attribute "PN" "249"
					( Origin gPackager )
				)
				( objectStatus "J1G1.249" )
			)
			( pin "@baseboard_fab2_lib.baseboard_fab2(sch_1):page77_i111:dq(36)"
				( attribute "PN" "95"
					( Origin gPackager )
				)
				( objectStatus "J1G1.95" )
			)
			( pin "@baseboard_fab2_lib.baseboard_fab2(sch_1):page77_i111:dq(37)"
				( attribute "PN" "240"
					( Origin gPackager )
				)
				( objectStatus "J1G1.240" )
			)
			( pin "@baseboard_fab2_lib.baseboard_fab2(sch_1):page77_i111:dq(38)"
				( attribute "PN" "102"
					( Origin gPackager )
				)
				( objectStatus "J1G1.102" )
			)
			( pin "@baseboard_fab2_lib.baseboard_fab2(sch_1):page77_i111:dq(39)"
				( attribute "PN" "247"
					( Origin gPackager )
				)
				( objectStatus "J1G1.247" )
			)
			( pin "@baseboard_fab2_lib.baseboard_fab2(sch_1):page77_i111:dq(40)"
				( attribute "PN" "108"
					( Origin gPackager )
				)
				( objectStatus "J1G1.108" )
			)
			( pin "@baseboard_fab2_lib.baseboard_fab2(sch_1):page77_i111:dq(41)"
				( attribute "PN" "253"
					( Origin gPackager )
				)
				( objectStatus "J1G1.253" )
			)
			( pin "@baseboard_fab2_lib.baseboard_fab2(sch_1):page77_i111:dq(42)"
				( attribute "PN" "115"
					( Origin gPackager )
				)
				( objectStatus "J1G1.115" )
			)
			( pin "@baseboard_fab2_lib.baseboard_fab2(sch_1):page77_i111:dq(43)"
				( attribute "PN" "260"
					( Origin gPackager )
				)
				( objectStatus "J1G1.260" )
			)
			( pin "@baseboard_fab2_lib.baseboard_fab2(sch_1):page77_i111:dq(44)"
				( attribute "PN" "106"
					( Origin gPackager )
				)
				( objectStatus "J1G1.106" )
			)
			( pin "@baseboard_fab2_lib.baseboard_fab2(sch_1):page77_i111:dq(45)"
				( attribute "PN" "251"
					( Origin gPackager )
				)
				( objectStatus "J1G1.251" )
			)
			( pin "@baseboard_fab2_lib.baseboard_fab2(sch_1):page77_i111:dq(46)"
				( attribute "PN" "113"
					( Origin gPackager )
				)
				( objectStatus "J1G1.113" )
			)
			( pin "@baseboard_fab2_lib.baseboard_fab2(sch_1):page77_i111:dq(47)"
				( attribute "PN" "258"
					( Origin gPackager )
				)
				( objectStatus "J1G1.258" )
			)
			( pin "@baseboard_fab2_lib.baseboard_fab2(sch_1):page77_i111:dq(48)"
				( attribute "PN" "119"
					( Origin gPackager )
				)
				( objectStatus "J1G1.119" )
			)
			( pin "@baseboard_fab2_lib.baseboard_fab2(sch_1):page77_i111:dq(49)"
				( attribute "PN" "264"
					( Origin gPackager )
				)
				( objectStatus "J1G1.264" )
			)
			( pin "@baseboard_fab2_lib.baseboard_fab2(sch_1):page77_i111:dq(50)"
				( attribute "PN" "126"
					( Origin gPackager )
				)
				( objectStatus "J1G1.126" )
			)
			( pin "@baseboard_fab2_lib.baseboard_fab2(sch_1):page77_i111:dq(51)"
				( attribute "PN" "271"
					( Origin gPackager )
				)
				( objectStatus "J1G1.271" )
			)
			( pin "@baseboard_fab2_lib.baseboard_fab2(sch_1):page77_i111:dq(52)"
				( attribute "PN" "117"
					( Origin gPackager )
				)
				( objectStatus "J1G1.117" )
			)
			( pin "@baseboard_fab2_lib.baseboard_fab2(sch_1):page77_i111:dq(53)"
				( attribute "PN" "262"
					( Origin gPackager )
				)
				( objectStatus "J1G1.262" )
			)
			( pin "@baseboard_fab2_lib.baseboard_fab2(sch_1):page77_i111:dq(54)"
				( attribute "PN" "124"
					( Origin gPackager )
				)
				( objectStatus "J1G1.124" )
			)
			( pin "@baseboard_fab2_lib.baseboard_fab2(sch_1):page77_i111:dq(55)"
				( attribute "PN" "269"
					( Origin gPackager )
				)
				( objectStatus "J1G1.269" )
			)
			( pin "@baseboard_fab2_lib.baseboard_fab2(sch_1):page77_i111:dq(56)"
				( attribute "PN" "130"
					( Origin gPackager )
				)
				( objectStatus "J1G1.130" )
			)
			( pin "@baseboard_fab2_lib.baseboard_fab2(sch_1):page77_i111:dq(57)"
				( attribute "PN" "275"
					( Origin gPackager )
				)
				( objectStatus "J1G1.275" )
			)
			( pin "@baseboard_fab2_lib.baseboard_fab2(sch_1):page77_i111:dq(58)"
				( attribute "PN" "137"
					( Origin gPackager )
				)
				( objectStatus "J1G1.137" )
			)
			( pin "@baseboard_fab2_lib.baseboard_fab2(sch_1):page77_i111:dq(59)"
				( attribute "PN" "282"
					( Origin gPackager )
				)
				( objectStatus "J1G1.282" )
			)
			( pin "@baseboard_fab2_lib.baseboard_fab2(sch_1):page77_i111:dq(60)"
				( attribute "PN" "128"
					( Origin gPackager )
				)
				( objectStatus "J1G1.128" )
			)
			( pin "@baseboard_fab2_lib.baseboard_fab2(sch_1):page77_i111:dq(61)"
				( attribute "PN" "273"
					( Origin gPackager )
				)
				( objectStatus "J1G1.273" )
			)
			( pin "@baseboard_fab2_lib.baseboard_fab2(sch_1):page77_i111:dq(62)"
				( attribute "PN" "135"
					( Origin gPackager )
				)
				( objectStatus "J1G1.135" )
			)
			( pin "@baseboard_fab2_lib.baseboard_fab2(sch_1):page77_i111:dq(63)"
				( attribute "PN" "280"
					( Origin gPackager )
				)
				( objectStatus "J1G1.280" )
			)
			( pin "@baseboard_fab2_lib.baseboard_fab2(sch_1):page77_i111:event_n"
				( attribute "PN" "78"
					( Origin gPackager )
				)
				( objectStatus "J1G1.78" )
			)
			( pin "@baseboard_fab2_lib.baseboard_fab2(sch_1):page77_i111:odt(0)"
				( attribute "PN" "87"
					( Origin gPackager )
				)
				( objectStatus "J1G1.87" )
			)
			( pin "@baseboard_fab2_lib.baseboard_fab2(sch_1):page77_i111:odt(1)"
				( attribute "PN" "91"
					( Origin gPackager )
				)
				( objectStatus "J1G1.91" )
			)
			( pin "@baseboard_fab2_lib.baseboard_fab2(sch_1):page77_i111:par"
				( attribute "PN" "222"
					( Origin gPackager )
				)
				( objectStatus "J1G1.222" )
			)
			( pin "@baseboard_fab2_lib.baseboard_fab2(sch_1):page77_i111:reset_n"
				( attribute "PN" "58"
					( Origin gPackager )
				)
				( objectStatus "J1G1.58" )
			)
			( pin "@baseboard_fab2_lib.baseboard_fab2(sch_1):page77_i111:rfu(0)"
				( attribute "PN" "205"
					( Origin gPackager )
				)
				( objectStatus "J1G1.205" )
			)
			( pin "@baseboard_fab2_lib.baseboard_fab2(sch_1):page77_i111:rfu(1)"
				( attribute "PN" "227"
					( Origin gPackager )
				)
				( objectStatus "J1G1.227" )
			)
			( pin "@baseboard_fab2_lib.baseboard_fab2(sch_1):page77_i111:rfu(2)"
				( attribute "PN" "144"
					( Origin gPackager )
				)
				( objectStatus "J1G1.144" )
			)
			( pin "@baseboard_fab2_lib.baseboard_fab2(sch_1):page77_i111:s0_n"
				( attribute "PN" "84"
					( Origin gPackager )
				)
				( objectStatus "J1G1.84" )
			)
			( pin "@baseboard_fab2_lib.baseboard_fab2(sch_1):page77_i111:s1_n"
				( attribute "PN" "89"
					( Origin gPackager )
				)
				( objectStatus "J1G1.89" )
			)
			( pin "@baseboard_fab2_lib.baseboard_fab2(sch_1):page77_i111:s2_n_c(0)"
				( attribute "PN" "93"
					( Origin gPackager )
				)
				( objectStatus "J1G1.93" )
			)
			( pin "@baseboard_fab2_lib.baseboard_fab2(sch_1):page77_i111:s3_n_c(1)"
				( attribute "PN" "237"
					( Origin gPackager )
				)
				( objectStatus "J1G1.237" )
			)
			( pin "@baseboard_fab2_lib.baseboard_fab2(sch_1):page77_i111:sa(0)"
				( attribute "PN" "139"
					( Origin gPackager )
				)
				( objectStatus "J1G1.139" )
			)
			( pin "@baseboard_fab2_lib.baseboard_fab2(sch_1):page77_i111:sa(1)"
				( attribute "PN" "140"
					( Origin gPackager )
				)
				( objectStatus "J1G1.140" )
			)
			( pin "@baseboard_fab2_lib.baseboard_fab2(sch_1):page77_i111:sa(2)"
				( attribute "PN" "238"
					( Origin gPackager )
				)
				( objectStatus "J1G1.238" )
			)
			( pin "@baseboard_fab2_lib.baseboard_fab2(sch_1):page77_i111:save_n_nc"
				( attribute "PN" "230"
					( Origin gPackager )
				)
				( objectStatus "J1G1.230" )
			)
			( pin "@baseboard_fab2_lib.baseboard_fab2(sch_1):page77_i111:scl"
				( attribute "PN" "141"
					( Origin gPackager )
				)
				( objectStatus "J1G1.141" )
			)
			( pin "@baseboard_fab2_lib.baseboard_fab2(sch_1):page77_i111:sda"
				( attribute "PN" "285"
					( Origin gPackager )
				)
				( objectStatus "J1G1.285" )
			)
			( pin "@baseboard_fab2_lib.baseboard_fab2(sch_1):page77_i111:vddspd"
				( attribute "PN" "284"
					( Origin gPackager )
				)
				( objectStatus "J1G1.284" )
			)
			( pin "@baseboard_fab2_lib.baseboard_fab2(sch_1):page77_i111:vrefca"
				( attribute "PN" "146"
					( Origin gPackager )
				)
				( objectStatus "J1G1.146" )
			)
			( pin "@baseboard_fab2_lib.baseboard_fab2(sch_1):page77_i171:\12v\(0)"
				( attribute "PN" "145"
					( Origin gPackager )
				)
				( objectStatus "J1G1.145" )
			)
			( pin "@baseboard_fab2_lib.baseboard_fab2(sch_1):page77_i171:\12v\(1)"
				( attribute "PN" "1"
					( Origin gPackager )
				)
				( objectStatus "J1G1.1" )
			)
			( pin "@baseboard_fab2_lib.baseboard_fab2(sch_1):page77_i171:vdd(0)"
				( attribute "PN" "236"
					( Origin gPackager )
				)
				( objectStatus "J1G1.236" )
			)
			( pin "@baseboard_fab2_lib.baseboard_fab2(sch_1):page77_i171:vdd(1)"
				( attribute "PN" "233"
					( Origin gPackager )
				)
				( objectStatus "J1G1.233" )
			)
			( pin "@baseboard_fab2_lib.baseboard_fab2(sch_1):page77_i171:vdd(2)"
				( attribute "PN" "231"
					( Origin gPackager )
				)
				( objectStatus "J1G1.231" )
			)
			( pin "@baseboard_fab2_lib.baseboard_fab2(sch_1):page77_i171:vdd(3)"
				( attribute "PN" "229"
					( Origin gPackager )
				)
				( objectStatus "J1G1.229" )
			)
			( pin "@baseboard_fab2_lib.baseboard_fab2(sch_1):page77_i171:vdd(4)"
				( attribute "PN" "226"
					( Origin gPackager )
				)
				( objectStatus "J1G1.226" )
			)
			( pin "@baseboard_fab2_lib.baseboard_fab2(sch_1):page77_i171:vdd(5)"
				( attribute "PN" "223"
					( Origin gPackager )
				)
				( objectStatus "J1G1.223" )
			)
			( pin "@baseboard_fab2_lib.baseboard_fab2(sch_1):page77_i171:vdd(6)"
				( attribute "PN" "220"
					( Origin gPackager )
				)
				( objectStatus "J1G1.220" )
			)
			( pin "@baseboard_fab2_lib.baseboard_fab2(sch_1):page77_i171:vdd(7)"
				( attribute "PN" "217"
					( Origin gPackager )
				)
				( objectStatus "J1G1.217" )
			)
			( pin "@baseboard_fab2_lib.baseboard_fab2(sch_1):page77_i171:vdd(8)"
				( attribute "PN" "215"
					( Origin gPackager )
				)
				( objectStatus "J1G1.215" )
			)
			( pin "@baseboard_fab2_lib.baseboard_fab2(sch_1):page77_i171:vdd(9)"
				( attribute "PN" "212"
					( Origin gPackager )
				)
				( objectStatus "J1G1.212" )
			)
			( pin "@baseboard_fab2_lib.baseboard_fab2(sch_1):page77_i171:vdd(10)"
				( attribute "PN" "209"
					( Origin gPackager )
				)
				( objectStatus "J1G1.209" )
			)
			( pin "@baseboard_fab2_lib.baseboard_fab2(sch_1):page77_i171:vdd(11)"
				( attribute "PN" "206"
					( Origin gPackager )
				)
				( objectStatus "J1G1.206" )
			)
			( pin "@baseboard_fab2_lib.baseboard_fab2(sch_1):page77_i171:vdd(12)"
				( attribute "PN" "204"
					( Origin gPackager )
				)
				( objectStatus "J1G1.204" )
			)
			( pin "@baseboard_fab2_lib.baseboard_fab2(sch_1):page77_i171:vdd(13)"
				( attribute "PN" "92"
					( Origin gPackager )
				)
				( objectStatus "J1G1.92" )
			)
			( pin "@baseboard_fab2_lib.baseboard_fab2(sch_1):page77_i171:vdd(14)"
				( attribute "PN" "90"
					( Origin gPackager )
				)
				( objectStatus "J1G1.90" )
			)
			( pin "@baseboard_fab2_lib.baseboard_fab2(sch_1):page77_i171:vdd(15)"
				( attribute "PN" "88"
					( Origin gPackager )
				)
				( objectStatus "J1G1.88" )
			)
			( pin "@baseboard_fab2_lib.baseboard_fab2(sch_1):page77_i171:vdd(16)"
				( attribute "PN" "85"
					( Origin gPackager )
				)
				( objectStatus "J1G1.85" )
			)
			( pin "@baseboard_fab2_lib.baseboard_fab2(sch_1):page77_i171:vdd(17)"
				( attribute "PN" "83"
					( Origin gPackager )
				)
				( objectStatus "J1G1.83" )
			)
			( pin "@baseboard_fab2_lib.baseboard_fab2(sch_1):page77_i171:vdd(18)"
				( attribute "PN" "80"
					( Origin gPackager )
				)
				( objectStatus "J1G1.80" )
			)
			( pin "@baseboard_fab2_lib.baseboard_fab2(sch_1):page77_i171:vdd(19)"
				( attribute "PN" "76"
					( Origin gPackager )
				)
				( objectStatus "J1G1.76" )
			)
			( pin "@baseboard_fab2_lib.baseboard_fab2(sch_1):page77_i171:vdd(20)"
				( attribute "PN" "73"
					( Origin gPackager )
				)
				( objectStatus "J1G1.73" )
			)
			( pin "@baseboard_fab2_lib.baseboard_fab2(sch_1):page77_i171:vdd(21)"
				( attribute "PN" "70"
					( Origin gPackager )
				)
				( objectStatus "J1G1.70" )
			)
			( pin "@baseboard_fab2_lib.baseboard_fab2(sch_1):page77_i171:vdd(22)"
				( attribute "PN" "67"
					( Origin gPackager )
				)
				( objectStatus "J1G1.67" )
			)
			( pin "@baseboard_fab2_lib.baseboard_fab2(sch_1):page77_i171:vdd(23)"
				( attribute "PN" "64"
					( Origin gPackager )
				)
				( objectStatus "J1G1.64" )
			)
			( pin "@baseboard_fab2_lib.baseboard_fab2(sch_1):page77_i171:vdd(24)"
				( attribute "PN" "61"
					( Origin gPackager )
				)
				( objectStatus "J1G1.61" )
			)
			( pin "@baseboard_fab2_lib.baseboard_fab2(sch_1):page77_i171:vdd(25)"
				( attribute "PN" "59"
					( Origin gPackager )
				)
				( objectStatus "J1G1.59" )
			)
			( pin "@baseboard_fab2_lib.baseboard_fab2(sch_1):page77_i171:vpp(0)"
				( attribute "PN" "287"
					( Origin gPackager )
				)
				( objectStatus "J1G1.287" )
			)
			( pin "@baseboard_fab2_lib.baseboard_fab2(sch_1):page77_i171:vpp(1)"
				( attribute "PN" "286"
					( Origin gPackager )
				)
				( objectStatus "J1G1.286" )
			)
			( pin "@baseboard_fab2_lib.baseboard_fab2(sch_1):page77_i171:vpp(2)"
				( attribute "PN" "288"
					( Origin gPackager )
				)
				( objectStatus "J1G1.288" )
			)
			( pin "@baseboard_fab2_lib.baseboard_fab2(sch_1):page77_i171:vpp(3)"
				( attribute "PN" "143"
					( Origin gPackager )
				)
				( objectStatus "J1G1.143" )
			)
			( pin "@baseboard_fab2_lib.baseboard_fab2(sch_1):page77_i171:vpp(4)"
				( attribute "PN" "142"
					( Origin gPackager )
				)
				( objectStatus "J1G1.142" )
			)
			( pin "@baseboard_fab2_lib.baseboard_fab2(sch_1):page77_i171:vtt(0)"
				( attribute "PN" "221"
					( Origin gPackager )
				)
				( objectStatus "J1G1.221" )
			)
			( pin "@baseboard_fab2_lib.baseboard_fab2(sch_1):page77_i171:vtt(1)"
				( attribute "PN" "77"
					( Origin gPackager )
				)
				( objectStatus "J1G1.77" )
			)
			( pin "@baseboard_fab2_lib.baseboard_fab2(sch_1):page77_i181:a"
				( attribute "PN" "1"
					( Origin gPackager )
				)
				( objectStatus "C1F22.1" )
			)
			( pin "@baseboard_fab2_lib.baseboard_fab2(sch_1):page77_i181:b"
				( attribute "PN" "2"
					( Origin gPackager )
				)
				( objectStatus "C1F22.2" )
			)
			( pin "@baseboard_fab2_lib.baseboard_fab2(sch_1):page78_i2:a"
				( attribute "PN" "1"
					( Origin gPackager )
				)
				( objectStatus "C9T7.1" )
			)
			( pin "@baseboard_fab2_lib.baseboard_fab2(sch_1):page78_i2:b"
				( attribute "PN" "2"
					( Origin gPackager )
				)
				( objectStatus "C9T7.2" )
			)
			( pin "@baseboard_fab2_lib.baseboard_fab2(sch_1):page78_i13:a0"
				( attribute "PN" "79"
					( Origin gPackager )
				)
				( objectStatus "J9T1.79" )
			)
			( pin "@baseboard_fab2_lib.baseboard_fab2(sch_1):page78_i13:a1"
				( attribute "PN" "72"
					( Origin gPackager )
				)
				( objectStatus "J9T1.72" )
			)
			( pin "@baseboard_fab2_lib.baseboard_fab2(sch_1):page78_i13:a2"
				( attribute "PN" "216"
					( Origin gPackager )
				)
				( objectStatus "J9T1.216" )
			)
			( pin "@baseboard_fab2_lib.baseboard_fab2(sch_1):page78_i13:a3"
				( attribute "PN" "71"
					( Origin gPackager )
				)
				( objectStatus "J9T1.71" )
			)
			( pin "@baseboard_fab2_lib.baseboard_fab2(sch_1):page78_i13:a4"
				( attribute "PN" "214"
					( Origin gPackager )
				)
				( objectStatus "J9T1.214" )
			)
			( pin "@baseboard_fab2_lib.baseboard_fab2(sch_1):page78_i13:a5"
				( attribute "PN" "213"
					( Origin gPackager )
				)
				( objectStatus "J9T1.213" )
			)
			( pin "@baseboard_fab2_lib.baseboard_fab2(sch_1):page78_i13:a6"
				( attribute "PN" "69"
					( Origin gPackager )
				)
				( objectStatus "J9T1.69" )
			)
			( pin "@baseboard_fab2_lib.baseboard_fab2(sch_1):page78_i13:a7"
				( attribute "PN" "211"
					( Origin gPackager )
				)
				( objectStatus "J9T1.211" )
			)
			( pin "@baseboard_fab2_lib.baseboard_fab2(sch_1):page78_i13:a8"
				( attribute "PN" "68"
					( Origin gPackager )
				)
				( objectStatus "J9T1.68" )
			)
			( pin "@baseboard_fab2_lib.baseboard_fab2(sch_1):page78_i13:a9"
				( attribute "PN" "66"
					( Origin gPackager )
				)
				( objectStatus "J9T1.66" )
			)
			( pin "@baseboard_fab2_lib.baseboard_fab2(sch_1):page78_i13:a10"
				( attribute "PN" "225"
					( Origin gPackager )
				)
				( objectStatus "J9T1.225" )
			)
			( pin "@baseboard_fab2_lib.baseboard_fab2(sch_1):page78_i13:a11"
				( attribute "PN" "210"
					( Origin gPackager )
				)
				( objectStatus "J9T1.210" )
			)
			( pin "@baseboard_fab2_lib.baseboard_fab2(sch_1):page78_i13:a12"
				( attribute "PN" "65"
					( Origin gPackager )
				)
				( objectStatus "J9T1.65" )
			)
			( pin "@baseboard_fab2_lib.baseboard_fab2(sch_1):page78_i13:a13"
				( attribute "PN" "232"
					( Origin gPackager )
				)
				( objectStatus "J9T1.232" )
			)
			( pin "@baseboard_fab2_lib.baseboard_fab2(sch_1):page78_i13:a14_we_n"
				( attribute "PN" "228"
					( Origin gPackager )
				)
				( objectStatus "J9T1.228" )
			)
			( pin "@baseboard_fab2_lib.baseboard_fab2(sch_1):page78_i13:a15_cas_n"
				( attribute "PN" "86"
					( Origin gPackager )
				)
				( objectStatus "J9T1.86" )
			)
			( pin "@baseboard_fab2_lib.baseboard_fab2(sch_1):page78_i13:a16_ras_n"
				( attribute "PN" "82"
					( Origin gPackager )
				)
				( objectStatus "J9T1.82" )
			)
			( pin "@baseboard_fab2_lib.baseboard_fab2(sch_1):page78_i13:a17"
				( attribute "PN" "234"
					( Origin gPackager )
				)
				( objectStatus "J9T1.234" )
			)
			( pin "@baseboard_fab2_lib.baseboard_fab2(sch_1):page78_i13:act_n"
				( attribute "PN" "62"
					( Origin gPackager )
				)
				( objectStatus "J9T1.62" )
			)
			( pin "@baseboard_fab2_lib.baseboard_fab2(sch_1):page78_i13:alert_n"
				( attribute "PN" "208"
					( Origin gPackager )
				)
				( objectStatus "J9T1.208" )
			)
			( pin "@baseboard_fab2_lib.baseboard_fab2(sch_1):page78_i13:ba(0)"
				( attribute "PN" "81"
					( Origin gPackager )
				)
				( objectStatus "J9T1.81" )
			)
			( pin "@baseboard_fab2_lib.baseboard_fab2(sch_1):page78_i13:ba(1)"
				( attribute "PN" "224"
					( Origin gPackager )
				)
				( objectStatus "J9T1.224" )
			)
			( pin "@baseboard_fab2_lib.baseboard_fab2(sch_1):page78_i13:bg(0)"
				( attribute "PN" "63"
					( Origin gPackager )
				)
				( objectStatus "J9T1.63" )
			)
			( pin "@baseboard_fab2_lib.baseboard_fab2(sch_1):page78_i13:bg(1)"
				( attribute "PN" "207"
					( Origin gPackager )
				)
				( objectStatus "J9T1.207" )
			)
			( pin "@baseboard_fab2_lib.baseboard_fab2(sch_1):page78_i13:c(2)"
				( attribute "PN" "235"
					( Origin gPackager )
				)
				( objectStatus "J9T1.235" )
			)
			( pin "@baseboard_fab2_lib.baseboard_fab2(sch_1):page78_i13:cb(0)"
				( attribute "PN" "49"
					( Origin gPackager )
				)
				( objectStatus "J9T1.49" )
			)
			( pin "@baseboard_fab2_lib.baseboard_fab2(sch_1):page78_i13:cb(1)"
				( attribute "PN" "194"
					( Origin gPackager )
				)
				( objectStatus "J9T1.194" )
			)
			( pin "@baseboard_fab2_lib.baseboard_fab2(sch_1):page78_i13:cb(2)"
				( attribute "PN" "56"
					( Origin gPackager )
				)
				( objectStatus "J9T1.56" )
			)
			( pin "@baseboard_fab2_lib.baseboard_fab2(sch_1):page78_i13:cb(3)"
				( attribute "PN" "201"
					( Origin gPackager )
				)
				( objectStatus "J9T1.201" )
			)
			( pin "@baseboard_fab2_lib.baseboard_fab2(sch_1):page78_i13:cb(4)"
				( attribute "PN" "47"
					( Origin gPackager )
				)
				( objectStatus "J9T1.47" )
			)
			( pin "@baseboard_fab2_lib.baseboard_fab2(sch_1):page78_i13:cb(5)"
				( attribute "PN" "192"
					( Origin gPackager )
				)
				( objectStatus "J9T1.192" )
			)
			( pin "@baseboard_fab2_lib.baseboard_fab2(sch_1):page78_i13:cb(6)"
				( attribute "PN" "54"
					( Origin gPackager )
				)
				( objectStatus "J9T1.54" )
			)
			( pin "@baseboard_fab2_lib.baseboard_fab2(sch_1):page78_i13:cb(7)"
				( attribute "PN" "199"
					( Origin gPackager )
				)
				( objectStatus "J9T1.199" )
			)
			( pin "@baseboard_fab2_lib.baseboard_fab2(sch_1):page78_i13:ck0n"
				( attribute "PN" "75"
					( Origin gPackager )
				)
				( objectStatus "J9T1.75" )
			)
			( pin "@baseboard_fab2_lib.baseboard_fab2(sch_1):page78_i13:ck0p"
				( attribute "PN" "74"
					( Origin gPackager )
				)
				( objectStatus "J9T1.74" )
			)
			( pin "@baseboard_fab2_lib.baseboard_fab2(sch_1):page78_i13:ck1n"
				( attribute "PN" "219"
					( Origin gPackager )
				)
				( objectStatus "J9T1.219" )
			)
			( pin "@baseboard_fab2_lib.baseboard_fab2(sch_1):page78_i13:ck1p"
				( attribute "PN" "218"
					( Origin gPackager )
				)
				( objectStatus "J9T1.218" )
			)
			( pin "@baseboard_fab2_lib.baseboard_fab2(sch_1):page78_i13:cke(0)"
				( attribute "PN" "60"
					( Origin gPackager )
				)
				( objectStatus "J9T1.60" )
			)
			( pin "@baseboard_fab2_lib.baseboard_fab2(sch_1):page78_i13:cke(1)"
				( attribute "PN" "203"
					( Origin gPackager )
				)
				( objectStatus "J9T1.203" )
			)
			( pin "@baseboard_fab2_lib.baseboard_fab2(sch_1):page78_i13:dq(0)"
				( attribute "PN" "5"
					( Origin gPackager )
				)
				( objectStatus "J9T1.5" )
			)
			( pin "@baseboard_fab2_lib.baseboard_fab2(sch_1):page78_i13:dq(1)"
				( attribute "PN" "150"
					( Origin gPackager )
				)
				( objectStatus "J9T1.150" )
			)
			( pin "@baseboard_fab2_lib.baseboard_fab2(sch_1):page78_i13:dq(2)"
				( attribute "PN" "12"
					( Origin gPackager )
				)
				( objectStatus "J9T1.12" )
			)
			( pin "@baseboard_fab2_lib.baseboard_fab2(sch_1):page78_i13:dq(3)"
				( attribute "PN" "157"
					( Origin gPackager )
				)
				( objectStatus "J9T1.157" )
			)
			( pin "@baseboard_fab2_lib.baseboard_fab2(sch_1):page78_i13:dq(4)"
				( attribute "PN" "3"
					( Origin gPackager )
				)
				( objectStatus "J9T1.3" )
			)
			( pin "@baseboard_fab2_lib.baseboard_fab2(sch_1):page78_i13:dq(5)"
				( attribute "PN" "148"
					( Origin gPackager )
				)
				( objectStatus "J9T1.148" )
			)
			( pin "@baseboard_fab2_lib.baseboard_fab2(sch_1):page78_i13:dq(6)"
				( attribute "PN" "10"
					( Origin gPackager )
				)
				( objectStatus "J9T1.10" )
			)
			( pin "@baseboard_fab2_lib.baseboard_fab2(sch_1):page78_i13:dq(7)"
				( attribute "PN" "155"
					( Origin gPackager )
				)
				( objectStatus "J9T1.155" )
			)
			( pin "@baseboard_fab2_lib.baseboard_fab2(sch_1):page78_i13:dq(8)"
				( attribute "PN" "16"
					( Origin gPackager )
				)
				( objectStatus "J9T1.16" )
			)
			( pin "@baseboard_fab2_lib.baseboard_fab2(sch_1):page78_i13:dq(9)"
				( attribute "PN" "161"
					( Origin gPackager )
				)
				( objectStatus "J9T1.161" )
			)
			( pin "@baseboard_fab2_lib.baseboard_fab2(sch_1):page78_i13:dq(10)"
				( attribute "PN" "23"
					( Origin gPackager )
				)
				( objectStatus "J9T1.23" )
			)
			( pin "@baseboard_fab2_lib.baseboard_fab2(sch_1):page78_i13:dq(11)"
				( attribute "PN" "168"
					( Origin gPackager )
				)
				( objectStatus "J9T1.168" )
			)
			( pin "@baseboard_fab2_lib.baseboard_fab2(sch_1):page78_i13:dq(12)"
				( attribute "PN" "14"
					( Origin gPackager )
				)
				( objectStatus "J9T1.14" )
			)
			( pin "@baseboard_fab2_lib.baseboard_fab2(sch_1):page78_i13:dq(13)"
				( attribute "PN" "159"
					( Origin gPackager )
				)
				( objectStatus "J9T1.159" )
			)
			( pin "@baseboard_fab2_lib.baseboard_fab2(sch_1):page78_i13:dq(14)"
				( attribute "PN" "21"
					( Origin gPackager )
				)
				( objectStatus "J9T1.21" )
			)
			( pin "@baseboard_fab2_lib.baseboard_fab2(sch_1):page78_i13:dq(15)"
				( attribute "PN" "166"
					( Origin gPackager )
				)
				( objectStatus "J9T1.166" )
			)
			( pin "@baseboard_fab2_lib.baseboard_fab2(sch_1):page78_i13:dq(16)"
				( attribute "PN" "27"
					( Origin gPackager )
				)
				( objectStatus "J9T1.27" )
			)
			( pin "@baseboard_fab2_lib.baseboard_fab2(sch_1):page78_i13:dq(17)"
				( attribute "PN" "172"
					( Origin gPackager )
				)
				( objectStatus "J9T1.172" )
			)
			( pin "@baseboard_fab2_lib.baseboard_fab2(sch_1):page78_i13:dq(18)"
				( attribute "PN" "34"
					( Origin gPackager )
				)
				( objectStatus "J9T1.34" )
			)
			( pin "@baseboard_fab2_lib.baseboard_fab2(sch_1):page78_i13:dq(19)"
				( attribute "PN" "179"
					( Origin gPackager )
				)
				( objectStatus "J9T1.179" )
			)
			( pin "@baseboard_fab2_lib.baseboard_fab2(sch_1):page78_i13:dq(20)"
				( attribute "PN" "25"
					( Origin gPackager )
				)
				( objectStatus "J9T1.25" )
			)
			( pin "@baseboard_fab2_lib.baseboard_fab2(sch_1):page78_i13:dq(21)"
				( attribute "PN" "170"
					( Origin gPackager )
				)
				( objectStatus "J9T1.170" )
			)
			( pin "@baseboard_fab2_lib.baseboard_fab2(sch_1):page78_i13:dq(22)"
				( attribute "PN" "32"
					( Origin gPackager )
				)
				( objectStatus "J9T1.32" )
			)
			( pin "@baseboard_fab2_lib.baseboard_fab2(sch_1):page78_i13:dq(23)"
				( attribute "PN" "177"
					( Origin gPackager )
				)
				( objectStatus "J9T1.177" )
			)
			( pin "@baseboard_fab2_lib.baseboard_fab2(sch_1):page78_i13:dq(24)"
				( attribute "PN" "38"
					( Origin gPackager )
				)
				( objectStatus "J9T1.38" )
			)
			( pin "@baseboard_fab2_lib.baseboard_fab2(sch_1):page78_i13:dq(25)"
				( attribute "PN" "183"
					( Origin gPackager )
				)
				( objectStatus "J9T1.183" )
			)
			( pin "@baseboard_fab2_lib.baseboard_fab2(sch_1):page78_i13:dq(26)"
				( attribute "PN" "45"
					( Origin gPackager )
				)
				( objectStatus "J9T1.45" )
			)
			( pin "@baseboard_fab2_lib.baseboard_fab2(sch_1):page78_i13:dq(27)"
				( attribute "PN" "190"
					( Origin gPackager )
				)
				( objectStatus "J9T1.190" )
			)
			( pin "@baseboard_fab2_lib.baseboard_fab2(sch_1):page78_i13:dq(28)"
				( attribute "PN" "36"
					( Origin gPackager )
				)
				( objectStatus "J9T1.36" )
			)
			( pin "@baseboard_fab2_lib.baseboard_fab2(sch_1):page78_i13:dq(29)"
				( attribute "PN" "181"
					( Origin gPackager )
				)
				( objectStatus "J9T1.181" )
			)
			( pin "@baseboard_fab2_lib.baseboard_fab2(sch_1):page78_i13:dq(30)"
				( attribute "PN" "43"
					( Origin gPackager )
				)
				( objectStatus "J9T1.43" )
			)
			( pin "@baseboard_fab2_lib.baseboard_fab2(sch_1):page78_i13:dq(31)"
				( attribute "PN" "188"
					( Origin gPackager )
				)
				( objectStatus "J9T1.188" )
			)
			( pin "@baseboard_fab2_lib.baseboard_fab2(sch_1):page78_i13:dq(32)"
				( attribute "PN" "97"
					( Origin gPackager )
				)
				( objectStatus "J9T1.97" )
			)
			( pin "@baseboard_fab2_lib.baseboard_fab2(sch_1):page78_i13:dq(33)"
				( attribute "PN" "242"
					( Origin gPackager )
				)
				( objectStatus "J9T1.242" )
			)
			( pin "@baseboard_fab2_lib.baseboard_fab2(sch_1):page78_i13:dq(34)"
				( attribute "PN" "104"
					( Origin gPackager )
				)
				( objectStatus "J9T1.104" )
			)
			( pin "@baseboard_fab2_lib.baseboard_fab2(sch_1):page78_i13:dq(35)"
				( attribute "PN" "249"
					( Origin gPackager )
				)
				( objectStatus "J9T1.249" )
			)
			( pin "@baseboard_fab2_lib.baseboard_fab2(sch_1):page78_i13:dq(36)"
				( attribute "PN" "95"
					( Origin gPackager )
				)
				( objectStatus "J9T1.95" )
			)
			( pin "@baseboard_fab2_lib.baseboard_fab2(sch_1):page78_i13:dq(37)"
				( attribute "PN" "240"
					( Origin gPackager )
				)
				( objectStatus "J9T1.240" )
			)
			( pin "@baseboard_fab2_lib.baseboard_fab2(sch_1):page78_i13:dq(38)"
				( attribute "PN" "102"
					( Origin gPackager )
				)
				( objectStatus "J9T1.102" )
			)
			( pin "@baseboard_fab2_lib.baseboard_fab2(sch_1):page78_i13:dq(39)"
				( attribute "PN" "247"
					( Origin gPackager )
				)
				( objectStatus "J9T1.247" )
			)
			( pin "@baseboard_fab2_lib.baseboard_fab2(sch_1):page78_i13:dq(40)"
				( attribute "PN" "108"
					( Origin gPackager )
				)
				( objectStatus "J9T1.108" )
			)
			( pin "@baseboard_fab2_lib.baseboard_fab2(sch_1):page78_i13:dq(41)"
				( attribute "PN" "253"
					( Origin gPackager )
				)
				( objectStatus "J9T1.253" )
			)
			( pin "@baseboard_fab2_lib.baseboard_fab2(sch_1):page78_i13:dq(42)"
				( attribute "PN" "115"
					( Origin gPackager )
				)
				( objectStatus "J9T1.115" )
			)
			( pin "@baseboard_fab2_lib.baseboard_fab2(sch_1):page78_i13:dq(43)"
				( attribute "PN" "260"
					( Origin gPackager )
				)
				( objectStatus "J9T1.260" )
			)
			( pin "@baseboard_fab2_lib.baseboard_fab2(sch_1):page78_i13:dq(44)"
				( attribute "PN" "106"
					( Origin gPackager )
				)
				( objectStatus "J9T1.106" )
			)
			( pin "@baseboard_fab2_lib.baseboard_fab2(sch_1):page78_i13:dq(45)"
				( attribute "PN" "251"
					( Origin gPackager )
				)
				( objectStatus "J9T1.251" )
			)
			( pin "@baseboard_fab2_lib.baseboard_fab2(sch_1):page78_i13:dq(46)"
				( attribute "PN" "113"
					( Origin gPackager )
				)
				( objectStatus "J9T1.113" )
			)
			( pin "@baseboard_fab2_lib.baseboard_fab2(sch_1):page78_i13:dq(47)"
				( attribute "PN" "258"
					( Origin gPackager )
				)
				( objectStatus "J9T1.258" )
			)
			( pin "@baseboard_fab2_lib.baseboard_fab2(sch_1):page78_i13:dq(48)"
				( attribute "PN" "119"
					( Origin gPackager )
				)
				( objectStatus "J9T1.119" )
			)
			( pin "@baseboard_fab2_lib.baseboard_fab2(sch_1):page78_i13:dq(49)"
				( attribute "PN" "264"
					( Origin gPackager )
				)
				( objectStatus "J9T1.264" )
			)
			( pin "@baseboard_fab2_lib.baseboard_fab2(sch_1):page78_i13:dq(50)"
				( attribute "PN" "126"
					( Origin gPackager )
				)
				( objectStatus "J9T1.126" )
			)
			( pin "@baseboard_fab2_lib.baseboard_fab2(sch_1):page78_i13:dq(51)"
				( attribute "PN" "271"
					( Origin gPackager )
				)
				( objectStatus "J9T1.271" )
			)
			( pin "@baseboard_fab2_lib.baseboard_fab2(sch_1):page78_i13:dq(52)"
				( attribute "PN" "117"
					( Origin gPackager )
				)
				( objectStatus "J9T1.117" )
			)
			( pin "@baseboard_fab2_lib.baseboard_fab2(sch_1):page78_i13:dq(53)"
				( attribute "PN" "262"
					( Origin gPackager )
				)
				( objectStatus "J9T1.262" )
			)
			( pin "@baseboard_fab2_lib.baseboard_fab2(sch_1):page78_i13:dq(54)"
				( attribute "PN" "124"
					( Origin gPackager )
				)
				( objectStatus "J9T1.124" )
			)
			( pin "@baseboard_fab2_lib.baseboard_fab2(sch_1):page78_i13:dq(55)"
				( attribute "PN" "269"
					( Origin gPackager )
				)
				( objectStatus "J9T1.269" )
			)
			( pin "@baseboard_fab2_lib.baseboard_fab2(sch_1):page78_i13:dq(56)"
				( attribute "PN" "130"
					( Origin gPackager )
				)
				( objectStatus "J9T1.130" )
			)
			( pin "@baseboard_fab2_lib.baseboard_fab2(sch_1):page78_i13:dq(57)"
				( attribute "PN" "275"
					( Origin gPackager )
				)
				( objectStatus "J9T1.275" )
			)
			( pin "@baseboard_fab2_lib.baseboard_fab2(sch_1):page78_i13:dq(58)"
				( attribute "PN" "137"
					( Origin gPackager )
				)
				( objectStatus "J9T1.137" )
			)
			( pin "@baseboard_fab2_lib.baseboard_fab2(sch_1):page78_i13:dq(59)"
				( attribute "PN" "282"
					( Origin gPackager )
				)
				( objectStatus "J9T1.282" )
			)
			( pin "@baseboard_fab2_lib.baseboard_fab2(sch_1):page78_i13:dq(60)"
				( attribute "PN" "128"
					( Origin gPackager )
				)
				( objectStatus "J9T1.128" )
			)
			( pin "@baseboard_fab2_lib.baseboard_fab2(sch_1):page78_i13:dq(61)"
				( attribute "PN" "273"
					( Origin gPackager )
				)
				( objectStatus "J9T1.273" )
			)
			( pin "@baseboard_fab2_lib.baseboard_fab2(sch_1):page78_i13:dq(62)"
				( attribute "PN" "135"
					( Origin gPackager )
				)
				( objectStatus "J9T1.135" )
			)
			( pin "@baseboard_fab2_lib.baseboard_fab2(sch_1):page78_i13:dq(63)"
				( attribute "PN" "280"
					( Origin gPackager )
				)
				( objectStatus "J9T1.280" )
			)
			( pin "@baseboard_fab2_lib.baseboard_fab2(sch_1):page78_i13:event_n"
				( attribute "PN" "78"
					( Origin gPackager )
				)
				( objectStatus "J9T1.78" )
			)
			( pin "@baseboard_fab2_lib.baseboard_fab2(sch_1):page78_i13:odt(0)"
				( attribute "PN" "87"
					( Origin gPackager )
				)
				( objectStatus "J9T1.87" )
			)
			( pin "@baseboard_fab2_lib.baseboard_fab2(sch_1):page78_i13:odt(1)"
				( attribute "PN" "91"
					( Origin gPackager )
				)
				( objectStatus "J9T1.91" )
			)
			( pin "@baseboard_fab2_lib.baseboard_fab2(sch_1):page78_i13:par"
				( attribute "PN" "222"
					( Origin gPackager )
				)
				( objectStatus "J9T1.222" )
			)
			( pin "@baseboard_fab2_lib.baseboard_fab2(sch_1):page78_i13:reset_n"
				( attribute "PN" "58"
					( Origin gPackager )
				)
				( objectStatus "J9T1.58" )
			)
			( pin "@baseboard_fab2_lib.baseboard_fab2(sch_1):page78_i13:rfu(0)"
				( attribute "PN" "205"
					( Origin gPackager )
				)
				( objectStatus "J9T1.205" )
			)
			( pin "@baseboard_fab2_lib.baseboard_fab2(sch_1):page78_i13:rfu(1)"
				( attribute "PN" "227"
					( Origin gPackager )
				)
				( objectStatus "J9T1.227" )
			)
			( pin "@baseboard_fab2_lib.baseboard_fab2(sch_1):page78_i13:rfu(2)"
				( attribute "PN" "144"
					( Origin gPackager )
				)
				( objectStatus "J9T1.144" )
			)
			( pin "@baseboard_fab2_lib.baseboard_fab2(sch_1):page78_i13:s0_n"
				( attribute "PN" "84"
					( Origin gPackager )
				)
				( objectStatus "J9T1.84" )
			)
			( pin "@baseboard_fab2_lib.baseboard_fab2(sch_1):page78_i13:s1_n"
				( attribute "PN" "89"
					( Origin gPackager )
				)
				( objectStatus "J9T1.89" )
			)
			( pin "@baseboard_fab2_lib.baseboard_fab2(sch_1):page78_i13:s2_n_c(0)"
				( attribute "PN" "93"
					( Origin gPackager )
				)
				( objectStatus "J9T1.93" )
			)
			( pin "@baseboard_fab2_lib.baseboard_fab2(sch_1):page78_i13:s3_n_c(1)"
				( attribute "PN" "237"
					( Origin gPackager )
				)
				( objectStatus "J9T1.237" )
			)
			( pin "@baseboard_fab2_lib.baseboard_fab2(sch_1):page78_i13:sa(0)"
				( attribute "PN" "139"
					( Origin gPackager )
				)
				( objectStatus "J9T1.139" )
			)
			( pin "@baseboard_fab2_lib.baseboard_fab2(sch_1):page78_i13:sa(1)"
				( attribute "PN" "140"
					( Origin gPackager )
				)
				( objectStatus "J9T1.140" )
			)
			( pin "@baseboard_fab2_lib.baseboard_fab2(sch_1):page78_i13:sa(2)"
				( attribute "PN" "238"
					( Origin gPackager )
				)
				( objectStatus "J9T1.238" )
			)
			( pin "@baseboard_fab2_lib.baseboard_fab2(sch_1):page78_i13:save_n_nc"
				( attribute "PN" "230"
					( Origin gPackager )
				)
				( objectStatus "J9T1.230" )
			)
			( pin "@baseboard_fab2_lib.baseboard_fab2(sch_1):page78_i13:scl"
				( attribute "PN" "141"
					( Origin gPackager )
				)
				( objectStatus "J9T1.141" )
			)
			( pin "@baseboard_fab2_lib.baseboard_fab2(sch_1):page78_i13:sda"
				( attribute "PN" "285"
					( Origin gPackager )
				)
				( objectStatus "J9T1.285" )
			)
			( pin "@baseboard_fab2_lib.baseboard_fab2(sch_1):page78_i13:vddspd"
				( attribute "PN" "284"
					( Origin gPackager )
				)
				( objectStatus "J9T1.284" )
			)
			( pin "@baseboard_fab2_lib.baseboard_fab2(sch_1):page78_i13:vrefca"
				( attribute "PN" "146"
					( Origin gPackager )
				)
				( objectStatus "J9T1.146" )
			)
			( pin "@baseboard_fab2_lib.baseboard_fab2(sch_1):page78_i75:\12v\(0)"
				( attribute "PN" "145"
					( Origin gPackager )
				)
				( objectStatus "J9T1.145" )
			)
			( pin "@baseboard_fab2_lib.baseboard_fab2(sch_1):page78_i75:\12v\(1)"
				( attribute "PN" "1"
					( Origin gPackager )
				)
				( objectStatus "J9T1.1" )
			)
			( pin "@baseboard_fab2_lib.baseboard_fab2(sch_1):page78_i75:vdd(0)"
				( attribute "PN" "236"
					( Origin gPackager )
				)
				( objectStatus "J9T1.236" )
			)
			( pin "@baseboard_fab2_lib.baseboard_fab2(sch_1):page78_i75:vdd(1)"
				( attribute "PN" "233"
					( Origin gPackager )
				)
				( objectStatus "J9T1.233" )
			)
			( pin "@baseboard_fab2_lib.baseboard_fab2(sch_1):page78_i75:vdd(2)"
				( attribute "PN" "231"
					( Origin gPackager )
				)
				( objectStatus "J9T1.231" )
			)
			( pin "@baseboard_fab2_lib.baseboard_fab2(sch_1):page78_i75:vdd(3)"
				( attribute "PN" "229"
					( Origin gPackager )
				)
				( objectStatus "J9T1.229" )
			)
			( pin "@baseboard_fab2_lib.baseboard_fab2(sch_1):page78_i75:vdd(4)"
				( attribute "PN" "226"
					( Origin gPackager )
				)
				( objectStatus "J9T1.226" )
			)
			( pin "@baseboard_fab2_lib.baseboard_fab2(sch_1):page78_i75:vdd(5)"
				( attribute "PN" "223"
					( Origin gPackager )
				)
				( objectStatus "J9T1.223" )
			)
			( pin "@baseboard_fab2_lib.baseboard_fab2(sch_1):page78_i75:vdd(6)"
				( attribute "PN" "220"
					( Origin gPackager )
				)
				( objectStatus "J9T1.220" )
			)
			( pin "@baseboard_fab2_lib.baseboard_fab2(sch_1):page78_i75:vdd(7)"
				( attribute "PN" "217"
					( Origin gPackager )
				)
				( objectStatus "J9T1.217" )
			)
			( pin "@baseboard_fab2_lib.baseboard_fab2(sch_1):page78_i75:vdd(8)"
				( attribute "PN" "215"
					( Origin gPackager )
				)
				( objectStatus "J9T1.215" )
			)
			( pin "@baseboard_fab2_lib.baseboard_fab2(sch_1):page78_i75:vdd(9)"
				( attribute "PN" "212"
					( Origin gPackager )
				)
				( objectStatus "J9T1.212" )
			)
			( pin "@baseboard_fab2_lib.baseboard_fab2(sch_1):page78_i75:vdd(10)"
				( attribute "PN" "209"
					( Origin gPackager )
				)
				( objectStatus "J9T1.209" )
			)
			( pin "@baseboard_fab2_lib.baseboard_fab2(sch_1):page78_i75:vdd(11)"
				( attribute "PN" "206"
					( Origin gPackager )
				)
				( objectStatus "J9T1.206" )
			)
			( pin "@baseboard_fab2_lib.baseboard_fab2(sch_1):page78_i75:vdd(12)"
				( attribute "PN" "204"
					( Origin gPackager )
				)
				( objectStatus "J9T1.204" )
			)
			( pin "@baseboard_fab2_lib.baseboard_fab2(sch_1):page78_i75:vdd(13)"
				( attribute "PN" "92"
					( Origin gPackager )
				)
				( objectStatus "J9T1.92" )
			)
			( pin "@baseboard_fab2_lib.baseboard_fab2(sch_1):page78_i75:vdd(14)"
				( attribute "PN" "90"
					( Origin gPackager )
				)
				( objectStatus "J9T1.90" )
			)
			( pin "@baseboard_fab2_lib.baseboard_fab2(sch_1):page78_i75:vdd(15)"
				( attribute "PN" "88"
					( Origin gPackager )
				)
				( objectStatus "J9T1.88" )
			)
			( pin "@baseboard_fab2_lib.baseboard_fab2(sch_1):page78_i75:vdd(16)"
				( attribute "PN" "85"
					( Origin gPackager )
				)
				( objectStatus "J9T1.85" )
			)
			( pin "@baseboard_fab2_lib.baseboard_fab2(sch_1):page78_i75:vdd(17)"
				( attribute "PN" "83"
					( Origin gPackager )
				)
				( objectStatus "J9T1.83" )
			)
			( pin "@baseboard_fab2_lib.baseboard_fab2(sch_1):page78_i75:vdd(18)"
				( attribute "PN" "80"
					( Origin gPackager )
				)
				( objectStatus "J9T1.80" )
			)
			( pin "@baseboard_fab2_lib.baseboard_fab2(sch_1):page78_i75:vdd(19)"
				( attribute "PN" "76"
					( Origin gPackager )
				)
				( objectStatus "J9T1.76" )
			)
			( pin "@baseboard_fab2_lib.baseboard_fab2(sch_1):page78_i75:vdd(20)"
				( attribute "PN" "73"
					( Origin gPackager )
				)
				( objectStatus "J9T1.73" )
			)
			( pin "@baseboard_fab2_lib.baseboard_fab2(sch_1):page78_i75:vdd(21)"
				( attribute "PN" "70"
					( Origin gPackager )
				)
				( objectStatus "J9T1.70" )
			)
			( pin "@baseboard_fab2_lib.baseboard_fab2(sch_1):page78_i75:vdd(22)"
				( attribute "PN" "67"
					( Origin gPackager )
				)
				( objectStatus "J9T1.67" )
			)
			( pin "@baseboard_fab2_lib.baseboard_fab2(sch_1):page78_i75:vdd(23)"
				( attribute "PN" "64"
					( Origin gPackager )
				)
				( objectStatus "J9T1.64" )
			)
			( pin "@baseboard_fab2_lib.baseboard_fab2(sch_1):page78_i75:vdd(24)"
				( attribute "PN" "61"
					( Origin gPackager )
				)
				( objectStatus "J9T1.61" )
			)
			( pin "@baseboard_fab2_lib.baseboard_fab2(sch_1):page78_i75:vdd(25)"
				( attribute "PN" "59"
					( Origin gPackager )
				)
				( objectStatus "J9T1.59" )
			)
			( pin "@baseboard_fab2_lib.baseboard_fab2(sch_1):page78_i75:vpp(0)"
				( attribute "PN" "287"
					( Origin gPackager )
				)
				( objectStatus "J9T1.287" )
			)
			( pin "@baseboard_fab2_lib.baseboard_fab2(sch_1):page78_i75:vpp(1)"
				( attribute "PN" "286"
					( Origin gPackager )
				)
				( objectStatus "J9T1.286" )
			)
			( pin "@baseboard_fab2_lib.baseboard_fab2(sch_1):page78_i75:vpp(2)"
				( attribute "PN" "288"
					( Origin gPackager )
				)
				( objectStatus "J9T1.288" )
			)
			( pin "@baseboard_fab2_lib.baseboard_fab2(sch_1):page78_i75:vpp(3)"
				( attribute "PN" "143"
					( Origin gPackager )
				)
				( objectStatus "J9T1.143" )
			)
			( pin "@baseboard_fab2_lib.baseboard_fab2(sch_1):page78_i75:vpp(4)"
				( attribute "PN" "142"
					( Origin gPackager )
				)
				( objectStatus "J9T1.142" )
			)
			( pin "@baseboard_fab2_lib.baseboard_fab2(sch_1):page78_i75:vtt(0)"
				( attribute "PN" "221"
					( Origin gPackager )
				)
				( objectStatus "J9T1.221" )
			)
			( pin "@baseboard_fab2_lib.baseboard_fab2(sch_1):page78_i75:vtt(1)"
				( attribute "PN" "77"
					( Origin gPackager )
				)
				( objectStatus "J9T1.77" )
			)
			( pin "@baseboard_fab2_lib.baseboard_fab2(sch_1):page78_i120:dqs0n"
				( attribute "PN" "152"
					( Origin gPackager )
				)
				( objectStatus "J9T1.152" )
			)
			( pin "@baseboard_fab2_lib.baseboard_fab2(sch_1):page78_i120:dqs0p"
				( attribute "PN" "153"
					( Origin gPackager )
				)
				( objectStatus "J9T1.153" )
			)
			( pin "@baseboard_fab2_lib.baseboard_fab2(sch_1):page78_i120:dqs1n"
				( attribute "PN" "163"
					( Origin gPackager )
				)
				( objectStatus "J9T1.163" )
			)
			( pin "@baseboard_fab2_lib.baseboard_fab2(sch_1):page78_i120:dqs1p"
				( attribute "PN" "164"
					( Origin gPackager )
				)
				( objectStatus "J9T1.164" )
			)
			( pin "@baseboard_fab2_lib.baseboard_fab2(sch_1):page78_i120:dqs2n"
				( attribute "PN" "174"
					( Origin gPackager )
				)
				( objectStatus "J9T1.174" )
			)
			( pin "@baseboard_fab2_lib.baseboard_fab2(sch_1):page78_i120:dqs2p"
				( attribute "PN" "175"
					( Origin gPackager )
				)
				( objectStatus "J9T1.175" )
			)
			( pin "@baseboard_fab2_lib.baseboard_fab2(sch_1):page78_i120:dqs3n"
				( attribute "PN" "185"
					( Origin gPackager )
				)
				( objectStatus "J9T1.185" )
			)
			( pin "@baseboard_fab2_lib.baseboard_fab2(sch_1):page78_i120:dqs3p"
				( attribute "PN" "186"
					( Origin gPackager )
				)
				( objectStatus "J9T1.186" )
			)
			( pin "@baseboard_fab2_lib.baseboard_fab2(sch_1):page78_i120:dqs4n"
				( attribute "PN" "244"
					( Origin gPackager )
				)
				( objectStatus "J9T1.244" )
			)
			( pin "@baseboard_fab2_lib.baseboard_fab2(sch_1):page78_i120:dqs4p"
				( attribute "PN" "245"
					( Origin gPackager )
				)
				( objectStatus "J9T1.245" )
			)
			( pin "@baseboard_fab2_lib.baseboard_fab2(sch_1):page78_i120:dqs5n"
				( attribute "PN" "255"
					( Origin gPackager )
				)
				( objectStatus "J9T1.255" )
			)
			( pin "@baseboard_fab2_lib.baseboard_fab2(sch_1):page78_i120:dqs5p"
				( attribute "PN" "256"
					( Origin gPackager )
				)
				( objectStatus "J9T1.256" )
			)
			( pin "@baseboard_fab2_lib.baseboard_fab2(sch_1):page78_i120:dqs6n"
				( attribute "PN" "266"
					( Origin gPackager )
				)
				( objectStatus "J9T1.266" )
			)
			( pin "@baseboard_fab2_lib.baseboard_fab2(sch_1):page78_i120:dqs6p"
				( attribute "PN" "267"
					( Origin gPackager )
				)
				( objectStatus "J9T1.267" )
			)
			( pin "@baseboard_fab2_lib.baseboard_fab2(sch_1):page78_i120:dqs7n"
				( attribute "PN" "277"
					( Origin gPackager )
				)
				( objectStatus "J9T1.277" )
			)
			( pin "@baseboard_fab2_lib.baseboard_fab2(sch_1):page78_i120:dqs7p"
				( attribute "PN" "278"
					( Origin gPackager )
				)
				( objectStatus "J9T1.278" )
			)
			( pin "@baseboard_fab2_lib.baseboard_fab2(sch_1):page78_i120:dqs8n"
				( attribute "PN" "196"
					( Origin gPackager )
				)
				( objectStatus "J9T1.196" )
			)
			( pin "@baseboard_fab2_lib.baseboard_fab2(sch_1):page78_i120:dqs8p"
				( attribute "PN" "197"
					( Origin gPackager )
				)
				( objectStatus "J9T1.197" )
			)
			( pin "@baseboard_fab2_lib.baseboard_fab2(sch_1):page78_i120:dqs9n"
				( attribute "PN" "8"
					( Origin gPackager )
				)
				( objectStatus "J9T1.8" )
			)
			( pin "@baseboard_fab2_lib.baseboard_fab2(sch_1):page78_i120:dqs9p"
				( attribute "PN" "7"
					( Origin gPackager )
				)
				( objectStatus "J9T1.7" )
			)
			( pin "@baseboard_fab2_lib.baseboard_fab2(sch_1):page78_i120:dqs10n"
				( attribute "PN" "19"
					( Origin gPackager )
				)
				( objectStatus "J9T1.19" )
			)
			( pin "@baseboard_fab2_lib.baseboard_fab2(sch_1):page78_i120:dqs10p"
				( attribute "PN" "18"
					( Origin gPackager )
				)
				( objectStatus "J9T1.18" )
			)
			( pin "@baseboard_fab2_lib.baseboard_fab2(sch_1):page78_i120:dqs11n"
				( attribute "PN" "30"
					( Origin gPackager )
				)
				( objectStatus "J9T1.30" )
			)
			( pin "@baseboard_fab2_lib.baseboard_fab2(sch_1):page78_i120:dqs11p"
				( attribute "PN" "29"
					( Origin gPackager )
				)
				( objectStatus "J9T1.29" )
			)
			( pin "@baseboard_fab2_lib.baseboard_fab2(sch_1):page78_i120:dqs12n"
				( attribute "PN" "41"
					( Origin gPackager )
				)
				( objectStatus "J9T1.41" )
			)
			( pin "@baseboard_fab2_lib.baseboard_fab2(sch_1):page78_i120:dqs12p"
				( attribute "PN" "40"
					( Origin gPackager )
				)
				( objectStatus "J9T1.40" )
			)
			( pin "@baseboard_fab2_lib.baseboard_fab2(sch_1):page78_i120:dqs13n"
				( attribute "PN" "100"
					( Origin gPackager )
				)
				( objectStatus "J9T1.100" )
			)
			( pin "@baseboard_fab2_lib.baseboard_fab2(sch_1):page78_i120:dqs13p"
				( attribute "PN" "99"
					( Origin gPackager )
				)
				( objectStatus "J9T1.99" )
			)
			( pin "@baseboard_fab2_lib.baseboard_fab2(sch_1):page78_i120:dqs14n"
				( attribute "PN" "111"
					( Origin gPackager )
				)
				( objectStatus "J9T1.111" )
			)
			( pin "@baseboard_fab2_lib.baseboard_fab2(sch_1):page78_i120:dqs14p"
				( attribute "PN" "110"
					( Origin gPackager )
				)
				( objectStatus "J9T1.110" )
			)
			( pin "@baseboard_fab2_lib.baseboard_fab2(sch_1):page78_i120:dqs15n"
				( attribute "PN" "122"
					( Origin gPackager )
				)
				( objectStatus "J9T1.122" )
			)
			( pin "@baseboard_fab2_lib.baseboard_fab2(sch_1):page78_i120:dqs15p"
				( attribute "PN" "121"
					( Origin gPackager )
				)
				( objectStatus "J9T1.121" )
			)
			( pin "@baseboard_fab2_lib.baseboard_fab2(sch_1):page78_i120:dqs16n"
				( attribute "PN" "133"
					( Origin gPackager )
				)
				( objectStatus "J9T1.133" )
			)
			( pin "@baseboard_fab2_lib.baseboard_fab2(sch_1):page78_i120:dqs16p"
				( attribute "PN" "132"
					( Origin gPackager )
				)
				( objectStatus "J9T1.132" )
			)
			( pin "@baseboard_fab2_lib.baseboard_fab2(sch_1):page78_i120:dqs17n"
				( attribute "PN" "52"
					( Origin gPackager )
				)
				( objectStatus "J9T1.52" )
			)
			( pin "@baseboard_fab2_lib.baseboard_fab2(sch_1):page78_i120:dqs17p"
				( attribute "PN" "51"
					( Origin gPackager )
				)
				( objectStatus "J9T1.51" )
			)
			( pin "@baseboard_fab2_lib.baseboard_fab2(sch_1):page78_i144:vss(0)"
				( attribute "PN" "283"
					( Origin gPackager )
				)
				( objectStatus "J9T1.283" )
			)
			( pin "@baseboard_fab2_lib.baseboard_fab2(sch_1):page78_i144:vss(1)"
				( attribute "PN" "281"
					( Origin gPackager )
				)
				( objectStatus "J9T1.281" )
			)
			( pin "@baseboard_fab2_lib.baseboard_fab2(sch_1):page78_i144:vss(2)"
				( attribute "PN" "279"
					( Origin gPackager )
				)
				( objectStatus "J9T1.279" )
			)
			( pin "@baseboard_fab2_lib.baseboard_fab2(sch_1):page78_i144:vss(3)"
				( attribute "PN" "276"
					( Origin gPackager )
				)
				( objectStatus "J9T1.276" )
			)
			( pin "@baseboard_fab2_lib.baseboard_fab2(sch_1):page78_i144:vss(4)"
				( attribute "PN" "274"
					( Origin gPackager )
				)
				( objectStatus "J9T1.274" )
			)
			( pin "@baseboard_fab2_lib.baseboard_fab2(sch_1):page78_i144:vss(5)"
				( attribute "PN" "272"
					( Origin gPackager )
				)
				( objectStatus "J9T1.272" )
			)
			( pin "@baseboard_fab2_lib.baseboard_fab2(sch_1):page78_i144:vss(6)"
				( attribute "PN" "270"
					( Origin gPackager )
				)
				( objectStatus "J9T1.270" )
			)
			( pin "@baseboard_fab2_lib.baseboard_fab2(sch_1):page78_i144:vss(7)"
				( attribute "PN" "268"
					( Origin gPackager )
				)
				( objectStatus "J9T1.268" )
			)
			( pin "@baseboard_fab2_lib.baseboard_fab2(sch_1):page78_i144:vss(8)"
				( attribute "PN" "265"
					( Origin gPackager )
				)
				( objectStatus "J9T1.265" )
			)
			( pin "@baseboard_fab2_lib.baseboard_fab2(sch_1):page78_i144:vss(9)"
				( attribute "PN" "263"
					( Origin gPackager )
				)
				( objectStatus "J9T1.263" )
			)
			( pin "@baseboard_fab2_lib.baseboard_fab2(sch_1):page78_i144:vss(10)"
				( attribute "PN" "261"
					( Origin gPackager )
				)
				( objectStatus "J9T1.261" )
			)
			( pin "@baseboard_fab2_lib.baseboard_fab2(sch_1):page78_i144:vss(11)"
				( attribute "PN" "259"
					( Origin gPackager )
				)
				( objectStatus "J9T1.259" )
			)
			( pin "@baseboard_fab2_lib.baseboard_fab2(sch_1):page78_i144:vss(12)"
				( attribute "PN" "257"
					( Origin gPackager )
				)
				( objectStatus "J9T1.257" )
			)
			( pin "@baseboard_fab2_lib.baseboard_fab2(sch_1):page78_i144:vss(13)"
				( attribute "PN" "254"
					( Origin gPackager )
				)
				( objectStatus "J9T1.254" )
			)
			( pin "@baseboard_fab2_lib.baseboard_fab2(sch_1):page78_i144:vss(14)"
				( attribute "PN" "252"
					( Origin gPackager )
				)
				( objectStatus "J9T1.252" )
			)
			( pin "@baseboard_fab2_lib.baseboard_fab2(sch_1):page78_i144:vss(15)"
				( attribute "PN" "250"
					( Origin gPackager )
				)
				( objectStatus "J9T1.250" )
			)
			( pin "@baseboard_fab2_lib.baseboard_fab2(sch_1):page78_i144:vss(16)"
				( attribute "PN" "248"
					( Origin gPackager )
				)
				( objectStatus "J9T1.248" )
			)
			( pin "@baseboard_fab2_lib.baseboard_fab2(sch_1):page78_i144:vss(17)"
				( attribute "PN" "246"
					( Origin gPackager )
				)
				( objectStatus "J9T1.246" )
			)
			( pin "@baseboard_fab2_lib.baseboard_fab2(sch_1):page78_i144:vss(18)"
				( attribute "PN" "243"
					( Origin gPackager )
				)
				( objectStatus "J9T1.243" )
			)
			( pin "@baseboard_fab2_lib.baseboard_fab2(sch_1):page78_i144:vss(19)"
				( attribute "PN" "241"
					( Origin gPackager )
				)
				( objectStatus "J9T1.241" )
			)
			( pin "@baseboard_fab2_lib.baseboard_fab2(sch_1):page78_i144:vss(20)"
				( attribute "PN" "239"
					( Origin gPackager )
				)
				( objectStatus "J9T1.239" )
			)
			( pin "@baseboard_fab2_lib.baseboard_fab2(sch_1):page78_i144:vss(21)"
				( attribute "PN" "202"
					( Origin gPackager )
				)
				( objectStatus "J9T1.202" )
			)
			( pin "@baseboard_fab2_lib.baseboard_fab2(sch_1):page78_i144:vss(22)"
				( attribute "PN" "200"
					( Origin gPackager )
				)
				( objectStatus "J9T1.200" )
			)
			( pin "@baseboard_fab2_lib.baseboard_fab2(sch_1):page78_i144:vss(23)"
				( attribute "PN" "198"
					( Origin gPackager )
				)
				( objectStatus "J9T1.198" )
			)
			( pin "@baseboard_fab2_lib.baseboard_fab2(sch_1):page78_i144:vss(24)"
				( attribute "PN" "195"
					( Origin gPackager )
				)
				( objectStatus "J9T1.195" )
			)
			( pin "@baseboard_fab2_lib.baseboard_fab2(sch_1):page78_i144:vss(25)"
				( attribute "PN" "193"
					( Origin gPackager )
				)
				( objectStatus "J9T1.193" )
			)
			( pin "@baseboard_fab2_lib.baseboard_fab2(sch_1):page78_i144:vss(26)"
				( attribute "PN" "191"
					( Origin gPackager )
				)
				( objectStatus "J9T1.191" )
			)
			( pin "@baseboard_fab2_lib.baseboard_fab2(sch_1):page78_i144:vss(27)"
				( attribute "PN" "189"
					( Origin gPackager )
				)
				( objectStatus "J9T1.189" )
			)
			( pin "@baseboard_fab2_lib.baseboard_fab2(sch_1):page78_i144:vss(28)"
				( attribute "PN" "187"
					( Origin gPackager )
				)
				( objectStatus "J9T1.187" )
			)
			( pin "@baseboard_fab2_lib.baseboard_fab2(sch_1):page78_i144:vss(29)"
				( attribute "PN" "184"
					( Origin gPackager )
				)
				( objectStatus "J9T1.184" )
			)
			( pin "@baseboard_fab2_lib.baseboard_fab2(sch_1):page78_i144:vss(30)"
				( attribute "PN" "182"
					( Origin gPackager )
				)
				( objectStatus "J9T1.182" )
			)
			( pin "@baseboard_fab2_lib.baseboard_fab2(sch_1):page78_i144:vss(31)"
				( attribute "PN" "180"
					( Origin gPackager )
				)
				( objectStatus "J9T1.180" )
			)
			( pin "@baseboard_fab2_lib.baseboard_fab2(sch_1):page78_i144:vss(32)"
				( attribute "PN" "178"
					( Origin gPackager )
				)
				( objectStatus "J9T1.178" )
			)
			( pin "@baseboard_fab2_lib.baseboard_fab2(sch_1):page78_i144:vss(33)"
				( attribute "PN" "176"
					( Origin gPackager )
				)
				( objectStatus "J9T1.176" )
			)
			( pin "@baseboard_fab2_lib.baseboard_fab2(sch_1):page78_i144:vss(34)"
				( attribute "PN" "173"
					( Origin gPackager )
				)
				( objectStatus "J9T1.173" )
			)
			( pin "@baseboard_fab2_lib.baseboard_fab2(sch_1):page78_i144:vss(35)"
				( attribute "PN" "171"
					( Origin gPackager )
				)
				( objectStatus "J9T1.171" )
			)
			( pin "@baseboard_fab2_lib.baseboard_fab2(sch_1):page78_i144:vss(36)"
				( attribute "PN" "169"
					( Origin gPackager )
				)
				( objectStatus "J9T1.169" )
			)
			( pin "@baseboard_fab2_lib.baseboard_fab2(sch_1):page78_i144:vss(37)"
				( attribute "PN" "167"
					( Origin gPackager )
				)
				( objectStatus "J9T1.167" )
			)
			( pin "@baseboard_fab2_lib.baseboard_fab2(sch_1):page78_i144:vss(38)"
				( attribute "PN" "165"
					( Origin gPackager )
				)
				( objectStatus "J9T1.165" )
			)
			( pin "@baseboard_fab2_lib.baseboard_fab2(sch_1):page78_i144:vss(39)"
				( attribute "PN" "162"
					( Origin gPackager )
				)
				( objectStatus "J9T1.162" )
			)
			( pin "@baseboard_fab2_lib.baseboard_fab2(sch_1):page78_i144:vss(40)"
				( attribute "PN" "160"
					( Origin gPackager )
				)
				( objectStatus "J9T1.160" )
			)
			( pin "@baseboard_fab2_lib.baseboard_fab2(sch_1):page78_i144:vss(41)"
				( attribute "PN" "158"
					( Origin gPackager )
				)
				( objectStatus "J9T1.158" )
			)
			( pin "@baseboard_fab2_lib.baseboard_fab2(sch_1):page78_i144:vss(42)"
				( attribute "PN" "156"
					( Origin gPackager )
				)
				( objectStatus "J9T1.156" )
			)
			( pin "@baseboard_fab2_lib.baseboard_fab2(sch_1):page78_i144:vss(43)"
				( attribute "PN" "154"
					( Origin gPackager )
				)
				( objectStatus "J9T1.154" )
			)
			( pin "@baseboard_fab2_lib.baseboard_fab2(sch_1):page78_i144:vss(44)"
				( attribute "PN" "151"
					( Origin gPackager )
				)
				( objectStatus "J9T1.151" )
			)
			( pin "@baseboard_fab2_lib.baseboard_fab2(sch_1):page78_i144:vss(45)"
				( attribute "PN" "149"
					( Origin gPackager )
				)
				( objectStatus "J9T1.149" )
			)
			( pin "@baseboard_fab2_lib.baseboard_fab2(sch_1):page78_i144:vss(46)"
				( attribute "PN" "147"
					( Origin gPackager )
				)
				( objectStatus "J9T1.147" )
			)
			( pin "@baseboard_fab2_lib.baseboard_fab2(sch_1):page78_i144:vss(47)"
				( attribute "PN" "138"
					( Origin gPackager )
				)
				( objectStatus "J9T1.138" )
			)
			( pin "@baseboard_fab2_lib.baseboard_fab2(sch_1):page78_i144:vss(48)"
				( attribute "PN" "136"
					( Origin gPackager )
				)
				( objectStatus "J9T1.136" )
			)
			( pin "@baseboard_fab2_lib.baseboard_fab2(sch_1):page78_i144:vss(49)"
				( attribute "PN" "134"
					( Origin gPackager )
				)
				( objectStatus "J9T1.134" )
			)
			( pin "@baseboard_fab2_lib.baseboard_fab2(sch_1):page78_i144:vss(50)"
				( attribute "PN" "131"
					( Origin gPackager )
				)
				( objectStatus "J9T1.131" )
			)
			( pin "@baseboard_fab2_lib.baseboard_fab2(sch_1):page78_i144:vss(51)"
				( attribute "PN" "129"
					( Origin gPackager )
				)
				( objectStatus "J9T1.129" )
			)
			( pin "@baseboard_fab2_lib.baseboard_fab2(sch_1):page78_i144:vss(52)"
				( attribute "PN" "127"
					( Origin gPackager )
				)
				( objectStatus "J9T1.127" )
			)
			( pin "@baseboard_fab2_lib.baseboard_fab2(sch_1):page78_i144:vss(53)"
				( attribute "PN" "125"
					( Origin gPackager )
				)
				( objectStatus "J9T1.125" )
			)
			( pin "@baseboard_fab2_lib.baseboard_fab2(sch_1):page78_i144:vss(54)"
				( attribute "PN" "123"
					( Origin gPackager )
				)
				( objectStatus "J9T1.123" )
			)
			( pin "@baseboard_fab2_lib.baseboard_fab2(sch_1):page78_i144:vss(55)"
				( attribute "PN" "120"
					( Origin gPackager )
				)
				( objectStatus "J9T1.120" )
			)
			( pin "@baseboard_fab2_lib.baseboard_fab2(sch_1):page78_i144:vss(56)"
				( attribute "PN" "118"
					( Origin gPackager )
				)
				( objectStatus "J9T1.118" )
			)
			( pin "@baseboard_fab2_lib.baseboard_fab2(sch_1):page78_i144:vss(57)"
				( attribute "PN" "116"
					( Origin gPackager )
				)
				( objectStatus "J9T1.116" )
			)
			( pin "@baseboard_fab2_lib.baseboard_fab2(sch_1):page78_i144:vss(58)"
				( attribute "PN" "114"
					( Origin gPackager )
				)
				( objectStatus "J9T1.114" )
			)
			( pin "@baseboard_fab2_lib.baseboard_fab2(sch_1):page78_i144:vss(59)"
				( attribute "PN" "112"
					( Origin gPackager )
				)
				( objectStatus "J9T1.112" )
			)
			( pin "@baseboard_fab2_lib.baseboard_fab2(sch_1):page78_i144:vss(60)"
				( attribute "PN" "109"
					( Origin gPackager )
				)
				( objectStatus "J9T1.109" )
			)
			( pin "@baseboard_fab2_lib.baseboard_fab2(sch_1):page78_i144:vss(61)"
				( attribute "PN" "107"
					( Origin gPackager )
				)
				( objectStatus "J9T1.107" )
			)
			( pin "@baseboard_fab2_lib.baseboard_fab2(sch_1):page78_i144:vss(62)"
				( attribute "PN" "105"
					( Origin gPackager )
				)
				( objectStatus "J9T1.105" )
			)
			( pin "@baseboard_fab2_lib.baseboard_fab2(sch_1):page78_i144:vss(63)"
				( attribute "PN" "103"
					( Origin gPackager )
				)
				( objectStatus "J9T1.103" )
			)
			( pin "@baseboard_fab2_lib.baseboard_fab2(sch_1):page78_i144:vss(64)"
				( attribute "PN" "101"
					( Origin gPackager )
				)
				( objectStatus "J9T1.101" )
			)
			( pin "@baseboard_fab2_lib.baseboard_fab2(sch_1):page78_i144:vss(65)"
				( attribute "PN" "98"
					( Origin gPackager )
				)
				( objectStatus "J9T1.98" )
			)
			( pin "@baseboard_fab2_lib.baseboard_fab2(sch_1):page78_i144:vss(66)"
				( attribute "PN" "96"
					( Origin gPackager )
				)
				( objectStatus "J9T1.96" )
			)
			( pin "@baseboard_fab2_lib.baseboard_fab2(sch_1):page78_i144:vss(67)"
				( attribute "PN" "94"
					( Origin gPackager )
				)
				( objectStatus "J9T1.94" )
			)
			( pin "@baseboard_fab2_lib.baseboard_fab2(sch_1):page78_i144:vss(68)"
				( attribute "PN" "57"
					( Origin gPackager )
				)
				( objectStatus "J9T1.57" )
			)
			( pin "@baseboard_fab2_lib.baseboard_fab2(sch_1):page78_i144:vss(69)"
				( attribute "PN" "55"
					( Origin gPackager )
				)
				( objectStatus "J9T1.55" )
			)
			( pin "@baseboard_fab2_lib.baseboard_fab2(sch_1):page78_i144:vss(70)"
				( attribute "PN" "53"
					( Origin gPackager )
				)
				( objectStatus "J9T1.53" )
			)
			( pin "@baseboard_fab2_lib.baseboard_fab2(sch_1):page78_i144:vss(71)"
				( attribute "PN" "50"
					( Origin gPackager )
				)
				( objectStatus "J9T1.50" )
			)
			( pin "@baseboard_fab2_lib.baseboard_fab2(sch_1):page78_i144:vss(72)"
				( attribute "PN" "48"
					( Origin gPackager )
				)
				( objectStatus "J9T1.48" )
			)
			( pin "@baseboard_fab2_lib.baseboard_fab2(sch_1):page78_i144:vss(73)"
				( attribute "PN" "46"
					( Origin gPackager )
				)
				( objectStatus "J9T1.46" )
			)
			( pin "@baseboard_fab2_lib.baseboard_fab2(sch_1):page78_i144:vss(74)"
				( attribute "PN" "44"
					( Origin gPackager )
				)
				( objectStatus "J9T1.44" )
			)
			( pin "@baseboard_fab2_lib.baseboard_fab2(sch_1):page78_i144:vss(75)"
				( attribute "PN" "42"
					( Origin gPackager )
				)
				( objectStatus "J9T1.42" )
			)
			( pin "@baseboard_fab2_lib.baseboard_fab2(sch_1):page78_i144:vss(76)"
				( attribute "PN" "39"
					( Origin gPackager )
				)
				( objectStatus "J9T1.39" )
			)
			( pin "@baseboard_fab2_lib.baseboard_fab2(sch_1):page78_i144:vss(77)"
				( attribute "PN" "37"
					( Origin gPackager )
				)
				( objectStatus "J9T1.37" )
			)
			( pin "@baseboard_fab2_lib.baseboard_fab2(sch_1):page78_i144:vss(78)"
				( attribute "PN" "35"
					( Origin gPackager )
				)
				( objectStatus "J9T1.35" )
			)
			( pin "@baseboard_fab2_lib.baseboard_fab2(sch_1):page78_i144:vss(79)"
				( attribute "PN" "33"
					( Origin gPackager )
				)
				( objectStatus "J9T1.33" )
			)
			( pin "@baseboard_fab2_lib.baseboard_fab2(sch_1):page78_i144:vss(80)"
				( attribute "PN" "31"
					( Origin gPackager )
				)
				( objectStatus "J9T1.31" )
			)
			( pin "@baseboard_fab2_lib.baseboard_fab2(sch_1):page78_i144:vss(81)"
				( attribute "PN" "28"
					( Origin gPackager )
				)
				( objectStatus "J9T1.28" )
			)
			( pin "@baseboard_fab2_lib.baseboard_fab2(sch_1):page78_i144:vss(82)"
				( attribute "PN" "26"
					( Origin gPackager )
				)
				( objectStatus "J9T1.26" )
			)
			( pin "@baseboard_fab2_lib.baseboard_fab2(sch_1):page78_i144:vss(83)"
				( attribute "PN" "24"
					( Origin gPackager )
				)
				( objectStatus "J9T1.24" )
			)
			( pin "@baseboard_fab2_lib.baseboard_fab2(sch_1):page78_i144:vss(84)"
				( attribute "PN" "22"
					( Origin gPackager )
				)
				( objectStatus "J9T1.22" )
			)
			( pin "@baseboard_fab2_lib.baseboard_fab2(sch_1):page78_i144:vss(85)"
				( attribute "PN" "20"
					( Origin gPackager )
				)
				( objectStatus "J9T1.20" )
			)
			( pin "@baseboard_fab2_lib.baseboard_fab2(sch_1):page78_i144:vss(86)"
				( attribute "PN" "17"
					( Origin gPackager )
				)
				( objectStatus "J9T1.17" )
			)
			( pin "@baseboard_fab2_lib.baseboard_fab2(sch_1):page78_i144:vss(87)"
				( attribute "PN" "15"
					( Origin gPackager )
				)
				( objectStatus "J9T1.15" )
			)
			( pin "@baseboard_fab2_lib.baseboard_fab2(sch_1):page78_i144:vss(88)"
				( attribute "PN" "13"
					( Origin gPackager )
				)
				( objectStatus "J9T1.13" )
			)
			( pin "@baseboard_fab2_lib.baseboard_fab2(sch_1):page78_i144:vss(89)"
				( attribute "PN" "11"
					( Origin gPackager )
				)
				( objectStatus "J9T1.11" )
			)
			( pin "@baseboard_fab2_lib.baseboard_fab2(sch_1):page78_i144:vss(90)"
				( attribute "PN" "9"
					( Origin gPackager )
				)
				( objectStatus "J9T1.9" )
			)
			( pin "@baseboard_fab2_lib.baseboard_fab2(sch_1):page78_i144:vss(91)"
				( attribute "PN" "6"
					( Origin gPackager )
				)
				( objectStatus "J9T1.6" )
			)
			( pin "@baseboard_fab2_lib.baseboard_fab2(sch_1):page78_i144:vss(92)"
				( attribute "PN" "4"
					( Origin gPackager )
				)
				( objectStatus "J9T1.4" )
			)
			( pin "@baseboard_fab2_lib.baseboard_fab2(sch_1):page78_i144:vss(93)"
				( attribute "PN" "2"
					( Origin gPackager )
				)
				( objectStatus "J9T1.2" )
			)
			( pin "@baseboard_fab2_lib.baseboard_fab2(sch_1):page79_i43:vss(0)"
				( attribute "PN" "283"
					( Origin gPackager )
				)
				( objectStatus "J1G2.283" )
			)
			( pin "@baseboard_fab2_lib.baseboard_fab2(sch_1):page79_i43:vss(1)"
				( attribute "PN" "281"
					( Origin gPackager )
				)
				( objectStatus "J1G2.281" )
			)
			( pin "@baseboard_fab2_lib.baseboard_fab2(sch_1):page79_i43:vss(2)"
				( attribute "PN" "279"
					( Origin gPackager )
				)
				( objectStatus "J1G2.279" )
			)
			( pin "@baseboard_fab2_lib.baseboard_fab2(sch_1):page79_i43:vss(3)"
				( attribute "PN" "276"
					( Origin gPackager )
				)
				( objectStatus "J1G2.276" )
			)
			( pin "@baseboard_fab2_lib.baseboard_fab2(sch_1):page79_i43:vss(4)"
				( attribute "PN" "274"
					( Origin gPackager )
				)
				( objectStatus "J1G2.274" )
			)
			( pin "@baseboard_fab2_lib.baseboard_fab2(sch_1):page79_i43:vss(5)"
				( attribute "PN" "272"
					( Origin gPackager )
				)
				( objectStatus "J1G2.272" )
			)
			( pin "@baseboard_fab2_lib.baseboard_fab2(sch_1):page79_i43:vss(6)"
				( attribute "PN" "270"
					( Origin gPackager )
				)
				( objectStatus "J1G2.270" )
			)
			( pin "@baseboard_fab2_lib.baseboard_fab2(sch_1):page79_i43:vss(7)"
				( attribute "PN" "268"
					( Origin gPackager )
				)
				( objectStatus "J1G2.268" )
			)
			( pin "@baseboard_fab2_lib.baseboard_fab2(sch_1):page79_i43:vss(8)"
				( attribute "PN" "265"
					( Origin gPackager )
				)
				( objectStatus "J1G2.265" )
			)
			( pin "@baseboard_fab2_lib.baseboard_fab2(sch_1):page79_i43:vss(9)"
				( attribute "PN" "263"
					( Origin gPackager )
				)
				( objectStatus "J1G2.263" )
			)
			( pin "@baseboard_fab2_lib.baseboard_fab2(sch_1):page79_i43:vss(10)"
				( attribute "PN" "261"
					( Origin gPackager )
				)
				( objectStatus "J1G2.261" )
			)
			( pin "@baseboard_fab2_lib.baseboard_fab2(sch_1):page79_i43:vss(11)"
				( attribute "PN" "259"
					( Origin gPackager )
				)
				( objectStatus "J1G2.259" )
			)
			( pin "@baseboard_fab2_lib.baseboard_fab2(sch_1):page79_i43:vss(12)"
				( attribute "PN" "257"
					( Origin gPackager )
				)
				( objectStatus "J1G2.257" )
			)
			( pin "@baseboard_fab2_lib.baseboard_fab2(sch_1):page79_i43:vss(13)"
				( attribute "PN" "254"
					( Origin gPackager )
				)
				( objectStatus "J1G2.254" )
			)
			( pin "@baseboard_fab2_lib.baseboard_fab2(sch_1):page79_i43:vss(14)"
				( attribute "PN" "252"
					( Origin gPackager )
				)
				( objectStatus "J1G2.252" )
			)
			( pin "@baseboard_fab2_lib.baseboard_fab2(sch_1):page79_i43:vss(15)"
				( attribute "PN" "250"
					( Origin gPackager )
				)
				( objectStatus "J1G2.250" )
			)
			( pin "@baseboard_fab2_lib.baseboard_fab2(sch_1):page79_i43:vss(16)"
				( attribute "PN" "248"
					( Origin gPackager )
				)
				( objectStatus "J1G2.248" )
			)
			( pin "@baseboard_fab2_lib.baseboard_fab2(sch_1):page79_i43:vss(17)"
				( attribute "PN" "246"
					( Origin gPackager )
				)
				( objectStatus "J1G2.246" )
			)
			( pin "@baseboard_fab2_lib.baseboard_fab2(sch_1):page79_i43:vss(18)"
				( attribute "PN" "243"
					( Origin gPackager )
				)
				( objectStatus "J1G2.243" )
			)
			( pin "@baseboard_fab2_lib.baseboard_fab2(sch_1):page79_i43:vss(19)"
				( attribute "PN" "241"
					( Origin gPackager )
				)
				( objectStatus "J1G2.241" )
			)
			( pin "@baseboard_fab2_lib.baseboard_fab2(sch_1):page79_i43:vss(20)"
				( attribute "PN" "239"
					( Origin gPackager )
				)
				( objectStatus "J1G2.239" )
			)
			( pin "@baseboard_fab2_lib.baseboard_fab2(sch_1):page79_i43:vss(21)"
				( attribute "PN" "202"
					( Origin gPackager )
				)
				( objectStatus "J1G2.202" )
			)
			( pin "@baseboard_fab2_lib.baseboard_fab2(sch_1):page79_i43:vss(22)"
				( attribute "PN" "200"
					( Origin gPackager )
				)
				( objectStatus "J1G2.200" )
			)
			( pin "@baseboard_fab2_lib.baseboard_fab2(sch_1):page79_i43:vss(23)"
				( attribute "PN" "198"
					( Origin gPackager )
				)
				( objectStatus "J1G2.198" )
			)
			( pin "@baseboard_fab2_lib.baseboard_fab2(sch_1):page79_i43:vss(24)"
				( attribute "PN" "195"
					( Origin gPackager )
				)
				( objectStatus "J1G2.195" )
			)
			( pin "@baseboard_fab2_lib.baseboard_fab2(sch_1):page79_i43:vss(25)"
				( attribute "PN" "193"
					( Origin gPackager )
				)
				( objectStatus "J1G2.193" )
			)
			( pin "@baseboard_fab2_lib.baseboard_fab2(sch_1):page79_i43:vss(26)"
				( attribute "PN" "191"
					( Origin gPackager )
				)
				( objectStatus "J1G2.191" )
			)
			( pin "@baseboard_fab2_lib.baseboard_fab2(sch_1):page79_i43:vss(27)"
				( attribute "PN" "189"
					( Origin gPackager )
				)
				( objectStatus "J1G2.189" )
			)
			( pin "@baseboard_fab2_lib.baseboard_fab2(sch_1):page79_i43:vss(28)"
				( attribute "PN" "187"
					( Origin gPackager )
				)
				( objectStatus "J1G2.187" )
			)
			( pin "@baseboard_fab2_lib.baseboard_fab2(sch_1):page79_i43:vss(29)"
				( attribute "PN" "184"
					( Origin gPackager )
				)
				( objectStatus "J1G2.184" )
			)
			( pin "@baseboard_fab2_lib.baseboard_fab2(sch_1):page79_i43:vss(30)"
				( attribute "PN" "182"
					( Origin gPackager )
				)
				( objectStatus "J1G2.182" )
			)
			( pin "@baseboard_fab2_lib.baseboard_fab2(sch_1):page79_i43:vss(31)"
				( attribute "PN" "180"
					( Origin gPackager )
				)
				( objectStatus "J1G2.180" )
			)
			( pin "@baseboard_fab2_lib.baseboard_fab2(sch_1):page79_i43:vss(32)"
				( attribute "PN" "178"
					( Origin gPackager )
				)
				( objectStatus "J1G2.178" )
			)
			( pin "@baseboard_fab2_lib.baseboard_fab2(sch_1):page79_i43:vss(33)"
				( attribute "PN" "176"
					( Origin gPackager )
				)
				( objectStatus "J1G2.176" )
			)
			( pin "@baseboard_fab2_lib.baseboard_fab2(sch_1):page79_i43:vss(34)"
				( attribute "PN" "173"
					( Origin gPackager )
				)
				( objectStatus "J1G2.173" )
			)
			( pin "@baseboard_fab2_lib.baseboard_fab2(sch_1):page79_i43:vss(35)"
				( attribute "PN" "171"
					( Origin gPackager )
				)
				( objectStatus "J1G2.171" )
			)
			( pin "@baseboard_fab2_lib.baseboard_fab2(sch_1):page79_i43:vss(36)"
				( attribute "PN" "169"
					( Origin gPackager )
				)
				( objectStatus "J1G2.169" )
			)
			( pin "@baseboard_fab2_lib.baseboard_fab2(sch_1):page79_i43:vss(37)"
				( attribute "PN" "167"
					( Origin gPackager )
				)
				( objectStatus "J1G2.167" )
			)
			( pin "@baseboard_fab2_lib.baseboard_fab2(sch_1):page79_i43:vss(38)"
				( attribute "PN" "165"
					( Origin gPackager )
				)
				( objectStatus "J1G2.165" )
			)
			( pin "@baseboard_fab2_lib.baseboard_fab2(sch_1):page79_i43:vss(39)"
				( attribute "PN" "162"
					( Origin gPackager )
				)
				( objectStatus "J1G2.162" )
			)
			( pin "@baseboard_fab2_lib.baseboard_fab2(sch_1):page79_i43:vss(40)"
				( attribute "PN" "160"
					( Origin gPackager )
				)
				( objectStatus "J1G2.160" )
			)
			( pin "@baseboard_fab2_lib.baseboard_fab2(sch_1):page79_i43:vss(41)"
				( attribute "PN" "158"
					( Origin gPackager )
				)
				( objectStatus "J1G2.158" )
			)
			( pin "@baseboard_fab2_lib.baseboard_fab2(sch_1):page79_i43:vss(42)"
				( attribute "PN" "156"
					( Origin gPackager )
				)
				( objectStatus "J1G2.156" )
			)
			( pin "@baseboard_fab2_lib.baseboard_fab2(sch_1):page79_i43:vss(43)"
				( attribute "PN" "154"
					( Origin gPackager )
				)
				( objectStatus "J1G2.154" )
			)
			( pin "@baseboard_fab2_lib.baseboard_fab2(sch_1):page79_i43:vss(44)"
				( attribute "PN" "151"
					( Origin gPackager )
				)
				( objectStatus "J1G2.151" )
			)
			( pin "@baseboard_fab2_lib.baseboard_fab2(sch_1):page79_i43:vss(45)"
				( attribute "PN" "149"
					( Origin gPackager )
				)
				( objectStatus "J1G2.149" )
			)
			( pin "@baseboard_fab2_lib.baseboard_fab2(sch_1):page79_i43:vss(46)"
				( attribute "PN" "147"
					( Origin gPackager )
				)
				( objectStatus "J1G2.147" )
			)
			( pin "@baseboard_fab2_lib.baseboard_fab2(sch_1):page79_i43:vss(47)"
				( attribute "PN" "138"
					( Origin gPackager )
				)
				( objectStatus "J1G2.138" )
			)
			( pin "@baseboard_fab2_lib.baseboard_fab2(sch_1):page79_i43:vss(48)"
				( attribute "PN" "136"
					( Origin gPackager )
				)
				( objectStatus "J1G2.136" )
			)
			( pin "@baseboard_fab2_lib.baseboard_fab2(sch_1):page79_i43:vss(49)"
				( attribute "PN" "134"
					( Origin gPackager )
				)
				( objectStatus "J1G2.134" )
			)
			( pin "@baseboard_fab2_lib.baseboard_fab2(sch_1):page79_i43:vss(50)"
				( attribute "PN" "131"
					( Origin gPackager )
				)
				( objectStatus "J1G2.131" )
			)
			( pin "@baseboard_fab2_lib.baseboard_fab2(sch_1):page79_i43:vss(51)"
				( attribute "PN" "129"
					( Origin gPackager )
				)
				( objectStatus "J1G2.129" )
			)
			( pin "@baseboard_fab2_lib.baseboard_fab2(sch_1):page79_i43:vss(52)"
				( attribute "PN" "127"
					( Origin gPackager )
				)
				( objectStatus "J1G2.127" )
			)
			( pin "@baseboard_fab2_lib.baseboard_fab2(sch_1):page79_i43:vss(53)"
				( attribute "PN" "125"
					( Origin gPackager )
				)
				( objectStatus "J1G2.125" )
			)
			( pin "@baseboard_fab2_lib.baseboard_fab2(sch_1):page79_i43:vss(54)"
				( attribute "PN" "123"
					( Origin gPackager )
				)
				( objectStatus "J1G2.123" )
			)
			( pin "@baseboard_fab2_lib.baseboard_fab2(sch_1):page79_i43:vss(55)"
				( attribute "PN" "120"
					( Origin gPackager )
				)
				( objectStatus "J1G2.120" )
			)
			( pin "@baseboard_fab2_lib.baseboard_fab2(sch_1):page79_i43:vss(56)"
				( attribute "PN" "118"
					( Origin gPackager )
				)
				( objectStatus "J1G2.118" )
			)
			( pin "@baseboard_fab2_lib.baseboard_fab2(sch_1):page79_i43:vss(57)"
				( attribute "PN" "116"
					( Origin gPackager )
				)
				( objectStatus "J1G2.116" )
			)
			( pin "@baseboard_fab2_lib.baseboard_fab2(sch_1):page79_i43:vss(58)"
				( attribute "PN" "114"
					( Origin gPackager )
				)
				( objectStatus "J1G2.114" )
			)
			( pin "@baseboard_fab2_lib.baseboard_fab2(sch_1):page79_i43:vss(59)"
				( attribute "PN" "112"
					( Origin gPackager )
				)
				( objectStatus "J1G2.112" )
			)
			( pin "@baseboard_fab2_lib.baseboard_fab2(sch_1):page79_i43:vss(60)"
				( attribute "PN" "109"
					( Origin gPackager )
				)
				( objectStatus "J1G2.109" )
			)
			( pin "@baseboard_fab2_lib.baseboard_fab2(sch_1):page79_i43:vss(61)"
				( attribute "PN" "107"
					( Origin gPackager )
				)
				( objectStatus "J1G2.107" )
			)
			( pin "@baseboard_fab2_lib.baseboard_fab2(sch_1):page79_i43:vss(62)"
				( attribute "PN" "105"
					( Origin gPackager )
				)
				( objectStatus "J1G2.105" )
			)
			( pin "@baseboard_fab2_lib.baseboard_fab2(sch_1):page79_i43:vss(63)"
				( attribute "PN" "103"
					( Origin gPackager )
				)
				( objectStatus "J1G2.103" )
			)
			( pin "@baseboard_fab2_lib.baseboard_fab2(sch_1):page79_i43:vss(64)"
				( attribute "PN" "101"
					( Origin gPackager )
				)
				( objectStatus "J1G2.101" )
			)
			( pin "@baseboard_fab2_lib.baseboard_fab2(sch_1):page79_i43:vss(65)"
				( attribute "PN" "98"
					( Origin gPackager )
				)
				( objectStatus "J1G2.98" )
			)
			( pin "@baseboard_fab2_lib.baseboard_fab2(sch_1):page79_i43:vss(66)"
				( attribute "PN" "96"
					( Origin gPackager )
				)
				( objectStatus "J1G2.96" )
			)
			( pin "@baseboard_fab2_lib.baseboard_fab2(sch_1):page79_i43:vss(67)"
				( attribute "PN" "94"
					( Origin gPackager )
				)
				( objectStatus "J1G2.94" )
			)
			( pin "@baseboard_fab2_lib.baseboard_fab2(sch_1):page79_i43:vss(68)"
				( attribute "PN" "57"
					( Origin gPackager )
				)
				( objectStatus "J1G2.57" )
			)
			( pin "@baseboard_fab2_lib.baseboard_fab2(sch_1):page79_i43:vss(69)"
				( attribute "PN" "55"
					( Origin gPackager )
				)
				( objectStatus "J1G2.55" )
			)
			( pin "@baseboard_fab2_lib.baseboard_fab2(sch_1):page79_i43:vss(70)"
				( attribute "PN" "53"
					( Origin gPackager )
				)
				( objectStatus "J1G2.53" )
			)
			( pin "@baseboard_fab2_lib.baseboard_fab2(sch_1):page79_i43:vss(71)"
				( attribute "PN" "50"
					( Origin gPackager )
				)
				( objectStatus "J1G2.50" )
			)
			( pin "@baseboard_fab2_lib.baseboard_fab2(sch_1):page79_i43:vss(72)"
				( attribute "PN" "48"
					( Origin gPackager )
				)
				( objectStatus "J1G2.48" )
			)
			( pin "@baseboard_fab2_lib.baseboard_fab2(sch_1):page79_i43:vss(73)"
				( attribute "PN" "46"
					( Origin gPackager )
				)
				( objectStatus "J1G2.46" )
			)
			( pin "@baseboard_fab2_lib.baseboard_fab2(sch_1):page79_i43:vss(74)"
				( attribute "PN" "44"
					( Origin gPackager )
				)
				( objectStatus "J1G2.44" )
			)
			( pin "@baseboard_fab2_lib.baseboard_fab2(sch_1):page79_i43:vss(75)"
				( attribute "PN" "42"
					( Origin gPackager )
				)
				( objectStatus "J1G2.42" )
			)
			( pin "@baseboard_fab2_lib.baseboard_fab2(sch_1):page79_i43:vss(76)"
				( attribute "PN" "39"
					( Origin gPackager )
				)
				( objectStatus "J1G2.39" )
			)
			( pin "@baseboard_fab2_lib.baseboard_fab2(sch_1):page79_i43:vss(77)"
				( attribute "PN" "37"
					( Origin gPackager )
				)
				( objectStatus "J1G2.37" )
			)
			( pin "@baseboard_fab2_lib.baseboard_fab2(sch_1):page79_i43:vss(78)"
				( attribute "PN" "35"
					( Origin gPackager )
				)
				( objectStatus "J1G2.35" )
			)
			( pin "@baseboard_fab2_lib.baseboard_fab2(sch_1):page79_i43:vss(79)"
				( attribute "PN" "33"
					( Origin gPackager )
				)
				( objectStatus "J1G2.33" )
			)
			( pin "@baseboard_fab2_lib.baseboard_fab2(sch_1):page79_i43:vss(80)"
				( attribute "PN" "31"
					( Origin gPackager )
				)
				( objectStatus "J1G2.31" )
			)
			( pin "@baseboard_fab2_lib.baseboard_fab2(sch_1):page79_i43:vss(81)"
				( attribute "PN" "28"
					( Origin gPackager )
				)
				( objectStatus "J1G2.28" )
			)
			( pin "@baseboard_fab2_lib.baseboard_fab2(sch_1):page79_i43:vss(82)"
				( attribute "PN" "26"
					( Origin gPackager )
				)
				( objectStatus "J1G2.26" )
			)
			( pin "@baseboard_fab2_lib.baseboard_fab2(sch_1):page79_i43:vss(83)"
				( attribute "PN" "24"
					( Origin gPackager )
				)
				( objectStatus "J1G2.24" )
			)
			( pin "@baseboard_fab2_lib.baseboard_fab2(sch_1):page79_i43:vss(84)"
				( attribute "PN" "22"
					( Origin gPackager )
				)
				( objectStatus "J1G2.22" )
			)
			( pin "@baseboard_fab2_lib.baseboard_fab2(sch_1):page79_i43:vss(85)"
				( attribute "PN" "20"
					( Origin gPackager )
				)
				( objectStatus "J1G2.20" )
			)
			( pin "@baseboard_fab2_lib.baseboard_fab2(sch_1):page79_i43:vss(86)"
				( attribute "PN" "17"
					( Origin gPackager )
				)
				( objectStatus "J1G2.17" )
			)
			( pin "@baseboard_fab2_lib.baseboard_fab2(sch_1):page79_i43:vss(87)"
				( attribute "PN" "15"
					( Origin gPackager )
				)
				( objectStatus "J1G2.15" )
			)
			( pin "@baseboard_fab2_lib.baseboard_fab2(sch_1):page79_i43:vss(88)"
				( attribute "PN" "13"
					( Origin gPackager )
				)
				( objectStatus "J1G2.13" )
			)
			( pin "@baseboard_fab2_lib.baseboard_fab2(sch_1):page79_i43:vss(89)"
				( attribute "PN" "11"
					( Origin gPackager )
				)
				( objectStatus "J1G2.11" )
			)
			( pin "@baseboard_fab2_lib.baseboard_fab2(sch_1):page79_i43:vss(90)"
				( attribute "PN" "9"
					( Origin gPackager )
				)
				( objectStatus "J1G2.9" )
			)
			( pin "@baseboard_fab2_lib.baseboard_fab2(sch_1):page79_i43:vss(91)"
				( attribute "PN" "6"
					( Origin gPackager )
				)
				( objectStatus "J1G2.6" )
			)
			( pin "@baseboard_fab2_lib.baseboard_fab2(sch_1):page79_i43:vss(92)"
				( attribute "PN" "4"
					( Origin gPackager )
				)
				( objectStatus "J1G2.4" )
			)
			( pin "@baseboard_fab2_lib.baseboard_fab2(sch_1):page79_i43:vss(93)"
				( attribute "PN" "2"
					( Origin gPackager )
				)
				( objectStatus "J1G2.2" )
			)
			( pin "@baseboard_fab2_lib.baseboard_fab2(sch_1):page79_i64:dqs0n"
				( attribute "PN" "152"
					( Origin gPackager )
				)
				( objectStatus "J1G2.152" )
			)
			( pin "@baseboard_fab2_lib.baseboard_fab2(sch_1):page79_i64:dqs0p"
				( attribute "PN" "153"
					( Origin gPackager )
				)
				( objectStatus "J1G2.153" )
			)
			( pin "@baseboard_fab2_lib.baseboard_fab2(sch_1):page79_i64:dqs1n"
				( attribute "PN" "163"
					( Origin gPackager )
				)
				( objectStatus "J1G2.163" )
			)
			( pin "@baseboard_fab2_lib.baseboard_fab2(sch_1):page79_i64:dqs1p"
				( attribute "PN" "164"
					( Origin gPackager )
				)
				( objectStatus "J1G2.164" )
			)
			( pin "@baseboard_fab2_lib.baseboard_fab2(sch_1):page79_i64:dqs2n"
				( attribute "PN" "174"
					( Origin gPackager )
				)
				( objectStatus "J1G2.174" )
			)
			( pin "@baseboard_fab2_lib.baseboard_fab2(sch_1):page79_i64:dqs2p"
				( attribute "PN" "175"
					( Origin gPackager )
				)
				( objectStatus "J1G2.175" )
			)
			( pin "@baseboard_fab2_lib.baseboard_fab2(sch_1):page79_i64:dqs3n"
				( attribute "PN" "185"
					( Origin gPackager )
				)
				( objectStatus "J1G2.185" )
			)
			( pin "@baseboard_fab2_lib.baseboard_fab2(sch_1):page79_i64:dqs3p"
				( attribute "PN" "186"
					( Origin gPackager )
				)
				( objectStatus "J1G2.186" )
			)
			( pin "@baseboard_fab2_lib.baseboard_fab2(sch_1):page79_i64:dqs4n"
				( attribute "PN" "244"
					( Origin gPackager )
				)
				( objectStatus "J1G2.244" )
			)
			( pin "@baseboard_fab2_lib.baseboard_fab2(sch_1):page79_i64:dqs4p"
				( attribute "PN" "245"
					( Origin gPackager )
				)
				( objectStatus "J1G2.245" )
			)
			( pin "@baseboard_fab2_lib.baseboard_fab2(sch_1):page79_i64:dqs5n"
				( attribute "PN" "255"
					( Origin gPackager )
				)
				( objectStatus "J1G2.255" )
			)
			( pin "@baseboard_fab2_lib.baseboard_fab2(sch_1):page79_i64:dqs5p"
				( attribute "PN" "256"
					( Origin gPackager )
				)
				( objectStatus "J1G2.256" )
			)
			( pin "@baseboard_fab2_lib.baseboard_fab2(sch_1):page79_i64:dqs6n"
				( attribute "PN" "266"
					( Origin gPackager )
				)
				( objectStatus "J1G2.266" )
			)
			( pin "@baseboard_fab2_lib.baseboard_fab2(sch_1):page79_i64:dqs6p"
				( attribute "PN" "267"
					( Origin gPackager )
				)
				( objectStatus "J1G2.267" )
			)
			( pin "@baseboard_fab2_lib.baseboard_fab2(sch_1):page79_i64:dqs7n"
				( attribute "PN" "277"
					( Origin gPackager )
				)
				( objectStatus "J1G2.277" )
			)
			( pin "@baseboard_fab2_lib.baseboard_fab2(sch_1):page79_i64:dqs7p"
				( attribute "PN" "278"
					( Origin gPackager )
				)
				( objectStatus "J1G2.278" )
			)
			( pin "@baseboard_fab2_lib.baseboard_fab2(sch_1):page79_i64:dqs8n"
				( attribute "PN" "196"
					( Origin gPackager )
				)
				( objectStatus "J1G2.196" )
			)
			( pin "@baseboard_fab2_lib.baseboard_fab2(sch_1):page79_i64:dqs8p"
				( attribute "PN" "197"
					( Origin gPackager )
				)
				( objectStatus "J1G2.197" )
			)
			( pin "@baseboard_fab2_lib.baseboard_fab2(sch_1):page79_i64:dqs9n"
				( attribute "PN" "8"
					( Origin gPackager )
				)
				( objectStatus "J1G2.8" )
			)
			( pin "@baseboard_fab2_lib.baseboard_fab2(sch_1):page79_i64:dqs9p"
				( attribute "PN" "7"
					( Origin gPackager )
				)
				( objectStatus "J1G2.7" )
			)
			( pin "@baseboard_fab2_lib.baseboard_fab2(sch_1):page79_i64:dqs10n"
				( attribute "PN" "19"
					( Origin gPackager )
				)
				( objectStatus "J1G2.19" )
			)
			( pin "@baseboard_fab2_lib.baseboard_fab2(sch_1):page79_i64:dqs10p"
				( attribute "PN" "18"
					( Origin gPackager )
				)
				( objectStatus "J1G2.18" )
			)
			( pin "@baseboard_fab2_lib.baseboard_fab2(sch_1):page79_i64:dqs11n"
				( attribute "PN" "30"
					( Origin gPackager )
				)
				( objectStatus "J1G2.30" )
			)
			( pin "@baseboard_fab2_lib.baseboard_fab2(sch_1):page79_i64:dqs11p"
				( attribute "PN" "29"
					( Origin gPackager )
				)
				( objectStatus "J1G2.29" )
			)
			( pin "@baseboard_fab2_lib.baseboard_fab2(sch_1):page79_i64:dqs12n"
				( attribute "PN" "41"
					( Origin gPackager )
				)
				( objectStatus "J1G2.41" )
			)
			( pin "@baseboard_fab2_lib.baseboard_fab2(sch_1):page79_i64:dqs12p"
				( attribute "PN" "40"
					( Origin gPackager )
				)
				( objectStatus "J1G2.40" )
			)
			( pin "@baseboard_fab2_lib.baseboard_fab2(sch_1):page79_i64:dqs13n"
				( attribute "PN" "100"
					( Origin gPackager )
				)
				( objectStatus "J1G2.100" )
			)
			( pin "@baseboard_fab2_lib.baseboard_fab2(sch_1):page79_i64:dqs13p"
				( attribute "PN" "99"
					( Origin gPackager )
				)
				( objectStatus "J1G2.99" )
			)
			( pin "@baseboard_fab2_lib.baseboard_fab2(sch_1):page79_i64:dqs14n"
				( attribute "PN" "111"
					( Origin gPackager )
				)
				( objectStatus "J1G2.111" )
			)
			( pin "@baseboard_fab2_lib.baseboard_fab2(sch_1):page79_i64:dqs14p"
				( attribute "PN" "110"
					( Origin gPackager )
				)
				( objectStatus "J1G2.110" )
			)
			( pin "@baseboard_fab2_lib.baseboard_fab2(sch_1):page79_i64:dqs15n"
				( attribute "PN" "122"
					( Origin gPackager )
				)
				( objectStatus "J1G2.122" )
			)
			( pin "@baseboard_fab2_lib.baseboard_fab2(sch_1):page79_i64:dqs15p"
				( attribute "PN" "121"
					( Origin gPackager )
				)
				( objectStatus "J1G2.121" )
			)
			( pin "@baseboard_fab2_lib.baseboard_fab2(sch_1):page79_i64:dqs16n"
				( attribute "PN" "133"
					( Origin gPackager )
				)
				( objectStatus "J1G2.133" )
			)
			( pin "@baseboard_fab2_lib.baseboard_fab2(sch_1):page79_i64:dqs16p"
				( attribute "PN" "132"
					( Origin gPackager )
				)
				( objectStatus "J1G2.132" )
			)
			( pin "@baseboard_fab2_lib.baseboard_fab2(sch_1):page79_i64:dqs17n"
				( attribute "PN" "52"
					( Origin gPackager )
				)
				( objectStatus "J1G2.52" )
			)
			( pin "@baseboard_fab2_lib.baseboard_fab2(sch_1):page79_i64:dqs17p"
				( attribute "PN" "51"
					( Origin gPackager )
				)
				( objectStatus "J1G2.51" )
			)
			( pin "@baseboard_fab2_lib.baseboard_fab2(sch_1):page79_i111:a0"
				( attribute "PN" "79"
					( Origin gPackager )
				)
				( objectStatus "J1G2.79" )
			)
			( pin "@baseboard_fab2_lib.baseboard_fab2(sch_1):page79_i111:a1"
				( attribute "PN" "72"
					( Origin gPackager )
				)
				( objectStatus "J1G2.72" )
			)
			( pin "@baseboard_fab2_lib.baseboard_fab2(sch_1):page79_i111:a2"
				( attribute "PN" "216"
					( Origin gPackager )
				)
				( objectStatus "J1G2.216" )
			)
			( pin "@baseboard_fab2_lib.baseboard_fab2(sch_1):page79_i111:a3"
				( attribute "PN" "71"
					( Origin gPackager )
				)
				( objectStatus "J1G2.71" )
			)
			( pin "@baseboard_fab2_lib.baseboard_fab2(sch_1):page79_i111:a4"
				( attribute "PN" "214"
					( Origin gPackager )
				)
				( objectStatus "J1G2.214" )
			)
			( pin "@baseboard_fab2_lib.baseboard_fab2(sch_1):page79_i111:a5"
				( attribute "PN" "213"
					( Origin gPackager )
				)
				( objectStatus "J1G2.213" )
			)
			( pin "@baseboard_fab2_lib.baseboard_fab2(sch_1):page79_i111:a6"
				( attribute "PN" "69"
					( Origin gPackager )
				)
				( objectStatus "J1G2.69" )
			)
			( pin "@baseboard_fab2_lib.baseboard_fab2(sch_1):page79_i111:a7"
				( attribute "PN" "211"
					( Origin gPackager )
				)
				( objectStatus "J1G2.211" )
			)
			( pin "@baseboard_fab2_lib.baseboard_fab2(sch_1):page79_i111:a8"
				( attribute "PN" "68"
					( Origin gPackager )
				)
				( objectStatus "J1G2.68" )
			)
			( pin "@baseboard_fab2_lib.baseboard_fab2(sch_1):page79_i111:a9"
				( attribute "PN" "66"
					( Origin gPackager )
				)
				( objectStatus "J1G2.66" )
			)
			( pin "@baseboard_fab2_lib.baseboard_fab2(sch_1):page79_i111:a10"
				( attribute "PN" "225"
					( Origin gPackager )
				)
				( objectStatus "J1G2.225" )
			)
			( pin "@baseboard_fab2_lib.baseboard_fab2(sch_1):page79_i111:a11"
				( attribute "PN" "210"
					( Origin gPackager )
				)
				( objectStatus "J1G2.210" )
			)
			( pin "@baseboard_fab2_lib.baseboard_fab2(sch_1):page79_i111:a12"
				( attribute "PN" "65"
					( Origin gPackager )
				)
				( objectStatus "J1G2.65" )
			)
			( pin "@baseboard_fab2_lib.baseboard_fab2(sch_1):page79_i111:a13"
				( attribute "PN" "232"
					( Origin gPackager )
				)
				( objectStatus "J1G2.232" )
			)
			( pin "@baseboard_fab2_lib.baseboard_fab2(sch_1):page79_i111:a14_we_n"
				( attribute "PN" "228"
					( Origin gPackager )
				)
				( objectStatus "J1G2.228" )
			)
			( pin "@baseboard_fab2_lib.baseboard_fab2(sch_1):page79_i111:a15_cas_n"
				( attribute "PN" "86"
					( Origin gPackager )
				)
				( objectStatus "J1G2.86" )
			)
			( pin "@baseboard_fab2_lib.baseboard_fab2(sch_1):page79_i111:a16_ras_n"
				( attribute "PN" "82"
					( Origin gPackager )
				)
				( objectStatus "J1G2.82" )
			)
			( pin "@baseboard_fab2_lib.baseboard_fab2(sch_1):page79_i111:a17"
				( attribute "PN" "234"
					( Origin gPackager )
				)
				( objectStatus "J1G2.234" )
			)
			( pin "@baseboard_fab2_lib.baseboard_fab2(sch_1):page79_i111:act_n"
				( attribute "PN" "62"
					( Origin gPackager )
				)
				( objectStatus "J1G2.62" )
			)
			( pin "@baseboard_fab2_lib.baseboard_fab2(sch_1):page79_i111:alert_n"
				( attribute "PN" "208"
					( Origin gPackager )
				)
				( objectStatus "J1G2.208" )
			)
			( pin "@baseboard_fab2_lib.baseboard_fab2(sch_1):page79_i111:ba(0)"
				( attribute "PN" "81"
					( Origin gPackager )
				)
				( objectStatus "J1G2.81" )
			)
			( pin "@baseboard_fab2_lib.baseboard_fab2(sch_1):page79_i111:ba(1)"
				( attribute "PN" "224"
					( Origin gPackager )
				)
				( objectStatus "J1G2.224" )
			)
			( pin "@baseboard_fab2_lib.baseboard_fab2(sch_1):page79_i111:bg(0)"
				( attribute "PN" "63"
					( Origin gPackager )
				)
				( objectStatus "J1G2.63" )
			)
			( pin "@baseboard_fab2_lib.baseboard_fab2(sch_1):page79_i111:bg(1)"
				( attribute "PN" "207"
					( Origin gPackager )
				)
				( objectStatus "J1G2.207" )
			)
			( pin "@baseboard_fab2_lib.baseboard_fab2(sch_1):page79_i111:c(2)"
				( attribute "PN" "235"
					( Origin gPackager )
				)
				( objectStatus "J1G2.235" )
			)
			( pin "@baseboard_fab2_lib.baseboard_fab2(sch_1):page79_i111:cb(0)"
				( attribute "PN" "49"
					( Origin gPackager )
				)
				( objectStatus "J1G2.49" )
			)
			( pin "@baseboard_fab2_lib.baseboard_fab2(sch_1):page79_i111:cb(1)"
				( attribute "PN" "194"
					( Origin gPackager )
				)
				( objectStatus "J1G2.194" )
			)
			( pin "@baseboard_fab2_lib.baseboard_fab2(sch_1):page79_i111:cb(2)"
				( attribute "PN" "56"
					( Origin gPackager )
				)
				( objectStatus "J1G2.56" )
			)
			( pin "@baseboard_fab2_lib.baseboard_fab2(sch_1):page79_i111:cb(3)"
				( attribute "PN" "201"
					( Origin gPackager )
				)
				( objectStatus "J1G2.201" )
			)
			( pin "@baseboard_fab2_lib.baseboard_fab2(sch_1):page79_i111:cb(4)"
				( attribute "PN" "47"
					( Origin gPackager )
				)
				( objectStatus "J1G2.47" )
			)
			( pin "@baseboard_fab2_lib.baseboard_fab2(sch_1):page79_i111:cb(5)"
				( attribute "PN" "192"
					( Origin gPackager )
				)
				( objectStatus "J1G2.192" )
			)
			( pin "@baseboard_fab2_lib.baseboard_fab2(sch_1):page79_i111:cb(6)"
				( attribute "PN" "54"
					( Origin gPackager )
				)
				( objectStatus "J1G2.54" )
			)
			( pin "@baseboard_fab2_lib.baseboard_fab2(sch_1):page79_i111:cb(7)"
				( attribute "PN" "199"
					( Origin gPackager )
				)
				( objectStatus "J1G2.199" )
			)
			( pin "@baseboard_fab2_lib.baseboard_fab2(sch_1):page79_i111:ck0n"
				( attribute "PN" "75"
					( Origin gPackager )
				)
				( objectStatus "J1G2.75" )
			)
			( pin "@baseboard_fab2_lib.baseboard_fab2(sch_1):page79_i111:ck0p"
				( attribute "PN" "74"
					( Origin gPackager )
				)
				( objectStatus "J1G2.74" )
			)
			( pin "@baseboard_fab2_lib.baseboard_fab2(sch_1):page79_i111:ck1n"
				( attribute "PN" "219"
					( Origin gPackager )
				)
				( objectStatus "J1G2.219" )
			)
			( pin "@baseboard_fab2_lib.baseboard_fab2(sch_1):page79_i111:ck1p"
				( attribute "PN" "218"
					( Origin gPackager )
				)
				( objectStatus "J1G2.218" )
			)
			( pin "@baseboard_fab2_lib.baseboard_fab2(sch_1):page79_i111:cke(0)"
				( attribute "PN" "60"
					( Origin gPackager )
				)
				( objectStatus "J1G2.60" )
			)
			( pin "@baseboard_fab2_lib.baseboard_fab2(sch_1):page79_i111:cke(1)"
				( attribute "PN" "203"
					( Origin gPackager )
				)
				( objectStatus "J1G2.203" )
			)
			( pin "@baseboard_fab2_lib.baseboard_fab2(sch_1):page79_i111:dq(0)"
				( attribute "PN" "5"
					( Origin gPackager )
				)
				( objectStatus "J1G2.5" )
			)
			( pin "@baseboard_fab2_lib.baseboard_fab2(sch_1):page79_i111:dq(1)"
				( attribute "PN" "150"
					( Origin gPackager )
				)
				( objectStatus "J1G2.150" )
			)
			( pin "@baseboard_fab2_lib.baseboard_fab2(sch_1):page79_i111:dq(2)"
				( attribute "PN" "12"
					( Origin gPackager )
				)
				( objectStatus "J1G2.12" )
			)
			( pin "@baseboard_fab2_lib.baseboard_fab2(sch_1):page79_i111:dq(3)"
				( attribute "PN" "157"
					( Origin gPackager )
				)
				( objectStatus "J1G2.157" )
			)
			( pin "@baseboard_fab2_lib.baseboard_fab2(sch_1):page79_i111:dq(4)"
				( attribute "PN" "3"
					( Origin gPackager )
				)
				( objectStatus "J1G2.3" )
			)
			( pin "@baseboard_fab2_lib.baseboard_fab2(sch_1):page79_i111:dq(5)"
				( attribute "PN" "148"
					( Origin gPackager )
				)
				( objectStatus "J1G2.148" )
			)
			( pin "@baseboard_fab2_lib.baseboard_fab2(sch_1):page79_i111:dq(6)"
				( attribute "PN" "10"
					( Origin gPackager )
				)
				( objectStatus "J1G2.10" )
			)
			( pin "@baseboard_fab2_lib.baseboard_fab2(sch_1):page79_i111:dq(7)"
				( attribute "PN" "155"
					( Origin gPackager )
				)
				( objectStatus "J1G2.155" )
			)
			( pin "@baseboard_fab2_lib.baseboard_fab2(sch_1):page79_i111:dq(8)"
				( attribute "PN" "16"
					( Origin gPackager )
				)
				( objectStatus "J1G2.16" )
			)
			( pin "@baseboard_fab2_lib.baseboard_fab2(sch_1):page79_i111:dq(9)"
				( attribute "PN" "161"
					( Origin gPackager )
				)
				( objectStatus "J1G2.161" )
			)
			( pin "@baseboard_fab2_lib.baseboard_fab2(sch_1):page79_i111:dq(10)"
				( attribute "PN" "23"
					( Origin gPackager )
				)
				( objectStatus "J1G2.23" )
			)
			( pin "@baseboard_fab2_lib.baseboard_fab2(sch_1):page79_i111:dq(11)"
				( attribute "PN" "168"
					( Origin gPackager )
				)
				( objectStatus "J1G2.168" )
			)
			( pin "@baseboard_fab2_lib.baseboard_fab2(sch_1):page79_i111:dq(12)"
				( attribute "PN" "14"
					( Origin gPackager )
				)
				( objectStatus "J1G2.14" )
			)
			( pin "@baseboard_fab2_lib.baseboard_fab2(sch_1):page79_i111:dq(13)"
				( attribute "PN" "159"
					( Origin gPackager )
				)
				( objectStatus "J1G2.159" )
			)
			( pin "@baseboard_fab2_lib.baseboard_fab2(sch_1):page79_i111:dq(14)"
				( attribute "PN" "21"
					( Origin gPackager )
				)
				( objectStatus "J1G2.21" )
			)
			( pin "@baseboard_fab2_lib.baseboard_fab2(sch_1):page79_i111:dq(15)"
				( attribute "PN" "166"
					( Origin gPackager )
				)
				( objectStatus "J1G2.166" )
			)
			( pin "@baseboard_fab2_lib.baseboard_fab2(sch_1):page79_i111:dq(16)"
				( attribute "PN" "27"
					( Origin gPackager )
				)
				( objectStatus "J1G2.27" )
			)
			( pin "@baseboard_fab2_lib.baseboard_fab2(sch_1):page79_i111:dq(17)"
				( attribute "PN" "172"
					( Origin gPackager )
				)
				( objectStatus "J1G2.172" )
			)
			( pin "@baseboard_fab2_lib.baseboard_fab2(sch_1):page79_i111:dq(18)"
				( attribute "PN" "34"
					( Origin gPackager )
				)
				( objectStatus "J1G2.34" )
			)
			( pin "@baseboard_fab2_lib.baseboard_fab2(sch_1):page79_i111:dq(19)"
				( attribute "PN" "179"
					( Origin gPackager )
				)
				( objectStatus "J1G2.179" )
			)
			( pin "@baseboard_fab2_lib.baseboard_fab2(sch_1):page79_i111:dq(20)"
				( attribute "PN" "25"
					( Origin gPackager )
				)
				( objectStatus "J1G2.25" )
			)
			( pin "@baseboard_fab2_lib.baseboard_fab2(sch_1):page79_i111:dq(21)"
				( attribute "PN" "170"
					( Origin gPackager )
				)
				( objectStatus "J1G2.170" )
			)
			( pin "@baseboard_fab2_lib.baseboard_fab2(sch_1):page79_i111:dq(22)"
				( attribute "PN" "32"
					( Origin gPackager )
				)
				( objectStatus "J1G2.32" )
			)
			( pin "@baseboard_fab2_lib.baseboard_fab2(sch_1):page79_i111:dq(23)"
				( attribute "PN" "177"
					( Origin gPackager )
				)
				( objectStatus "J1G2.177" )
			)
			( pin "@baseboard_fab2_lib.baseboard_fab2(sch_1):page79_i111:dq(24)"
				( attribute "PN" "38"
					( Origin gPackager )
				)
				( objectStatus "J1G2.38" )
			)
			( pin "@baseboard_fab2_lib.baseboard_fab2(sch_1):page79_i111:dq(25)"
				( attribute "PN" "183"
					( Origin gPackager )
				)
				( objectStatus "J1G2.183" )
			)
			( pin "@baseboard_fab2_lib.baseboard_fab2(sch_1):page79_i111:dq(26)"
				( attribute "PN" "45"
					( Origin gPackager )
				)
				( objectStatus "J1G2.45" )
			)
			( pin "@baseboard_fab2_lib.baseboard_fab2(sch_1):page79_i111:dq(27)"
				( attribute "PN" "190"
					( Origin gPackager )
				)
				( objectStatus "J1G2.190" )
			)
			( pin "@baseboard_fab2_lib.baseboard_fab2(sch_1):page79_i111:dq(28)"
				( attribute "PN" "36"
					( Origin gPackager )
				)
				( objectStatus "J1G2.36" )
			)
			( pin "@baseboard_fab2_lib.baseboard_fab2(sch_1):page79_i111:dq(29)"
				( attribute "PN" "181"
					( Origin gPackager )
				)
				( objectStatus "J1G2.181" )
			)
			( pin "@baseboard_fab2_lib.baseboard_fab2(sch_1):page79_i111:dq(30)"
				( attribute "PN" "43"
					( Origin gPackager )
				)
				( objectStatus "J1G2.43" )
			)
			( pin "@baseboard_fab2_lib.baseboard_fab2(sch_1):page79_i111:dq(31)"
				( attribute "PN" "188"
					( Origin gPackager )
				)
				( objectStatus "J1G2.188" )
			)
			( pin "@baseboard_fab2_lib.baseboard_fab2(sch_1):page79_i111:dq(32)"
				( attribute "PN" "97"
					( Origin gPackager )
				)
				( objectStatus "J1G2.97" )
			)
			( pin "@baseboard_fab2_lib.baseboard_fab2(sch_1):page79_i111:dq(33)"
				( attribute "PN" "242"
					( Origin gPackager )
				)
				( objectStatus "J1G2.242" )
			)
			( pin "@baseboard_fab2_lib.baseboard_fab2(sch_1):page79_i111:dq(34)"
				( attribute "PN" "104"
					( Origin gPackager )
				)
				( objectStatus "J1G2.104" )
			)
			( pin "@baseboard_fab2_lib.baseboard_fab2(sch_1):page79_i111:dq(35)"
				( attribute "PN" "249"
					( Origin gPackager )
				)
				( objectStatus "J1G2.249" )
			)
			( pin "@baseboard_fab2_lib.baseboard_fab2(sch_1):page79_i111:dq(36)"
				( attribute "PN" "95"
					( Origin gPackager )
				)
				( objectStatus "J1G2.95" )
			)
			( pin "@baseboard_fab2_lib.baseboard_fab2(sch_1):page79_i111:dq(37)"
				( attribute "PN" "240"
					( Origin gPackager )
				)
				( objectStatus "J1G2.240" )
			)
			( pin "@baseboard_fab2_lib.baseboard_fab2(sch_1):page79_i111:dq(38)"
				( attribute "PN" "102"
					( Origin gPackager )
				)
				( objectStatus "J1G2.102" )
			)
			( pin "@baseboard_fab2_lib.baseboard_fab2(sch_1):page79_i111:dq(39)"
				( attribute "PN" "247"
					( Origin gPackager )
				)
				( objectStatus "J1G2.247" )
			)
			( pin "@baseboard_fab2_lib.baseboard_fab2(sch_1):page79_i111:dq(40)"
				( attribute "PN" "108"
					( Origin gPackager )
				)
				( objectStatus "J1G2.108" )
			)
			( pin "@baseboard_fab2_lib.baseboard_fab2(sch_1):page79_i111:dq(41)"
				( attribute "PN" "253"
					( Origin gPackager )
				)
				( objectStatus "J1G2.253" )
			)
			( pin "@baseboard_fab2_lib.baseboard_fab2(sch_1):page79_i111:dq(42)"
				( attribute "PN" "115"
					( Origin gPackager )
				)
				( objectStatus "J1G2.115" )
			)
			( pin "@baseboard_fab2_lib.baseboard_fab2(sch_1):page79_i111:dq(43)"
				( attribute "PN" "260"
					( Origin gPackager )
				)
				( objectStatus "J1G2.260" )
			)
			( pin "@baseboard_fab2_lib.baseboard_fab2(sch_1):page79_i111:dq(44)"
				( attribute "PN" "106"
					( Origin gPackager )
				)
				( objectStatus "J1G2.106" )
			)
			( pin "@baseboard_fab2_lib.baseboard_fab2(sch_1):page79_i111:dq(45)"
				( attribute "PN" "251"
					( Origin gPackager )
				)
				( objectStatus "J1G2.251" )
			)
			( pin "@baseboard_fab2_lib.baseboard_fab2(sch_1):page79_i111:dq(46)"
				( attribute "PN" "113"
					( Origin gPackager )
				)
				( objectStatus "J1G2.113" )
			)
			( pin "@baseboard_fab2_lib.baseboard_fab2(sch_1):page79_i111:dq(47)"
				( attribute "PN" "258"
					( Origin gPackager )
				)
				( objectStatus "J1G2.258" )
			)
			( pin "@baseboard_fab2_lib.baseboard_fab2(sch_1):page79_i111:dq(48)"
				( attribute "PN" "119"
					( Origin gPackager )
				)
				( objectStatus "J1G2.119" )
			)
			( pin "@baseboard_fab2_lib.baseboard_fab2(sch_1):page79_i111:dq(49)"
				( attribute "PN" "264"
					( Origin gPackager )
				)
				( objectStatus "J1G2.264" )
			)
			( pin "@baseboard_fab2_lib.baseboard_fab2(sch_1):page79_i111:dq(50)"
				( attribute "PN" "126"
					( Origin gPackager )
				)
				( objectStatus "J1G2.126" )
			)
			( pin "@baseboard_fab2_lib.baseboard_fab2(sch_1):page79_i111:dq(51)"
				( attribute "PN" "271"
					( Origin gPackager )
				)
				( objectStatus "J1G2.271" )
			)
			( pin "@baseboard_fab2_lib.baseboard_fab2(sch_1):page79_i111:dq(52)"
				( attribute "PN" "117"
					( Origin gPackager )
				)
				( objectStatus "J1G2.117" )
			)
			( pin "@baseboard_fab2_lib.baseboard_fab2(sch_1):page79_i111:dq(53)"
				( attribute "PN" "262"
					( Origin gPackager )
				)
				( objectStatus "J1G2.262" )
			)
			( pin "@baseboard_fab2_lib.baseboard_fab2(sch_1):page79_i111:dq(54)"
				( attribute "PN" "124"
					( Origin gPackager )
				)
				( objectStatus "J1G2.124" )
			)
			( pin "@baseboard_fab2_lib.baseboard_fab2(sch_1):page79_i111:dq(55)"
				( attribute "PN" "269"
					( Origin gPackager )
				)
				( objectStatus "J1G2.269" )
			)
			( pin "@baseboard_fab2_lib.baseboard_fab2(sch_1):page79_i111:dq(56)"
				( attribute "PN" "130"
					( Origin gPackager )
				)
				( objectStatus "J1G2.130" )
			)
			( pin "@baseboard_fab2_lib.baseboard_fab2(sch_1):page79_i111:dq(57)"
				( attribute "PN" "275"
					( Origin gPackager )
				)
				( objectStatus "J1G2.275" )
			)
			( pin "@baseboard_fab2_lib.baseboard_fab2(sch_1):page79_i111:dq(58)"
				( attribute "PN" "137"
					( Origin gPackager )
				)
				( objectStatus "J1G2.137" )
			)
			( pin "@baseboard_fab2_lib.baseboard_fab2(sch_1):page79_i111:dq(59)"
				( attribute "PN" "282"
					( Origin gPackager )
				)
				( objectStatus "J1G2.282" )
			)
			( pin "@baseboard_fab2_lib.baseboard_fab2(sch_1):page79_i111:dq(60)"
				( attribute "PN" "128"
					( Origin gPackager )
				)
				( objectStatus "J1G2.128" )
			)
			( pin "@baseboard_fab2_lib.baseboard_fab2(sch_1):page79_i111:dq(61)"
				( attribute "PN" "273"
					( Origin gPackager )
				)
				( objectStatus "J1G2.273" )
			)
			( pin "@baseboard_fab2_lib.baseboard_fab2(sch_1):page79_i111:dq(62)"
				( attribute "PN" "135"
					( Origin gPackager )
				)
				( objectStatus "J1G2.135" )
			)
			( pin "@baseboard_fab2_lib.baseboard_fab2(sch_1):page79_i111:dq(63)"
				( attribute "PN" "280"
					( Origin gPackager )
				)
				( objectStatus "J1G2.280" )
			)
			( pin "@baseboard_fab2_lib.baseboard_fab2(sch_1):page79_i111:event_n"
				( attribute "PN" "78"
					( Origin gPackager )
				)
				( objectStatus "J1G2.78" )
			)
			( pin "@baseboard_fab2_lib.baseboard_fab2(sch_1):page79_i111:odt(0)"
				( attribute "PN" "87"
					( Origin gPackager )
				)
				( objectStatus "J1G2.87" )
			)
			( pin "@baseboard_fab2_lib.baseboard_fab2(sch_1):page79_i111:odt(1)"
				( attribute "PN" "91"
					( Origin gPackager )
				)
				( objectStatus "J1G2.91" )
			)
			( pin "@baseboard_fab2_lib.baseboard_fab2(sch_1):page79_i111:par"
				( attribute "PN" "222"
					( Origin gPackager )
				)
				( objectStatus "J1G2.222" )
			)
			( pin "@baseboard_fab2_lib.baseboard_fab2(sch_1):page79_i111:reset_n"
				( attribute "PN" "58"
					( Origin gPackager )
				)
				( objectStatus "J1G2.58" )
			)
			( pin "@baseboard_fab2_lib.baseboard_fab2(sch_1):page79_i111:rfu(0)"
				( attribute "PN" "205"
					( Origin gPackager )
				)
				( objectStatus "J1G2.205" )
			)
			( pin "@baseboard_fab2_lib.baseboard_fab2(sch_1):page79_i111:rfu(1)"
				( attribute "PN" "227"
					( Origin gPackager )
				)
				( objectStatus "J1G2.227" )
			)
			( pin "@baseboard_fab2_lib.baseboard_fab2(sch_1):page79_i111:rfu(2)"
				( attribute "PN" "144"
					( Origin gPackager )
				)
				( objectStatus "J1G2.144" )
			)
			( pin "@baseboard_fab2_lib.baseboard_fab2(sch_1):page79_i111:s0_n"
				( attribute "PN" "84"
					( Origin gPackager )
				)
				( objectStatus "J1G2.84" )
			)
			( pin "@baseboard_fab2_lib.baseboard_fab2(sch_1):page79_i111:s1_n"
				( attribute "PN" "89"
					( Origin gPackager )
				)
				( objectStatus "J1G2.89" )
			)
			( pin "@baseboard_fab2_lib.baseboard_fab2(sch_1):page79_i111:s2_n_c(0)"
				( attribute "PN" "93"
					( Origin gPackager )
				)
				( objectStatus "J1G2.93" )
			)
			( pin "@baseboard_fab2_lib.baseboard_fab2(sch_1):page79_i111:s3_n_c(1)"
				( attribute "PN" "237"
					( Origin gPackager )
				)
				( objectStatus "J1G2.237" )
			)
			( pin "@baseboard_fab2_lib.baseboard_fab2(sch_1):page79_i111:sa(0)"
				( attribute "PN" "139"
					( Origin gPackager )
				)
				( objectStatus "J1G2.139" )
			)
			( pin "@baseboard_fab2_lib.baseboard_fab2(sch_1):page79_i111:sa(1)"
				( attribute "PN" "140"
					( Origin gPackager )
				)
				( objectStatus "J1G2.140" )
			)
			( pin "@baseboard_fab2_lib.baseboard_fab2(sch_1):page79_i111:sa(2)"
				( attribute "PN" "238"
					( Origin gPackager )
				)
				( objectStatus "J1G2.238" )
			)
			( pin "@baseboard_fab2_lib.baseboard_fab2(sch_1):page79_i111:save_n_nc"
				( attribute "PN" "230"
					( Origin gPackager )
				)
				( objectStatus "J1G2.230" )
			)
			( pin "@baseboard_fab2_lib.baseboard_fab2(sch_1):page79_i111:scl"
				( attribute "PN" "141"
					( Origin gPackager )
				)
				( objectStatus "J1G2.141" )
			)
			( pin "@baseboard_fab2_lib.baseboard_fab2(sch_1):page79_i111:sda"
				( attribute "PN" "285"
					( Origin gPackager )
				)
				( objectStatus "J1G2.285" )
			)
			( pin "@baseboard_fab2_lib.baseboard_fab2(sch_1):page79_i111:vddspd"
				( attribute "PN" "284"
					( Origin gPackager )
				)
				( objectStatus "J1G2.284" )
			)
			( pin "@baseboard_fab2_lib.baseboard_fab2(sch_1):page79_i111:vrefca"
				( attribute "PN" "146"
					( Origin gPackager )
				)
				( objectStatus "J1G2.146" )
			)
			( pin "@baseboard_fab2_lib.baseboard_fab2(sch_1):page79_i169:\12v\(0)"
				( attribute "PN" "145"
					( Origin gPackager )
				)
				( objectStatus "J1G2.145" )
			)
			( pin "@baseboard_fab2_lib.baseboard_fab2(sch_1):page79_i169:\12v\(1)"
				( attribute "PN" "1"
					( Origin gPackager )
				)
				( objectStatus "J1G2.1" )
			)
			( pin "@baseboard_fab2_lib.baseboard_fab2(sch_1):page79_i169:vdd(0)"
				( attribute "PN" "236"
					( Origin gPackager )
				)
				( objectStatus "J1G2.236" )
			)
			( pin "@baseboard_fab2_lib.baseboard_fab2(sch_1):page79_i169:vdd(1)"
				( attribute "PN" "233"
					( Origin gPackager )
				)
				( objectStatus "J1G2.233" )
			)
			( pin "@baseboard_fab2_lib.baseboard_fab2(sch_1):page79_i169:vdd(2)"
				( attribute "PN" "231"
					( Origin gPackager )
				)
				( objectStatus "J1G2.231" )
			)
			( pin "@baseboard_fab2_lib.baseboard_fab2(sch_1):page79_i169:vdd(3)"
				( attribute "PN" "229"
					( Origin gPackager )
				)
				( objectStatus "J1G2.229" )
			)
			( pin "@baseboard_fab2_lib.baseboard_fab2(sch_1):page79_i169:vdd(4)"
				( attribute "PN" "226"
					( Origin gPackager )
				)
				( objectStatus "J1G2.226" )
			)
			( pin "@baseboard_fab2_lib.baseboard_fab2(sch_1):page79_i169:vdd(5)"
				( attribute "PN" "223"
					( Origin gPackager )
				)
				( objectStatus "J1G2.223" )
			)
			( pin "@baseboard_fab2_lib.baseboard_fab2(sch_1):page79_i169:vdd(6)"
				( attribute "PN" "220"
					( Origin gPackager )
				)
				( objectStatus "J1G2.220" )
			)
			( pin "@baseboard_fab2_lib.baseboard_fab2(sch_1):page79_i169:vdd(7)"
				( attribute "PN" "217"
					( Origin gPackager )
				)
				( objectStatus "J1G2.217" )
			)
			( pin "@baseboard_fab2_lib.baseboard_fab2(sch_1):page79_i169:vdd(8)"
				( attribute "PN" "215"
					( Origin gPackager )
				)
				( objectStatus "J1G2.215" )
			)
			( pin "@baseboard_fab2_lib.baseboard_fab2(sch_1):page79_i169:vdd(9)"
				( attribute "PN" "212"
					( Origin gPackager )
				)
				( objectStatus "J1G2.212" )
			)
			( pin "@baseboard_fab2_lib.baseboard_fab2(sch_1):page79_i169:vdd(10)"
				( attribute "PN" "209"
					( Origin gPackager )
				)
				( objectStatus "J1G2.209" )
			)
			( pin "@baseboard_fab2_lib.baseboard_fab2(sch_1):page79_i169:vdd(11)"
				( attribute "PN" "206"
					( Origin gPackager )
				)
				( objectStatus "J1G2.206" )
			)
			( pin "@baseboard_fab2_lib.baseboard_fab2(sch_1):page79_i169:vdd(12)"
				( attribute "PN" "204"
					( Origin gPackager )
				)
				( objectStatus "J1G2.204" )
			)
			( pin "@baseboard_fab2_lib.baseboard_fab2(sch_1):page79_i169:vdd(13)"
				( attribute "PN" "92"
					( Origin gPackager )
				)
				( objectStatus "J1G2.92" )
			)
			( pin "@baseboard_fab2_lib.baseboard_fab2(sch_1):page79_i169:vdd(14)"
				( attribute "PN" "90"
					( Origin gPackager )
				)
				( objectStatus "J1G2.90" )
			)
			( pin "@baseboard_fab2_lib.baseboard_fab2(sch_1):page79_i169:vdd(15)"
				( attribute "PN" "88"
					( Origin gPackager )
				)
				( objectStatus "J1G2.88" )
			)
			( pin "@baseboard_fab2_lib.baseboard_fab2(sch_1):page79_i169:vdd(16)"
				( attribute "PN" "85"
					( Origin gPackager )
				)
				( objectStatus "J1G2.85" )
			)
			( pin "@baseboard_fab2_lib.baseboard_fab2(sch_1):page79_i169:vdd(17)"
				( attribute "PN" "83"
					( Origin gPackager )
				)
				( objectStatus "J1G2.83" )
			)
			( pin "@baseboard_fab2_lib.baseboard_fab2(sch_1):page79_i169:vdd(18)"
				( attribute "PN" "80"
					( Origin gPackager )
				)
				( objectStatus "J1G2.80" )
			)
			( pin "@baseboard_fab2_lib.baseboard_fab2(sch_1):page79_i169:vdd(19)"
				( attribute "PN" "76"
					( Origin gPackager )
				)
				( objectStatus "J1G2.76" )
			)
			( pin "@baseboard_fab2_lib.baseboard_fab2(sch_1):page79_i169:vdd(20)"
				( attribute "PN" "73"
					( Origin gPackager )
				)
				( objectStatus "J1G2.73" )
			)
			( pin "@baseboard_fab2_lib.baseboard_fab2(sch_1):page79_i169:vdd(21)"
				( attribute "PN" "70"
					( Origin gPackager )
				)
				( objectStatus "J1G2.70" )
			)
			( pin "@baseboard_fab2_lib.baseboard_fab2(sch_1):page79_i169:vdd(22)"
				( attribute "PN" "67"
					( Origin gPackager )
				)
				( objectStatus "J1G2.67" )
			)
			( pin "@baseboard_fab2_lib.baseboard_fab2(sch_1):page79_i169:vdd(23)"
				( attribute "PN" "64"
					( Origin gPackager )
				)
				( objectStatus "J1G2.64" )
			)
			( pin "@baseboard_fab2_lib.baseboard_fab2(sch_1):page79_i169:vdd(24)"
				( attribute "PN" "61"
					( Origin gPackager )
				)
				( objectStatus "J1G2.61" )
			)
			( pin "@baseboard_fab2_lib.baseboard_fab2(sch_1):page79_i169:vdd(25)"
				( attribute "PN" "59"
					( Origin gPackager )
				)
				( objectStatus "J1G2.59" )
			)
			( pin "@baseboard_fab2_lib.baseboard_fab2(sch_1):page79_i169:vpp(0)"
				( attribute "PN" "287"
					( Origin gPackager )
				)
				( objectStatus "J1G2.287" )
			)
			( pin "@baseboard_fab2_lib.baseboard_fab2(sch_1):page79_i169:vpp(1)"
				( attribute "PN" "286"
					( Origin gPackager )
				)
				( objectStatus "J1G2.286" )
			)
			( pin "@baseboard_fab2_lib.baseboard_fab2(sch_1):page79_i169:vpp(2)"
				( attribute "PN" "288"
					( Origin gPackager )
				)
				( objectStatus "J1G2.288" )
			)
			( pin "@baseboard_fab2_lib.baseboard_fab2(sch_1):page79_i169:vpp(3)"
				( attribute "PN" "143"
					( Origin gPackager )
				)
				( objectStatus "J1G2.143" )
			)
			( pin "@baseboard_fab2_lib.baseboard_fab2(sch_1):page79_i169:vpp(4)"
				( attribute "PN" "142"
					( Origin gPackager )
				)
				( objectStatus "J1G2.142" )
			)
			( pin "@baseboard_fab2_lib.baseboard_fab2(sch_1):page79_i169:vtt(0)"
				( attribute "PN" "221"
					( Origin gPackager )
				)
				( objectStatus "J1G2.221" )
			)
			( pin "@baseboard_fab2_lib.baseboard_fab2(sch_1):page79_i169:vtt(1)"
				( attribute "PN" "77"
					( Origin gPackager )
				)
				( objectStatus "J1G2.77" )
			)
			( pin "@baseboard_fab2_lib.baseboard_fab2(sch_1):page79_i178:a"
				( attribute "PN" "1"
					( Origin gPackager )
				)
				( objectStatus "C9U7.1" )
			)
			( pin "@baseboard_fab2_lib.baseboard_fab2(sch_1):page79_i178:b"
				( attribute "PN" "2"
					( Origin gPackager )
				)
				( objectStatus "C9U7.2" )
			)
			( pin "@baseboard_fab2_lib.baseboard_fab2(sch_1):page80_i3:a"
				( attribute "PN" "1"
					( Origin gPackager )
				)
				( objectStatus "C1G10.1" )
			)
			( pin "@baseboard_fab2_lib.baseboard_fab2(sch_1):page80_i3:b"
				( attribute "PN" "2"
					( Origin gPackager )
				)
				( objectStatus "C1G10.2" )
			)
			( pin "@baseboard_fab2_lib.baseboard_fab2(sch_1):page80_i24:a0"
				( attribute "PN" "79"
					( Origin gPackager )
				)
				( objectStatus "J9U1.79" )
			)
			( pin "@baseboard_fab2_lib.baseboard_fab2(sch_1):page80_i24:a1"
				( attribute "PN" "72"
					( Origin gPackager )
				)
				( objectStatus "J9U1.72" )
			)
			( pin "@baseboard_fab2_lib.baseboard_fab2(sch_1):page80_i24:a2"
				( attribute "PN" "216"
					( Origin gPackager )
				)
				( objectStatus "J9U1.216" )
			)
			( pin "@baseboard_fab2_lib.baseboard_fab2(sch_1):page80_i24:a3"
				( attribute "PN" "71"
					( Origin gPackager )
				)
				( objectStatus "J9U1.71" )
			)
			( pin "@baseboard_fab2_lib.baseboard_fab2(sch_1):page80_i24:a4"
				( attribute "PN" "214"
					( Origin gPackager )
				)
				( objectStatus "J9U1.214" )
			)
			( pin "@baseboard_fab2_lib.baseboard_fab2(sch_1):page80_i24:a5"
				( attribute "PN" "213"
					( Origin gPackager )
				)
				( objectStatus "J9U1.213" )
			)
			( pin "@baseboard_fab2_lib.baseboard_fab2(sch_1):page80_i24:a6"
				( attribute "PN" "69"
					( Origin gPackager )
				)
				( objectStatus "J9U1.69" )
			)
			( pin "@baseboard_fab2_lib.baseboard_fab2(sch_1):page80_i24:a7"
				( attribute "PN" "211"
					( Origin gPackager )
				)
				( objectStatus "J9U1.211" )
			)
			( pin "@baseboard_fab2_lib.baseboard_fab2(sch_1):page80_i24:a8"
				( attribute "PN" "68"
					( Origin gPackager )
				)
				( objectStatus "J9U1.68" )
			)
			( pin "@baseboard_fab2_lib.baseboard_fab2(sch_1):page80_i24:a9"
				( attribute "PN" "66"
					( Origin gPackager )
				)
				( objectStatus "J9U1.66" )
			)
			( pin "@baseboard_fab2_lib.baseboard_fab2(sch_1):page80_i24:a10"
				( attribute "PN" "225"
					( Origin gPackager )
				)
				( objectStatus "J9U1.225" )
			)
			( pin "@baseboard_fab2_lib.baseboard_fab2(sch_1):page80_i24:a11"
				( attribute "PN" "210"
					( Origin gPackager )
				)
				( objectStatus "J9U1.210" )
			)
			( pin "@baseboard_fab2_lib.baseboard_fab2(sch_1):page80_i24:a12"
				( attribute "PN" "65"
					( Origin gPackager )
				)
				( objectStatus "J9U1.65" )
			)
			( pin "@baseboard_fab2_lib.baseboard_fab2(sch_1):page80_i24:a13"
				( attribute "PN" "232"
					( Origin gPackager )
				)
				( objectStatus "J9U1.232" )
			)
			( pin "@baseboard_fab2_lib.baseboard_fab2(sch_1):page80_i24:a14_we_n"
				( attribute "PN" "228"
					( Origin gPackager )
				)
				( objectStatus "J9U1.228" )
			)
			( pin "@baseboard_fab2_lib.baseboard_fab2(sch_1):page80_i24:a15_cas_n"
				( attribute "PN" "86"
					( Origin gPackager )
				)
				( objectStatus "J9U1.86" )
			)
			( pin "@baseboard_fab2_lib.baseboard_fab2(sch_1):page80_i24:a16_ras_n"
				( attribute "PN" "82"
					( Origin gPackager )
				)
				( objectStatus "J9U1.82" )
			)
			( pin "@baseboard_fab2_lib.baseboard_fab2(sch_1):page80_i24:a17"
				( attribute "PN" "234"
					( Origin gPackager )
				)
				( objectStatus "J9U1.234" )
			)
			( pin "@baseboard_fab2_lib.baseboard_fab2(sch_1):page80_i24:act_n"
				( attribute "PN" "62"
					( Origin gPackager )
				)
				( objectStatus "J9U1.62" )
			)
			( pin "@baseboard_fab2_lib.baseboard_fab2(sch_1):page80_i24:alert_n"
				( attribute "PN" "208"
					( Origin gPackager )
				)
				( objectStatus "J9U1.208" )
			)
			( pin "@baseboard_fab2_lib.baseboard_fab2(sch_1):page80_i24:ba(0)"
				( attribute "PN" "81"
					( Origin gPackager )
				)
				( objectStatus "J9U1.81" )
			)
			( pin "@baseboard_fab2_lib.baseboard_fab2(sch_1):page80_i24:ba(1)"
				( attribute "PN" "224"
					( Origin gPackager )
				)
				( objectStatus "J9U1.224" )
			)
			( pin "@baseboard_fab2_lib.baseboard_fab2(sch_1):page80_i24:bg(0)"
				( attribute "PN" "63"
					( Origin gPackager )
				)
				( objectStatus "J9U1.63" )
			)
			( pin "@baseboard_fab2_lib.baseboard_fab2(sch_1):page80_i24:bg(1)"
				( attribute "PN" "207"
					( Origin gPackager )
				)
				( objectStatus "J9U1.207" )
			)
			( pin "@baseboard_fab2_lib.baseboard_fab2(sch_1):page80_i24:c(2)"
				( attribute "PN" "235"
					( Origin gPackager )
				)
				( objectStatus "J9U1.235" )
			)
			( pin "@baseboard_fab2_lib.baseboard_fab2(sch_1):page80_i24:cb(0)"
				( attribute "PN" "49"
					( Origin gPackager )
				)
				( objectStatus "J9U1.49" )
			)
			( pin "@baseboard_fab2_lib.baseboard_fab2(sch_1):page80_i24:cb(1)"
				( attribute "PN" "194"
					( Origin gPackager )
				)
				( objectStatus "J9U1.194" )
			)
			( pin "@baseboard_fab2_lib.baseboard_fab2(sch_1):page80_i24:cb(2)"
				( attribute "PN" "56"
					( Origin gPackager )
				)
				( objectStatus "J9U1.56" )
			)
			( pin "@baseboard_fab2_lib.baseboard_fab2(sch_1):page80_i24:cb(3)"
				( attribute "PN" "201"
					( Origin gPackager )
				)
				( objectStatus "J9U1.201" )
			)
			( pin "@baseboard_fab2_lib.baseboard_fab2(sch_1):page80_i24:cb(4)"
				( attribute "PN" "47"
					( Origin gPackager )
				)
				( objectStatus "J9U1.47" )
			)
			( pin "@baseboard_fab2_lib.baseboard_fab2(sch_1):page80_i24:cb(5)"
				( attribute "PN" "192"
					( Origin gPackager )
				)
				( objectStatus "J9U1.192" )
			)
			( pin "@baseboard_fab2_lib.baseboard_fab2(sch_1):page80_i24:cb(6)"
				( attribute "PN" "54"
					( Origin gPackager )
				)
				( objectStatus "J9U1.54" )
			)
			( pin "@baseboard_fab2_lib.baseboard_fab2(sch_1):page80_i24:cb(7)"
				( attribute "PN" "199"
					( Origin gPackager )
				)
				( objectStatus "J9U1.199" )
			)
			( pin "@baseboard_fab2_lib.baseboard_fab2(sch_1):page80_i24:ck0n"
				( attribute "PN" "75"
					( Origin gPackager )
				)
				( objectStatus "J9U1.75" )
			)
			( pin "@baseboard_fab2_lib.baseboard_fab2(sch_1):page80_i24:ck0p"
				( attribute "PN" "74"
					( Origin gPackager )
				)
				( objectStatus "J9U1.74" )
			)
			( pin "@baseboard_fab2_lib.baseboard_fab2(sch_1):page80_i24:ck1n"
				( attribute "PN" "219"
					( Origin gPackager )
				)
				( objectStatus "J9U1.219" )
			)
			( pin "@baseboard_fab2_lib.baseboard_fab2(sch_1):page80_i24:ck1p"
				( attribute "PN" "218"
					( Origin gPackager )
				)
				( objectStatus "J9U1.218" )
			)
			( pin "@baseboard_fab2_lib.baseboard_fab2(sch_1):page80_i24:cke(0)"
				( attribute "PN" "60"
					( Origin gPackager )
				)
				( objectStatus "J9U1.60" )
			)
			( pin "@baseboard_fab2_lib.baseboard_fab2(sch_1):page80_i24:cke(1)"
				( attribute "PN" "203"
					( Origin gPackager )
				)
				( objectStatus "J9U1.203" )
			)
			( pin "@baseboard_fab2_lib.baseboard_fab2(sch_1):page80_i24:dq(0)"
				( attribute "PN" "5"
					( Origin gPackager )
				)
				( objectStatus "J9U1.5" )
			)
			( pin "@baseboard_fab2_lib.baseboard_fab2(sch_1):page80_i24:dq(1)"
				( attribute "PN" "150"
					( Origin gPackager )
				)
				( objectStatus "J9U1.150" )
			)
			( pin "@baseboard_fab2_lib.baseboard_fab2(sch_1):page80_i24:dq(2)"
				( attribute "PN" "12"
					( Origin gPackager )
				)
				( objectStatus "J9U1.12" )
			)
			( pin "@baseboard_fab2_lib.baseboard_fab2(sch_1):page80_i24:dq(3)"
				( attribute "PN" "157"
					( Origin gPackager )
				)
				( objectStatus "J9U1.157" )
			)
			( pin "@baseboard_fab2_lib.baseboard_fab2(sch_1):page80_i24:dq(4)"
				( attribute "PN" "3"
					( Origin gPackager )
				)
				( objectStatus "J9U1.3" )
			)
			( pin "@baseboard_fab2_lib.baseboard_fab2(sch_1):page80_i24:dq(5)"
				( attribute "PN" "148"
					( Origin gPackager )
				)
				( objectStatus "J9U1.148" )
			)
			( pin "@baseboard_fab2_lib.baseboard_fab2(sch_1):page80_i24:dq(6)"
				( attribute "PN" "10"
					( Origin gPackager )
				)
				( objectStatus "J9U1.10" )
			)
			( pin "@baseboard_fab2_lib.baseboard_fab2(sch_1):page80_i24:dq(7)"
				( attribute "PN" "155"
					( Origin gPackager )
				)
				( objectStatus "J9U1.155" )
			)
			( pin "@baseboard_fab2_lib.baseboard_fab2(sch_1):page80_i24:dq(8)"
				( attribute "PN" "16"
					( Origin gPackager )
				)
				( objectStatus "J9U1.16" )
			)
			( pin "@baseboard_fab2_lib.baseboard_fab2(sch_1):page80_i24:dq(9)"
				( attribute "PN" "161"
					( Origin gPackager )
				)
				( objectStatus "J9U1.161" )
			)
			( pin "@baseboard_fab2_lib.baseboard_fab2(sch_1):page80_i24:dq(10)"
				( attribute "PN" "23"
					( Origin gPackager )
				)
				( objectStatus "J9U1.23" )
			)
			( pin "@baseboard_fab2_lib.baseboard_fab2(sch_1):page80_i24:dq(11)"
				( attribute "PN" "168"
					( Origin gPackager )
				)
				( objectStatus "J9U1.168" )
			)
			( pin "@baseboard_fab2_lib.baseboard_fab2(sch_1):page80_i24:dq(12)"
				( attribute "PN" "14"
					( Origin gPackager )
				)
				( objectStatus "J9U1.14" )
			)
			( pin "@baseboard_fab2_lib.baseboard_fab2(sch_1):page80_i24:dq(13)"
				( attribute "PN" "159"
					( Origin gPackager )
				)
				( objectStatus "J9U1.159" )
			)
			( pin "@baseboard_fab2_lib.baseboard_fab2(sch_1):page80_i24:dq(14)"
				( attribute "PN" "21"
					( Origin gPackager )
				)
				( objectStatus "J9U1.21" )
			)
			( pin "@baseboard_fab2_lib.baseboard_fab2(sch_1):page80_i24:dq(15)"
				( attribute "PN" "166"
					( Origin gPackager )
				)
				( objectStatus "J9U1.166" )
			)
			( pin "@baseboard_fab2_lib.baseboard_fab2(sch_1):page80_i24:dq(16)"
				( attribute "PN" "27"
					( Origin gPackager )
				)
				( objectStatus "J9U1.27" )
			)
			( pin "@baseboard_fab2_lib.baseboard_fab2(sch_1):page80_i24:dq(17)"
				( attribute "PN" "172"
					( Origin gPackager )
				)
				( objectStatus "J9U1.172" )
			)
			( pin "@baseboard_fab2_lib.baseboard_fab2(sch_1):page80_i24:dq(18)"
				( attribute "PN" "34"
					( Origin gPackager )
				)
				( objectStatus "J9U1.34" )
			)
			( pin "@baseboard_fab2_lib.baseboard_fab2(sch_1):page80_i24:dq(19)"
				( attribute "PN" "179"
					( Origin gPackager )
				)
				( objectStatus "J9U1.179" )
			)
			( pin "@baseboard_fab2_lib.baseboard_fab2(sch_1):page80_i24:dq(20)"
				( attribute "PN" "25"
					( Origin gPackager )
				)
				( objectStatus "J9U1.25" )
			)
			( pin "@baseboard_fab2_lib.baseboard_fab2(sch_1):page80_i24:dq(21)"
				( attribute "PN" "170"
					( Origin gPackager )
				)
				( objectStatus "J9U1.170" )
			)
			( pin "@baseboard_fab2_lib.baseboard_fab2(sch_1):page80_i24:dq(22)"
				( attribute "PN" "32"
					( Origin gPackager )
				)
				( objectStatus "J9U1.32" )
			)
			( pin "@baseboard_fab2_lib.baseboard_fab2(sch_1):page80_i24:dq(23)"
				( attribute "PN" "177"
					( Origin gPackager )
				)
				( objectStatus "J9U1.177" )
			)
			( pin "@baseboard_fab2_lib.baseboard_fab2(sch_1):page80_i24:dq(24)"
				( attribute "PN" "38"
					( Origin gPackager )
				)
				( objectStatus "J9U1.38" )
			)
			( pin "@baseboard_fab2_lib.baseboard_fab2(sch_1):page80_i24:dq(25)"
				( attribute "PN" "183"
					( Origin gPackager )
				)
				( objectStatus "J9U1.183" )
			)
			( pin "@baseboard_fab2_lib.baseboard_fab2(sch_1):page80_i24:dq(26)"
				( attribute "PN" "45"
					( Origin gPackager )
				)
				( objectStatus "J9U1.45" )
			)
			( pin "@baseboard_fab2_lib.baseboard_fab2(sch_1):page80_i24:dq(27)"
				( attribute "PN" "190"
					( Origin gPackager )
				)
				( objectStatus "J9U1.190" )
			)
			( pin "@baseboard_fab2_lib.baseboard_fab2(sch_1):page80_i24:dq(28)"
				( attribute "PN" "36"
					( Origin gPackager )
				)
				( objectStatus "J9U1.36" )
			)
			( pin "@baseboard_fab2_lib.baseboard_fab2(sch_1):page80_i24:dq(29)"
				( attribute "PN" "181"
					( Origin gPackager )
				)
				( objectStatus "J9U1.181" )
			)
			( pin "@baseboard_fab2_lib.baseboard_fab2(sch_1):page80_i24:dq(30)"
				( attribute "PN" "43"
					( Origin gPackager )
				)
				( objectStatus "J9U1.43" )
			)
			( pin "@baseboard_fab2_lib.baseboard_fab2(sch_1):page80_i24:dq(31)"
				( attribute "PN" "188"
					( Origin gPackager )
				)
				( objectStatus "J9U1.188" )
			)
			( pin "@baseboard_fab2_lib.baseboard_fab2(sch_1):page80_i24:dq(32)"
				( attribute "PN" "97"
					( Origin gPackager )
				)
				( objectStatus "J9U1.97" )
			)
			( pin "@baseboard_fab2_lib.baseboard_fab2(sch_1):page80_i24:dq(33)"
				( attribute "PN" "242"
					( Origin gPackager )
				)
				( objectStatus "J9U1.242" )
			)
			( pin "@baseboard_fab2_lib.baseboard_fab2(sch_1):page80_i24:dq(34)"
				( attribute "PN" "104"
					( Origin gPackager )
				)
				( objectStatus "J9U1.104" )
			)
			( pin "@baseboard_fab2_lib.baseboard_fab2(sch_1):page80_i24:dq(35)"
				( attribute "PN" "249"
					( Origin gPackager )
				)
				( objectStatus "J9U1.249" )
			)
			( pin "@baseboard_fab2_lib.baseboard_fab2(sch_1):page80_i24:dq(36)"
				( attribute "PN" "95"
					( Origin gPackager )
				)
				( objectStatus "J9U1.95" )
			)
			( pin "@baseboard_fab2_lib.baseboard_fab2(sch_1):page80_i24:dq(37)"
				( attribute "PN" "240"
					( Origin gPackager )
				)
				( objectStatus "J9U1.240" )
			)
			( pin "@baseboard_fab2_lib.baseboard_fab2(sch_1):page80_i24:dq(38)"
				( attribute "PN" "102"
					( Origin gPackager )
				)
				( objectStatus "J9U1.102" )
			)
			( pin "@baseboard_fab2_lib.baseboard_fab2(sch_1):page80_i24:dq(39)"
				( attribute "PN" "247"
					( Origin gPackager )
				)
				( objectStatus "J9U1.247" )
			)
			( pin "@baseboard_fab2_lib.baseboard_fab2(sch_1):page80_i24:dq(40)"
				( attribute "PN" "108"
					( Origin gPackager )
				)
				( objectStatus "J9U1.108" )
			)
			( pin "@baseboard_fab2_lib.baseboard_fab2(sch_1):page80_i24:dq(41)"
				( attribute "PN" "253"
					( Origin gPackager )
				)
				( objectStatus "J9U1.253" )
			)
			( pin "@baseboard_fab2_lib.baseboard_fab2(sch_1):page80_i24:dq(42)"
				( attribute "PN" "115"
					( Origin gPackager )
				)
				( objectStatus "J9U1.115" )
			)
			( pin "@baseboard_fab2_lib.baseboard_fab2(sch_1):page80_i24:dq(43)"
				( attribute "PN" "260"
					( Origin gPackager )
				)
				( objectStatus "J9U1.260" )
			)
			( pin "@baseboard_fab2_lib.baseboard_fab2(sch_1):page80_i24:dq(44)"
				( attribute "PN" "106"
					( Origin gPackager )
				)
				( objectStatus "J9U1.106" )
			)
			( pin "@baseboard_fab2_lib.baseboard_fab2(sch_1):page80_i24:dq(45)"
				( attribute "PN" "251"
					( Origin gPackager )
				)
				( objectStatus "J9U1.251" )
			)
			( pin "@baseboard_fab2_lib.baseboard_fab2(sch_1):page80_i24:dq(46)"
				( attribute "PN" "113"
					( Origin gPackager )
				)
				( objectStatus "J9U1.113" )
			)
			( pin "@baseboard_fab2_lib.baseboard_fab2(sch_1):page80_i24:dq(47)"
				( attribute "PN" "258"
					( Origin gPackager )
				)
				( objectStatus "J9U1.258" )
			)
			( pin "@baseboard_fab2_lib.baseboard_fab2(sch_1):page80_i24:dq(48)"
				( attribute "PN" "119"
					( Origin gPackager )
				)
				( objectStatus "J9U1.119" )
			)
			( pin "@baseboard_fab2_lib.baseboard_fab2(sch_1):page80_i24:dq(49)"
				( attribute "PN" "264"
					( Origin gPackager )
				)
				( objectStatus "J9U1.264" )
			)
			( pin "@baseboard_fab2_lib.baseboard_fab2(sch_1):page80_i24:dq(50)"
				( attribute "PN" "126"
					( Origin gPackager )
				)
				( objectStatus "J9U1.126" )
			)
			( pin "@baseboard_fab2_lib.baseboard_fab2(sch_1):page80_i24:dq(51)"
				( attribute "PN" "271"
					( Origin gPackager )
				)
				( objectStatus "J9U1.271" )
			)
			( pin "@baseboard_fab2_lib.baseboard_fab2(sch_1):page80_i24:dq(52)"
				( attribute "PN" "117"
					( Origin gPackager )
				)
				( objectStatus "J9U1.117" )
			)
			( pin "@baseboard_fab2_lib.baseboard_fab2(sch_1):page80_i24:dq(53)"
				( attribute "PN" "262"
					( Origin gPackager )
				)
				( objectStatus "J9U1.262" )
			)
			( pin "@baseboard_fab2_lib.baseboard_fab2(sch_1):page80_i24:dq(54)"
				( attribute "PN" "124"
					( Origin gPackager )
				)
				( objectStatus "J9U1.124" )
			)
			( pin "@baseboard_fab2_lib.baseboard_fab2(sch_1):page80_i24:dq(55)"
				( attribute "PN" "269"
					( Origin gPackager )
				)
				( objectStatus "J9U1.269" )
			)
			( pin "@baseboard_fab2_lib.baseboard_fab2(sch_1):page80_i24:dq(56)"
				( attribute "PN" "130"
					( Origin gPackager )
				)
				( objectStatus "J9U1.130" )
			)
			( pin "@baseboard_fab2_lib.baseboard_fab2(sch_1):page80_i24:dq(57)"
				( attribute "PN" "275"
					( Origin gPackager )
				)
				( objectStatus "J9U1.275" )
			)
			( pin "@baseboard_fab2_lib.baseboard_fab2(sch_1):page80_i24:dq(58)"
				( attribute "PN" "137"
					( Origin gPackager )
				)
				( objectStatus "J9U1.137" )
			)
			( pin "@baseboard_fab2_lib.baseboard_fab2(sch_1):page80_i24:dq(59)"
				( attribute "PN" "282"
					( Origin gPackager )
				)
				( objectStatus "J9U1.282" )
			)
			( pin "@baseboard_fab2_lib.baseboard_fab2(sch_1):page80_i24:dq(60)"
				( attribute "PN" "128"
					( Origin gPackager )
				)
				( objectStatus "J9U1.128" )
			)
			( pin "@baseboard_fab2_lib.baseboard_fab2(sch_1):page80_i24:dq(61)"
				( attribute "PN" "273"
					( Origin gPackager )
				)
				( objectStatus "J9U1.273" )
			)
			( pin "@baseboard_fab2_lib.baseboard_fab2(sch_1):page80_i24:dq(62)"
				( attribute "PN" "135"
					( Origin gPackager )
				)
				( objectStatus "J9U1.135" )
			)
			( pin "@baseboard_fab2_lib.baseboard_fab2(sch_1):page80_i24:dq(63)"
				( attribute "PN" "280"
					( Origin gPackager )
				)
				( objectStatus "J9U1.280" )
			)
			( pin "@baseboard_fab2_lib.baseboard_fab2(sch_1):page80_i24:event_n"
				( attribute "PN" "78"
					( Origin gPackager )
				)
				( objectStatus "J9U1.78" )
			)
			( pin "@baseboard_fab2_lib.baseboard_fab2(sch_1):page80_i24:odt(0)"
				( attribute "PN" "87"
					( Origin gPackager )
				)
				( objectStatus "J9U1.87" )
			)
			( pin "@baseboard_fab2_lib.baseboard_fab2(sch_1):page80_i24:odt(1)"
				( attribute "PN" "91"
					( Origin gPackager )
				)
				( objectStatus "J9U1.91" )
			)
			( pin "@baseboard_fab2_lib.baseboard_fab2(sch_1):page80_i24:par"
				( attribute "PN" "222"
					( Origin gPackager )
				)
				( objectStatus "J9U1.222" )
			)
			( pin "@baseboard_fab2_lib.baseboard_fab2(sch_1):page80_i24:reset_n"
				( attribute "PN" "58"
					( Origin gPackager )
				)
				( objectStatus "J9U1.58" )
			)
			( pin "@baseboard_fab2_lib.baseboard_fab2(sch_1):page80_i24:rfu(0)"
				( attribute "PN" "205"
					( Origin gPackager )
				)
				( objectStatus "J9U1.205" )
			)
			( pin "@baseboard_fab2_lib.baseboard_fab2(sch_1):page80_i24:rfu(1)"
				( attribute "PN" "227"
					( Origin gPackager )
				)
				( objectStatus "J9U1.227" )
			)
			( pin "@baseboard_fab2_lib.baseboard_fab2(sch_1):page80_i24:rfu(2)"
				( attribute "PN" "144"
					( Origin gPackager )
				)
				( objectStatus "J9U1.144" )
			)
			( pin "@baseboard_fab2_lib.baseboard_fab2(sch_1):page80_i24:s0_n"
				( attribute "PN" "84"
					( Origin gPackager )
				)
				( objectStatus "J9U1.84" )
			)
			( pin "@baseboard_fab2_lib.baseboard_fab2(sch_1):page80_i24:s1_n"
				( attribute "PN" "89"
					( Origin gPackager )
				)
				( objectStatus "J9U1.89" )
			)
			( pin "@baseboard_fab2_lib.baseboard_fab2(sch_1):page80_i24:s2_n_c(0)"
				( attribute "PN" "93"
					( Origin gPackager )
				)
				( objectStatus "J9U1.93" )
			)
			( pin "@baseboard_fab2_lib.baseboard_fab2(sch_1):page80_i24:s3_n_c(1)"
				( attribute "PN" "237"
					( Origin gPackager )
				)
				( objectStatus "J9U1.237" )
			)
			( pin "@baseboard_fab2_lib.baseboard_fab2(sch_1):page80_i24:sa(0)"
				( attribute "PN" "139"
					( Origin gPackager )
				)
				( objectStatus "J9U1.139" )
			)
			( pin "@baseboard_fab2_lib.baseboard_fab2(sch_1):page80_i24:sa(1)"
				( attribute "PN" "140"
					( Origin gPackager )
				)
				( objectStatus "J9U1.140" )
			)
			( pin "@baseboard_fab2_lib.baseboard_fab2(sch_1):page80_i24:sa(2)"
				( attribute "PN" "238"
					( Origin gPackager )
				)
				( objectStatus "J9U1.238" )
			)
			( pin "@baseboard_fab2_lib.baseboard_fab2(sch_1):page80_i24:save_n_nc"
				( attribute "PN" "230"
					( Origin gPackager )
				)
				( objectStatus "J9U1.230" )
			)
			( pin "@baseboard_fab2_lib.baseboard_fab2(sch_1):page80_i24:scl"
				( attribute "PN" "141"
					( Origin gPackager )
				)
				( objectStatus "J9U1.141" )
			)
			( pin "@baseboard_fab2_lib.baseboard_fab2(sch_1):page80_i24:sda"
				( attribute "PN" "285"
					( Origin gPackager )
				)
				( objectStatus "J9U1.285" )
			)
			( pin "@baseboard_fab2_lib.baseboard_fab2(sch_1):page80_i24:vddspd"
				( attribute "PN" "284"
					( Origin gPackager )
				)
				( objectStatus "J9U1.284" )
			)
			( pin "@baseboard_fab2_lib.baseboard_fab2(sch_1):page80_i24:vrefca"
				( attribute "PN" "146"
					( Origin gPackager )
				)
				( objectStatus "J9U1.146" )
			)
			( pin "@baseboard_fab2_lib.baseboard_fab2(sch_1):page80_i56:\12v\(0)"
				( attribute "PN" "145"
					( Origin gPackager )
				)
				( objectStatus "J9U1.145" )
			)
			( pin "@baseboard_fab2_lib.baseboard_fab2(sch_1):page80_i56:\12v\(1)"
				( attribute "PN" "1"
					( Origin gPackager )
				)
				( objectStatus "J9U1.1" )
			)
			( pin "@baseboard_fab2_lib.baseboard_fab2(sch_1):page80_i56:vdd(0)"
				( attribute "PN" "236"
					( Origin gPackager )
				)
				( objectStatus "J9U1.236" )
			)
			( pin "@baseboard_fab2_lib.baseboard_fab2(sch_1):page80_i56:vdd(1)"
				( attribute "PN" "233"
					( Origin gPackager )
				)
				( objectStatus "J9U1.233" )
			)
			( pin "@baseboard_fab2_lib.baseboard_fab2(sch_1):page80_i56:vdd(2)"
				( attribute "PN" "231"
					( Origin gPackager )
				)
				( objectStatus "J9U1.231" )
			)
			( pin "@baseboard_fab2_lib.baseboard_fab2(sch_1):page80_i56:vdd(3)"
				( attribute "PN" "229"
					( Origin gPackager )
				)
				( objectStatus "J9U1.229" )
			)
			( pin "@baseboard_fab2_lib.baseboard_fab2(sch_1):page80_i56:vdd(4)"
				( attribute "PN" "226"
					( Origin gPackager )
				)
				( objectStatus "J9U1.226" )
			)
			( pin "@baseboard_fab2_lib.baseboard_fab2(sch_1):page80_i56:vdd(5)"
				( attribute "PN" "223"
					( Origin gPackager )
				)
				( objectStatus "J9U1.223" )
			)
			( pin "@baseboard_fab2_lib.baseboard_fab2(sch_1):page80_i56:vdd(6)"
				( attribute "PN" "220"
					( Origin gPackager )
				)
				( objectStatus "J9U1.220" )
			)
			( pin "@baseboard_fab2_lib.baseboard_fab2(sch_1):page80_i56:vdd(7)"
				( attribute "PN" "217"
					( Origin gPackager )
				)
				( objectStatus "J9U1.217" )
			)
			( pin "@baseboard_fab2_lib.baseboard_fab2(sch_1):page80_i56:vdd(8)"
				( attribute "PN" "215"
					( Origin gPackager )
				)
				( objectStatus "J9U1.215" )
			)
			( pin "@baseboard_fab2_lib.baseboard_fab2(sch_1):page80_i56:vdd(9)"
				( attribute "PN" "212"
					( Origin gPackager )
				)
				( objectStatus "J9U1.212" )
			)
			( pin "@baseboard_fab2_lib.baseboard_fab2(sch_1):page80_i56:vdd(10)"
				( attribute "PN" "209"
					( Origin gPackager )
				)
				( objectStatus "J9U1.209" )
			)
			( pin "@baseboard_fab2_lib.baseboard_fab2(sch_1):page80_i56:vdd(11)"
				( attribute "PN" "206"
					( Origin gPackager )
				)
				( objectStatus "J9U1.206" )
			)
			( pin "@baseboard_fab2_lib.baseboard_fab2(sch_1):page80_i56:vdd(12)"
				( attribute "PN" "204"
					( Origin gPackager )
				)
				( objectStatus "J9U1.204" )
			)
			( pin "@baseboard_fab2_lib.baseboard_fab2(sch_1):page80_i56:vdd(13)"
				( attribute "PN" "92"
					( Origin gPackager )
				)
				( objectStatus "J9U1.92" )
			)
			( pin "@baseboard_fab2_lib.baseboard_fab2(sch_1):page80_i56:vdd(14)"
				( attribute "PN" "90"
					( Origin gPackager )
				)
				( objectStatus "J9U1.90" )
			)
			( pin "@baseboard_fab2_lib.baseboard_fab2(sch_1):page80_i56:vdd(15)"
				( attribute "PN" "88"
					( Origin gPackager )
				)
				( objectStatus "J9U1.88" )
			)
			( pin "@baseboard_fab2_lib.baseboard_fab2(sch_1):page80_i56:vdd(16)"
				( attribute "PN" "85"
					( Origin gPackager )
				)
				( objectStatus "J9U1.85" )
			)
			( pin "@baseboard_fab2_lib.baseboard_fab2(sch_1):page80_i56:vdd(17)"
				( attribute "PN" "83"
					( Origin gPackager )
				)
				( objectStatus "J9U1.83" )
			)
			( pin "@baseboard_fab2_lib.baseboard_fab2(sch_1):page80_i56:vdd(18)"
				( attribute "PN" "80"
					( Origin gPackager )
				)
				( objectStatus "J9U1.80" )
			)
			( pin "@baseboard_fab2_lib.baseboard_fab2(sch_1):page80_i56:vdd(19)"
				( attribute "PN" "76"
					( Origin gPackager )
				)
				( objectStatus "J9U1.76" )
			)
			( pin "@baseboard_fab2_lib.baseboard_fab2(sch_1):page80_i56:vdd(20)"
				( attribute "PN" "73"
					( Origin gPackager )
				)
				( objectStatus "J9U1.73" )
			)
			( pin "@baseboard_fab2_lib.baseboard_fab2(sch_1):page80_i56:vdd(21)"
				( attribute "PN" "70"
					( Origin gPackager )
				)
				( objectStatus "J9U1.70" )
			)
			( pin "@baseboard_fab2_lib.baseboard_fab2(sch_1):page80_i56:vdd(22)"
				( attribute "PN" "67"
					( Origin gPackager )
				)
				( objectStatus "J9U1.67" )
			)
			( pin "@baseboard_fab2_lib.baseboard_fab2(sch_1):page80_i56:vdd(23)"
				( attribute "PN" "64"
					( Origin gPackager )
				)
				( objectStatus "J9U1.64" )
			)
			( pin "@baseboard_fab2_lib.baseboard_fab2(sch_1):page80_i56:vdd(24)"
				( attribute "PN" "61"
					( Origin gPackager )
				)
				( objectStatus "J9U1.61" )
			)
			( pin "@baseboard_fab2_lib.baseboard_fab2(sch_1):page80_i56:vdd(25)"
				( attribute "PN" "59"
					( Origin gPackager )
				)
				( objectStatus "J9U1.59" )
			)
			( pin "@baseboard_fab2_lib.baseboard_fab2(sch_1):page80_i56:vpp(0)"
				( attribute "PN" "287"
					( Origin gPackager )
				)
				( objectStatus "J9U1.287" )
			)
			( pin "@baseboard_fab2_lib.baseboard_fab2(sch_1):page80_i56:vpp(1)"
				( attribute "PN" "286"
					( Origin gPackager )
				)
				( objectStatus "J9U1.286" )
			)
			( pin "@baseboard_fab2_lib.baseboard_fab2(sch_1):page80_i56:vpp(2)"
				( attribute "PN" "288"
					( Origin gPackager )
				)
				( objectStatus "J9U1.288" )
			)
			( pin "@baseboard_fab2_lib.baseboard_fab2(sch_1):page80_i56:vpp(3)"
				( attribute "PN" "143"
					( Origin gPackager )
				)
				( objectStatus "J9U1.143" )
			)
			( pin "@baseboard_fab2_lib.baseboard_fab2(sch_1):page80_i56:vpp(4)"
				( attribute "PN" "142"
					( Origin gPackager )
				)
				( objectStatus "J9U1.142" )
			)
			( pin "@baseboard_fab2_lib.baseboard_fab2(sch_1):page80_i56:vtt(0)"
				( attribute "PN" "221"
					( Origin gPackager )
				)
				( objectStatus "J9U1.221" )
			)
			( pin "@baseboard_fab2_lib.baseboard_fab2(sch_1):page80_i56:vtt(1)"
				( attribute "PN" "77"
					( Origin gPackager )
				)
				( objectStatus "J9U1.77" )
			)
			( pin "@baseboard_fab2_lib.baseboard_fab2(sch_1):page80_i101:dqs0n"
				( attribute "PN" "152"
					( Origin gPackager )
				)
				( objectStatus "J9U1.152" )
			)
			( pin "@baseboard_fab2_lib.baseboard_fab2(sch_1):page80_i101:dqs0p"
				( attribute "PN" "153"
					( Origin gPackager )
				)
				( objectStatus "J9U1.153" )
			)
			( pin "@baseboard_fab2_lib.baseboard_fab2(sch_1):page80_i101:dqs1n"
				( attribute "PN" "163"
					( Origin gPackager )
				)
				( objectStatus "J9U1.163" )
			)
			( pin "@baseboard_fab2_lib.baseboard_fab2(sch_1):page80_i101:dqs1p"
				( attribute "PN" "164"
					( Origin gPackager )
				)
				( objectStatus "J9U1.164" )
			)
			( pin "@baseboard_fab2_lib.baseboard_fab2(sch_1):page80_i101:dqs2n"
				( attribute "PN" "174"
					( Origin gPackager )
				)
				( objectStatus "J9U1.174" )
			)
			( pin "@baseboard_fab2_lib.baseboard_fab2(sch_1):page80_i101:dqs2p"
				( attribute "PN" "175"
					( Origin gPackager )
				)
				( objectStatus "J9U1.175" )
			)
			( pin "@baseboard_fab2_lib.baseboard_fab2(sch_1):page80_i101:dqs3n"
				( attribute "PN" "185"
					( Origin gPackager )
				)
				( objectStatus "J9U1.185" )
			)
			( pin "@baseboard_fab2_lib.baseboard_fab2(sch_1):page80_i101:dqs3p"
				( attribute "PN" "186"
					( Origin gPackager )
				)
				( objectStatus "J9U1.186" )
			)
			( pin "@baseboard_fab2_lib.baseboard_fab2(sch_1):page80_i101:dqs4n"
				( attribute "PN" "244"
					( Origin gPackager )
				)
				( objectStatus "J9U1.244" )
			)
			( pin "@baseboard_fab2_lib.baseboard_fab2(sch_1):page80_i101:dqs4p"
				( attribute "PN" "245"
					( Origin gPackager )
				)
				( objectStatus "J9U1.245" )
			)
			( pin "@baseboard_fab2_lib.baseboard_fab2(sch_1):page80_i101:dqs5n"
				( attribute "PN" "255"
					( Origin gPackager )
				)
				( objectStatus "J9U1.255" )
			)
			( pin "@baseboard_fab2_lib.baseboard_fab2(sch_1):page80_i101:dqs5p"
				( attribute "PN" "256"
					( Origin gPackager )
				)
				( objectStatus "J9U1.256" )
			)
			( pin "@baseboard_fab2_lib.baseboard_fab2(sch_1):page80_i101:dqs6n"
				( attribute "PN" "266"
					( Origin gPackager )
				)
				( objectStatus "J9U1.266" )
			)
			( pin "@baseboard_fab2_lib.baseboard_fab2(sch_1):page80_i101:dqs6p"
				( attribute "PN" "267"
					( Origin gPackager )
				)
				( objectStatus "J9U1.267" )
			)
			( pin "@baseboard_fab2_lib.baseboard_fab2(sch_1):page80_i101:dqs7n"
				( attribute "PN" "277"
					( Origin gPackager )
				)
				( objectStatus "J9U1.277" )
			)
			( pin "@baseboard_fab2_lib.baseboard_fab2(sch_1):page80_i101:dqs7p"
				( attribute "PN" "278"
					( Origin gPackager )
				)
				( objectStatus "J9U1.278" )
			)
			( pin "@baseboard_fab2_lib.baseboard_fab2(sch_1):page80_i101:dqs8n"
				( attribute "PN" "196"
					( Origin gPackager )
				)
				( objectStatus "J9U1.196" )
			)
			( pin "@baseboard_fab2_lib.baseboard_fab2(sch_1):page80_i101:dqs8p"
				( attribute "PN" "197"
					( Origin gPackager )
				)
				( objectStatus "J9U1.197" )
			)
			( pin "@baseboard_fab2_lib.baseboard_fab2(sch_1):page80_i101:dqs9n"
				( attribute "PN" "8"
					( Origin gPackager )
				)
				( objectStatus "J9U1.8" )
			)
			( pin "@baseboard_fab2_lib.baseboard_fab2(sch_1):page80_i101:dqs9p"
				( attribute "PN" "7"
					( Origin gPackager )
				)
				( objectStatus "J9U1.7" )
			)
			( pin "@baseboard_fab2_lib.baseboard_fab2(sch_1):page80_i101:dqs10n"
				( attribute "PN" "19"
					( Origin gPackager )
				)
				( objectStatus "J9U1.19" )
			)
			( pin "@baseboard_fab2_lib.baseboard_fab2(sch_1):page80_i101:dqs10p"
				( attribute "PN" "18"
					( Origin gPackager )
				)
				( objectStatus "J9U1.18" )
			)
			( pin "@baseboard_fab2_lib.baseboard_fab2(sch_1):page80_i101:dqs11n"
				( attribute "PN" "30"
					( Origin gPackager )
				)
				( objectStatus "J9U1.30" )
			)
			( pin "@baseboard_fab2_lib.baseboard_fab2(sch_1):page80_i101:dqs11p"
				( attribute "PN" "29"
					( Origin gPackager )
				)
				( objectStatus "J9U1.29" )
			)
			( pin "@baseboard_fab2_lib.baseboard_fab2(sch_1):page80_i101:dqs12n"
				( attribute "PN" "41"
					( Origin gPackager )
				)
				( objectStatus "J9U1.41" )
			)
			( pin "@baseboard_fab2_lib.baseboard_fab2(sch_1):page80_i101:dqs12p"
				( attribute "PN" "40"
					( Origin gPackager )
				)
				( objectStatus "J9U1.40" )
			)
			( pin "@baseboard_fab2_lib.baseboard_fab2(sch_1):page80_i101:dqs13n"
				( attribute "PN" "100"
					( Origin gPackager )
				)
				( objectStatus "J9U1.100" )
			)
			( pin "@baseboard_fab2_lib.baseboard_fab2(sch_1):page80_i101:dqs13p"
				( attribute "PN" "99"
					( Origin gPackager )
				)
				( objectStatus "J9U1.99" )
			)
			( pin "@baseboard_fab2_lib.baseboard_fab2(sch_1):page80_i101:dqs14n"
				( attribute "PN" "111"
					( Origin gPackager )
				)
				( objectStatus "J9U1.111" )
			)
			( pin "@baseboard_fab2_lib.baseboard_fab2(sch_1):page80_i101:dqs14p"
				( attribute "PN" "110"
					( Origin gPackager )
				)
				( objectStatus "J9U1.110" )
			)
			( pin "@baseboard_fab2_lib.baseboard_fab2(sch_1):page80_i101:dqs15n"
				( attribute "PN" "122"
					( Origin gPackager )
				)
				( objectStatus "J9U1.122" )
			)
			( pin "@baseboard_fab2_lib.baseboard_fab2(sch_1):page80_i101:dqs15p"
				( attribute "PN" "121"
					( Origin gPackager )
				)
				( objectStatus "J9U1.121" )
			)
			( pin "@baseboard_fab2_lib.baseboard_fab2(sch_1):page80_i101:dqs16n"
				( attribute "PN" "133"
					( Origin gPackager )
				)
				( objectStatus "J9U1.133" )
			)
			( pin "@baseboard_fab2_lib.baseboard_fab2(sch_1):page80_i101:dqs16p"
				( attribute "PN" "132"
					( Origin gPackager )
				)
				( objectStatus "J9U1.132" )
			)
			( pin "@baseboard_fab2_lib.baseboard_fab2(sch_1):page80_i101:dqs17n"
				( attribute "PN" "52"
					( Origin gPackager )
				)
				( objectStatus "J9U1.52" )
			)
			( pin "@baseboard_fab2_lib.baseboard_fab2(sch_1):page80_i101:dqs17p"
				( attribute "PN" "51"
					( Origin gPackager )
				)
				( objectStatus "J9U1.51" )
			)
			( pin "@baseboard_fab2_lib.baseboard_fab2(sch_1):page80_i138:vss(0)"
				( attribute "PN" "283"
					( Origin gPackager )
				)
				( objectStatus "J9U1.283" )
			)
			( pin "@baseboard_fab2_lib.baseboard_fab2(sch_1):page80_i138:vss(1)"
				( attribute "PN" "281"
					( Origin gPackager )
				)
				( objectStatus "J9U1.281" )
			)
			( pin "@baseboard_fab2_lib.baseboard_fab2(sch_1):page80_i138:vss(2)"
				( attribute "PN" "279"
					( Origin gPackager )
				)
				( objectStatus "J9U1.279" )
			)
			( pin "@baseboard_fab2_lib.baseboard_fab2(sch_1):page80_i138:vss(3)"
				( attribute "PN" "276"
					( Origin gPackager )
				)
				( objectStatus "J9U1.276" )
			)
			( pin "@baseboard_fab2_lib.baseboard_fab2(sch_1):page80_i138:vss(4)"
				( attribute "PN" "274"
					( Origin gPackager )
				)
				( objectStatus "J9U1.274" )
			)
			( pin "@baseboard_fab2_lib.baseboard_fab2(sch_1):page80_i138:vss(5)"
				( attribute "PN" "272"
					( Origin gPackager )
				)
				( objectStatus "J9U1.272" )
			)
			( pin "@baseboard_fab2_lib.baseboard_fab2(sch_1):page80_i138:vss(6)"
				( attribute "PN" "270"
					( Origin gPackager )
				)
				( objectStatus "J9U1.270" )
			)
			( pin "@baseboard_fab2_lib.baseboard_fab2(sch_1):page80_i138:vss(7)"
				( attribute "PN" "268"
					( Origin gPackager )
				)
				( objectStatus "J9U1.268" )
			)
			( pin "@baseboard_fab2_lib.baseboard_fab2(sch_1):page80_i138:vss(8)"
				( attribute "PN" "265"
					( Origin gPackager )
				)
				( objectStatus "J9U1.265" )
			)
			( pin "@baseboard_fab2_lib.baseboard_fab2(sch_1):page80_i138:vss(9)"
				( attribute "PN" "263"
					( Origin gPackager )
				)
				( objectStatus "J9U1.263" )
			)
			( pin "@baseboard_fab2_lib.baseboard_fab2(sch_1):page80_i138:vss(10)"
				( attribute "PN" "261"
					( Origin gPackager )
				)
				( objectStatus "J9U1.261" )
			)
			( pin "@baseboard_fab2_lib.baseboard_fab2(sch_1):page80_i138:vss(11)"
				( attribute "PN" "259"
					( Origin gPackager )
				)
				( objectStatus "J9U1.259" )
			)
			( pin "@baseboard_fab2_lib.baseboard_fab2(sch_1):page80_i138:vss(12)"
				( attribute "PN" "257"
					( Origin gPackager )
				)
				( objectStatus "J9U1.257" )
			)
			( pin "@baseboard_fab2_lib.baseboard_fab2(sch_1):page80_i138:vss(13)"
				( attribute "PN" "254"
					( Origin gPackager )
				)
				( objectStatus "J9U1.254" )
			)
			( pin "@baseboard_fab2_lib.baseboard_fab2(sch_1):page80_i138:vss(14)"
				( attribute "PN" "252"
					( Origin gPackager )
				)
				( objectStatus "J9U1.252" )
			)
			( pin "@baseboard_fab2_lib.baseboard_fab2(sch_1):page80_i138:vss(15)"
				( attribute "PN" "250"
					( Origin gPackager )
				)
				( objectStatus "J9U1.250" )
			)
			( pin "@baseboard_fab2_lib.baseboard_fab2(sch_1):page80_i138:vss(16)"
				( attribute "PN" "248"
					( Origin gPackager )
				)
				( objectStatus "J9U1.248" )
			)
			( pin "@baseboard_fab2_lib.baseboard_fab2(sch_1):page80_i138:vss(17)"
				( attribute "PN" "246"
					( Origin gPackager )
				)
				( objectStatus "J9U1.246" )
			)
			( pin "@baseboard_fab2_lib.baseboard_fab2(sch_1):page80_i138:vss(18)"
				( attribute "PN" "243"
					( Origin gPackager )
				)
				( objectStatus "J9U1.243" )
			)
			( pin "@baseboard_fab2_lib.baseboard_fab2(sch_1):page80_i138:vss(19)"
				( attribute "PN" "241"
					( Origin gPackager )
				)
				( objectStatus "J9U1.241" )
			)
			( pin "@baseboard_fab2_lib.baseboard_fab2(sch_1):page80_i138:vss(20)"
				( attribute "PN" "239"
					( Origin gPackager )
				)
				( objectStatus "J9U1.239" )
			)
			( pin "@baseboard_fab2_lib.baseboard_fab2(sch_1):page80_i138:vss(21)"
				( attribute "PN" "202"
					( Origin gPackager )
				)
				( objectStatus "J9U1.202" )
			)
			( pin "@baseboard_fab2_lib.baseboard_fab2(sch_1):page80_i138:vss(22)"
				( attribute "PN" "200"
					( Origin gPackager )
				)
				( objectStatus "J9U1.200" )
			)
			( pin "@baseboard_fab2_lib.baseboard_fab2(sch_1):page80_i138:vss(23)"
				( attribute "PN" "198"
					( Origin gPackager )
				)
				( objectStatus "J9U1.198" )
			)
			( pin "@baseboard_fab2_lib.baseboard_fab2(sch_1):page80_i138:vss(24)"
				( attribute "PN" "195"
					( Origin gPackager )
				)
				( objectStatus "J9U1.195" )
			)
			( pin "@baseboard_fab2_lib.baseboard_fab2(sch_1):page80_i138:vss(25)"
				( attribute "PN" "193"
					( Origin gPackager )
				)
				( objectStatus "J9U1.193" )
			)
			( pin "@baseboard_fab2_lib.baseboard_fab2(sch_1):page80_i138:vss(26)"
				( attribute "PN" "191"
					( Origin gPackager )
				)
				( objectStatus "J9U1.191" )
			)
			( pin "@baseboard_fab2_lib.baseboard_fab2(sch_1):page80_i138:vss(27)"
				( attribute "PN" "189"
					( Origin gPackager )
				)
				( objectStatus "J9U1.189" )
			)
			( pin "@baseboard_fab2_lib.baseboard_fab2(sch_1):page80_i138:vss(28)"
				( attribute "PN" "187"
					( Origin gPackager )
				)
				( objectStatus "J9U1.187" )
			)
			( pin "@baseboard_fab2_lib.baseboard_fab2(sch_1):page80_i138:vss(29)"
				( attribute "PN" "184"
					( Origin gPackager )
				)
				( objectStatus "J9U1.184" )
			)
			( pin "@baseboard_fab2_lib.baseboard_fab2(sch_1):page80_i138:vss(30)"
				( attribute "PN" "182"
					( Origin gPackager )
				)
				( objectStatus "J9U1.182" )
			)
			( pin "@baseboard_fab2_lib.baseboard_fab2(sch_1):page80_i138:vss(31)"
				( attribute "PN" "180"
					( Origin gPackager )
				)
				( objectStatus "J9U1.180" )
			)
			( pin "@baseboard_fab2_lib.baseboard_fab2(sch_1):page80_i138:vss(32)"
				( attribute "PN" "178"
					( Origin gPackager )
				)
				( objectStatus "J9U1.178" )
			)
			( pin "@baseboard_fab2_lib.baseboard_fab2(sch_1):page80_i138:vss(33)"
				( attribute "PN" "176"
					( Origin gPackager )
				)
				( objectStatus "J9U1.176" )
			)
			( pin "@baseboard_fab2_lib.baseboard_fab2(sch_1):page80_i138:vss(34)"
				( attribute "PN" "173"
					( Origin gPackager )
				)
				( objectStatus "J9U1.173" )
			)
			( pin "@baseboard_fab2_lib.baseboard_fab2(sch_1):page80_i138:vss(35)"
				( attribute "PN" "171"
					( Origin gPackager )
				)
				( objectStatus "J9U1.171" )
			)
			( pin "@baseboard_fab2_lib.baseboard_fab2(sch_1):page80_i138:vss(36)"
				( attribute "PN" "169"
					( Origin gPackager )
				)
				( objectStatus "J9U1.169" )
			)
			( pin "@baseboard_fab2_lib.baseboard_fab2(sch_1):page80_i138:vss(37)"
				( attribute "PN" "167"
					( Origin gPackager )
				)
				( objectStatus "J9U1.167" )
			)
			( pin "@baseboard_fab2_lib.baseboard_fab2(sch_1):page80_i138:vss(38)"
				( attribute "PN" "165"
					( Origin gPackager )
				)
				( objectStatus "J9U1.165" )
			)
			( pin "@baseboard_fab2_lib.baseboard_fab2(sch_1):page80_i138:vss(39)"
				( attribute "PN" "162"
					( Origin gPackager )
				)
				( objectStatus "J9U1.162" )
			)
			( pin "@baseboard_fab2_lib.baseboard_fab2(sch_1):page80_i138:vss(40)"
				( attribute "PN" "160"
					( Origin gPackager )
				)
				( objectStatus "J9U1.160" )
			)
			( pin "@baseboard_fab2_lib.baseboard_fab2(sch_1):page80_i138:vss(41)"
				( attribute "PN" "158"
					( Origin gPackager )
				)
				( objectStatus "J9U1.158" )
			)
			( pin "@baseboard_fab2_lib.baseboard_fab2(sch_1):page80_i138:vss(42)"
				( attribute "PN" "156"
					( Origin gPackager )
				)
				( objectStatus "J9U1.156" )
			)
			( pin "@baseboard_fab2_lib.baseboard_fab2(sch_1):page80_i138:vss(43)"
				( attribute "PN" "154"
					( Origin gPackager )
				)
				( objectStatus "J9U1.154" )
			)
			( pin "@baseboard_fab2_lib.baseboard_fab2(sch_1):page80_i138:vss(44)"
				( attribute "PN" "151"
					( Origin gPackager )
				)
				( objectStatus "J9U1.151" )
			)
			( pin "@baseboard_fab2_lib.baseboard_fab2(sch_1):page80_i138:vss(45)"
				( attribute "PN" "149"
					( Origin gPackager )
				)
				( objectStatus "J9U1.149" )
			)
			( pin "@baseboard_fab2_lib.baseboard_fab2(sch_1):page80_i138:vss(46)"
				( attribute "PN" "147"
					( Origin gPackager )
				)
				( objectStatus "J9U1.147" )
			)
			( pin "@baseboard_fab2_lib.baseboard_fab2(sch_1):page80_i138:vss(47)"
				( attribute "PN" "138"
					( Origin gPackager )
				)
				( objectStatus "J9U1.138" )
			)
			( pin "@baseboard_fab2_lib.baseboard_fab2(sch_1):page80_i138:vss(48)"
				( attribute "PN" "136"
					( Origin gPackager )
				)
				( objectStatus "J9U1.136" )
			)
			( pin "@baseboard_fab2_lib.baseboard_fab2(sch_1):page80_i138:vss(49)"
				( attribute "PN" "134"
					( Origin gPackager )
				)
				( objectStatus "J9U1.134" )
			)
			( pin "@baseboard_fab2_lib.baseboard_fab2(sch_1):page80_i138:vss(50)"
				( attribute "PN" "131"
					( Origin gPackager )
				)
				( objectStatus "J9U1.131" )
			)
			( pin "@baseboard_fab2_lib.baseboard_fab2(sch_1):page80_i138:vss(51)"
				( attribute "PN" "129"
					( Origin gPackager )
				)
				( objectStatus "J9U1.129" )
			)
			( pin "@baseboard_fab2_lib.baseboard_fab2(sch_1):page80_i138:vss(52)"
				( attribute "PN" "127"
					( Origin gPackager )
				)
				( objectStatus "J9U1.127" )
			)
			( pin "@baseboard_fab2_lib.baseboard_fab2(sch_1):page80_i138:vss(53)"
				( attribute "PN" "125"
					( Origin gPackager )
				)
				( objectStatus "J9U1.125" )
			)
			( pin "@baseboard_fab2_lib.baseboard_fab2(sch_1):page80_i138:vss(54)"
				( attribute "PN" "123"
					( Origin gPackager )
				)
				( objectStatus "J9U1.123" )
			)
			( pin "@baseboard_fab2_lib.baseboard_fab2(sch_1):page80_i138:vss(55)"
				( attribute "PN" "120"
					( Origin gPackager )
				)
				( objectStatus "J9U1.120" )
			)
			( pin "@baseboard_fab2_lib.baseboard_fab2(sch_1):page80_i138:vss(56)"
				( attribute "PN" "118"
					( Origin gPackager )
				)
				( objectStatus "J9U1.118" )
			)
			( pin "@baseboard_fab2_lib.baseboard_fab2(sch_1):page80_i138:vss(57)"
				( attribute "PN" "116"
					( Origin gPackager )
				)
				( objectStatus "J9U1.116" )
			)
			( pin "@baseboard_fab2_lib.baseboard_fab2(sch_1):page80_i138:vss(58)"
				( attribute "PN" "114"
					( Origin gPackager )
				)
				( objectStatus "J9U1.114" )
			)
			( pin "@baseboard_fab2_lib.baseboard_fab2(sch_1):page80_i138:vss(59)"
				( attribute "PN" "112"
					( Origin gPackager )
				)
				( objectStatus "J9U1.112" )
			)
			( pin "@baseboard_fab2_lib.baseboard_fab2(sch_1):page80_i138:vss(60)"
				( attribute "PN" "109"
					( Origin gPackager )
				)
				( objectStatus "J9U1.109" )
			)
			( pin "@baseboard_fab2_lib.baseboard_fab2(sch_1):page80_i138:vss(61)"
				( attribute "PN" "107"
					( Origin gPackager )
				)
				( objectStatus "J9U1.107" )
			)
			( pin "@baseboard_fab2_lib.baseboard_fab2(sch_1):page80_i138:vss(62)"
				( attribute "PN" "105"
					( Origin gPackager )
				)
				( objectStatus "J9U1.105" )
			)
			( pin "@baseboard_fab2_lib.baseboard_fab2(sch_1):page80_i138:vss(63)"
				( attribute "PN" "103"
					( Origin gPackager )
				)
				( objectStatus "J9U1.103" )
			)
			( pin "@baseboard_fab2_lib.baseboard_fab2(sch_1):page80_i138:vss(64)"
				( attribute "PN" "101"
					( Origin gPackager )
				)
				( objectStatus "J9U1.101" )
			)
			( pin "@baseboard_fab2_lib.baseboard_fab2(sch_1):page80_i138:vss(65)"
				( attribute "PN" "98"
					( Origin gPackager )
				)
				( objectStatus "J9U1.98" )
			)
			( pin "@baseboard_fab2_lib.baseboard_fab2(sch_1):page80_i138:vss(66)"
				( attribute "PN" "96"
					( Origin gPackager )
				)
				( objectStatus "J9U1.96" )
			)
			( pin "@baseboard_fab2_lib.baseboard_fab2(sch_1):page80_i138:vss(67)"
				( attribute "PN" "94"
					( Origin gPackager )
				)
				( objectStatus "J9U1.94" )
			)
			( pin "@baseboard_fab2_lib.baseboard_fab2(sch_1):page80_i138:vss(68)"
				( attribute "PN" "57"
					( Origin gPackager )
				)
				( objectStatus "J9U1.57" )
			)
			( pin "@baseboard_fab2_lib.baseboard_fab2(sch_1):page80_i138:vss(69)"
				( attribute "PN" "55"
					( Origin gPackager )
				)
				( objectStatus "J9U1.55" )
			)
			( pin "@baseboard_fab2_lib.baseboard_fab2(sch_1):page80_i138:vss(70)"
				( attribute "PN" "53"
					( Origin gPackager )
				)
				( objectStatus "J9U1.53" )
			)
			( pin "@baseboard_fab2_lib.baseboard_fab2(sch_1):page80_i138:vss(71)"
				( attribute "PN" "50"
					( Origin gPackager )
				)
				( objectStatus "J9U1.50" )
			)
			( pin "@baseboard_fab2_lib.baseboard_fab2(sch_1):page80_i138:vss(72)"
				( attribute "PN" "48"
					( Origin gPackager )
				)
				( objectStatus "J9U1.48" )
			)
			( pin "@baseboard_fab2_lib.baseboard_fab2(sch_1):page80_i138:vss(73)"
				( attribute "PN" "46"
					( Origin gPackager )
				)
				( objectStatus "J9U1.46" )
			)
			( pin "@baseboard_fab2_lib.baseboard_fab2(sch_1):page80_i138:vss(74)"
				( attribute "PN" "44"
					( Origin gPackager )
				)
				( objectStatus "J9U1.44" )
			)
			( pin "@baseboard_fab2_lib.baseboard_fab2(sch_1):page80_i138:vss(75)"
				( attribute "PN" "42"
					( Origin gPackager )
				)
				( objectStatus "J9U1.42" )
			)
			( pin "@baseboard_fab2_lib.baseboard_fab2(sch_1):page80_i138:vss(76)"
				( attribute "PN" "39"
					( Origin gPackager )
				)
				( objectStatus "J9U1.39" )
			)
			( pin "@baseboard_fab2_lib.baseboard_fab2(sch_1):page80_i138:vss(77)"
				( attribute "PN" "37"
					( Origin gPackager )
				)
				( objectStatus "J9U1.37" )
			)
			( pin "@baseboard_fab2_lib.baseboard_fab2(sch_1):page80_i138:vss(78)"
				( attribute "PN" "35"
					( Origin gPackager )
				)
				( objectStatus "J9U1.35" )
			)
			( pin "@baseboard_fab2_lib.baseboard_fab2(sch_1):page80_i138:vss(79)"
				( attribute "PN" "33"
					( Origin gPackager )
				)
				( objectStatus "J9U1.33" )
			)
			( pin "@baseboard_fab2_lib.baseboard_fab2(sch_1):page80_i138:vss(80)"
				( attribute "PN" "31"
					( Origin gPackager )
				)
				( objectStatus "J9U1.31" )
			)
			( pin "@baseboard_fab2_lib.baseboard_fab2(sch_1):page80_i138:vss(81)"
				( attribute "PN" "28"
					( Origin gPackager )
				)
				( objectStatus "J9U1.28" )
			)
			( pin "@baseboard_fab2_lib.baseboard_fab2(sch_1):page80_i138:vss(82)"
				( attribute "PN" "26"
					( Origin gPackager )
				)
				( objectStatus "J9U1.26" )
			)
			( pin "@baseboard_fab2_lib.baseboard_fab2(sch_1):page80_i138:vss(83)"
				( attribute "PN" "24"
					( Origin gPackager )
				)
				( objectStatus "J9U1.24" )
			)
			( pin "@baseboard_fab2_lib.baseboard_fab2(sch_1):page80_i138:vss(84)"
				( attribute "PN" "22"
					( Origin gPackager )
				)
				( objectStatus "J9U1.22" )
			)
			( pin "@baseboard_fab2_lib.baseboard_fab2(sch_1):page80_i138:vss(85)"
				( attribute "PN" "20"
					( Origin gPackager )
				)
				( objectStatus "J9U1.20" )
			)
			( pin "@baseboard_fab2_lib.baseboard_fab2(sch_1):page80_i138:vss(86)"
				( attribute "PN" "17"
					( Origin gPackager )
				)
				( objectStatus "J9U1.17" )
			)
			( pin "@baseboard_fab2_lib.baseboard_fab2(sch_1):page80_i138:vss(87)"
				( attribute "PN" "15"
					( Origin gPackager )
				)
				( objectStatus "J9U1.15" )
			)
			( pin "@baseboard_fab2_lib.baseboard_fab2(sch_1):page80_i138:vss(88)"
				( attribute "PN" "13"
					( Origin gPackager )
				)
				( objectStatus "J9U1.13" )
			)
			( pin "@baseboard_fab2_lib.baseboard_fab2(sch_1):page80_i138:vss(89)"
				( attribute "PN" "11"
					( Origin gPackager )
				)
				( objectStatus "J9U1.11" )
			)
			( pin "@baseboard_fab2_lib.baseboard_fab2(sch_1):page80_i138:vss(90)"
				( attribute "PN" "9"
					( Origin gPackager )
				)
				( objectStatus "J9U1.9" )
			)
			( pin "@baseboard_fab2_lib.baseboard_fab2(sch_1):page80_i138:vss(91)"
				( attribute "PN" "6"
					( Origin gPackager )
				)
				( objectStatus "J9U1.6" )
			)
			( pin "@baseboard_fab2_lib.baseboard_fab2(sch_1):page80_i138:vss(92)"
				( attribute "PN" "4"
					( Origin gPackager )
				)
				( objectStatus "J9U1.4" )
			)
			( pin "@baseboard_fab2_lib.baseboard_fab2(sch_1):page80_i138:vss(93)"
				( attribute "PN" "2"
					( Origin gPackager )
				)
				( objectStatus "J9U1.2" )
			)
			( pin "@baseboard_fab2_lib.baseboard_fab2(sch_1):page81_i67:dqs0n"
				( attribute "PN" "152"
					( Origin gPackager )
				)
				( objectStatus "J1G3.152" )
			)
			( pin "@baseboard_fab2_lib.baseboard_fab2(sch_1):page81_i67:dqs0p"
				( attribute "PN" "153"
					( Origin gPackager )
				)
				( objectStatus "J1G3.153" )
			)
			( pin "@baseboard_fab2_lib.baseboard_fab2(sch_1):page81_i67:dqs1n"
				( attribute "PN" "163"
					( Origin gPackager )
				)
				( objectStatus "J1G3.163" )
			)
			( pin "@baseboard_fab2_lib.baseboard_fab2(sch_1):page81_i67:dqs1p"
				( attribute "PN" "164"
					( Origin gPackager )
				)
				( objectStatus "J1G3.164" )
			)
			( pin "@baseboard_fab2_lib.baseboard_fab2(sch_1):page81_i67:dqs2n"
				( attribute "PN" "174"
					( Origin gPackager )
				)
				( objectStatus "J1G3.174" )
			)
			( pin "@baseboard_fab2_lib.baseboard_fab2(sch_1):page81_i67:dqs2p"
				( attribute "PN" "175"
					( Origin gPackager )
				)
				( objectStatus "J1G3.175" )
			)
			( pin "@baseboard_fab2_lib.baseboard_fab2(sch_1):page81_i67:dqs3n"
				( attribute "PN" "185"
					( Origin gPackager )
				)
				( objectStatus "J1G3.185" )
			)
			( pin "@baseboard_fab2_lib.baseboard_fab2(sch_1):page81_i67:dqs3p"
				( attribute "PN" "186"
					( Origin gPackager )
				)
				( objectStatus "J1G3.186" )
			)
			( pin "@baseboard_fab2_lib.baseboard_fab2(sch_1):page81_i67:dqs4n"
				( attribute "PN" "244"
					( Origin gPackager )
				)
				( objectStatus "J1G3.244" )
			)
			( pin "@baseboard_fab2_lib.baseboard_fab2(sch_1):page81_i67:dqs4p"
				( attribute "PN" "245"
					( Origin gPackager )
				)
				( objectStatus "J1G3.245" )
			)
			( pin "@baseboard_fab2_lib.baseboard_fab2(sch_1):page81_i67:dqs5n"
				( attribute "PN" "255"
					( Origin gPackager )
				)
				( objectStatus "J1G3.255" )
			)
			( pin "@baseboard_fab2_lib.baseboard_fab2(sch_1):page81_i67:dqs5p"
				( attribute "PN" "256"
					( Origin gPackager )
				)
				( objectStatus "J1G3.256" )
			)
			( pin "@baseboard_fab2_lib.baseboard_fab2(sch_1):page81_i67:dqs6n"
				( attribute "PN" "266"
					( Origin gPackager )
				)
				( objectStatus "J1G3.266" )
			)
			( pin "@baseboard_fab2_lib.baseboard_fab2(sch_1):page81_i67:dqs6p"
				( attribute "PN" "267"
					( Origin gPackager )
				)
				( objectStatus "J1G3.267" )
			)
			( pin "@baseboard_fab2_lib.baseboard_fab2(sch_1):page81_i67:dqs7n"
				( attribute "PN" "277"
					( Origin gPackager )
				)
				( objectStatus "J1G3.277" )
			)
			( pin "@baseboard_fab2_lib.baseboard_fab2(sch_1):page81_i67:dqs7p"
				( attribute "PN" "278"
					( Origin gPackager )
				)
				( objectStatus "J1G3.278" )
			)
			( pin "@baseboard_fab2_lib.baseboard_fab2(sch_1):page81_i67:dqs8n"
				( attribute "PN" "196"
					( Origin gPackager )
				)
				( objectStatus "J1G3.196" )
			)
			( pin "@baseboard_fab2_lib.baseboard_fab2(sch_1):page81_i67:dqs8p"
				( attribute "PN" "197"
					( Origin gPackager )
				)
				( objectStatus "J1G3.197" )
			)
			( pin "@baseboard_fab2_lib.baseboard_fab2(sch_1):page81_i67:dqs9n"
				( attribute "PN" "8"
					( Origin gPackager )
				)
				( objectStatus "J1G3.8" )
			)
			( pin "@baseboard_fab2_lib.baseboard_fab2(sch_1):page81_i67:dqs9p"
				( attribute "PN" "7"
					( Origin gPackager )
				)
				( objectStatus "J1G3.7" )
			)
			( pin "@baseboard_fab2_lib.baseboard_fab2(sch_1):page81_i67:dqs10n"
				( attribute "PN" "19"
					( Origin gPackager )
				)
				( objectStatus "J1G3.19" )
			)
			( pin "@baseboard_fab2_lib.baseboard_fab2(sch_1):page81_i67:dqs10p"
				( attribute "PN" "18"
					( Origin gPackager )
				)
				( objectStatus "J1G3.18" )
			)
			( pin "@baseboard_fab2_lib.baseboard_fab2(sch_1):page81_i67:dqs11n"
				( attribute "PN" "30"
					( Origin gPackager )
				)
				( objectStatus "J1G3.30" )
			)
			( pin "@baseboard_fab2_lib.baseboard_fab2(sch_1):page81_i67:dqs11p"
				( attribute "PN" "29"
					( Origin gPackager )
				)
				( objectStatus "J1G3.29" )
			)
			( pin "@baseboard_fab2_lib.baseboard_fab2(sch_1):page81_i67:dqs12n"
				( attribute "PN" "41"
					( Origin gPackager )
				)
				( objectStatus "J1G3.41" )
			)
			( pin "@baseboard_fab2_lib.baseboard_fab2(sch_1):page81_i67:dqs12p"
				( attribute "PN" "40"
					( Origin gPackager )
				)
				( objectStatus "J1G3.40" )
			)
			( pin "@baseboard_fab2_lib.baseboard_fab2(sch_1):page81_i67:dqs13n"
				( attribute "PN" "100"
					( Origin gPackager )
				)
				( objectStatus "J1G3.100" )
			)
			( pin "@baseboard_fab2_lib.baseboard_fab2(sch_1):page81_i67:dqs13p"
				( attribute "PN" "99"
					( Origin gPackager )
				)
				( objectStatus "J1G3.99" )
			)
			( pin "@baseboard_fab2_lib.baseboard_fab2(sch_1):page81_i67:dqs14n"
				( attribute "PN" "111"
					( Origin gPackager )
				)
				( objectStatus "J1G3.111" )
			)
			( pin "@baseboard_fab2_lib.baseboard_fab2(sch_1):page81_i67:dqs14p"
				( attribute "PN" "110"
					( Origin gPackager )
				)
				( objectStatus "J1G3.110" )
			)
			( pin "@baseboard_fab2_lib.baseboard_fab2(sch_1):page81_i67:dqs15n"
				( attribute "PN" "122"
					( Origin gPackager )
				)
				( objectStatus "J1G3.122" )
			)
			( pin "@baseboard_fab2_lib.baseboard_fab2(sch_1):page81_i67:dqs15p"
				( attribute "PN" "121"
					( Origin gPackager )
				)
				( objectStatus "J1G3.121" )
			)
			( pin "@baseboard_fab2_lib.baseboard_fab2(sch_1):page81_i67:dqs16n"
				( attribute "PN" "133"
					( Origin gPackager )
				)
				( objectStatus "J1G3.133" )
			)
			( pin "@baseboard_fab2_lib.baseboard_fab2(sch_1):page81_i67:dqs16p"
				( attribute "PN" "132"
					( Origin gPackager )
				)
				( objectStatus "J1G3.132" )
			)
			( pin "@baseboard_fab2_lib.baseboard_fab2(sch_1):page81_i67:dqs17n"
				( attribute "PN" "52"
					( Origin gPackager )
				)
				( objectStatus "J1G3.52" )
			)
			( pin "@baseboard_fab2_lib.baseboard_fab2(sch_1):page81_i67:dqs17p"
				( attribute "PN" "51"
					( Origin gPackager )
				)
				( objectStatus "J1G3.51" )
			)
			( pin "@baseboard_fab2_lib.baseboard_fab2(sch_1):page81_i169:\12v\(0)"
				( attribute "PN" "145"
					( Origin gPackager )
				)
				( objectStatus "J1G3.145" )
			)
			( pin "@baseboard_fab2_lib.baseboard_fab2(sch_1):page81_i169:\12v\(1)"
				( attribute "PN" "1"
					( Origin gPackager )
				)
				( objectStatus "J1G3.1" )
			)
			( pin "@baseboard_fab2_lib.baseboard_fab2(sch_1):page81_i169:vdd(0)"
				( attribute "PN" "236"
					( Origin gPackager )
				)
				( objectStatus "J1G3.236" )
			)
			( pin "@baseboard_fab2_lib.baseboard_fab2(sch_1):page81_i169:vdd(1)"
				( attribute "PN" "233"
					( Origin gPackager )
				)
				( objectStatus "J1G3.233" )
			)
			( pin "@baseboard_fab2_lib.baseboard_fab2(sch_1):page81_i169:vdd(2)"
				( attribute "PN" "231"
					( Origin gPackager )
				)
				( objectStatus "J1G3.231" )
			)
			( pin "@baseboard_fab2_lib.baseboard_fab2(sch_1):page81_i169:vdd(3)"
				( attribute "PN" "229"
					( Origin gPackager )
				)
				( objectStatus "J1G3.229" )
			)
			( pin "@baseboard_fab2_lib.baseboard_fab2(sch_1):page81_i169:vdd(4)"
				( attribute "PN" "226"
					( Origin gPackager )
				)
				( objectStatus "J1G3.226" )
			)
			( pin "@baseboard_fab2_lib.baseboard_fab2(sch_1):page81_i169:vdd(5)"
				( attribute "PN" "223"
					( Origin gPackager )
				)
				( objectStatus "J1G3.223" )
			)
			( pin "@baseboard_fab2_lib.baseboard_fab2(sch_1):page81_i169:vdd(6)"
				( attribute "PN" "220"
					( Origin gPackager )
				)
				( objectStatus "J1G3.220" )
			)
			( pin "@baseboard_fab2_lib.baseboard_fab2(sch_1):page81_i169:vdd(7)"
				( attribute "PN" "217"
					( Origin gPackager )
				)
				( objectStatus "J1G3.217" )
			)
			( pin "@baseboard_fab2_lib.baseboard_fab2(sch_1):page81_i169:vdd(8)"
				( attribute "PN" "215"
					( Origin gPackager )
				)
				( objectStatus "J1G3.215" )
			)
			( pin "@baseboard_fab2_lib.baseboard_fab2(sch_1):page81_i169:vdd(9)"
				( attribute "PN" "212"
					( Origin gPackager )
				)
				( objectStatus "J1G3.212" )
			)
			( pin "@baseboard_fab2_lib.baseboard_fab2(sch_1):page81_i169:vdd(10)"
				( attribute "PN" "209"
					( Origin gPackager )
				)
				( objectStatus "J1G3.209" )
			)
			( pin "@baseboard_fab2_lib.baseboard_fab2(sch_1):page81_i169:vdd(11)"
				( attribute "PN" "206"
					( Origin gPackager )
				)
				( objectStatus "J1G3.206" )
			)
			( pin "@baseboard_fab2_lib.baseboard_fab2(sch_1):page81_i169:vdd(12)"
				( attribute "PN" "204"
					( Origin gPackager )
				)
				( objectStatus "J1G3.204" )
			)
			( pin "@baseboard_fab2_lib.baseboard_fab2(sch_1):page81_i169:vdd(13)"
				( attribute "PN" "92"
					( Origin gPackager )
				)
				( objectStatus "J1G3.92" )
			)
			( pin "@baseboard_fab2_lib.baseboard_fab2(sch_1):page81_i169:vdd(14)"
				( attribute "PN" "90"
					( Origin gPackager )
				)
				( objectStatus "J1G3.90" )
			)
			( pin "@baseboard_fab2_lib.baseboard_fab2(sch_1):page81_i169:vdd(15)"
				( attribute "PN" "88"
					( Origin gPackager )
				)
				( objectStatus "J1G3.88" )
			)
			( pin "@baseboard_fab2_lib.baseboard_fab2(sch_1):page81_i169:vdd(16)"
				( attribute "PN" "85"
					( Origin gPackager )
				)
				( objectStatus "J1G3.85" )
			)
			( pin "@baseboard_fab2_lib.baseboard_fab2(sch_1):page81_i169:vdd(17)"
				( attribute "PN" "83"
					( Origin gPackager )
				)
				( objectStatus "J1G3.83" )
			)
			( pin "@baseboard_fab2_lib.baseboard_fab2(sch_1):page81_i169:vdd(18)"
				( attribute "PN" "80"
					( Origin gPackager )
				)
				( objectStatus "J1G3.80" )
			)
			( pin "@baseboard_fab2_lib.baseboard_fab2(sch_1):page81_i169:vdd(19)"
				( attribute "PN" "76"
					( Origin gPackager )
				)
				( objectStatus "J1G3.76" )
			)
			( pin "@baseboard_fab2_lib.baseboard_fab2(sch_1):page81_i169:vdd(20)"
				( attribute "PN" "73"
					( Origin gPackager )
				)
				( objectStatus "J1G3.73" )
			)
			( pin "@baseboard_fab2_lib.baseboard_fab2(sch_1):page81_i169:vdd(21)"
				( attribute "PN" "70"
					( Origin gPackager )
				)
				( objectStatus "J1G3.70" )
			)
			( pin "@baseboard_fab2_lib.baseboard_fab2(sch_1):page81_i169:vdd(22)"
				( attribute "PN" "67"
					( Origin gPackager )
				)
				( objectStatus "J1G3.67" )
			)
			( pin "@baseboard_fab2_lib.baseboard_fab2(sch_1):page81_i169:vdd(23)"
				( attribute "PN" "64"
					( Origin gPackager )
				)
				( objectStatus "J1G3.64" )
			)
			( pin "@baseboard_fab2_lib.baseboard_fab2(sch_1):page81_i169:vdd(24)"
				( attribute "PN" "61"
					( Origin gPackager )
				)
				( objectStatus "J1G3.61" )
			)
			( pin "@baseboard_fab2_lib.baseboard_fab2(sch_1):page81_i169:vdd(25)"
				( attribute "PN" "59"
					( Origin gPackager )
				)
				( objectStatus "J1G3.59" )
			)
			( pin "@baseboard_fab2_lib.baseboard_fab2(sch_1):page81_i169:vpp(0)"
				( attribute "PN" "287"
					( Origin gPackager )
				)
				( objectStatus "J1G3.287" )
			)
			( pin "@baseboard_fab2_lib.baseboard_fab2(sch_1):page81_i169:vpp(1)"
				( attribute "PN" "286"
					( Origin gPackager )
				)
				( objectStatus "J1G3.286" )
			)
			( pin "@baseboard_fab2_lib.baseboard_fab2(sch_1):page81_i169:vpp(2)"
				( attribute "PN" "288"
					( Origin gPackager )
				)
				( objectStatus "J1G3.288" )
			)
			( pin "@baseboard_fab2_lib.baseboard_fab2(sch_1):page81_i169:vpp(3)"
				( attribute "PN" "143"
					( Origin gPackager )
				)
				( objectStatus "J1G3.143" )
			)
			( pin "@baseboard_fab2_lib.baseboard_fab2(sch_1):page81_i169:vpp(4)"
				( attribute "PN" "142"
					( Origin gPackager )
				)
				( objectStatus "J1G3.142" )
			)
			( pin "@baseboard_fab2_lib.baseboard_fab2(sch_1):page81_i169:vtt(0)"
				( attribute "PN" "221"
					( Origin gPackager )
				)
				( objectStatus "J1G3.221" )
			)
			( pin "@baseboard_fab2_lib.baseboard_fab2(sch_1):page81_i169:vtt(1)"
				( attribute "PN" "77"
					( Origin gPackager )
				)
				( objectStatus "J1G3.77" )
			)
			( pin "@baseboard_fab2_lib.baseboard_fab2(sch_1):page81_i178:a"
				( attribute "PN" "1"
					( Origin gPackager )
				)
				( objectStatus "C9U10.1" )
			)
			( pin "@baseboard_fab2_lib.baseboard_fab2(sch_1):page81_i178:b"
				( attribute "PN" "2"
					( Origin gPackager )
				)
				( objectStatus "C9U10.2" )
			)
			( pin "@baseboard_fab2_lib.baseboard_fab2(sch_1):page81_i185:vss(0)"
				( attribute "PN" "283"
					( Origin gPackager )
				)
				( objectStatus "J1G3.283" )
			)
			( pin "@baseboard_fab2_lib.baseboard_fab2(sch_1):page81_i185:vss(1)"
				( attribute "PN" "281"
					( Origin gPackager )
				)
				( objectStatus "J1G3.281" )
			)
			( pin "@baseboard_fab2_lib.baseboard_fab2(sch_1):page81_i185:vss(2)"
				( attribute "PN" "279"
					( Origin gPackager )
				)
				( objectStatus "J1G3.279" )
			)
			( pin "@baseboard_fab2_lib.baseboard_fab2(sch_1):page81_i185:vss(3)"
				( attribute "PN" "276"
					( Origin gPackager )
				)
				( objectStatus "J1G3.276" )
			)
			( pin "@baseboard_fab2_lib.baseboard_fab2(sch_1):page81_i185:vss(4)"
				( attribute "PN" "274"
					( Origin gPackager )
				)
				( objectStatus "J1G3.274" )
			)
			( pin "@baseboard_fab2_lib.baseboard_fab2(sch_1):page81_i185:vss(5)"
				( attribute "PN" "272"
					( Origin gPackager )
				)
				( objectStatus "J1G3.272" )
			)
			( pin "@baseboard_fab2_lib.baseboard_fab2(sch_1):page81_i185:vss(6)"
				( attribute "PN" "270"
					( Origin gPackager )
				)
				( objectStatus "J1G3.270" )
			)
			( pin "@baseboard_fab2_lib.baseboard_fab2(sch_1):page81_i185:vss(7)"
				( attribute "PN" "268"
					( Origin gPackager )
				)
				( objectStatus "J1G3.268" )
			)
			( pin "@baseboard_fab2_lib.baseboard_fab2(sch_1):page81_i185:vss(8)"
				( attribute "PN" "265"
					( Origin gPackager )
				)
				( objectStatus "J1G3.265" )
			)
			( pin "@baseboard_fab2_lib.baseboard_fab2(sch_1):page81_i185:vss(9)"
				( attribute "PN" "263"
					( Origin gPackager )
				)
				( objectStatus "J1G3.263" )
			)
			( pin "@baseboard_fab2_lib.baseboard_fab2(sch_1):page81_i185:vss(10)"
				( attribute "PN" "261"
					( Origin gPackager )
				)
				( objectStatus "J1G3.261" )
			)
			( pin "@baseboard_fab2_lib.baseboard_fab2(sch_1):page81_i185:vss(11)"
				( attribute "PN" "259"
					( Origin gPackager )
				)
				( objectStatus "J1G3.259" )
			)
			( pin "@baseboard_fab2_lib.baseboard_fab2(sch_1):page81_i185:vss(12)"
				( attribute "PN" "257"
					( Origin gPackager )
				)
				( objectStatus "J1G3.257" )
			)
			( pin "@baseboard_fab2_lib.baseboard_fab2(sch_1):page81_i185:vss(13)"
				( attribute "PN" "254"
					( Origin gPackager )
				)
				( objectStatus "J1G3.254" )
			)
			( pin "@baseboard_fab2_lib.baseboard_fab2(sch_1):page81_i185:vss(14)"
				( attribute "PN" "252"
					( Origin gPackager )
				)
				( objectStatus "J1G3.252" )
			)
			( pin "@baseboard_fab2_lib.baseboard_fab2(sch_1):page81_i185:vss(15)"
				( attribute "PN" "250"
					( Origin gPackager )
				)
				( objectStatus "J1G3.250" )
			)
			( pin "@baseboard_fab2_lib.baseboard_fab2(sch_1):page81_i185:vss(16)"
				( attribute "PN" "248"
					( Origin gPackager )
				)
				( objectStatus "J1G3.248" )
			)
			( pin "@baseboard_fab2_lib.baseboard_fab2(sch_1):page81_i185:vss(17)"
				( attribute "PN" "246"
					( Origin gPackager )
				)
				( objectStatus "J1G3.246" )
			)
			( pin "@baseboard_fab2_lib.baseboard_fab2(sch_1):page81_i185:vss(18)"
				( attribute "PN" "243"
					( Origin gPackager )
				)
				( objectStatus "J1G3.243" )
			)
			( pin "@baseboard_fab2_lib.baseboard_fab2(sch_1):page81_i185:vss(19)"
				( attribute "PN" "241"
					( Origin gPackager )
				)
				( objectStatus "J1G3.241" )
			)
			( pin "@baseboard_fab2_lib.baseboard_fab2(sch_1):page81_i185:vss(20)"
				( attribute "PN" "239"
					( Origin gPackager )
				)
				( objectStatus "J1G3.239" )
			)
			( pin "@baseboard_fab2_lib.baseboard_fab2(sch_1):page81_i185:vss(21)"
				( attribute "PN" "202"
					( Origin gPackager )
				)
				( objectStatus "J1G3.202" )
			)
			( pin "@baseboard_fab2_lib.baseboard_fab2(sch_1):page81_i185:vss(22)"
				( attribute "PN" "200"
					( Origin gPackager )
				)
				( objectStatus "J1G3.200" )
			)
			( pin "@baseboard_fab2_lib.baseboard_fab2(sch_1):page81_i185:vss(23)"
				( attribute "PN" "198"
					( Origin gPackager )
				)
				( objectStatus "J1G3.198" )
			)
			( pin "@baseboard_fab2_lib.baseboard_fab2(sch_1):page81_i185:vss(24)"
				( attribute "PN" "195"
					( Origin gPackager )
				)
				( objectStatus "J1G3.195" )
			)
			( pin "@baseboard_fab2_lib.baseboard_fab2(sch_1):page81_i185:vss(25)"
				( attribute "PN" "193"
					( Origin gPackager )
				)
				( objectStatus "J1G3.193" )
			)
			( pin "@baseboard_fab2_lib.baseboard_fab2(sch_1):page81_i185:vss(26)"
				( attribute "PN" "191"
					( Origin gPackager )
				)
				( objectStatus "J1G3.191" )
			)
			( pin "@baseboard_fab2_lib.baseboard_fab2(sch_1):page81_i185:vss(27)"
				( attribute "PN" "189"
					( Origin gPackager )
				)
				( objectStatus "J1G3.189" )
			)
			( pin "@baseboard_fab2_lib.baseboard_fab2(sch_1):page81_i185:vss(28)"
				( attribute "PN" "187"
					( Origin gPackager )
				)
				( objectStatus "J1G3.187" )
			)
			( pin "@baseboard_fab2_lib.baseboard_fab2(sch_1):page81_i185:vss(29)"
				( attribute "PN" "184"
					( Origin gPackager )
				)
				( objectStatus "J1G3.184" )
			)
			( pin "@baseboard_fab2_lib.baseboard_fab2(sch_1):page81_i185:vss(30)"
				( attribute "PN" "182"
					( Origin gPackager )
				)
				( objectStatus "J1G3.182" )
			)
			( pin "@baseboard_fab2_lib.baseboard_fab2(sch_1):page81_i185:vss(31)"
				( attribute "PN" "180"
					( Origin gPackager )
				)
				( objectStatus "J1G3.180" )
			)
			( pin "@baseboard_fab2_lib.baseboard_fab2(sch_1):page81_i185:vss(32)"
				( attribute "PN" "178"
					( Origin gPackager )
				)
				( objectStatus "J1G3.178" )
			)
			( pin "@baseboard_fab2_lib.baseboard_fab2(sch_1):page81_i185:vss(33)"
				( attribute "PN" "176"
					( Origin gPackager )
				)
				( objectStatus "J1G3.176" )
			)
			( pin "@baseboard_fab2_lib.baseboard_fab2(sch_1):page81_i185:vss(34)"
				( attribute "PN" "173"
					( Origin gPackager )
				)
				( objectStatus "J1G3.173" )
			)
			( pin "@baseboard_fab2_lib.baseboard_fab2(sch_1):page81_i185:vss(35)"
				( attribute "PN" "171"
					( Origin gPackager )
				)
				( objectStatus "J1G3.171" )
			)
			( pin "@baseboard_fab2_lib.baseboard_fab2(sch_1):page81_i185:vss(36)"
				( attribute "PN" "169"
					( Origin gPackager )
				)
				( objectStatus "J1G3.169" )
			)
			( pin "@baseboard_fab2_lib.baseboard_fab2(sch_1):page81_i185:vss(37)"
				( attribute "PN" "167"
					( Origin gPackager )
				)
				( objectStatus "J1G3.167" )
			)
			( pin "@baseboard_fab2_lib.baseboard_fab2(sch_1):page81_i185:vss(38)"
				( attribute "PN" "165"
					( Origin gPackager )
				)
				( objectStatus "J1G3.165" )
			)
			( pin "@baseboard_fab2_lib.baseboard_fab2(sch_1):page81_i185:vss(39)"
				( attribute "PN" "162"
					( Origin gPackager )
				)
				( objectStatus "J1G3.162" )
			)
			( pin "@baseboard_fab2_lib.baseboard_fab2(sch_1):page81_i185:vss(40)"
				( attribute "PN" "160"
					( Origin gPackager )
				)
				( objectStatus "J1G3.160" )
			)
			( pin "@baseboard_fab2_lib.baseboard_fab2(sch_1):page81_i185:vss(41)"
				( attribute "PN" "158"
					( Origin gPackager )
				)
				( objectStatus "J1G3.158" )
			)
			( pin "@baseboard_fab2_lib.baseboard_fab2(sch_1):page81_i185:vss(42)"
				( attribute "PN" "156"
					( Origin gPackager )
				)
				( objectStatus "J1G3.156" )
			)
			( pin "@baseboard_fab2_lib.baseboard_fab2(sch_1):page81_i185:vss(43)"
				( attribute "PN" "154"
					( Origin gPackager )
				)
				( objectStatus "J1G3.154" )
			)
			( pin "@baseboard_fab2_lib.baseboard_fab2(sch_1):page81_i185:vss(44)"
				( attribute "PN" "151"
					( Origin gPackager )
				)
				( objectStatus "J1G3.151" )
			)
			( pin "@baseboard_fab2_lib.baseboard_fab2(sch_1):page81_i185:vss(45)"
				( attribute "PN" "149"
					( Origin gPackager )
				)
				( objectStatus "J1G3.149" )
			)
			( pin "@baseboard_fab2_lib.baseboard_fab2(sch_1):page81_i185:vss(46)"
				( attribute "PN" "147"
					( Origin gPackager )
				)
				( objectStatus "J1G3.147" )
			)
			( pin "@baseboard_fab2_lib.baseboard_fab2(sch_1):page81_i185:vss(47)"
				( attribute "PN" "138"
					( Origin gPackager )
				)
				( objectStatus "J1G3.138" )
			)
			( pin "@baseboard_fab2_lib.baseboard_fab2(sch_1):page81_i185:vss(48)"
				( attribute "PN" "136"
					( Origin gPackager )
				)
				( objectStatus "J1G3.136" )
			)
			( pin "@baseboard_fab2_lib.baseboard_fab2(sch_1):page81_i185:vss(49)"
				( attribute "PN" "134"
					( Origin gPackager )
				)
				( objectStatus "J1G3.134" )
			)
			( pin "@baseboard_fab2_lib.baseboard_fab2(sch_1):page81_i185:vss(50)"
				( attribute "PN" "131"
					( Origin gPackager )
				)
				( objectStatus "J1G3.131" )
			)
			( pin "@baseboard_fab2_lib.baseboard_fab2(sch_1):page81_i185:vss(51)"
				( attribute "PN" "129"
					( Origin gPackager )
				)
				( objectStatus "J1G3.129" )
			)
			( pin "@baseboard_fab2_lib.baseboard_fab2(sch_1):page81_i185:vss(52)"
				( attribute "PN" "127"
					( Origin gPackager )
				)
				( objectStatus "J1G3.127" )
			)
			( pin "@baseboard_fab2_lib.baseboard_fab2(sch_1):page81_i185:vss(53)"
				( attribute "PN" "125"
					( Origin gPackager )
				)
				( objectStatus "J1G3.125" )
			)
			( pin "@baseboard_fab2_lib.baseboard_fab2(sch_1):page81_i185:vss(54)"
				( attribute "PN" "123"
					( Origin gPackager )
				)
				( objectStatus "J1G3.123" )
			)
			( pin "@baseboard_fab2_lib.baseboard_fab2(sch_1):page81_i185:vss(55)"
				( attribute "PN" "120"
					( Origin gPackager )
				)
				( objectStatus "J1G3.120" )
			)
			( pin "@baseboard_fab2_lib.baseboard_fab2(sch_1):page81_i185:vss(56)"
				( attribute "PN" "118"
					( Origin gPackager )
				)
				( objectStatus "J1G3.118" )
			)
			( pin "@baseboard_fab2_lib.baseboard_fab2(sch_1):page81_i185:vss(57)"
				( attribute "PN" "116"
					( Origin gPackager )
				)
				( objectStatus "J1G3.116" )
			)
			( pin "@baseboard_fab2_lib.baseboard_fab2(sch_1):page81_i185:vss(58)"
				( attribute "PN" "114"
					( Origin gPackager )
				)
				( objectStatus "J1G3.114" )
			)
			( pin "@baseboard_fab2_lib.baseboard_fab2(sch_1):page81_i185:vss(59)"
				( attribute "PN" "112"
					( Origin gPackager )
				)
				( objectStatus "J1G3.112" )
			)
			( pin "@baseboard_fab2_lib.baseboard_fab2(sch_1):page81_i185:vss(60)"
				( attribute "PN" "109"
					( Origin gPackager )
				)
				( objectStatus "J1G3.109" )
			)
			( pin "@baseboard_fab2_lib.baseboard_fab2(sch_1):page81_i185:vss(61)"
				( attribute "PN" "107"
					( Origin gPackager )
				)
				( objectStatus "J1G3.107" )
			)
			( pin "@baseboard_fab2_lib.baseboard_fab2(sch_1):page81_i185:vss(62)"
				( attribute "PN" "105"
					( Origin gPackager )
				)
				( objectStatus "J1G3.105" )
			)
			( pin "@baseboard_fab2_lib.baseboard_fab2(sch_1):page81_i185:vss(63)"
				( attribute "PN" "103"
					( Origin gPackager )
				)
				( objectStatus "J1G3.103" )
			)
			( pin "@baseboard_fab2_lib.baseboard_fab2(sch_1):page81_i185:vss(64)"
				( attribute "PN" "101"
					( Origin gPackager )
				)
				( objectStatus "J1G3.101" )
			)
			( pin "@baseboard_fab2_lib.baseboard_fab2(sch_1):page81_i185:vss(65)"
				( attribute "PN" "98"
					( Origin gPackager )
				)
				( objectStatus "J1G3.98" )
			)
			( pin "@baseboard_fab2_lib.baseboard_fab2(sch_1):page81_i185:vss(66)"
				( attribute "PN" "96"
					( Origin gPackager )
				)
				( objectStatus "J1G3.96" )
			)
			( pin "@baseboard_fab2_lib.baseboard_fab2(sch_1):page81_i185:vss(67)"
				( attribute "PN" "94"
					( Origin gPackager )
				)
				( objectStatus "J1G3.94" )
			)
			( pin "@baseboard_fab2_lib.baseboard_fab2(sch_1):page81_i185:vss(68)"
				( attribute "PN" "57"
					( Origin gPackager )
				)
				( objectStatus "J1G3.57" )
			)
			( pin "@baseboard_fab2_lib.baseboard_fab2(sch_1):page81_i185:vss(69)"
				( attribute "PN" "55"
					( Origin gPackager )
				)
				( objectStatus "J1G3.55" )
			)
			( pin "@baseboard_fab2_lib.baseboard_fab2(sch_1):page81_i185:vss(70)"
				( attribute "PN" "53"
					( Origin gPackager )
				)
				( objectStatus "J1G3.53" )
			)
			( pin "@baseboard_fab2_lib.baseboard_fab2(sch_1):page81_i185:vss(71)"
				( attribute "PN" "50"
					( Origin gPackager )
				)
				( objectStatus "J1G3.50" )
			)
			( pin "@baseboard_fab2_lib.baseboard_fab2(sch_1):page81_i185:vss(72)"
				( attribute "PN" "48"
					( Origin gPackager )
				)
				( objectStatus "J1G3.48" )
			)
			( pin "@baseboard_fab2_lib.baseboard_fab2(sch_1):page81_i185:vss(73)"
				( attribute "PN" "46"
					( Origin gPackager )
				)
				( objectStatus "J1G3.46" )
			)
			( pin "@baseboard_fab2_lib.baseboard_fab2(sch_1):page81_i185:vss(74)"
				( attribute "PN" "44"
					( Origin gPackager )
				)
				( objectStatus "J1G3.44" )
			)
			( pin "@baseboard_fab2_lib.baseboard_fab2(sch_1):page81_i185:vss(75)"
				( attribute "PN" "42"
					( Origin gPackager )
				)
				( objectStatus "J1G3.42" )
			)
			( pin "@baseboard_fab2_lib.baseboard_fab2(sch_1):page81_i185:vss(76)"
				( attribute "PN" "39"
					( Origin gPackager )
				)
				( objectStatus "J1G3.39" )
			)
			( pin "@baseboard_fab2_lib.baseboard_fab2(sch_1):page81_i185:vss(77)"
				( attribute "PN" "37"
					( Origin gPackager )
				)
				( objectStatus "J1G3.37" )
			)
			( pin "@baseboard_fab2_lib.baseboard_fab2(sch_1):page81_i185:vss(78)"
				( attribute "PN" "35"
					( Origin gPackager )
				)
				( objectStatus "J1G3.35" )
			)
			( pin "@baseboard_fab2_lib.baseboard_fab2(sch_1):page81_i185:vss(79)"
				( attribute "PN" "33"
					( Origin gPackager )
				)
				( objectStatus "J1G3.33" )
			)
			( pin "@baseboard_fab2_lib.baseboard_fab2(sch_1):page81_i185:vss(80)"
				( attribute "PN" "31"
					( Origin gPackager )
				)
				( objectStatus "J1G3.31" )
			)
			( pin "@baseboard_fab2_lib.baseboard_fab2(sch_1):page81_i185:vss(81)"
				( attribute "PN" "28"
					( Origin gPackager )
				)
				( objectStatus "J1G3.28" )
			)
			( pin "@baseboard_fab2_lib.baseboard_fab2(sch_1):page81_i185:vss(82)"
				( attribute "PN" "26"
					( Origin gPackager )
				)
				( objectStatus "J1G3.26" )
			)
			( pin "@baseboard_fab2_lib.baseboard_fab2(sch_1):page81_i185:vss(83)"
				( attribute "PN" "24"
					( Origin gPackager )
				)
				( objectStatus "J1G3.24" )
			)
			( pin "@baseboard_fab2_lib.baseboard_fab2(sch_1):page81_i185:vss(84)"
				( attribute "PN" "22"
					( Origin gPackager )
				)
				( objectStatus "J1G3.22" )
			)
			( pin "@baseboard_fab2_lib.baseboard_fab2(sch_1):page81_i185:vss(85)"
				( attribute "PN" "20"
					( Origin gPackager )
				)
				( objectStatus "J1G3.20" )
			)
			( pin "@baseboard_fab2_lib.baseboard_fab2(sch_1):page81_i185:vss(86)"
				( attribute "PN" "17"
					( Origin gPackager )
				)
				( objectStatus "J1G3.17" )
			)
			( pin "@baseboard_fab2_lib.baseboard_fab2(sch_1):page81_i185:vss(87)"
				( attribute "PN" "15"
					( Origin gPackager )
				)
				( objectStatus "J1G3.15" )
			)
			( pin "@baseboard_fab2_lib.baseboard_fab2(sch_1):page81_i185:vss(88)"
				( attribute "PN" "13"
					( Origin gPackager )
				)
				( objectStatus "J1G3.13" )
			)
			( pin "@baseboard_fab2_lib.baseboard_fab2(sch_1):page81_i185:vss(89)"
				( attribute "PN" "11"
					( Origin gPackager )
				)
				( objectStatus "J1G3.11" )
			)
			( pin "@baseboard_fab2_lib.baseboard_fab2(sch_1):page81_i185:vss(90)"
				( attribute "PN" "9"
					( Origin gPackager )
				)
				( objectStatus "J1G3.9" )
			)
			( pin "@baseboard_fab2_lib.baseboard_fab2(sch_1):page81_i185:vss(91)"
				( attribute "PN" "6"
					( Origin gPackager )
				)
				( objectStatus "J1G3.6" )
			)
			( pin "@baseboard_fab2_lib.baseboard_fab2(sch_1):page81_i185:vss(92)"
				( attribute "PN" "4"
					( Origin gPackager )
				)
				( objectStatus "J1G3.4" )
			)
			( pin "@baseboard_fab2_lib.baseboard_fab2(sch_1):page81_i185:vss(93)"
				( attribute "PN" "2"
					( Origin gPackager )
				)
				( objectStatus "J1G3.2" )
			)
			( pin "@baseboard_fab2_lib.baseboard_fab2(sch_1):page81_i186:a0"
				( attribute "PN" "79"
					( Origin gPackager )
				)
				( objectStatus "J1G3.79" )
			)
			( pin "@baseboard_fab2_lib.baseboard_fab2(sch_1):page81_i186:a1"
				( attribute "PN" "72"
					( Origin gPackager )
				)
				( objectStatus "J1G3.72" )
			)
			( pin "@baseboard_fab2_lib.baseboard_fab2(sch_1):page81_i186:a2"
				( attribute "PN" "216"
					( Origin gPackager )
				)
				( objectStatus "J1G3.216" )
			)
			( pin "@baseboard_fab2_lib.baseboard_fab2(sch_1):page81_i186:a3"
				( attribute "PN" "71"
					( Origin gPackager )
				)
				( objectStatus "J1G3.71" )
			)
			( pin "@baseboard_fab2_lib.baseboard_fab2(sch_1):page81_i186:a4"
				( attribute "PN" "214"
					( Origin gPackager )
				)
				( objectStatus "J1G3.214" )
			)
			( pin "@baseboard_fab2_lib.baseboard_fab2(sch_1):page81_i186:a5"
				( attribute "PN" "213"
					( Origin gPackager )
				)
				( objectStatus "J1G3.213" )
			)
			( pin "@baseboard_fab2_lib.baseboard_fab2(sch_1):page81_i186:a6"
				( attribute "PN" "69"
					( Origin gPackager )
				)
				( objectStatus "J1G3.69" )
			)
			( pin "@baseboard_fab2_lib.baseboard_fab2(sch_1):page81_i186:a7"
				( attribute "PN" "211"
					( Origin gPackager )
				)
				( objectStatus "J1G3.211" )
			)
			( pin "@baseboard_fab2_lib.baseboard_fab2(sch_1):page81_i186:a8"
				( attribute "PN" "68"
					( Origin gPackager )
				)
				( objectStatus "J1G3.68" )
			)
			( pin "@baseboard_fab2_lib.baseboard_fab2(sch_1):page81_i186:a9"
				( attribute "PN" "66"
					( Origin gPackager )
				)
				( objectStatus "J1G3.66" )
			)
			( pin "@baseboard_fab2_lib.baseboard_fab2(sch_1):page81_i186:a10"
				( attribute "PN" "225"
					( Origin gPackager )
				)
				( objectStatus "J1G3.225" )
			)
			( pin "@baseboard_fab2_lib.baseboard_fab2(sch_1):page81_i186:a11"
				( attribute "PN" "210"
					( Origin gPackager )
				)
				( objectStatus "J1G3.210" )
			)
			( pin "@baseboard_fab2_lib.baseboard_fab2(sch_1):page81_i186:a12"
				( attribute "PN" "65"
					( Origin gPackager )
				)
				( objectStatus "J1G3.65" )
			)
			( pin "@baseboard_fab2_lib.baseboard_fab2(sch_1):page81_i186:a13"
				( attribute "PN" "232"
					( Origin gPackager )
				)
				( objectStatus "J1G3.232" )
			)
			( pin "@baseboard_fab2_lib.baseboard_fab2(sch_1):page81_i186:a14_we_n"
				( attribute "PN" "228"
					( Origin gPackager )
				)
				( objectStatus "J1G3.228" )
			)
			( pin "@baseboard_fab2_lib.baseboard_fab2(sch_1):page81_i186:a15_cas_n"
				( attribute "PN" "86"
					( Origin gPackager )
				)
				( objectStatus "J1G3.86" )
			)
			( pin "@baseboard_fab2_lib.baseboard_fab2(sch_1):page81_i186:a16_ras_n"
				( attribute "PN" "82"
					( Origin gPackager )
				)
				( objectStatus "J1G3.82" )
			)
			( pin "@baseboard_fab2_lib.baseboard_fab2(sch_1):page81_i186:a17"
				( attribute "PN" "234"
					( Origin gPackager )
				)
				( objectStatus "J1G3.234" )
			)
			( pin "@baseboard_fab2_lib.baseboard_fab2(sch_1):page81_i186:act_n"
				( attribute "PN" "62"
					( Origin gPackager )
				)
				( objectStatus "J1G3.62" )
			)
			( pin "@baseboard_fab2_lib.baseboard_fab2(sch_1):page81_i186:alert_n"
				( attribute "PN" "208"
					( Origin gPackager )
				)
				( objectStatus "J1G3.208" )
			)
			( pin "@baseboard_fab2_lib.baseboard_fab2(sch_1):page81_i186:ba(0)"
				( attribute "PN" "81"
					( Origin gPackager )
				)
				( objectStatus "J1G3.81" )
			)
			( pin "@baseboard_fab2_lib.baseboard_fab2(sch_1):page81_i186:ba(1)"
				( attribute "PN" "224"
					( Origin gPackager )
				)
				( objectStatus "J1G3.224" )
			)
			( pin "@baseboard_fab2_lib.baseboard_fab2(sch_1):page81_i186:bg(0)"
				( attribute "PN" "63"
					( Origin gPackager )
				)
				( objectStatus "J1G3.63" )
			)
			( pin "@baseboard_fab2_lib.baseboard_fab2(sch_1):page81_i186:bg(1)"
				( attribute "PN" "207"
					( Origin gPackager )
				)
				( objectStatus "J1G3.207" )
			)
			( pin "@baseboard_fab2_lib.baseboard_fab2(sch_1):page81_i186:c(2)"
				( attribute "PN" "235"
					( Origin gPackager )
				)
				( objectStatus "J1G3.235" )
			)
			( pin "@baseboard_fab2_lib.baseboard_fab2(sch_1):page81_i186:cb(0)"
				( attribute "PN" "49"
					( Origin gPackager )
				)
				( objectStatus "J1G3.49" )
			)
			( pin "@baseboard_fab2_lib.baseboard_fab2(sch_1):page81_i186:cb(1)"
				( attribute "PN" "194"
					( Origin gPackager )
				)
				( objectStatus "J1G3.194" )
			)
			( pin "@baseboard_fab2_lib.baseboard_fab2(sch_1):page81_i186:cb(2)"
				( attribute "PN" "56"
					( Origin gPackager )
				)
				( objectStatus "J1G3.56" )
			)
			( pin "@baseboard_fab2_lib.baseboard_fab2(sch_1):page81_i186:cb(3)"
				( attribute "PN" "201"
					( Origin gPackager )
				)
				( objectStatus "J1G3.201" )
			)
			( pin "@baseboard_fab2_lib.baseboard_fab2(sch_1):page81_i186:cb(4)"
				( attribute "PN" "47"
					( Origin gPackager )
				)
				( objectStatus "J1G3.47" )
			)
			( pin "@baseboard_fab2_lib.baseboard_fab2(sch_1):page81_i186:cb(5)"
				( attribute "PN" "192"
					( Origin gPackager )
				)
				( objectStatus "J1G3.192" )
			)
			( pin "@baseboard_fab2_lib.baseboard_fab2(sch_1):page81_i186:cb(6)"
				( attribute "PN" "54"
					( Origin gPackager )
				)
				( objectStatus "J1G3.54" )
			)
			( pin "@baseboard_fab2_lib.baseboard_fab2(sch_1):page81_i186:cb(7)"
				( attribute "PN" "199"
					( Origin gPackager )
				)
				( objectStatus "J1G3.199" )
			)
			( pin "@baseboard_fab2_lib.baseboard_fab2(sch_1):page81_i186:ck0n"
				( attribute "PN" "75"
					( Origin gPackager )
				)
				( objectStatus "J1G3.75" )
			)
			( pin "@baseboard_fab2_lib.baseboard_fab2(sch_1):page81_i186:ck0p"
				( attribute "PN" "74"
					( Origin gPackager )
				)
				( objectStatus "J1G3.74" )
			)
			( pin "@baseboard_fab2_lib.baseboard_fab2(sch_1):page81_i186:ck1n"
				( attribute "PN" "219"
					( Origin gPackager )
				)
				( objectStatus "J1G3.219" )
			)
			( pin "@baseboard_fab2_lib.baseboard_fab2(sch_1):page81_i186:ck1p"
				( attribute "PN" "218"
					( Origin gPackager )
				)
				( objectStatus "J1G3.218" )
			)
			( pin "@baseboard_fab2_lib.baseboard_fab2(sch_1):page81_i186:cke(0)"
				( attribute "PN" "60"
					( Origin gPackager )
				)
				( objectStatus "J1G3.60" )
			)
			( pin "@baseboard_fab2_lib.baseboard_fab2(sch_1):page81_i186:cke(1)"
				( attribute "PN" "203"
					( Origin gPackager )
				)
				( objectStatus "J1G3.203" )
			)
			( pin "@baseboard_fab2_lib.baseboard_fab2(sch_1):page81_i186:dq(0)"
				( attribute "PN" "5"
					( Origin gPackager )
				)
				( objectStatus "J1G3.5" )
			)
			( pin "@baseboard_fab2_lib.baseboard_fab2(sch_1):page81_i186:dq(1)"
				( attribute "PN" "150"
					( Origin gPackager )
				)
				( objectStatus "J1G3.150" )
			)
			( pin "@baseboard_fab2_lib.baseboard_fab2(sch_1):page81_i186:dq(2)"
				( attribute "PN" "12"
					( Origin gPackager )
				)
				( objectStatus "J1G3.12" )
			)
			( pin "@baseboard_fab2_lib.baseboard_fab2(sch_1):page81_i186:dq(3)"
				( attribute "PN" "157"
					( Origin gPackager )
				)
				( objectStatus "J1G3.157" )
			)
			( pin "@baseboard_fab2_lib.baseboard_fab2(sch_1):page81_i186:dq(4)"
				( attribute "PN" "3"
					( Origin gPackager )
				)
				( objectStatus "J1G3.3" )
			)
			( pin "@baseboard_fab2_lib.baseboard_fab2(sch_1):page81_i186:dq(5)"
				( attribute "PN" "148"
					( Origin gPackager )
				)
				( objectStatus "J1G3.148" )
			)
			( pin "@baseboard_fab2_lib.baseboard_fab2(sch_1):page81_i186:dq(6)"
				( attribute "PN" "10"
					( Origin gPackager )
				)
				( objectStatus "J1G3.10" )
			)
			( pin "@baseboard_fab2_lib.baseboard_fab2(sch_1):page81_i186:dq(7)"
				( attribute "PN" "155"
					( Origin gPackager )
				)
				( objectStatus "J1G3.155" )
			)
			( pin "@baseboard_fab2_lib.baseboard_fab2(sch_1):page81_i186:dq(8)"
				( attribute "PN" "16"
					( Origin gPackager )
				)
				( objectStatus "J1G3.16" )
			)
			( pin "@baseboard_fab2_lib.baseboard_fab2(sch_1):page81_i186:dq(9)"
				( attribute "PN" "161"
					( Origin gPackager )
				)
				( objectStatus "J1G3.161" )
			)
			( pin "@baseboard_fab2_lib.baseboard_fab2(sch_1):page81_i186:dq(10)"
				( attribute "PN" "23"
					( Origin gPackager )
				)
				( objectStatus "J1G3.23" )
			)
			( pin "@baseboard_fab2_lib.baseboard_fab2(sch_1):page81_i186:dq(11)"
				( attribute "PN" "168"
					( Origin gPackager )
				)
				( objectStatus "J1G3.168" )
			)
			( pin "@baseboard_fab2_lib.baseboard_fab2(sch_1):page81_i186:dq(12)"
				( attribute "PN" "14"
					( Origin gPackager )
				)
				( objectStatus "J1G3.14" )
			)
			( pin "@baseboard_fab2_lib.baseboard_fab2(sch_1):page81_i186:dq(13)"
				( attribute "PN" "159"
					( Origin gPackager )
				)
				( objectStatus "J1G3.159" )
			)
			( pin "@baseboard_fab2_lib.baseboard_fab2(sch_1):page81_i186:dq(14)"
				( attribute "PN" "21"
					( Origin gPackager )
				)
				( objectStatus "J1G3.21" )
			)
			( pin "@baseboard_fab2_lib.baseboard_fab2(sch_1):page81_i186:dq(15)"
				( attribute "PN" "166"
					( Origin gPackager )
				)
				( objectStatus "J1G3.166" )
			)
			( pin "@baseboard_fab2_lib.baseboard_fab2(sch_1):page81_i186:dq(16)"
				( attribute "PN" "27"
					( Origin gPackager )
				)
				( objectStatus "J1G3.27" )
			)
			( pin "@baseboard_fab2_lib.baseboard_fab2(sch_1):page81_i186:dq(17)"
				( attribute "PN" "172"
					( Origin gPackager )
				)
				( objectStatus "J1G3.172" )
			)
			( pin "@baseboard_fab2_lib.baseboard_fab2(sch_1):page81_i186:dq(18)"
				( attribute "PN" "34"
					( Origin gPackager )
				)
				( objectStatus "J1G3.34" )
			)
			( pin "@baseboard_fab2_lib.baseboard_fab2(sch_1):page81_i186:dq(19)"
				( attribute "PN" "179"
					( Origin gPackager )
				)
				( objectStatus "J1G3.179" )
			)
			( pin "@baseboard_fab2_lib.baseboard_fab2(sch_1):page81_i186:dq(20)"
				( attribute "PN" "25"
					( Origin gPackager )
				)
				( objectStatus "J1G3.25" )
			)
			( pin "@baseboard_fab2_lib.baseboard_fab2(sch_1):page81_i186:dq(21)"
				( attribute "PN" "170"
					( Origin gPackager )
				)
				( objectStatus "J1G3.170" )
			)
			( pin "@baseboard_fab2_lib.baseboard_fab2(sch_1):page81_i186:dq(22)"
				( attribute "PN" "32"
					( Origin gPackager )
				)
				( objectStatus "J1G3.32" )
			)
			( pin "@baseboard_fab2_lib.baseboard_fab2(sch_1):page81_i186:dq(23)"
				( attribute "PN" "177"
					( Origin gPackager )
				)
				( objectStatus "J1G3.177" )
			)
			( pin "@baseboard_fab2_lib.baseboard_fab2(sch_1):page81_i186:dq(24)"
				( attribute "PN" "38"
					( Origin gPackager )
				)
				( objectStatus "J1G3.38" )
			)
			( pin "@baseboard_fab2_lib.baseboard_fab2(sch_1):page81_i186:dq(25)"
				( attribute "PN" "183"
					( Origin gPackager )
				)
				( objectStatus "J1G3.183" )
			)
			( pin "@baseboard_fab2_lib.baseboard_fab2(sch_1):page81_i186:dq(26)"
				( attribute "PN" "45"
					( Origin gPackager )
				)
				( objectStatus "J1G3.45" )
			)
			( pin "@baseboard_fab2_lib.baseboard_fab2(sch_1):page81_i186:dq(27)"
				( attribute "PN" "190"
					( Origin gPackager )
				)
				( objectStatus "J1G3.190" )
			)
			( pin "@baseboard_fab2_lib.baseboard_fab2(sch_1):page81_i186:dq(28)"
				( attribute "PN" "36"
					( Origin gPackager )
				)
				( objectStatus "J1G3.36" )
			)
			( pin "@baseboard_fab2_lib.baseboard_fab2(sch_1):page81_i186:dq(29)"
				( attribute "PN" "181"
					( Origin gPackager )
				)
				( objectStatus "J1G3.181" )
			)
			( pin "@baseboard_fab2_lib.baseboard_fab2(sch_1):page81_i186:dq(30)"
				( attribute "PN" "43"
					( Origin gPackager )
				)
				( objectStatus "J1G3.43" )
			)
			( pin "@baseboard_fab2_lib.baseboard_fab2(sch_1):page81_i186:dq(31)"
				( attribute "PN" "188"
					( Origin gPackager )
				)
				( objectStatus "J1G3.188" )
			)
			( pin "@baseboard_fab2_lib.baseboard_fab2(sch_1):page81_i186:dq(32)"
				( attribute "PN" "97"
					( Origin gPackager )
				)
				( objectStatus "J1G3.97" )
			)
			( pin "@baseboard_fab2_lib.baseboard_fab2(sch_1):page81_i186:dq(33)"
				( attribute "PN" "242"
					( Origin gPackager )
				)
				( objectStatus "J1G3.242" )
			)
			( pin "@baseboard_fab2_lib.baseboard_fab2(sch_1):page81_i186:dq(34)"
				( attribute "PN" "104"
					( Origin gPackager )
				)
				( objectStatus "J1G3.104" )
			)
			( pin "@baseboard_fab2_lib.baseboard_fab2(sch_1):page81_i186:dq(35)"
				( attribute "PN" "249"
					( Origin gPackager )
				)
				( objectStatus "J1G3.249" )
			)
			( pin "@baseboard_fab2_lib.baseboard_fab2(sch_1):page81_i186:dq(36)"
				( attribute "PN" "95"
					( Origin gPackager )
				)
				( objectStatus "J1G3.95" )
			)
			( pin "@baseboard_fab2_lib.baseboard_fab2(sch_1):page81_i186:dq(37)"
				( attribute "PN" "240"
					( Origin gPackager )
				)
				( objectStatus "J1G3.240" )
			)
			( pin "@baseboard_fab2_lib.baseboard_fab2(sch_1):page81_i186:dq(38)"
				( attribute "PN" "102"
					( Origin gPackager )
				)
				( objectStatus "J1G3.102" )
			)
			( pin "@baseboard_fab2_lib.baseboard_fab2(sch_1):page81_i186:dq(39)"
				( attribute "PN" "247"
					( Origin gPackager )
				)
				( objectStatus "J1G3.247" )
			)
			( pin "@baseboard_fab2_lib.baseboard_fab2(sch_1):page81_i186:dq(40)"
				( attribute "PN" "108"
					( Origin gPackager )
				)
				( objectStatus "J1G3.108" )
			)
			( pin "@baseboard_fab2_lib.baseboard_fab2(sch_1):page81_i186:dq(41)"
				( attribute "PN" "253"
					( Origin gPackager )
				)
				( objectStatus "J1G3.253" )
			)
			( pin "@baseboard_fab2_lib.baseboard_fab2(sch_1):page81_i186:dq(42)"
				( attribute "PN" "115"
					( Origin gPackager )
				)
				( objectStatus "J1G3.115" )
			)
			( pin "@baseboard_fab2_lib.baseboard_fab2(sch_1):page81_i186:dq(43)"
				( attribute "PN" "260"
					( Origin gPackager )
				)
				( objectStatus "J1G3.260" )
			)
			( pin "@baseboard_fab2_lib.baseboard_fab2(sch_1):page81_i186:dq(44)"
				( attribute "PN" "106"
					( Origin gPackager )
				)
				( objectStatus "J1G3.106" )
			)
			( pin "@baseboard_fab2_lib.baseboard_fab2(sch_1):page81_i186:dq(45)"
				( attribute "PN" "251"
					( Origin gPackager )
				)
				( objectStatus "J1G3.251" )
			)
			( pin "@baseboard_fab2_lib.baseboard_fab2(sch_1):page81_i186:dq(46)"
				( attribute "PN" "113"
					( Origin gPackager )
				)
				( objectStatus "J1G3.113" )
			)
			( pin "@baseboard_fab2_lib.baseboard_fab2(sch_1):page81_i186:dq(47)"
				( attribute "PN" "258"
					( Origin gPackager )
				)
				( objectStatus "J1G3.258" )
			)
			( pin "@baseboard_fab2_lib.baseboard_fab2(sch_1):page81_i186:dq(48)"
				( attribute "PN" "119"
					( Origin gPackager )
				)
				( objectStatus "J1G3.119" )
			)
			( pin "@baseboard_fab2_lib.baseboard_fab2(sch_1):page81_i186:dq(49)"
				( attribute "PN" "264"
					( Origin gPackager )
				)
				( objectStatus "J1G3.264" )
			)
			( pin "@baseboard_fab2_lib.baseboard_fab2(sch_1):page81_i186:dq(50)"
				( attribute "PN" "126"
					( Origin gPackager )
				)
				( objectStatus "J1G3.126" )
			)
			( pin "@baseboard_fab2_lib.baseboard_fab2(sch_1):page81_i186:dq(51)"
				( attribute "PN" "271"
					( Origin gPackager )
				)
				( objectStatus "J1G3.271" )
			)
			( pin "@baseboard_fab2_lib.baseboard_fab2(sch_1):page81_i186:dq(52)"
				( attribute "PN" "117"
					( Origin gPackager )
				)
				( objectStatus "J1G3.117" )
			)
			( pin "@baseboard_fab2_lib.baseboard_fab2(sch_1):page81_i186:dq(53)"
				( attribute "PN" "262"
					( Origin gPackager )
				)
				( objectStatus "J1G3.262" )
			)
			( pin "@baseboard_fab2_lib.baseboard_fab2(sch_1):page81_i186:dq(54)"
				( attribute "PN" "124"
					( Origin gPackager )
				)
				( objectStatus "J1G3.124" )
			)
			( pin "@baseboard_fab2_lib.baseboard_fab2(sch_1):page81_i186:dq(55)"
				( attribute "PN" "269"
					( Origin gPackager )
				)
				( objectStatus "J1G3.269" )
			)
			( pin "@baseboard_fab2_lib.baseboard_fab2(sch_1):page81_i186:dq(56)"
				( attribute "PN" "130"
					( Origin gPackager )
				)
				( objectStatus "J1G3.130" )
			)
			( pin "@baseboard_fab2_lib.baseboard_fab2(sch_1):page81_i186:dq(57)"
				( attribute "PN" "275"
					( Origin gPackager )
				)
				( objectStatus "J1G3.275" )
			)
			( pin "@baseboard_fab2_lib.baseboard_fab2(sch_1):page81_i186:dq(58)"
				( attribute "PN" "137"
					( Origin gPackager )
				)
				( objectStatus "J1G3.137" )
			)
			( pin "@baseboard_fab2_lib.baseboard_fab2(sch_1):page81_i186:dq(59)"
				( attribute "PN" "282"
					( Origin gPackager )
				)
				( objectStatus "J1G3.282" )
			)
			( pin "@baseboard_fab2_lib.baseboard_fab2(sch_1):page81_i186:dq(60)"
				( attribute "PN" "128"
					( Origin gPackager )
				)
				( objectStatus "J1G3.128" )
			)
			( pin "@baseboard_fab2_lib.baseboard_fab2(sch_1):page81_i186:dq(61)"
				( attribute "PN" "273"
					( Origin gPackager )
				)
				( objectStatus "J1G3.273" )
			)
			( pin "@baseboard_fab2_lib.baseboard_fab2(sch_1):page81_i186:dq(62)"
				( attribute "PN" "135"
					( Origin gPackager )
				)
				( objectStatus "J1G3.135" )
			)
			( pin "@baseboard_fab2_lib.baseboard_fab2(sch_1):page81_i186:dq(63)"
				( attribute "PN" "280"
					( Origin gPackager )
				)
				( objectStatus "J1G3.280" )
			)
			( pin "@baseboard_fab2_lib.baseboard_fab2(sch_1):page81_i186:event_n"
				( attribute "PN" "78"
					( Origin gPackager )
				)
				( objectStatus "J1G3.78" )
			)
			( pin "@baseboard_fab2_lib.baseboard_fab2(sch_1):page81_i186:odt(0)"
				( attribute "PN" "87"
					( Origin gPackager )
				)
				( objectStatus "J1G3.87" )
			)
			( pin "@baseboard_fab2_lib.baseboard_fab2(sch_1):page81_i186:odt(1)"
				( attribute "PN" "91"
					( Origin gPackager )
				)
				( objectStatus "J1G3.91" )
			)
			( pin "@baseboard_fab2_lib.baseboard_fab2(sch_1):page81_i186:par"
				( attribute "PN" "222"
					( Origin gPackager )
				)
				( objectStatus "J1G3.222" )
			)
			( pin "@baseboard_fab2_lib.baseboard_fab2(sch_1):page81_i186:reset_n"
				( attribute "PN" "58"
					( Origin gPackager )
				)
				( objectStatus "J1G3.58" )
			)
			( pin "@baseboard_fab2_lib.baseboard_fab2(sch_1):page81_i186:rfu(0)"
				( attribute "PN" "205"
					( Origin gPackager )
				)
				( objectStatus "J1G3.205" )
			)
			( pin "@baseboard_fab2_lib.baseboard_fab2(sch_1):page81_i186:rfu(1)"
				( attribute "PN" "227"
					( Origin gPackager )
				)
				( objectStatus "J1G3.227" )
			)
			( pin "@baseboard_fab2_lib.baseboard_fab2(sch_1):page81_i186:rfu(2)"
				( attribute "PN" "144"
					( Origin gPackager )
				)
				( objectStatus "J1G3.144" )
			)
			( pin "@baseboard_fab2_lib.baseboard_fab2(sch_1):page81_i186:s0_n"
				( attribute "PN" "84"
					( Origin gPackager )
				)
				( objectStatus "J1G3.84" )
			)
			( pin "@baseboard_fab2_lib.baseboard_fab2(sch_1):page81_i186:s1_n"
				( attribute "PN" "89"
					( Origin gPackager )
				)
				( objectStatus "J1G3.89" )
			)
			( pin "@baseboard_fab2_lib.baseboard_fab2(sch_1):page81_i186:s2_n_c(0)"
				( attribute "PN" "93"
					( Origin gPackager )
				)
				( objectStatus "J1G3.93" )
			)
			( pin "@baseboard_fab2_lib.baseboard_fab2(sch_1):page81_i186:s3_n_c(1)"
				( attribute "PN" "237"
					( Origin gPackager )
				)
				( objectStatus "J1G3.237" )
			)
			( pin "@baseboard_fab2_lib.baseboard_fab2(sch_1):page81_i186:sa(0)"
				( attribute "PN" "139"
					( Origin gPackager )
				)
				( objectStatus "J1G3.139" )
			)
			( pin "@baseboard_fab2_lib.baseboard_fab2(sch_1):page81_i186:sa(1)"
				( attribute "PN" "140"
					( Origin gPackager )
				)
				( objectStatus "J1G3.140" )
			)
			( pin "@baseboard_fab2_lib.baseboard_fab2(sch_1):page81_i186:sa(2)"
				( attribute "PN" "238"
					( Origin gPackager )
				)
				( objectStatus "J1G3.238" )
			)
			( pin "@baseboard_fab2_lib.baseboard_fab2(sch_1):page81_i186:save_n_nc"
				( attribute "PN" "230"
					( Origin gPackager )
				)
				( objectStatus "J1G3.230" )
			)
			( pin "@baseboard_fab2_lib.baseboard_fab2(sch_1):page81_i186:scl"
				( attribute "PN" "141"
					( Origin gPackager )
				)
				( objectStatus "J1G3.141" )
			)
			( pin "@baseboard_fab2_lib.baseboard_fab2(sch_1):page81_i186:sda"
				( attribute "PN" "285"
					( Origin gPackager )
				)
				( objectStatus "J1G3.285" )
			)
			( pin "@baseboard_fab2_lib.baseboard_fab2(sch_1):page81_i186:vddspd"
				( attribute "PN" "284"
					( Origin gPackager )
				)
				( objectStatus "J1G3.284" )
			)
			( pin "@baseboard_fab2_lib.baseboard_fab2(sch_1):page81_i186:vrefca"
				( attribute "PN" "146"
					( Origin gPackager )
				)
				( objectStatus "J1G3.146" )
			)
			( pin "@baseboard_fab2_lib.baseboard_fab2(sch_1):page82_i64:dqs0n"
				( attribute "PN" "152"
					( Origin gPackager )
				)
				( objectStatus "J9U2.152" )
			)
			( pin "@baseboard_fab2_lib.baseboard_fab2(sch_1):page82_i64:dqs0p"
				( attribute "PN" "153"
					( Origin gPackager )
				)
				( objectStatus "J9U2.153" )
			)
			( pin "@baseboard_fab2_lib.baseboard_fab2(sch_1):page82_i64:dqs1n"
				( attribute "PN" "163"
					( Origin gPackager )
				)
				( objectStatus "J9U2.163" )
			)
			( pin "@baseboard_fab2_lib.baseboard_fab2(sch_1):page82_i64:dqs1p"
				( attribute "PN" "164"
					( Origin gPackager )
				)
				( objectStatus "J9U2.164" )
			)
			( pin "@baseboard_fab2_lib.baseboard_fab2(sch_1):page82_i64:dqs2n"
				( attribute "PN" "174"
					( Origin gPackager )
				)
				( objectStatus "J9U2.174" )
			)
			( pin "@baseboard_fab2_lib.baseboard_fab2(sch_1):page82_i64:dqs2p"
				( attribute "PN" "175"
					( Origin gPackager )
				)
				( objectStatus "J9U2.175" )
			)
			( pin "@baseboard_fab2_lib.baseboard_fab2(sch_1):page82_i64:dqs3n"
				( attribute "PN" "185"
					( Origin gPackager )
				)
				( objectStatus "J9U2.185" )
			)
			( pin "@baseboard_fab2_lib.baseboard_fab2(sch_1):page82_i64:dqs3p"
				( attribute "PN" "186"
					( Origin gPackager )
				)
				( objectStatus "J9U2.186" )
			)
			( pin "@baseboard_fab2_lib.baseboard_fab2(sch_1):page82_i64:dqs4n"
				( attribute "PN" "244"
					( Origin gPackager )
				)
				( objectStatus "J9U2.244" )
			)
			( pin "@baseboard_fab2_lib.baseboard_fab2(sch_1):page82_i64:dqs4p"
				( attribute "PN" "245"
					( Origin gPackager )
				)
				( objectStatus "J9U2.245" )
			)
			( pin "@baseboard_fab2_lib.baseboard_fab2(sch_1):page82_i64:dqs5n"
				( attribute "PN" "255"
					( Origin gPackager )
				)
				( objectStatus "J9U2.255" )
			)
			( pin "@baseboard_fab2_lib.baseboard_fab2(sch_1):page82_i64:dqs5p"
				( attribute "PN" "256"
					( Origin gPackager )
				)
				( objectStatus "J9U2.256" )
			)
			( pin "@baseboard_fab2_lib.baseboard_fab2(sch_1):page82_i64:dqs6n"
				( attribute "PN" "266"
					( Origin gPackager )
				)
				( objectStatus "J9U2.266" )
			)
			( pin "@baseboard_fab2_lib.baseboard_fab2(sch_1):page82_i64:dqs6p"
				( attribute "PN" "267"
					( Origin gPackager )
				)
				( objectStatus "J9U2.267" )
			)
			( pin "@baseboard_fab2_lib.baseboard_fab2(sch_1):page82_i64:dqs7n"
				( attribute "PN" "277"
					( Origin gPackager )
				)
				( objectStatus "J9U2.277" )
			)
			( pin "@baseboard_fab2_lib.baseboard_fab2(sch_1):page82_i64:dqs7p"
				( attribute "PN" "278"
					( Origin gPackager )
				)
				( objectStatus "J9U2.278" )
			)
			( pin "@baseboard_fab2_lib.baseboard_fab2(sch_1):page82_i64:dqs8n"
				( attribute "PN" "196"
					( Origin gPackager )
				)
				( objectStatus "J9U2.196" )
			)
			( pin "@baseboard_fab2_lib.baseboard_fab2(sch_1):page82_i64:dqs8p"
				( attribute "PN" "197"
					( Origin gPackager )
				)
				( objectStatus "J9U2.197" )
			)
			( pin "@baseboard_fab2_lib.baseboard_fab2(sch_1):page82_i64:dqs9n"
				( attribute "PN" "8"
					( Origin gPackager )
				)
				( objectStatus "J9U2.8" )
			)
			( pin "@baseboard_fab2_lib.baseboard_fab2(sch_1):page82_i64:dqs9p"
				( attribute "PN" "7"
					( Origin gPackager )
				)
				( objectStatus "J9U2.7" )
			)
			( pin "@baseboard_fab2_lib.baseboard_fab2(sch_1):page82_i64:dqs10n"
				( attribute "PN" "19"
					( Origin gPackager )
				)
				( objectStatus "J9U2.19" )
			)
			( pin "@baseboard_fab2_lib.baseboard_fab2(sch_1):page82_i64:dqs10p"
				( attribute "PN" "18"
					( Origin gPackager )
				)
				( objectStatus "J9U2.18" )
			)
			( pin "@baseboard_fab2_lib.baseboard_fab2(sch_1):page82_i64:dqs11n"
				( attribute "PN" "30"
					( Origin gPackager )
				)
				( objectStatus "J9U2.30" )
			)
			( pin "@baseboard_fab2_lib.baseboard_fab2(sch_1):page82_i64:dqs11p"
				( attribute "PN" "29"
					( Origin gPackager )
				)
				( objectStatus "J9U2.29" )
			)
			( pin "@baseboard_fab2_lib.baseboard_fab2(sch_1):page82_i64:dqs12n"
				( attribute "PN" "41"
					( Origin gPackager )
				)
				( objectStatus "J9U2.41" )
			)
			( pin "@baseboard_fab2_lib.baseboard_fab2(sch_1):page82_i64:dqs12p"
				( attribute "PN" "40"
					( Origin gPackager )
				)
				( objectStatus "J9U2.40" )
			)
			( pin "@baseboard_fab2_lib.baseboard_fab2(sch_1):page82_i64:dqs13n"
				( attribute "PN" "100"
					( Origin gPackager )
				)
				( objectStatus "J9U2.100" )
			)
			( pin "@baseboard_fab2_lib.baseboard_fab2(sch_1):page82_i64:dqs13p"
				( attribute "PN" "99"
					( Origin gPackager )
				)
				( objectStatus "J9U2.99" )
			)
			( pin "@baseboard_fab2_lib.baseboard_fab2(sch_1):page82_i64:dqs14n"
				( attribute "PN" "111"
					( Origin gPackager )
				)
				( objectStatus "J9U2.111" )
			)
			( pin "@baseboard_fab2_lib.baseboard_fab2(sch_1):page82_i64:dqs14p"
				( attribute "PN" "110"
					( Origin gPackager )
				)
				( objectStatus "J9U2.110" )
			)
			( pin "@baseboard_fab2_lib.baseboard_fab2(sch_1):page82_i64:dqs15n"
				( attribute "PN" "122"
					( Origin gPackager )
				)
				( objectStatus "J9U2.122" )
			)
			( pin "@baseboard_fab2_lib.baseboard_fab2(sch_1):page82_i64:dqs15p"
				( attribute "PN" "121"
					( Origin gPackager )
				)
				( objectStatus "J9U2.121" )
			)
			( pin "@baseboard_fab2_lib.baseboard_fab2(sch_1):page82_i64:dqs16n"
				( attribute "PN" "133"
					( Origin gPackager )
				)
				( objectStatus "J9U2.133" )
			)
			( pin "@baseboard_fab2_lib.baseboard_fab2(sch_1):page82_i64:dqs16p"
				( attribute "PN" "132"
					( Origin gPackager )
				)
				( objectStatus "J9U2.132" )
			)
			( pin "@baseboard_fab2_lib.baseboard_fab2(sch_1):page82_i64:dqs17n"
				( attribute "PN" "52"
					( Origin gPackager )
				)
				( objectStatus "J9U2.52" )
			)
			( pin "@baseboard_fab2_lib.baseboard_fab2(sch_1):page82_i64:dqs17p"
				( attribute "PN" "51"
					( Origin gPackager )
				)
				( objectStatus "J9U2.51" )
			)
			( pin "@baseboard_fab2_lib.baseboard_fab2(sch_1):page82_i171:\12v\(0)"
				( attribute "PN" "145"
					( Origin gPackager )
				)
				( objectStatus "J9U2.145" )
			)
			( pin "@baseboard_fab2_lib.baseboard_fab2(sch_1):page82_i171:\12v\(1)"
				( attribute "PN" "1"
					( Origin gPackager )
				)
				( objectStatus "J9U2.1" )
			)
			( pin "@baseboard_fab2_lib.baseboard_fab2(sch_1):page82_i171:vdd(0)"
				( attribute "PN" "236"
					( Origin gPackager )
				)
				( objectStatus "J9U2.236" )
			)
			( pin "@baseboard_fab2_lib.baseboard_fab2(sch_1):page82_i171:vdd(1)"
				( attribute "PN" "233"
					( Origin gPackager )
				)
				( objectStatus "J9U2.233" )
			)
			( pin "@baseboard_fab2_lib.baseboard_fab2(sch_1):page82_i171:vdd(2)"
				( attribute "PN" "231"
					( Origin gPackager )
				)
				( objectStatus "J9U2.231" )
			)
			( pin "@baseboard_fab2_lib.baseboard_fab2(sch_1):page82_i171:vdd(3)"
				( attribute "PN" "229"
					( Origin gPackager )
				)
				( objectStatus "J9U2.229" )
			)
			( pin "@baseboard_fab2_lib.baseboard_fab2(sch_1):page82_i171:vdd(4)"
				( attribute "PN" "226"
					( Origin gPackager )
				)
				( objectStatus "J9U2.226" )
			)
			( pin "@baseboard_fab2_lib.baseboard_fab2(sch_1):page82_i171:vdd(5)"
				( attribute "PN" "223"
					( Origin gPackager )
				)
				( objectStatus "J9U2.223" )
			)
			( pin "@baseboard_fab2_lib.baseboard_fab2(sch_1):page82_i171:vdd(6)"
				( attribute "PN" "220"
					( Origin gPackager )
				)
				( objectStatus "J9U2.220" )
			)
			( pin "@baseboard_fab2_lib.baseboard_fab2(sch_1):page82_i171:vdd(7)"
				( attribute "PN" "217"
					( Origin gPackager )
				)
				( objectStatus "J9U2.217" )
			)
			( pin "@baseboard_fab2_lib.baseboard_fab2(sch_1):page82_i171:vdd(8)"
				( attribute "PN" "215"
					( Origin gPackager )
				)
				( objectStatus "J9U2.215" )
			)
			( pin "@baseboard_fab2_lib.baseboard_fab2(sch_1):page82_i171:vdd(9)"
				( attribute "PN" "212"
					( Origin gPackager )
				)
				( objectStatus "J9U2.212" )
			)
			( pin "@baseboard_fab2_lib.baseboard_fab2(sch_1):page82_i171:vdd(10)"
				( attribute "PN" "209"
					( Origin gPackager )
				)
				( objectStatus "J9U2.209" )
			)
			( pin "@baseboard_fab2_lib.baseboard_fab2(sch_1):page82_i171:vdd(11)"
				( attribute "PN" "206"
					( Origin gPackager )
				)
				( objectStatus "J9U2.206" )
			)
			( pin "@baseboard_fab2_lib.baseboard_fab2(sch_1):page82_i171:vdd(12)"
				( attribute "PN" "204"
					( Origin gPackager )
				)
				( objectStatus "J9U2.204" )
			)
			( pin "@baseboard_fab2_lib.baseboard_fab2(sch_1):page82_i171:vdd(13)"
				( attribute "PN" "92"
					( Origin gPackager )
				)
				( objectStatus "J9U2.92" )
			)
			( pin "@baseboard_fab2_lib.baseboard_fab2(sch_1):page82_i171:vdd(14)"
				( attribute "PN" "90"
					( Origin gPackager )
				)
				( objectStatus "J9U2.90" )
			)
			( pin "@baseboard_fab2_lib.baseboard_fab2(sch_1):page82_i171:vdd(15)"
				( attribute "PN" "88"
					( Origin gPackager )
				)
				( objectStatus "J9U2.88" )
			)
			( pin "@baseboard_fab2_lib.baseboard_fab2(sch_1):page82_i171:vdd(16)"
				( attribute "PN" "85"
					( Origin gPackager )
				)
				( objectStatus "J9U2.85" )
			)
			( pin "@baseboard_fab2_lib.baseboard_fab2(sch_1):page82_i171:vdd(17)"
				( attribute "PN" "83"
					( Origin gPackager )
				)
				( objectStatus "J9U2.83" )
			)
			( pin "@baseboard_fab2_lib.baseboard_fab2(sch_1):page82_i171:vdd(18)"
				( attribute "PN" "80"
					( Origin gPackager )
				)
				( objectStatus "J9U2.80" )
			)
			( pin "@baseboard_fab2_lib.baseboard_fab2(sch_1):page82_i171:vdd(19)"
				( attribute "PN" "76"
					( Origin gPackager )
				)
				( objectStatus "J9U2.76" )
			)
			( pin "@baseboard_fab2_lib.baseboard_fab2(sch_1):page82_i171:vdd(20)"
				( attribute "PN" "73"
					( Origin gPackager )
				)
				( objectStatus "J9U2.73" )
			)
			( pin "@baseboard_fab2_lib.baseboard_fab2(sch_1):page82_i171:vdd(21)"
				( attribute "PN" "70"
					( Origin gPackager )
				)
				( objectStatus "J9U2.70" )
			)
			( pin "@baseboard_fab2_lib.baseboard_fab2(sch_1):page82_i171:vdd(22)"
				( attribute "PN" "67"
					( Origin gPackager )
				)
				( objectStatus "J9U2.67" )
			)
			( pin "@baseboard_fab2_lib.baseboard_fab2(sch_1):page82_i171:vdd(23)"
				( attribute "PN" "64"
					( Origin gPackager )
				)
				( objectStatus "J9U2.64" )
			)
			( pin "@baseboard_fab2_lib.baseboard_fab2(sch_1):page82_i171:vdd(24)"
				( attribute "PN" "61"
					( Origin gPackager )
				)
				( objectStatus "J9U2.61" )
			)
			( pin "@baseboard_fab2_lib.baseboard_fab2(sch_1):page82_i171:vdd(25)"
				( attribute "PN" "59"
					( Origin gPackager )
				)
				( objectStatus "J9U2.59" )
			)
			( pin "@baseboard_fab2_lib.baseboard_fab2(sch_1):page82_i171:vpp(0)"
				( attribute "PN" "287"
					( Origin gPackager )
				)
				( objectStatus "J9U2.287" )
			)
			( pin "@baseboard_fab2_lib.baseboard_fab2(sch_1):page82_i171:vpp(1)"
				( attribute "PN" "286"
					( Origin gPackager )
				)
				( objectStatus "J9U2.286" )
			)
			( pin "@baseboard_fab2_lib.baseboard_fab2(sch_1):page82_i171:vpp(2)"
				( attribute "PN" "288"
					( Origin gPackager )
				)
				( objectStatus "J9U2.288" )
			)
			( pin "@baseboard_fab2_lib.baseboard_fab2(sch_1):page82_i171:vpp(3)"
				( attribute "PN" "143"
					( Origin gPackager )
				)
				( objectStatus "J9U2.143" )
			)
			( pin "@baseboard_fab2_lib.baseboard_fab2(sch_1):page82_i171:vpp(4)"
				( attribute "PN" "142"
					( Origin gPackager )
				)
				( objectStatus "J9U2.142" )
			)
			( pin "@baseboard_fab2_lib.baseboard_fab2(sch_1):page82_i171:vtt(0)"
				( attribute "PN" "221"
					( Origin gPackager )
				)
				( objectStatus "J9U2.221" )
			)
			( pin "@baseboard_fab2_lib.baseboard_fab2(sch_1):page82_i171:vtt(1)"
				( attribute "PN" "77"
					( Origin gPackager )
				)
				( objectStatus "J9U2.77" )
			)
			( pin "@baseboard_fab2_lib.baseboard_fab2(sch_1):page82_i180:a"
				( attribute "PN" "1"
					( Origin gPackager )
				)
				( objectStatus "C1G19.1" )
			)
			( pin "@baseboard_fab2_lib.baseboard_fab2(sch_1):page82_i180:b"
				( attribute "PN" "2"
					( Origin gPackager )
				)
				( objectStatus "C1G19.2" )
			)
			( pin "@baseboard_fab2_lib.baseboard_fab2(sch_1):page82_i187:a0"
				( attribute "PN" "79"
					( Origin gPackager )
				)
				( objectStatus "J9U2.79" )
			)
			( pin "@baseboard_fab2_lib.baseboard_fab2(sch_1):page82_i187:a1"
				( attribute "PN" "72"
					( Origin gPackager )
				)
				( objectStatus "J9U2.72" )
			)
			( pin "@baseboard_fab2_lib.baseboard_fab2(sch_1):page82_i187:a2"
				( attribute "PN" "216"
					( Origin gPackager )
				)
				( objectStatus "J9U2.216" )
			)
			( pin "@baseboard_fab2_lib.baseboard_fab2(sch_1):page82_i187:a3"
				( attribute "PN" "71"
					( Origin gPackager )
				)
				( objectStatus "J9U2.71" )
			)
			( pin "@baseboard_fab2_lib.baseboard_fab2(sch_1):page82_i187:a4"
				( attribute "PN" "214"
					( Origin gPackager )
				)
				( objectStatus "J9U2.214" )
			)
			( pin "@baseboard_fab2_lib.baseboard_fab2(sch_1):page82_i187:a5"
				( attribute "PN" "213"
					( Origin gPackager )
				)
				( objectStatus "J9U2.213" )
			)
			( pin "@baseboard_fab2_lib.baseboard_fab2(sch_1):page82_i187:a6"
				( attribute "PN" "69"
					( Origin gPackager )
				)
				( objectStatus "J9U2.69" )
			)
			( pin "@baseboard_fab2_lib.baseboard_fab2(sch_1):page82_i187:a7"
				( attribute "PN" "211"
					( Origin gPackager )
				)
				( objectStatus "J9U2.211" )
			)
			( pin "@baseboard_fab2_lib.baseboard_fab2(sch_1):page82_i187:a8"
				( attribute "PN" "68"
					( Origin gPackager )
				)
				( objectStatus "J9U2.68" )
			)
			( pin "@baseboard_fab2_lib.baseboard_fab2(sch_1):page82_i187:a9"
				( attribute "PN" "66"
					( Origin gPackager )
				)
				( objectStatus "J9U2.66" )
			)
			( pin "@baseboard_fab2_lib.baseboard_fab2(sch_1):page82_i187:a10"
				( attribute "PN" "225"
					( Origin gPackager )
				)
				( objectStatus "J9U2.225" )
			)
			( pin "@baseboard_fab2_lib.baseboard_fab2(sch_1):page82_i187:a11"
				( attribute "PN" "210"
					( Origin gPackager )
				)
				( objectStatus "J9U2.210" )
			)
			( pin "@baseboard_fab2_lib.baseboard_fab2(sch_1):page82_i187:a12"
				( attribute "PN" "65"
					( Origin gPackager )
				)
				( objectStatus "J9U2.65" )
			)
			( pin "@baseboard_fab2_lib.baseboard_fab2(sch_1):page82_i187:a13"
				( attribute "PN" "232"
					( Origin gPackager )
				)
				( objectStatus "J9U2.232" )
			)
			( pin "@baseboard_fab2_lib.baseboard_fab2(sch_1):page82_i187:a14_we_n"
				( attribute "PN" "228"
					( Origin gPackager )
				)
				( objectStatus "J9U2.228" )
			)
			( pin "@baseboard_fab2_lib.baseboard_fab2(sch_1):page82_i187:a15_cas_n"
				( attribute "PN" "86"
					( Origin gPackager )
				)
				( objectStatus "J9U2.86" )
			)
			( pin "@baseboard_fab2_lib.baseboard_fab2(sch_1):page82_i187:a16_ras_n"
				( attribute "PN" "82"
					( Origin gPackager )
				)
				( objectStatus "J9U2.82" )
			)
			( pin "@baseboard_fab2_lib.baseboard_fab2(sch_1):page82_i187:a17"
				( attribute "PN" "234"
					( Origin gPackager )
				)
				( objectStatus "J9U2.234" )
			)
			( pin "@baseboard_fab2_lib.baseboard_fab2(sch_1):page82_i187:act_n"
				( attribute "PN" "62"
					( Origin gPackager )
				)
				( objectStatus "J9U2.62" )
			)
			( pin "@baseboard_fab2_lib.baseboard_fab2(sch_1):page82_i187:alert_n"
				( attribute "PN" "208"
					( Origin gPackager )
				)
				( objectStatus "J9U2.208" )
			)
			( pin "@baseboard_fab2_lib.baseboard_fab2(sch_1):page82_i187:ba(0)"
				( attribute "PN" "81"
					( Origin gPackager )
				)
				( objectStatus "J9U2.81" )
			)
			( pin "@baseboard_fab2_lib.baseboard_fab2(sch_1):page82_i187:ba(1)"
				( attribute "PN" "224"
					( Origin gPackager )
				)
				( objectStatus "J9U2.224" )
			)
			( pin "@baseboard_fab2_lib.baseboard_fab2(sch_1):page82_i187:bg(0)"
				( attribute "PN" "63"
					( Origin gPackager )
				)
				( objectStatus "J9U2.63" )
			)
			( pin "@baseboard_fab2_lib.baseboard_fab2(sch_1):page82_i187:bg(1)"
				( attribute "PN" "207"
					( Origin gPackager )
				)
				( objectStatus "J9U2.207" )
			)
			( pin "@baseboard_fab2_lib.baseboard_fab2(sch_1):page82_i187:c(2)"
				( attribute "PN" "235"
					( Origin gPackager )
				)
				( objectStatus "J9U2.235" )
			)
			( pin "@baseboard_fab2_lib.baseboard_fab2(sch_1):page82_i187:cb(0)"
				( attribute "PN" "49"
					( Origin gPackager )
				)
				( objectStatus "J9U2.49" )
			)
			( pin "@baseboard_fab2_lib.baseboard_fab2(sch_1):page82_i187:cb(1)"
				( attribute "PN" "194"
					( Origin gPackager )
				)
				( objectStatus "J9U2.194" )
			)
			( pin "@baseboard_fab2_lib.baseboard_fab2(sch_1):page82_i187:cb(2)"
				( attribute "PN" "56"
					( Origin gPackager )
				)
				( objectStatus "J9U2.56" )
			)
			( pin "@baseboard_fab2_lib.baseboard_fab2(sch_1):page82_i187:cb(3)"
				( attribute "PN" "201"
					( Origin gPackager )
				)
				( objectStatus "J9U2.201" )
			)
			( pin "@baseboard_fab2_lib.baseboard_fab2(sch_1):page82_i187:cb(4)"
				( attribute "PN" "47"
					( Origin gPackager )
				)
				( objectStatus "J9U2.47" )
			)
			( pin "@baseboard_fab2_lib.baseboard_fab2(sch_1):page82_i187:cb(5)"
				( attribute "PN" "192"
					( Origin gPackager )
				)
				( objectStatus "J9U2.192" )
			)
			( pin "@baseboard_fab2_lib.baseboard_fab2(sch_1):page82_i187:cb(6)"
				( attribute "PN" "54"
					( Origin gPackager )
				)
				( objectStatus "J9U2.54" )
			)
			( pin "@baseboard_fab2_lib.baseboard_fab2(sch_1):page82_i187:cb(7)"
				( attribute "PN" "199"
					( Origin gPackager )
				)
				( objectStatus "J9U2.199" )
			)
			( pin "@baseboard_fab2_lib.baseboard_fab2(sch_1):page82_i187:ck0n"
				( attribute "PN" "75"
					( Origin gPackager )
				)
				( objectStatus "J9U2.75" )
			)
			( pin "@baseboard_fab2_lib.baseboard_fab2(sch_1):page82_i187:ck0p"
				( attribute "PN" "74"
					( Origin gPackager )
				)
				( objectStatus "J9U2.74" )
			)
			( pin "@baseboard_fab2_lib.baseboard_fab2(sch_1):page82_i187:ck1n"
				( attribute "PN" "219"
					( Origin gPackager )
				)
				( objectStatus "J9U2.219" )
			)
			( pin "@baseboard_fab2_lib.baseboard_fab2(sch_1):page82_i187:ck1p"
				( attribute "PN" "218"
					( Origin gPackager )
				)
				( objectStatus "J9U2.218" )
			)
			( pin "@baseboard_fab2_lib.baseboard_fab2(sch_1):page82_i187:cke(0)"
				( attribute "PN" "60"
					( Origin gPackager )
				)
				( objectStatus "J9U2.60" )
			)
			( pin "@baseboard_fab2_lib.baseboard_fab2(sch_1):page82_i187:cke(1)"
				( attribute "PN" "203"
					( Origin gPackager )
				)
				( objectStatus "J9U2.203" )
			)
			( pin "@baseboard_fab2_lib.baseboard_fab2(sch_1):page82_i187:dq(0)"
				( attribute "PN" "5"
					( Origin gPackager )
				)
				( objectStatus "J9U2.5" )
			)
			( pin "@baseboard_fab2_lib.baseboard_fab2(sch_1):page82_i187:dq(1)"
				( attribute "PN" "150"
					( Origin gPackager )
				)
				( objectStatus "J9U2.150" )
			)
			( pin "@baseboard_fab2_lib.baseboard_fab2(sch_1):page82_i187:dq(2)"
				( attribute "PN" "12"
					( Origin gPackager )
				)
				( objectStatus "J9U2.12" )
			)
			( pin "@baseboard_fab2_lib.baseboard_fab2(sch_1):page82_i187:dq(3)"
				( attribute "PN" "157"
					( Origin gPackager )
				)
				( objectStatus "J9U2.157" )
			)
			( pin "@baseboard_fab2_lib.baseboard_fab2(sch_1):page82_i187:dq(4)"
				( attribute "PN" "3"
					( Origin gPackager )
				)
				( objectStatus "J9U2.3" )
			)
			( pin "@baseboard_fab2_lib.baseboard_fab2(sch_1):page82_i187:dq(5)"
				( attribute "PN" "148"
					( Origin gPackager )
				)
				( objectStatus "J9U2.148" )
			)
			( pin "@baseboard_fab2_lib.baseboard_fab2(sch_1):page82_i187:dq(6)"
				( attribute "PN" "10"
					( Origin gPackager )
				)
				( objectStatus "J9U2.10" )
			)
			( pin "@baseboard_fab2_lib.baseboard_fab2(sch_1):page82_i187:dq(7)"
				( attribute "PN" "155"
					( Origin gPackager )
				)
				( objectStatus "J9U2.155" )
			)
			( pin "@baseboard_fab2_lib.baseboard_fab2(sch_1):page82_i187:dq(8)"
				( attribute "PN" "16"
					( Origin gPackager )
				)
				( objectStatus "J9U2.16" )
			)
			( pin "@baseboard_fab2_lib.baseboard_fab2(sch_1):page82_i187:dq(9)"
				( attribute "PN" "161"
					( Origin gPackager )
				)
				( objectStatus "J9U2.161" )
			)
			( pin "@baseboard_fab2_lib.baseboard_fab2(sch_1):page82_i187:dq(10)"
				( attribute "PN" "23"
					( Origin gPackager )
				)
				( objectStatus "J9U2.23" )
			)
			( pin "@baseboard_fab2_lib.baseboard_fab2(sch_1):page82_i187:dq(11)"
				( attribute "PN" "168"
					( Origin gPackager )
				)
				( objectStatus "J9U2.168" )
			)
			( pin "@baseboard_fab2_lib.baseboard_fab2(sch_1):page82_i187:dq(12)"
				( attribute "PN" "14"
					( Origin gPackager )
				)
				( objectStatus "J9U2.14" )
			)
			( pin "@baseboard_fab2_lib.baseboard_fab2(sch_1):page82_i187:dq(13)"
				( attribute "PN" "159"
					( Origin gPackager )
				)
				( objectStatus "J9U2.159" )
			)
			( pin "@baseboard_fab2_lib.baseboard_fab2(sch_1):page82_i187:dq(14)"
				( attribute "PN" "21"
					( Origin gPackager )
				)
				( objectStatus "J9U2.21" )
			)
			( pin "@baseboard_fab2_lib.baseboard_fab2(sch_1):page82_i187:dq(15)"
				( attribute "PN" "166"
					( Origin gPackager )
				)
				( objectStatus "J9U2.166" )
			)
			( pin "@baseboard_fab2_lib.baseboard_fab2(sch_1):page82_i187:dq(16)"
				( attribute "PN" "27"
					( Origin gPackager )
				)
				( objectStatus "J9U2.27" )
			)
			( pin "@baseboard_fab2_lib.baseboard_fab2(sch_1):page82_i187:dq(17)"
				( attribute "PN" "172"
					( Origin gPackager )
				)
				( objectStatus "J9U2.172" )
			)
			( pin "@baseboard_fab2_lib.baseboard_fab2(sch_1):page82_i187:dq(18)"
				( attribute "PN" "34"
					( Origin gPackager )
				)
				( objectStatus "J9U2.34" )
			)
			( pin "@baseboard_fab2_lib.baseboard_fab2(sch_1):page82_i187:dq(19)"
				( attribute "PN" "179"
					( Origin gPackager )
				)
				( objectStatus "J9U2.179" )
			)
			( pin "@baseboard_fab2_lib.baseboard_fab2(sch_1):page82_i187:dq(20)"
				( attribute "PN" "25"
					( Origin gPackager )
				)
				( objectStatus "J9U2.25" )
			)
			( pin "@baseboard_fab2_lib.baseboard_fab2(sch_1):page82_i187:dq(21)"
				( attribute "PN" "170"
					( Origin gPackager )
				)
				( objectStatus "J9U2.170" )
			)
			( pin "@baseboard_fab2_lib.baseboard_fab2(sch_1):page82_i187:dq(22)"
				( attribute "PN" "32"
					( Origin gPackager )
				)
				( objectStatus "J9U2.32" )
			)
			( pin "@baseboard_fab2_lib.baseboard_fab2(sch_1):page82_i187:dq(23)"
				( attribute "PN" "177"
					( Origin gPackager )
				)
				( objectStatus "J9U2.177" )
			)
			( pin "@baseboard_fab2_lib.baseboard_fab2(sch_1):page82_i187:dq(24)"
				( attribute "PN" "38"
					( Origin gPackager )
				)
				( objectStatus "J9U2.38" )
			)
			( pin "@baseboard_fab2_lib.baseboard_fab2(sch_1):page82_i187:dq(25)"
				( attribute "PN" "183"
					( Origin gPackager )
				)
				( objectStatus "J9U2.183" )
			)
			( pin "@baseboard_fab2_lib.baseboard_fab2(sch_1):page82_i187:dq(26)"
				( attribute "PN" "45"
					( Origin gPackager )
				)
				( objectStatus "J9U2.45" )
			)
			( pin "@baseboard_fab2_lib.baseboard_fab2(sch_1):page82_i187:dq(27)"
				( attribute "PN" "190"
					( Origin gPackager )
				)
				( objectStatus "J9U2.190" )
			)
			( pin "@baseboard_fab2_lib.baseboard_fab2(sch_1):page82_i187:dq(28)"
				( attribute "PN" "36"
					( Origin gPackager )
				)
				( objectStatus "J9U2.36" )
			)
			( pin "@baseboard_fab2_lib.baseboard_fab2(sch_1):page82_i187:dq(29)"
				( attribute "PN" "181"
					( Origin gPackager )
				)
				( objectStatus "J9U2.181" )
			)
			( pin "@baseboard_fab2_lib.baseboard_fab2(sch_1):page82_i187:dq(30)"
				( attribute "PN" "43"
					( Origin gPackager )
				)
				( objectStatus "J9U2.43" )
			)
			( pin "@baseboard_fab2_lib.baseboard_fab2(sch_1):page82_i187:dq(31)"
				( attribute "PN" "188"
					( Origin gPackager )
				)
				( objectStatus "J9U2.188" )
			)
			( pin "@baseboard_fab2_lib.baseboard_fab2(sch_1):page82_i187:dq(32)"
				( attribute "PN" "97"
					( Origin gPackager )
				)
				( objectStatus "J9U2.97" )
			)
			( pin "@baseboard_fab2_lib.baseboard_fab2(sch_1):page82_i187:dq(33)"
				( attribute "PN" "242"
					( Origin gPackager )
				)
				( objectStatus "J9U2.242" )
			)
			( pin "@baseboard_fab2_lib.baseboard_fab2(sch_1):page82_i187:dq(34)"
				( attribute "PN" "104"
					( Origin gPackager )
				)
				( objectStatus "J9U2.104" )
			)
			( pin "@baseboard_fab2_lib.baseboard_fab2(sch_1):page82_i187:dq(35)"
				( attribute "PN" "249"
					( Origin gPackager )
				)
				( objectStatus "J9U2.249" )
			)
			( pin "@baseboard_fab2_lib.baseboard_fab2(sch_1):page82_i187:dq(36)"
				( attribute "PN" "95"
					( Origin gPackager )
				)
				( objectStatus "J9U2.95" )
			)
			( pin "@baseboard_fab2_lib.baseboard_fab2(sch_1):page82_i187:dq(37)"
				( attribute "PN" "240"
					( Origin gPackager )
				)
				( objectStatus "J9U2.240" )
			)
			( pin "@baseboard_fab2_lib.baseboard_fab2(sch_1):page82_i187:dq(38)"
				( attribute "PN" "102"
					( Origin gPackager )
				)
				( objectStatus "J9U2.102" )
			)
			( pin "@baseboard_fab2_lib.baseboard_fab2(sch_1):page82_i187:dq(39)"
				( attribute "PN" "247"
					( Origin gPackager )
				)
				( objectStatus "J9U2.247" )
			)
			( pin "@baseboard_fab2_lib.baseboard_fab2(sch_1):page82_i187:dq(40)"
				( attribute "PN" "108"
					( Origin gPackager )
				)
				( objectStatus "J9U2.108" )
			)
			( pin "@baseboard_fab2_lib.baseboard_fab2(sch_1):page82_i187:dq(41)"
				( attribute "PN" "253"
					( Origin gPackager )
				)
				( objectStatus "J9U2.253" )
			)
			( pin "@baseboard_fab2_lib.baseboard_fab2(sch_1):page82_i187:dq(42)"
				( attribute "PN" "115"
					( Origin gPackager )
				)
				( objectStatus "J9U2.115" )
			)
			( pin "@baseboard_fab2_lib.baseboard_fab2(sch_1):page82_i187:dq(43)"
				( attribute "PN" "260"
					( Origin gPackager )
				)
				( objectStatus "J9U2.260" )
			)
			( pin "@baseboard_fab2_lib.baseboard_fab2(sch_1):page82_i187:dq(44)"
				( attribute "PN" "106"
					( Origin gPackager )
				)
				( objectStatus "J9U2.106" )
			)
			( pin "@baseboard_fab2_lib.baseboard_fab2(sch_1):page82_i187:dq(45)"
				( attribute "PN" "251"
					( Origin gPackager )
				)
				( objectStatus "J9U2.251" )
			)
			( pin "@baseboard_fab2_lib.baseboard_fab2(sch_1):page82_i187:dq(46)"
				( attribute "PN" "113"
					( Origin gPackager )
				)
				( objectStatus "J9U2.113" )
			)
			( pin "@baseboard_fab2_lib.baseboard_fab2(sch_1):page82_i187:dq(47)"
				( attribute "PN" "258"
					( Origin gPackager )
				)
				( objectStatus "J9U2.258" )
			)
			( pin "@baseboard_fab2_lib.baseboard_fab2(sch_1):page82_i187:dq(48)"
				( attribute "PN" "119"
					( Origin gPackager )
				)
				( objectStatus "J9U2.119" )
			)
			( pin "@baseboard_fab2_lib.baseboard_fab2(sch_1):page82_i187:dq(49)"
				( attribute "PN" "264"
					( Origin gPackager )
				)
				( objectStatus "J9U2.264" )
			)
			( pin "@baseboard_fab2_lib.baseboard_fab2(sch_1):page82_i187:dq(50)"
				( attribute "PN" "126"
					( Origin gPackager )
				)
				( objectStatus "J9U2.126" )
			)
			( pin "@baseboard_fab2_lib.baseboard_fab2(sch_1):page82_i187:dq(51)"
				( attribute "PN" "271"
					( Origin gPackager )
				)
				( objectStatus "J9U2.271" )
			)
			( pin "@baseboard_fab2_lib.baseboard_fab2(sch_1):page82_i187:dq(52)"
				( attribute "PN" "117"
					( Origin gPackager )
				)
				( objectStatus "J9U2.117" )
			)
			( pin "@baseboard_fab2_lib.baseboard_fab2(sch_1):page82_i187:dq(53)"
				( attribute "PN" "262"
					( Origin gPackager )
				)
				( objectStatus "J9U2.262" )
			)
			( pin "@baseboard_fab2_lib.baseboard_fab2(sch_1):page82_i187:dq(54)"
				( attribute "PN" "124"
					( Origin gPackager )
				)
				( objectStatus "J9U2.124" )
			)
			( pin "@baseboard_fab2_lib.baseboard_fab2(sch_1):page82_i187:dq(55)"
				( attribute "PN" "269"
					( Origin gPackager )
				)
				( objectStatus "J9U2.269" )
			)
			( pin "@baseboard_fab2_lib.baseboard_fab2(sch_1):page82_i187:dq(56)"
				( attribute "PN" "130"
					( Origin gPackager )
				)
				( objectStatus "J9U2.130" )
			)
			( pin "@baseboard_fab2_lib.baseboard_fab2(sch_1):page82_i187:dq(57)"
				( attribute "PN" "275"
					( Origin gPackager )
				)
				( objectStatus "J9U2.275" )
			)
			( pin "@baseboard_fab2_lib.baseboard_fab2(sch_1):page82_i187:dq(58)"
				( attribute "PN" "137"
					( Origin gPackager )
				)
				( objectStatus "J9U2.137" )
			)
			( pin "@baseboard_fab2_lib.baseboard_fab2(sch_1):page82_i187:dq(59)"
				( attribute "PN" "282"
					( Origin gPackager )
				)
				( objectStatus "J9U2.282" )
			)
			( pin "@baseboard_fab2_lib.baseboard_fab2(sch_1):page82_i187:dq(60)"
				( attribute "PN" "128"
					( Origin gPackager )
				)
				( objectStatus "J9U2.128" )
			)
			( pin "@baseboard_fab2_lib.baseboard_fab2(sch_1):page82_i187:dq(61)"
				( attribute "PN" "273"
					( Origin gPackager )
				)
				( objectStatus "J9U2.273" )
			)
			( pin "@baseboard_fab2_lib.baseboard_fab2(sch_1):page82_i187:dq(62)"
				( attribute "PN" "135"
					( Origin gPackager )
				)
				( objectStatus "J9U2.135" )
			)
			( pin "@baseboard_fab2_lib.baseboard_fab2(sch_1):page82_i187:dq(63)"
				( attribute "PN" "280"
					( Origin gPackager )
				)
				( objectStatus "J9U2.280" )
			)
			( pin "@baseboard_fab2_lib.baseboard_fab2(sch_1):page82_i187:event_n"
				( attribute "PN" "78"
					( Origin gPackager )
				)
				( objectStatus "J9U2.78" )
			)
			( pin "@baseboard_fab2_lib.baseboard_fab2(sch_1):page82_i187:odt(0)"
				( attribute "PN" "87"
					( Origin gPackager )
				)
				( objectStatus "J9U2.87" )
			)
			( pin "@baseboard_fab2_lib.baseboard_fab2(sch_1):page82_i187:odt(1)"
				( attribute "PN" "91"
					( Origin gPackager )
				)
				( objectStatus "J9U2.91" )
			)
			( pin "@baseboard_fab2_lib.baseboard_fab2(sch_1):page82_i187:par"
				( attribute "PN" "222"
					( Origin gPackager )
				)
				( objectStatus "J9U2.222" )
			)
			( pin "@baseboard_fab2_lib.baseboard_fab2(sch_1):page82_i187:reset_n"
				( attribute "PN" "58"
					( Origin gPackager )
				)
				( objectStatus "J9U2.58" )
			)
			( pin "@baseboard_fab2_lib.baseboard_fab2(sch_1):page82_i187:rfu(0)"
				( attribute "PN" "205"
					( Origin gPackager )
				)
				( objectStatus "J9U2.205" )
			)
			( pin "@baseboard_fab2_lib.baseboard_fab2(sch_1):page82_i187:rfu(1)"
				( attribute "PN" "227"
					( Origin gPackager )
				)
				( objectStatus "J9U2.227" )
			)
			( pin "@baseboard_fab2_lib.baseboard_fab2(sch_1):page82_i187:rfu(2)"
				( attribute "PN" "144"
					( Origin gPackager )
				)
				( objectStatus "J9U2.144" )
			)
			( pin "@baseboard_fab2_lib.baseboard_fab2(sch_1):page82_i187:s0_n"
				( attribute "PN" "84"
					( Origin gPackager )
				)
				( objectStatus "J9U2.84" )
			)
			( pin "@baseboard_fab2_lib.baseboard_fab2(sch_1):page82_i187:s1_n"
				( attribute "PN" "89"
					( Origin gPackager )
				)
				( objectStatus "J9U2.89" )
			)
			( pin "@baseboard_fab2_lib.baseboard_fab2(sch_1):page82_i187:s2_n_c(0)"
				( attribute "PN" "93"
					( Origin gPackager )
				)
				( objectStatus "J9U2.93" )
			)
			( pin "@baseboard_fab2_lib.baseboard_fab2(sch_1):page82_i187:s3_n_c(1)"
				( attribute "PN" "237"
					( Origin gPackager )
				)
				( objectStatus "J9U2.237" )
			)
			( pin "@baseboard_fab2_lib.baseboard_fab2(sch_1):page82_i187:sa(0)"
				( attribute "PN" "139"
					( Origin gPackager )
				)
				( objectStatus "J9U2.139" )
			)
			( pin "@baseboard_fab2_lib.baseboard_fab2(sch_1):page82_i187:sa(1)"
				( attribute "PN" "140"
					( Origin gPackager )
				)
				( objectStatus "J9U2.140" )
			)
			( pin "@baseboard_fab2_lib.baseboard_fab2(sch_1):page82_i187:sa(2)"
				( attribute "PN" "238"
					( Origin gPackager )
				)
				( objectStatus "J9U2.238" )
			)
			( pin "@baseboard_fab2_lib.baseboard_fab2(sch_1):page82_i187:save_n_nc"
				( attribute "PN" "230"
					( Origin gPackager )
				)
				( objectStatus "J9U2.230" )
			)
			( pin "@baseboard_fab2_lib.baseboard_fab2(sch_1):page82_i187:scl"
				( attribute "PN" "141"
					( Origin gPackager )
				)
				( objectStatus "J9U2.141" )
			)
			( pin "@baseboard_fab2_lib.baseboard_fab2(sch_1):page82_i187:sda"
				( attribute "PN" "285"
					( Origin gPackager )
				)
				( objectStatus "J9U2.285" )
			)
			( pin "@baseboard_fab2_lib.baseboard_fab2(sch_1):page82_i187:vddspd"
				( attribute "PN" "284"
					( Origin gPackager )
				)
				( objectStatus "J9U2.284" )
			)
			( pin "@baseboard_fab2_lib.baseboard_fab2(sch_1):page82_i187:vrefca"
				( attribute "PN" "146"
					( Origin gPackager )
				)
				( objectStatus "J9U2.146" )
			)
			( pin "@baseboard_fab2_lib.baseboard_fab2(sch_1):page82_i188:vss(0)"
				( attribute "PN" "283"
					( Origin gPackager )
				)
				( objectStatus "J9U2.283" )
			)
			( pin "@baseboard_fab2_lib.baseboard_fab2(sch_1):page82_i188:vss(1)"
				( attribute "PN" "281"
					( Origin gPackager )
				)
				( objectStatus "J9U2.281" )
			)
			( pin "@baseboard_fab2_lib.baseboard_fab2(sch_1):page82_i188:vss(2)"
				( attribute "PN" "279"
					( Origin gPackager )
				)
				( objectStatus "J9U2.279" )
			)
			( pin "@baseboard_fab2_lib.baseboard_fab2(sch_1):page82_i188:vss(3)"
				( attribute "PN" "276"
					( Origin gPackager )
				)
				( objectStatus "J9U2.276" )
			)
			( pin "@baseboard_fab2_lib.baseboard_fab2(sch_1):page82_i188:vss(4)"
				( attribute "PN" "274"
					( Origin gPackager )
				)
				( objectStatus "J9U2.274" )
			)
			( pin "@baseboard_fab2_lib.baseboard_fab2(sch_1):page82_i188:vss(5)"
				( attribute "PN" "272"
					( Origin gPackager )
				)
				( objectStatus "J9U2.272" )
			)
			( pin "@baseboard_fab2_lib.baseboard_fab2(sch_1):page82_i188:vss(6)"
				( attribute "PN" "270"
					( Origin gPackager )
				)
				( objectStatus "J9U2.270" )
			)
			( pin "@baseboard_fab2_lib.baseboard_fab2(sch_1):page82_i188:vss(7)"
				( attribute "PN" "268"
					( Origin gPackager )
				)
				( objectStatus "J9U2.268" )
			)
			( pin "@baseboard_fab2_lib.baseboard_fab2(sch_1):page82_i188:vss(8)"
				( attribute "PN" "265"
					( Origin gPackager )
				)
				( objectStatus "J9U2.265" )
			)
			( pin "@baseboard_fab2_lib.baseboard_fab2(sch_1):page82_i188:vss(9)"
				( attribute "PN" "263"
					( Origin gPackager )
				)
				( objectStatus "J9U2.263" )
			)
			( pin "@baseboard_fab2_lib.baseboard_fab2(sch_1):page82_i188:vss(10)"
				( attribute "PN" "261"
					( Origin gPackager )
				)
				( objectStatus "J9U2.261" )
			)
			( pin "@baseboard_fab2_lib.baseboard_fab2(sch_1):page82_i188:vss(11)"
				( attribute "PN" "259"
					( Origin gPackager )
				)
				( objectStatus "J9U2.259" )
			)
			( pin "@baseboard_fab2_lib.baseboard_fab2(sch_1):page82_i188:vss(12)"
				( attribute "PN" "257"
					( Origin gPackager )
				)
				( objectStatus "J9U2.257" )
			)
			( pin "@baseboard_fab2_lib.baseboard_fab2(sch_1):page82_i188:vss(13)"
				( attribute "PN" "254"
					( Origin gPackager )
				)
				( objectStatus "J9U2.254" )
			)
			( pin "@baseboard_fab2_lib.baseboard_fab2(sch_1):page82_i188:vss(14)"
				( attribute "PN" "252"
					( Origin gPackager )
				)
				( objectStatus "J9U2.252" )
			)
			( pin "@baseboard_fab2_lib.baseboard_fab2(sch_1):page82_i188:vss(15)"
				( attribute "PN" "250"
					( Origin gPackager )
				)
				( objectStatus "J9U2.250" )
			)
			( pin "@baseboard_fab2_lib.baseboard_fab2(sch_1):page82_i188:vss(16)"
				( attribute "PN" "248"
					( Origin gPackager )
				)
				( objectStatus "J9U2.248" )
			)
			( pin "@baseboard_fab2_lib.baseboard_fab2(sch_1):page82_i188:vss(17)"
				( attribute "PN" "246"
					( Origin gPackager )
				)
				( objectStatus "J9U2.246" )
			)
			( pin "@baseboard_fab2_lib.baseboard_fab2(sch_1):page82_i188:vss(18)"
				( attribute "PN" "243"
					( Origin gPackager )
				)
				( objectStatus "J9U2.243" )
			)
			( pin "@baseboard_fab2_lib.baseboard_fab2(sch_1):page82_i188:vss(19)"
				( attribute "PN" "241"
					( Origin gPackager )
				)
				( objectStatus "J9U2.241" )
			)
			( pin "@baseboard_fab2_lib.baseboard_fab2(sch_1):page82_i188:vss(20)"
				( attribute "PN" "239"
					( Origin gPackager )
				)
				( objectStatus "J9U2.239" )
			)
			( pin "@baseboard_fab2_lib.baseboard_fab2(sch_1):page82_i188:vss(21)"
				( attribute "PN" "202"
					( Origin gPackager )
				)
				( objectStatus "J9U2.202" )
			)
			( pin "@baseboard_fab2_lib.baseboard_fab2(sch_1):page82_i188:vss(22)"
				( attribute "PN" "200"
					( Origin gPackager )
				)
				( objectStatus "J9U2.200" )
			)
			( pin "@baseboard_fab2_lib.baseboard_fab2(sch_1):page82_i188:vss(23)"
				( attribute "PN" "198"
					( Origin gPackager )
				)
				( objectStatus "J9U2.198" )
			)
			( pin "@baseboard_fab2_lib.baseboard_fab2(sch_1):page82_i188:vss(24)"
				( attribute "PN" "195"
					( Origin gPackager )
				)
				( objectStatus "J9U2.195" )
			)
			( pin "@baseboard_fab2_lib.baseboard_fab2(sch_1):page82_i188:vss(25)"
				( attribute "PN" "193"
					( Origin gPackager )
				)
				( objectStatus "J9U2.193" )
			)
			( pin "@baseboard_fab2_lib.baseboard_fab2(sch_1):page82_i188:vss(26)"
				( attribute "PN" "191"
					( Origin gPackager )
				)
				( objectStatus "J9U2.191" )
			)
			( pin "@baseboard_fab2_lib.baseboard_fab2(sch_1):page82_i188:vss(27)"
				( attribute "PN" "189"
					( Origin gPackager )
				)
				( objectStatus "J9U2.189" )
			)
			( pin "@baseboard_fab2_lib.baseboard_fab2(sch_1):page82_i188:vss(28)"
				( attribute "PN" "187"
					( Origin gPackager )
				)
				( objectStatus "J9U2.187" )
			)
			( pin "@baseboard_fab2_lib.baseboard_fab2(sch_1):page82_i188:vss(29)"
				( attribute "PN" "184"
					( Origin gPackager )
				)
				( objectStatus "J9U2.184" )
			)
			( pin "@baseboard_fab2_lib.baseboard_fab2(sch_1):page82_i188:vss(30)"
				( attribute "PN" "182"
					( Origin gPackager )
				)
				( objectStatus "J9U2.182" )
			)
			( pin "@baseboard_fab2_lib.baseboard_fab2(sch_1):page82_i188:vss(31)"
				( attribute "PN" "180"
					( Origin gPackager )
				)
				( objectStatus "J9U2.180" )
			)
			( pin "@baseboard_fab2_lib.baseboard_fab2(sch_1):page82_i188:vss(32)"
				( attribute "PN" "178"
					( Origin gPackager )
				)
				( objectStatus "J9U2.178" )
			)
			( pin "@baseboard_fab2_lib.baseboard_fab2(sch_1):page82_i188:vss(33)"
				( attribute "PN" "176"
					( Origin gPackager )
				)
				( objectStatus "J9U2.176" )
			)
			( pin "@baseboard_fab2_lib.baseboard_fab2(sch_1):page82_i188:vss(34)"
				( attribute "PN" "173"
					( Origin gPackager )
				)
				( objectStatus "J9U2.173" )
			)
			( pin "@baseboard_fab2_lib.baseboard_fab2(sch_1):page82_i188:vss(35)"
				( attribute "PN" "171"
					( Origin gPackager )
				)
				( objectStatus "J9U2.171" )
			)
			( pin "@baseboard_fab2_lib.baseboard_fab2(sch_1):page82_i188:vss(36)"
				( attribute "PN" "169"
					( Origin gPackager )
				)
				( objectStatus "J9U2.169" )
			)
			( pin "@baseboard_fab2_lib.baseboard_fab2(sch_1):page82_i188:vss(37)"
				( attribute "PN" "167"
					( Origin gPackager )
				)
				( objectStatus "J9U2.167" )
			)
			( pin "@baseboard_fab2_lib.baseboard_fab2(sch_1):page82_i188:vss(38)"
				( attribute "PN" "165"
					( Origin gPackager )
				)
				( objectStatus "J9U2.165" )
			)
			( pin "@baseboard_fab2_lib.baseboard_fab2(sch_1):page82_i188:vss(39)"
				( attribute "PN" "162"
					( Origin gPackager )
				)
				( objectStatus "J9U2.162" )
			)
			( pin "@baseboard_fab2_lib.baseboard_fab2(sch_1):page82_i188:vss(40)"
				( attribute "PN" "160"
					( Origin gPackager )
				)
				( objectStatus "J9U2.160" )
			)
			( pin "@baseboard_fab2_lib.baseboard_fab2(sch_1):page82_i188:vss(41)"
				( attribute "PN" "158"
					( Origin gPackager )
				)
				( objectStatus "J9U2.158" )
			)
			( pin "@baseboard_fab2_lib.baseboard_fab2(sch_1):page82_i188:vss(42)"
				( attribute "PN" "156"
					( Origin gPackager )
				)
				( objectStatus "J9U2.156" )
			)
			( pin "@baseboard_fab2_lib.baseboard_fab2(sch_1):page82_i188:vss(43)"
				( attribute "PN" "154"
					( Origin gPackager )
				)
				( objectStatus "J9U2.154" )
			)
			( pin "@baseboard_fab2_lib.baseboard_fab2(sch_1):page82_i188:vss(44)"
				( attribute "PN" "151"
					( Origin gPackager )
				)
				( objectStatus "J9U2.151" )
			)
			( pin "@baseboard_fab2_lib.baseboard_fab2(sch_1):page82_i188:vss(45)"
				( attribute "PN" "149"
					( Origin gPackager )
				)
				( objectStatus "J9U2.149" )
			)
			( pin "@baseboard_fab2_lib.baseboard_fab2(sch_1):page82_i188:vss(46)"
				( attribute "PN" "147"
					( Origin gPackager )
				)
				( objectStatus "J9U2.147" )
			)
			( pin "@baseboard_fab2_lib.baseboard_fab2(sch_1):page82_i188:vss(47)"
				( attribute "PN" "138"
					( Origin gPackager )
				)
				( objectStatus "J9U2.138" )
			)
			( pin "@baseboard_fab2_lib.baseboard_fab2(sch_1):page82_i188:vss(48)"
				( attribute "PN" "136"
					( Origin gPackager )
				)
				( objectStatus "J9U2.136" )
			)
			( pin "@baseboard_fab2_lib.baseboard_fab2(sch_1):page82_i188:vss(49)"
				( attribute "PN" "134"
					( Origin gPackager )
				)
				( objectStatus "J9U2.134" )
			)
			( pin "@baseboard_fab2_lib.baseboard_fab2(sch_1):page82_i188:vss(50)"
				( attribute "PN" "131"
					( Origin gPackager )
				)
				( objectStatus "J9U2.131" )
			)
			( pin "@baseboard_fab2_lib.baseboard_fab2(sch_1):page82_i188:vss(51)"
				( attribute "PN" "129"
					( Origin gPackager )
				)
				( objectStatus "J9U2.129" )
			)
			( pin "@baseboard_fab2_lib.baseboard_fab2(sch_1):page82_i188:vss(52)"
				( attribute "PN" "127"
					( Origin gPackager )
				)
				( objectStatus "J9U2.127" )
			)
			( pin "@baseboard_fab2_lib.baseboard_fab2(sch_1):page82_i188:vss(53)"
				( attribute "PN" "125"
					( Origin gPackager )
				)
				( objectStatus "J9U2.125" )
			)
			( pin "@baseboard_fab2_lib.baseboard_fab2(sch_1):page82_i188:vss(54)"
				( attribute "PN" "123"
					( Origin gPackager )
				)
				( objectStatus "J9U2.123" )
			)
			( pin "@baseboard_fab2_lib.baseboard_fab2(sch_1):page82_i188:vss(55)"
				( attribute "PN" "120"
					( Origin gPackager )
				)
				( objectStatus "J9U2.120" )
			)
			( pin "@baseboard_fab2_lib.baseboard_fab2(sch_1):page82_i188:vss(56)"
				( attribute "PN" "118"
					( Origin gPackager )
				)
				( objectStatus "J9U2.118" )
			)
			( pin "@baseboard_fab2_lib.baseboard_fab2(sch_1):page82_i188:vss(57)"
				( attribute "PN" "116"
					( Origin gPackager )
				)
				( objectStatus "J9U2.116" )
			)
			( pin "@baseboard_fab2_lib.baseboard_fab2(sch_1):page82_i188:vss(58)"
				( attribute "PN" "114"
					( Origin gPackager )
				)
				( objectStatus "J9U2.114" )
			)
			( pin "@baseboard_fab2_lib.baseboard_fab2(sch_1):page82_i188:vss(59)"
				( attribute "PN" "112"
					( Origin gPackager )
				)
				( objectStatus "J9U2.112" )
			)
			( pin "@baseboard_fab2_lib.baseboard_fab2(sch_1):page82_i188:vss(60)"
				( attribute "PN" "109"
					( Origin gPackager )
				)
				( objectStatus "J9U2.109" )
			)
			( pin "@baseboard_fab2_lib.baseboard_fab2(sch_1):page82_i188:vss(61)"
				( attribute "PN" "107"
					( Origin gPackager )
				)
				( objectStatus "J9U2.107" )
			)
			( pin "@baseboard_fab2_lib.baseboard_fab2(sch_1):page82_i188:vss(62)"
				( attribute "PN" "105"
					( Origin gPackager )
				)
				( objectStatus "J9U2.105" )
			)
			( pin "@baseboard_fab2_lib.baseboard_fab2(sch_1):page82_i188:vss(63)"
				( attribute "PN" "103"
					( Origin gPackager )
				)
				( objectStatus "J9U2.103" )
			)
			( pin "@baseboard_fab2_lib.baseboard_fab2(sch_1):page82_i188:vss(64)"
				( attribute "PN" "101"
					( Origin gPackager )
				)
				( objectStatus "J9U2.101" )
			)
			( pin "@baseboard_fab2_lib.baseboard_fab2(sch_1):page82_i188:vss(65)"
				( attribute "PN" "98"
					( Origin gPackager )
				)
				( objectStatus "J9U2.98" )
			)
			( pin "@baseboard_fab2_lib.baseboard_fab2(sch_1):page82_i188:vss(66)"
				( attribute "PN" "96"
					( Origin gPackager )
				)
				( objectStatus "J9U2.96" )
			)
			( pin "@baseboard_fab2_lib.baseboard_fab2(sch_1):page82_i188:vss(67)"
				( attribute "PN" "94"
					( Origin gPackager )
				)
				( objectStatus "J9U2.94" )
			)
			( pin "@baseboard_fab2_lib.baseboard_fab2(sch_1):page82_i188:vss(68)"
				( attribute "PN" "57"
					( Origin gPackager )
				)
				( objectStatus "J9U2.57" )
			)
			( pin "@baseboard_fab2_lib.baseboard_fab2(sch_1):page82_i188:vss(69)"
				( attribute "PN" "55"
					( Origin gPackager )
				)
				( objectStatus "J9U2.55" )
			)
			( pin "@baseboard_fab2_lib.baseboard_fab2(sch_1):page82_i188:vss(70)"
				( attribute "PN" "53"
					( Origin gPackager )
				)
				( objectStatus "J9U2.53" )
			)
			( pin "@baseboard_fab2_lib.baseboard_fab2(sch_1):page82_i188:vss(71)"
				( attribute "PN" "50"
					( Origin gPackager )
				)
				( objectStatus "J9U2.50" )
			)
			( pin "@baseboard_fab2_lib.baseboard_fab2(sch_1):page82_i188:vss(72)"
				( attribute "PN" "48"
					( Origin gPackager )
				)
				( objectStatus "J9U2.48" )
			)
			( pin "@baseboard_fab2_lib.baseboard_fab2(sch_1):page82_i188:vss(73)"
				( attribute "PN" "46"
					( Origin gPackager )
				)
				( objectStatus "J9U2.46" )
			)
			( pin "@baseboard_fab2_lib.baseboard_fab2(sch_1):page82_i188:vss(74)"
				( attribute "PN" "44"
					( Origin gPackager )
				)
				( objectStatus "J9U2.44" )
			)
			( pin "@baseboard_fab2_lib.baseboard_fab2(sch_1):page82_i188:vss(75)"
				( attribute "PN" "42"
					( Origin gPackager )
				)
				( objectStatus "J9U2.42" )
			)
			( pin "@baseboard_fab2_lib.baseboard_fab2(sch_1):page82_i188:vss(76)"
				( attribute "PN" "39"
					( Origin gPackager )
				)
				( objectStatus "J9U2.39" )
			)
			( pin "@baseboard_fab2_lib.baseboard_fab2(sch_1):page82_i188:vss(77)"
				( attribute "PN" "37"
					( Origin gPackager )
				)
				( objectStatus "J9U2.37" )
			)
			( pin "@baseboard_fab2_lib.baseboard_fab2(sch_1):page82_i188:vss(78)"
				( attribute "PN" "35"
					( Origin gPackager )
				)
				( objectStatus "J9U2.35" )
			)
			( pin "@baseboard_fab2_lib.baseboard_fab2(sch_1):page82_i188:vss(79)"
				( attribute "PN" "33"
					( Origin gPackager )
				)
				( objectStatus "J9U2.33" )
			)
			( pin "@baseboard_fab2_lib.baseboard_fab2(sch_1):page82_i188:vss(80)"
				( attribute "PN" "31"
					( Origin gPackager )
				)
				( objectStatus "J9U2.31" )
			)
			( pin "@baseboard_fab2_lib.baseboard_fab2(sch_1):page82_i188:vss(81)"
				( attribute "PN" "28"
					( Origin gPackager )
				)
				( objectStatus "J9U2.28" )
			)
			( pin "@baseboard_fab2_lib.baseboard_fab2(sch_1):page82_i188:vss(82)"
				( attribute "PN" "26"
					( Origin gPackager )
				)
				( objectStatus "J9U2.26" )
			)
			( pin "@baseboard_fab2_lib.baseboard_fab2(sch_1):page82_i188:vss(83)"
				( attribute "PN" "24"
					( Origin gPackager )
				)
				( objectStatus "J9U2.24" )
			)
			( pin "@baseboard_fab2_lib.baseboard_fab2(sch_1):page82_i188:vss(84)"
				( attribute "PN" "22"
					( Origin gPackager )
				)
				( objectStatus "J9U2.22" )
			)
			( pin "@baseboard_fab2_lib.baseboard_fab2(sch_1):page82_i188:vss(85)"
				( attribute "PN" "20"
					( Origin gPackager )
				)
				( objectStatus "J9U2.20" )
			)
			( pin "@baseboard_fab2_lib.baseboard_fab2(sch_1):page82_i188:vss(86)"
				( attribute "PN" "17"
					( Origin gPackager )
				)
				( objectStatus "J9U2.17" )
			)
			( pin "@baseboard_fab2_lib.baseboard_fab2(sch_1):page82_i188:vss(87)"
				( attribute "PN" "15"
					( Origin gPackager )
				)
				( objectStatus "J9U2.15" )
			)
			( pin "@baseboard_fab2_lib.baseboard_fab2(sch_1):page82_i188:vss(88)"
				( attribute "PN" "13"
					( Origin gPackager )
				)
				( objectStatus "J9U2.13" )
			)
			( pin "@baseboard_fab2_lib.baseboard_fab2(sch_1):page82_i188:vss(89)"
				( attribute "PN" "11"
					( Origin gPackager )
				)
				( objectStatus "J9U2.11" )
			)
			( pin "@baseboard_fab2_lib.baseboard_fab2(sch_1):page82_i188:vss(90)"
				( attribute "PN" "9"
					( Origin gPackager )
				)
				( objectStatus "J9U2.9" )
			)
			( pin "@baseboard_fab2_lib.baseboard_fab2(sch_1):page82_i188:vss(91)"
				( attribute "PN" "6"
					( Origin gPackager )
				)
				( objectStatus "J9U2.6" )
			)
			( pin "@baseboard_fab2_lib.baseboard_fab2(sch_1):page82_i188:vss(92)"
				( attribute "PN" "4"
					( Origin gPackager )
				)
				( objectStatus "J9U2.4" )
			)
			( pin "@baseboard_fab2_lib.baseboard_fab2(sch_1):page82_i188:vss(93)"
				( attribute "PN" "2"
					( Origin gPackager )
				)
				( objectStatus "J9U2.2" )
			)
			( pin "@baseboard_fab2_lib.baseboard_fab2(sch_1):page83_i43:vss(0)"
				( attribute "PN" "283"
					( Origin gPackager )
				)
				( objectStatus "J1B1.283" )
			)
			( pin "@baseboard_fab2_lib.baseboard_fab2(sch_1):page83_i43:vss(1)"
				( attribute "PN" "281"
					( Origin gPackager )
				)
				( objectStatus "J1B1.281" )
			)
			( pin "@baseboard_fab2_lib.baseboard_fab2(sch_1):page83_i43:vss(2)"
				( attribute "PN" "279"
					( Origin gPackager )
				)
				( objectStatus "J1B1.279" )
			)
			( pin "@baseboard_fab2_lib.baseboard_fab2(sch_1):page83_i43:vss(3)"
				( attribute "PN" "276"
					( Origin gPackager )
				)
				( objectStatus "J1B1.276" )
			)
			( pin "@baseboard_fab2_lib.baseboard_fab2(sch_1):page83_i43:vss(4)"
				( attribute "PN" "274"
					( Origin gPackager )
				)
				( objectStatus "J1B1.274" )
			)
			( pin "@baseboard_fab2_lib.baseboard_fab2(sch_1):page83_i43:vss(5)"
				( attribute "PN" "272"
					( Origin gPackager )
				)
				( objectStatus "J1B1.272" )
			)
			( pin "@baseboard_fab2_lib.baseboard_fab2(sch_1):page83_i43:vss(6)"
				( attribute "PN" "270"
					( Origin gPackager )
				)
				( objectStatus "J1B1.270" )
			)
			( pin "@baseboard_fab2_lib.baseboard_fab2(sch_1):page83_i43:vss(7)"
				( attribute "PN" "268"
					( Origin gPackager )
				)
				( objectStatus "J1B1.268" )
			)
			( pin "@baseboard_fab2_lib.baseboard_fab2(sch_1):page83_i43:vss(8)"
				( attribute "PN" "265"
					( Origin gPackager )
				)
				( objectStatus "J1B1.265" )
			)
			( pin "@baseboard_fab2_lib.baseboard_fab2(sch_1):page83_i43:vss(9)"
				( attribute "PN" "263"
					( Origin gPackager )
				)
				( objectStatus "J1B1.263" )
			)
			( pin "@baseboard_fab2_lib.baseboard_fab2(sch_1):page83_i43:vss(10)"
				( attribute "PN" "261"
					( Origin gPackager )
				)
				( objectStatus "J1B1.261" )
			)
			( pin "@baseboard_fab2_lib.baseboard_fab2(sch_1):page83_i43:vss(11)"
				( attribute "PN" "259"
					( Origin gPackager )
				)
				( objectStatus "J1B1.259" )
			)
			( pin "@baseboard_fab2_lib.baseboard_fab2(sch_1):page83_i43:vss(12)"
				( attribute "PN" "257"
					( Origin gPackager )
				)
				( objectStatus "J1B1.257" )
			)
			( pin "@baseboard_fab2_lib.baseboard_fab2(sch_1):page83_i43:vss(13)"
				( attribute "PN" "254"
					( Origin gPackager )
				)
				( objectStatus "J1B1.254" )
			)
			( pin "@baseboard_fab2_lib.baseboard_fab2(sch_1):page83_i43:vss(14)"
				( attribute "PN" "252"
					( Origin gPackager )
				)
				( objectStatus "J1B1.252" )
			)
			( pin "@baseboard_fab2_lib.baseboard_fab2(sch_1):page83_i43:vss(15)"
				( attribute "PN" "250"
					( Origin gPackager )
				)
				( objectStatus "J1B1.250" )
			)
			( pin "@baseboard_fab2_lib.baseboard_fab2(sch_1):page83_i43:vss(16)"
				( attribute "PN" "248"
					( Origin gPackager )
				)
				( objectStatus "J1B1.248" )
			)
			( pin "@baseboard_fab2_lib.baseboard_fab2(sch_1):page83_i43:vss(17)"
				( attribute "PN" "246"
					( Origin gPackager )
				)
				( objectStatus "J1B1.246" )
			)
			( pin "@baseboard_fab2_lib.baseboard_fab2(sch_1):page83_i43:vss(18)"
				( attribute "PN" "243"
					( Origin gPackager )
				)
				( objectStatus "J1B1.243" )
			)
			( pin "@baseboard_fab2_lib.baseboard_fab2(sch_1):page83_i43:vss(19)"
				( attribute "PN" "241"
					( Origin gPackager )
				)
				( objectStatus "J1B1.241" )
			)
			( pin "@baseboard_fab2_lib.baseboard_fab2(sch_1):page83_i43:vss(20)"
				( attribute "PN" "239"
					( Origin gPackager )
				)
				( objectStatus "J1B1.239" )
			)
			( pin "@baseboard_fab2_lib.baseboard_fab2(sch_1):page83_i43:vss(21)"
				( attribute "PN" "202"
					( Origin gPackager )
				)
				( objectStatus "J1B1.202" )
			)
			( pin "@baseboard_fab2_lib.baseboard_fab2(sch_1):page83_i43:vss(22)"
				( attribute "PN" "200"
					( Origin gPackager )
				)
				( objectStatus "J1B1.200" )
			)
			( pin "@baseboard_fab2_lib.baseboard_fab2(sch_1):page83_i43:vss(23)"
				( attribute "PN" "198"
					( Origin gPackager )
				)
				( objectStatus "J1B1.198" )
			)
			( pin "@baseboard_fab2_lib.baseboard_fab2(sch_1):page83_i43:vss(24)"
				( attribute "PN" "195"
					( Origin gPackager )
				)
				( objectStatus "J1B1.195" )
			)
			( pin "@baseboard_fab2_lib.baseboard_fab2(sch_1):page83_i43:vss(25)"
				( attribute "PN" "193"
					( Origin gPackager )
				)
				( objectStatus "J1B1.193" )
			)
			( pin "@baseboard_fab2_lib.baseboard_fab2(sch_1):page83_i43:vss(26)"
				( attribute "PN" "191"
					( Origin gPackager )
				)
				( objectStatus "J1B1.191" )
			)
			( pin "@baseboard_fab2_lib.baseboard_fab2(sch_1):page83_i43:vss(27)"
				( attribute "PN" "189"
					( Origin gPackager )
				)
				( objectStatus "J1B1.189" )
			)
			( pin "@baseboard_fab2_lib.baseboard_fab2(sch_1):page83_i43:vss(28)"
				( attribute "PN" "187"
					( Origin gPackager )
				)
				( objectStatus "J1B1.187" )
			)
			( pin "@baseboard_fab2_lib.baseboard_fab2(sch_1):page83_i43:vss(29)"
				( attribute "PN" "184"
					( Origin gPackager )
				)
				( objectStatus "J1B1.184" )
			)
			( pin "@baseboard_fab2_lib.baseboard_fab2(sch_1):page83_i43:vss(30)"
				( attribute "PN" "182"
					( Origin gPackager )
				)
				( objectStatus "J1B1.182" )
			)
			( pin "@baseboard_fab2_lib.baseboard_fab2(sch_1):page83_i43:vss(31)"
				( attribute "PN" "180"
					( Origin gPackager )
				)
				( objectStatus "J1B1.180" )
			)
			( pin "@baseboard_fab2_lib.baseboard_fab2(sch_1):page83_i43:vss(32)"
				( attribute "PN" "178"
					( Origin gPackager )
				)
				( objectStatus "J1B1.178" )
			)
			( pin "@baseboard_fab2_lib.baseboard_fab2(sch_1):page83_i43:vss(33)"
				( attribute "PN" "176"
					( Origin gPackager )
				)
				( objectStatus "J1B1.176" )
			)
			( pin "@baseboard_fab2_lib.baseboard_fab2(sch_1):page83_i43:vss(34)"
				( attribute "PN" "173"
					( Origin gPackager )
				)
				( objectStatus "J1B1.173" )
			)
			( pin "@baseboard_fab2_lib.baseboard_fab2(sch_1):page83_i43:vss(35)"
				( attribute "PN" "171"
					( Origin gPackager )
				)
				( objectStatus "J1B1.171" )
			)
			( pin "@baseboard_fab2_lib.baseboard_fab2(sch_1):page83_i43:vss(36)"
				( attribute "PN" "169"
					( Origin gPackager )
				)
				( objectStatus "J1B1.169" )
			)
			( pin "@baseboard_fab2_lib.baseboard_fab2(sch_1):page83_i43:vss(37)"
				( attribute "PN" "167"
					( Origin gPackager )
				)
				( objectStatus "J1B1.167" )
			)
			( pin "@baseboard_fab2_lib.baseboard_fab2(sch_1):page83_i43:vss(38)"
				( attribute "PN" "165"
					( Origin gPackager )
				)
				( objectStatus "J1B1.165" )
			)
			( pin "@baseboard_fab2_lib.baseboard_fab2(sch_1):page83_i43:vss(39)"
				( attribute "PN" "162"
					( Origin gPackager )
				)
				( objectStatus "J1B1.162" )
			)
			( pin "@baseboard_fab2_lib.baseboard_fab2(sch_1):page83_i43:vss(40)"
				( attribute "PN" "160"
					( Origin gPackager )
				)
				( objectStatus "J1B1.160" )
			)
			( pin "@baseboard_fab2_lib.baseboard_fab2(sch_1):page83_i43:vss(41)"
				( attribute "PN" "158"
					( Origin gPackager )
				)
				( objectStatus "J1B1.158" )
			)
			( pin "@baseboard_fab2_lib.baseboard_fab2(sch_1):page83_i43:vss(42)"
				( attribute "PN" "156"
					( Origin gPackager )
				)
				( objectStatus "J1B1.156" )
			)
			( pin "@baseboard_fab2_lib.baseboard_fab2(sch_1):page83_i43:vss(43)"
				( attribute "PN" "154"
					( Origin gPackager )
				)
				( objectStatus "J1B1.154" )
			)
			( pin "@baseboard_fab2_lib.baseboard_fab2(sch_1):page83_i43:vss(44)"
				( attribute "PN" "151"
					( Origin gPackager )
				)
				( objectStatus "J1B1.151" )
			)
			( pin "@baseboard_fab2_lib.baseboard_fab2(sch_1):page83_i43:vss(45)"
				( attribute "PN" "149"
					( Origin gPackager )
				)
				( objectStatus "J1B1.149" )
			)
			( pin "@baseboard_fab2_lib.baseboard_fab2(sch_1):page83_i43:vss(46)"
				( attribute "PN" "147"
					( Origin gPackager )
				)
				( objectStatus "J1B1.147" )
			)
			( pin "@baseboard_fab2_lib.baseboard_fab2(sch_1):page83_i43:vss(47)"
				( attribute "PN" "138"
					( Origin gPackager )
				)
				( objectStatus "J1B1.138" )
			)
			( pin "@baseboard_fab2_lib.baseboard_fab2(sch_1):page83_i43:vss(48)"
				( attribute "PN" "136"
					( Origin gPackager )
				)
				( objectStatus "J1B1.136" )
			)
			( pin "@baseboard_fab2_lib.baseboard_fab2(sch_1):page83_i43:vss(49)"
				( attribute "PN" "134"
					( Origin gPackager )
				)
				( objectStatus "J1B1.134" )
			)
			( pin "@baseboard_fab2_lib.baseboard_fab2(sch_1):page83_i43:vss(50)"
				( attribute "PN" "131"
					( Origin gPackager )
				)
				( objectStatus "J1B1.131" )
			)
			( pin "@baseboard_fab2_lib.baseboard_fab2(sch_1):page83_i43:vss(51)"
				( attribute "PN" "129"
					( Origin gPackager )
				)
				( objectStatus "J1B1.129" )
			)
			( pin "@baseboard_fab2_lib.baseboard_fab2(sch_1):page83_i43:vss(52)"
				( attribute "PN" "127"
					( Origin gPackager )
				)
				( objectStatus "J1B1.127" )
			)
			( pin "@baseboard_fab2_lib.baseboard_fab2(sch_1):page83_i43:vss(53)"
				( attribute "PN" "125"
					( Origin gPackager )
				)
				( objectStatus "J1B1.125" )
			)
			( pin "@baseboard_fab2_lib.baseboard_fab2(sch_1):page83_i43:vss(54)"
				( attribute "PN" "123"
					( Origin gPackager )
				)
				( objectStatus "J1B1.123" )
			)
			( pin "@baseboard_fab2_lib.baseboard_fab2(sch_1):page83_i43:vss(55)"
				( attribute "PN" "120"
					( Origin gPackager )
				)
				( objectStatus "J1B1.120" )
			)
			( pin "@baseboard_fab2_lib.baseboard_fab2(sch_1):page83_i43:vss(56)"
				( attribute "PN" "118"
					( Origin gPackager )
				)
				( objectStatus "J1B1.118" )
			)
			( pin "@baseboard_fab2_lib.baseboard_fab2(sch_1):page83_i43:vss(57)"
				( attribute "PN" "116"
					( Origin gPackager )
				)
				( objectStatus "J1B1.116" )
			)
			( pin "@baseboard_fab2_lib.baseboard_fab2(sch_1):page83_i43:vss(58)"
				( attribute "PN" "114"
					( Origin gPackager )
				)
				( objectStatus "J1B1.114" )
			)
			( pin "@baseboard_fab2_lib.baseboard_fab2(sch_1):page83_i43:vss(59)"
				( attribute "PN" "112"
					( Origin gPackager )
				)
				( objectStatus "J1B1.112" )
			)
			( pin "@baseboard_fab2_lib.baseboard_fab2(sch_1):page83_i43:vss(60)"
				( attribute "PN" "109"
					( Origin gPackager )
				)
				( objectStatus "J1B1.109" )
			)
			( pin "@baseboard_fab2_lib.baseboard_fab2(sch_1):page83_i43:vss(61)"
				( attribute "PN" "107"
					( Origin gPackager )
				)
				( objectStatus "J1B1.107" )
			)
			( pin "@baseboard_fab2_lib.baseboard_fab2(sch_1):page83_i43:vss(62)"
				( attribute "PN" "105"
					( Origin gPackager )
				)
				( objectStatus "J1B1.105" )
			)
			( pin "@baseboard_fab2_lib.baseboard_fab2(sch_1):page83_i43:vss(63)"
				( attribute "PN" "103"
					( Origin gPackager )
				)
				( objectStatus "J1B1.103" )
			)
			( pin "@baseboard_fab2_lib.baseboard_fab2(sch_1):page83_i43:vss(64)"
				( attribute "PN" "101"
					( Origin gPackager )
				)
				( objectStatus "J1B1.101" )
			)
			( pin "@baseboard_fab2_lib.baseboard_fab2(sch_1):page83_i43:vss(65)"
				( attribute "PN" "98"
					( Origin gPackager )
				)
				( objectStatus "J1B1.98" )
			)
			( pin "@baseboard_fab2_lib.baseboard_fab2(sch_1):page83_i43:vss(66)"
				( attribute "PN" "96"
					( Origin gPackager )
				)
				( objectStatus "J1B1.96" )
			)
			( pin "@baseboard_fab2_lib.baseboard_fab2(sch_1):page83_i43:vss(67)"
				( attribute "PN" "94"
					( Origin gPackager )
				)
				( objectStatus "J1B1.94" )
			)
			( pin "@baseboard_fab2_lib.baseboard_fab2(sch_1):page83_i43:vss(68)"
				( attribute "PN" "57"
					( Origin gPackager )
				)
				( objectStatus "J1B1.57" )
			)
			( pin "@baseboard_fab2_lib.baseboard_fab2(sch_1):page83_i43:vss(69)"
				( attribute "PN" "55"
					( Origin gPackager )
				)
				( objectStatus "J1B1.55" )
			)
			( pin "@baseboard_fab2_lib.baseboard_fab2(sch_1):page83_i43:vss(70)"
				( attribute "PN" "53"
					( Origin gPackager )
				)
				( objectStatus "J1B1.53" )
			)
			( pin "@baseboard_fab2_lib.baseboard_fab2(sch_1):page83_i43:vss(71)"
				( attribute "PN" "50"
					( Origin gPackager )
				)
				( objectStatus "J1B1.50" )
			)
			( pin "@baseboard_fab2_lib.baseboard_fab2(sch_1):page83_i43:vss(72)"
				( attribute "PN" "48"
					( Origin gPackager )
				)
				( objectStatus "J1B1.48" )
			)
			( pin "@baseboard_fab2_lib.baseboard_fab2(sch_1):page83_i43:vss(73)"
				( attribute "PN" "46"
					( Origin gPackager )
				)
				( objectStatus "J1B1.46" )
			)
			( pin "@baseboard_fab2_lib.baseboard_fab2(sch_1):page83_i43:vss(74)"
				( attribute "PN" "44"
					( Origin gPackager )
				)
				( objectStatus "J1B1.44" )
			)
			( pin "@baseboard_fab2_lib.baseboard_fab2(sch_1):page83_i43:vss(75)"
				( attribute "PN" "42"
					( Origin gPackager )
				)
				( objectStatus "J1B1.42" )
			)
			( pin "@baseboard_fab2_lib.baseboard_fab2(sch_1):page83_i43:vss(76)"
				( attribute "PN" "39"
					( Origin gPackager )
				)
				( objectStatus "J1B1.39" )
			)
			( pin "@baseboard_fab2_lib.baseboard_fab2(sch_1):page83_i43:vss(77)"
				( attribute "PN" "37"
					( Origin gPackager )
				)
				( objectStatus "J1B1.37" )
			)
			( pin "@baseboard_fab2_lib.baseboard_fab2(sch_1):page83_i43:vss(78)"
				( attribute "PN" "35"
					( Origin gPackager )
				)
				( objectStatus "J1B1.35" )
			)
			( pin "@baseboard_fab2_lib.baseboard_fab2(sch_1):page83_i43:vss(79)"
				( attribute "PN" "33"
					( Origin gPackager )
				)
				( objectStatus "J1B1.33" )
			)
			( pin "@baseboard_fab2_lib.baseboard_fab2(sch_1):page83_i43:vss(80)"
				( attribute "PN" "31"
					( Origin gPackager )
				)
				( objectStatus "J1B1.31" )
			)
			( pin "@baseboard_fab2_lib.baseboard_fab2(sch_1):page83_i43:vss(81)"
				( attribute "PN" "28"
					( Origin gPackager )
				)
				( objectStatus "J1B1.28" )
			)
			( pin "@baseboard_fab2_lib.baseboard_fab2(sch_1):page83_i43:vss(82)"
				( attribute "PN" "26"
					( Origin gPackager )
				)
				( objectStatus "J1B1.26" )
			)
			( pin "@baseboard_fab2_lib.baseboard_fab2(sch_1):page83_i43:vss(83)"
				( attribute "PN" "24"
					( Origin gPackager )
				)
				( objectStatus "J1B1.24" )
			)
			( pin "@baseboard_fab2_lib.baseboard_fab2(sch_1):page83_i43:vss(84)"
				( attribute "PN" "22"
					( Origin gPackager )
				)
				( objectStatus "J1B1.22" )
			)
			( pin "@baseboard_fab2_lib.baseboard_fab2(sch_1):page83_i43:vss(85)"
				( attribute "PN" "20"
					( Origin gPackager )
				)
				( objectStatus "J1B1.20" )
			)
			( pin "@baseboard_fab2_lib.baseboard_fab2(sch_1):page83_i43:vss(86)"
				( attribute "PN" "17"
					( Origin gPackager )
				)
				( objectStatus "J1B1.17" )
			)
			( pin "@baseboard_fab2_lib.baseboard_fab2(sch_1):page83_i43:vss(87)"
				( attribute "PN" "15"
					( Origin gPackager )
				)
				( objectStatus "J1B1.15" )
			)
			( pin "@baseboard_fab2_lib.baseboard_fab2(sch_1):page83_i43:vss(88)"
				( attribute "PN" "13"
					( Origin gPackager )
				)
				( objectStatus "J1B1.13" )
			)
			( pin "@baseboard_fab2_lib.baseboard_fab2(sch_1):page83_i43:vss(89)"
				( attribute "PN" "11"
					( Origin gPackager )
				)
				( objectStatus "J1B1.11" )
			)
			( pin "@baseboard_fab2_lib.baseboard_fab2(sch_1):page83_i43:vss(90)"
				( attribute "PN" "9"
					( Origin gPackager )
				)
				( objectStatus "J1B1.9" )
			)
			( pin "@baseboard_fab2_lib.baseboard_fab2(sch_1):page83_i43:vss(91)"
				( attribute "PN" "6"
					( Origin gPackager )
				)
				( objectStatus "J1B1.6" )
			)
			( pin "@baseboard_fab2_lib.baseboard_fab2(sch_1):page83_i43:vss(92)"
				( attribute "PN" "4"
					( Origin gPackager )
				)
				( objectStatus "J1B1.4" )
			)
			( pin "@baseboard_fab2_lib.baseboard_fab2(sch_1):page83_i43:vss(93)"
				( attribute "PN" "2"
					( Origin gPackager )
				)
				( objectStatus "J1B1.2" )
			)
			( pin "@baseboard_fab2_lib.baseboard_fab2(sch_1):page83_i66:dqs0n"
				( attribute "PN" "152"
					( Origin gPackager )
				)
				( objectStatus "J1B1.152" )
			)
			( pin "@baseboard_fab2_lib.baseboard_fab2(sch_1):page83_i66:dqs0p"
				( attribute "PN" "153"
					( Origin gPackager )
				)
				( objectStatus "J1B1.153" )
			)
			( pin "@baseboard_fab2_lib.baseboard_fab2(sch_1):page83_i66:dqs1n"
				( attribute "PN" "163"
					( Origin gPackager )
				)
				( objectStatus "J1B1.163" )
			)
			( pin "@baseboard_fab2_lib.baseboard_fab2(sch_1):page83_i66:dqs1p"
				( attribute "PN" "164"
					( Origin gPackager )
				)
				( objectStatus "J1B1.164" )
			)
			( pin "@baseboard_fab2_lib.baseboard_fab2(sch_1):page83_i66:dqs2n"
				( attribute "PN" "174"
					( Origin gPackager )
				)
				( objectStatus "J1B1.174" )
			)
			( pin "@baseboard_fab2_lib.baseboard_fab2(sch_1):page83_i66:dqs2p"
				( attribute "PN" "175"
					( Origin gPackager )
				)
				( objectStatus "J1B1.175" )
			)
			( pin "@baseboard_fab2_lib.baseboard_fab2(sch_1):page83_i66:dqs3n"
				( attribute "PN" "185"
					( Origin gPackager )
				)
				( objectStatus "J1B1.185" )
			)
			( pin "@baseboard_fab2_lib.baseboard_fab2(sch_1):page83_i66:dqs3p"
				( attribute "PN" "186"
					( Origin gPackager )
				)
				( objectStatus "J1B1.186" )
			)
			( pin "@baseboard_fab2_lib.baseboard_fab2(sch_1):page83_i66:dqs4n"
				( attribute "PN" "244"
					( Origin gPackager )
				)
				( objectStatus "J1B1.244" )
			)
			( pin "@baseboard_fab2_lib.baseboard_fab2(sch_1):page83_i66:dqs4p"
				( attribute "PN" "245"
					( Origin gPackager )
				)
				( objectStatus "J1B1.245" )
			)
			( pin "@baseboard_fab2_lib.baseboard_fab2(sch_1):page83_i66:dqs5n"
				( attribute "PN" "255"
					( Origin gPackager )
				)
				( objectStatus "J1B1.255" )
			)
			( pin "@baseboard_fab2_lib.baseboard_fab2(sch_1):page83_i66:dqs5p"
				( attribute "PN" "256"
					( Origin gPackager )
				)
				( objectStatus "J1B1.256" )
			)
			( pin "@baseboard_fab2_lib.baseboard_fab2(sch_1):page83_i66:dqs6n"
				( attribute "PN" "266"
					( Origin gPackager )
				)
				( objectStatus "J1B1.266" )
			)
			( pin "@baseboard_fab2_lib.baseboard_fab2(sch_1):page83_i66:dqs6p"
				( attribute "PN" "267"
					( Origin gPackager )
				)
				( objectStatus "J1B1.267" )
			)
			( pin "@baseboard_fab2_lib.baseboard_fab2(sch_1):page83_i66:dqs7n"
				( attribute "PN" "277"
					( Origin gPackager )
				)
				( objectStatus "J1B1.277" )
			)
			( pin "@baseboard_fab2_lib.baseboard_fab2(sch_1):page83_i66:dqs7p"
				( attribute "PN" "278"
					( Origin gPackager )
				)
				( objectStatus "J1B1.278" )
			)
			( pin "@baseboard_fab2_lib.baseboard_fab2(sch_1):page83_i66:dqs8n"
				( attribute "PN" "196"
					( Origin gPackager )
				)
				( objectStatus "J1B1.196" )
			)
			( pin "@baseboard_fab2_lib.baseboard_fab2(sch_1):page83_i66:dqs8p"
				( attribute "PN" "197"
					( Origin gPackager )
				)
				( objectStatus "J1B1.197" )
			)
			( pin "@baseboard_fab2_lib.baseboard_fab2(sch_1):page83_i66:dqs9n"
				( attribute "PN" "8"
					( Origin gPackager )
				)
				( objectStatus "J1B1.8" )
			)
			( pin "@baseboard_fab2_lib.baseboard_fab2(sch_1):page83_i66:dqs9p"
				( attribute "PN" "7"
					( Origin gPackager )
				)
				( objectStatus "J1B1.7" )
			)
			( pin "@baseboard_fab2_lib.baseboard_fab2(sch_1):page83_i66:dqs10n"
				( attribute "PN" "19"
					( Origin gPackager )
				)
				( objectStatus "J1B1.19" )
			)
			( pin "@baseboard_fab2_lib.baseboard_fab2(sch_1):page83_i66:dqs10p"
				( attribute "PN" "18"
					( Origin gPackager )
				)
				( objectStatus "J1B1.18" )
			)
			( pin "@baseboard_fab2_lib.baseboard_fab2(sch_1):page83_i66:dqs11n"
				( attribute "PN" "30"
					( Origin gPackager )
				)
				( objectStatus "J1B1.30" )
			)
			( pin "@baseboard_fab2_lib.baseboard_fab2(sch_1):page83_i66:dqs11p"
				( attribute "PN" "29"
					( Origin gPackager )
				)
				( objectStatus "J1B1.29" )
			)
			( pin "@baseboard_fab2_lib.baseboard_fab2(sch_1):page83_i66:dqs12n"
				( attribute "PN" "41"
					( Origin gPackager )
				)
				( objectStatus "J1B1.41" )
			)
			( pin "@baseboard_fab2_lib.baseboard_fab2(sch_1):page83_i66:dqs12p"
				( attribute "PN" "40"
					( Origin gPackager )
				)
				( objectStatus "J1B1.40" )
			)
			( pin "@baseboard_fab2_lib.baseboard_fab2(sch_1):page83_i66:dqs13n"
				( attribute "PN" "100"
					( Origin gPackager )
				)
				( objectStatus "J1B1.100" )
			)
			( pin "@baseboard_fab2_lib.baseboard_fab2(sch_1):page83_i66:dqs13p"
				( attribute "PN" "99"
					( Origin gPackager )
				)
				( objectStatus "J1B1.99" )
			)
			( pin "@baseboard_fab2_lib.baseboard_fab2(sch_1):page83_i66:dqs14n"
				( attribute "PN" "111"
					( Origin gPackager )
				)
				( objectStatus "J1B1.111" )
			)
			( pin "@baseboard_fab2_lib.baseboard_fab2(sch_1):page83_i66:dqs14p"
				( attribute "PN" "110"
					( Origin gPackager )
				)
				( objectStatus "J1B1.110" )
			)
			( pin "@baseboard_fab2_lib.baseboard_fab2(sch_1):page83_i66:dqs15n"
				( attribute "PN" "122"
					( Origin gPackager )
				)
				( objectStatus "J1B1.122" )
			)
			( pin "@baseboard_fab2_lib.baseboard_fab2(sch_1):page83_i66:dqs15p"
				( attribute "PN" "121"
					( Origin gPackager )
				)
				( objectStatus "J1B1.121" )
			)
			( pin "@baseboard_fab2_lib.baseboard_fab2(sch_1):page83_i66:dqs16n"
				( attribute "PN" "133"
					( Origin gPackager )
				)
				( objectStatus "J1B1.133" )
			)
			( pin "@baseboard_fab2_lib.baseboard_fab2(sch_1):page83_i66:dqs16p"
				( attribute "PN" "132"
					( Origin gPackager )
				)
				( objectStatus "J1B1.132" )
			)
			( pin "@baseboard_fab2_lib.baseboard_fab2(sch_1):page83_i66:dqs17n"
				( attribute "PN" "52"
					( Origin gPackager )
				)
				( objectStatus "J1B1.52" )
			)
			( pin "@baseboard_fab2_lib.baseboard_fab2(sch_1):page83_i66:dqs17p"
				( attribute "PN" "51"
					( Origin gPackager )
				)
				( objectStatus "J1B1.51" )
			)
			( pin "@baseboard_fab2_lib.baseboard_fab2(sch_1):page83_i111:a0"
				( attribute "PN" "79"
					( Origin gPackager )
				)
				( objectStatus "J1B1.79" )
			)
			( pin "@baseboard_fab2_lib.baseboard_fab2(sch_1):page83_i111:a1"
				( attribute "PN" "72"
					( Origin gPackager )
				)
				( objectStatus "J1B1.72" )
			)
			( pin "@baseboard_fab2_lib.baseboard_fab2(sch_1):page83_i111:a2"
				( attribute "PN" "216"
					( Origin gPackager )
				)
				( objectStatus "J1B1.216" )
			)
			( pin "@baseboard_fab2_lib.baseboard_fab2(sch_1):page83_i111:a3"
				( attribute "PN" "71"
					( Origin gPackager )
				)
				( objectStatus "J1B1.71" )
			)
			( pin "@baseboard_fab2_lib.baseboard_fab2(sch_1):page83_i111:a4"
				( attribute "PN" "214"
					( Origin gPackager )
				)
				( objectStatus "J1B1.214" )
			)
			( pin "@baseboard_fab2_lib.baseboard_fab2(sch_1):page83_i111:a5"
				( attribute "PN" "213"
					( Origin gPackager )
				)
				( objectStatus "J1B1.213" )
			)
			( pin "@baseboard_fab2_lib.baseboard_fab2(sch_1):page83_i111:a6"
				( attribute "PN" "69"
					( Origin gPackager )
				)
				( objectStatus "J1B1.69" )
			)
			( pin "@baseboard_fab2_lib.baseboard_fab2(sch_1):page83_i111:a7"
				( attribute "PN" "211"
					( Origin gPackager )
				)
				( objectStatus "J1B1.211" )
			)
			( pin "@baseboard_fab2_lib.baseboard_fab2(sch_1):page83_i111:a8"
				( attribute "PN" "68"
					( Origin gPackager )
				)
				( objectStatus "J1B1.68" )
			)
			( pin "@baseboard_fab2_lib.baseboard_fab2(sch_1):page83_i111:a9"
				( attribute "PN" "66"
					( Origin gPackager )
				)
				( objectStatus "J1B1.66" )
			)
			( pin "@baseboard_fab2_lib.baseboard_fab2(sch_1):page83_i111:a10"
				( attribute "PN" "225"
					( Origin gPackager )
				)
				( objectStatus "J1B1.225" )
			)
			( pin "@baseboard_fab2_lib.baseboard_fab2(sch_1):page83_i111:a11"
				( attribute "PN" "210"
					( Origin gPackager )
				)
				( objectStatus "J1B1.210" )
			)
			( pin "@baseboard_fab2_lib.baseboard_fab2(sch_1):page83_i111:a12"
				( attribute "PN" "65"
					( Origin gPackager )
				)
				( objectStatus "J1B1.65" )
			)
			( pin "@baseboard_fab2_lib.baseboard_fab2(sch_1):page83_i111:a13"
				( attribute "PN" "232"
					( Origin gPackager )
				)
				( objectStatus "J1B1.232" )
			)
			( pin "@baseboard_fab2_lib.baseboard_fab2(sch_1):page83_i111:a14_we_n"
				( attribute "PN" "228"
					( Origin gPackager )
				)
				( objectStatus "J1B1.228" )
			)
			( pin "@baseboard_fab2_lib.baseboard_fab2(sch_1):page83_i111:a15_cas_n"
				( attribute "PN" "86"
					( Origin gPackager )
				)
				( objectStatus "J1B1.86" )
			)
			( pin "@baseboard_fab2_lib.baseboard_fab2(sch_1):page83_i111:a16_ras_n"
				( attribute "PN" "82"
					( Origin gPackager )
				)
				( objectStatus "J1B1.82" )
			)
			( pin "@baseboard_fab2_lib.baseboard_fab2(sch_1):page83_i111:a17"
				( attribute "PN" "234"
					( Origin gPackager )
				)
				( objectStatus "J1B1.234" )
			)
			( pin "@baseboard_fab2_lib.baseboard_fab2(sch_1):page83_i111:act_n"
				( attribute "PN" "62"
					( Origin gPackager )
				)
				( objectStatus "J1B1.62" )
			)
			( pin "@baseboard_fab2_lib.baseboard_fab2(sch_1):page83_i111:alert_n"
				( attribute "PN" "208"
					( Origin gPackager )
				)
				( objectStatus "J1B1.208" )
			)
			( pin "@baseboard_fab2_lib.baseboard_fab2(sch_1):page83_i111:ba(0)"
				( attribute "PN" "81"
					( Origin gPackager )
				)
				( objectStatus "J1B1.81" )
			)
			( pin "@baseboard_fab2_lib.baseboard_fab2(sch_1):page83_i111:ba(1)"
				( attribute "PN" "224"
					( Origin gPackager )
				)
				( objectStatus "J1B1.224" )
			)
			( pin "@baseboard_fab2_lib.baseboard_fab2(sch_1):page83_i111:bg(0)"
				( attribute "PN" "63"
					( Origin gPackager )
				)
				( objectStatus "J1B1.63" )
			)
			( pin "@baseboard_fab2_lib.baseboard_fab2(sch_1):page83_i111:bg(1)"
				( attribute "PN" "207"
					( Origin gPackager )
				)
				( objectStatus "J1B1.207" )
			)
			( pin "@baseboard_fab2_lib.baseboard_fab2(sch_1):page83_i111:c(2)"
				( attribute "PN" "235"
					( Origin gPackager )
				)
				( objectStatus "J1B1.235" )
			)
			( pin "@baseboard_fab2_lib.baseboard_fab2(sch_1):page83_i111:cb(0)"
				( attribute "PN" "49"
					( Origin gPackager )
				)
				( objectStatus "J1B1.49" )
			)
			( pin "@baseboard_fab2_lib.baseboard_fab2(sch_1):page83_i111:cb(1)"
				( attribute "PN" "194"
					( Origin gPackager )
				)
				( objectStatus "J1B1.194" )
			)
			( pin "@baseboard_fab2_lib.baseboard_fab2(sch_1):page83_i111:cb(2)"
				( attribute "PN" "56"
					( Origin gPackager )
				)
				( objectStatus "J1B1.56" )
			)
			( pin "@baseboard_fab2_lib.baseboard_fab2(sch_1):page83_i111:cb(3)"
				( attribute "PN" "201"
					( Origin gPackager )
				)
				( objectStatus "J1B1.201" )
			)
			( pin "@baseboard_fab2_lib.baseboard_fab2(sch_1):page83_i111:cb(4)"
				( attribute "PN" "47"
					( Origin gPackager )
				)
				( objectStatus "J1B1.47" )
			)
			( pin "@baseboard_fab2_lib.baseboard_fab2(sch_1):page83_i111:cb(5)"
				( attribute "PN" "192"
					( Origin gPackager )
				)
				( objectStatus "J1B1.192" )
			)
			( pin "@baseboard_fab2_lib.baseboard_fab2(sch_1):page83_i111:cb(6)"
				( attribute "PN" "54"
					( Origin gPackager )
				)
				( objectStatus "J1B1.54" )
			)
			( pin "@baseboard_fab2_lib.baseboard_fab2(sch_1):page83_i111:cb(7)"
				( attribute "PN" "199"
					( Origin gPackager )
				)
				( objectStatus "J1B1.199" )
			)
			( pin "@baseboard_fab2_lib.baseboard_fab2(sch_1):page83_i111:ck0n"
				( attribute "PN" "75"
					( Origin gPackager )
				)
				( objectStatus "J1B1.75" )
			)
			( pin "@baseboard_fab2_lib.baseboard_fab2(sch_1):page83_i111:ck0p"
				( attribute "PN" "74"
					( Origin gPackager )
				)
				( objectStatus "J1B1.74" )
			)
			( pin "@baseboard_fab2_lib.baseboard_fab2(sch_1):page83_i111:ck1n"
				( attribute "PN" "219"
					( Origin gPackager )
				)
				( objectStatus "J1B1.219" )
			)
			( pin "@baseboard_fab2_lib.baseboard_fab2(sch_1):page83_i111:ck1p"
				( attribute "PN" "218"
					( Origin gPackager )
				)
				( objectStatus "J1B1.218" )
			)
			( pin "@baseboard_fab2_lib.baseboard_fab2(sch_1):page83_i111:cke(0)"
				( attribute "PN" "60"
					( Origin gPackager )
				)
				( objectStatus "J1B1.60" )
			)
			( pin "@baseboard_fab2_lib.baseboard_fab2(sch_1):page83_i111:cke(1)"
				( attribute "PN" "203"
					( Origin gPackager )
				)
				( objectStatus "J1B1.203" )
			)
			( pin "@baseboard_fab2_lib.baseboard_fab2(sch_1):page83_i111:dq(0)"
				( attribute "PN" "5"
					( Origin gPackager )
				)
				( objectStatus "J1B1.5" )
			)
			( pin "@baseboard_fab2_lib.baseboard_fab2(sch_1):page83_i111:dq(1)"
				( attribute "PN" "150"
					( Origin gPackager )
				)
				( objectStatus "J1B1.150" )
			)
			( pin "@baseboard_fab2_lib.baseboard_fab2(sch_1):page83_i111:dq(2)"
				( attribute "PN" "12"
					( Origin gPackager )
				)
				( objectStatus "J1B1.12" )
			)
			( pin "@baseboard_fab2_lib.baseboard_fab2(sch_1):page83_i111:dq(3)"
				( attribute "PN" "157"
					( Origin gPackager )
				)
				( objectStatus "J1B1.157" )
			)
			( pin "@baseboard_fab2_lib.baseboard_fab2(sch_1):page83_i111:dq(4)"
				( attribute "PN" "3"
					( Origin gPackager )
				)
				( objectStatus "J1B1.3" )
			)
			( pin "@baseboard_fab2_lib.baseboard_fab2(sch_1):page83_i111:dq(5)"
				( attribute "PN" "148"
					( Origin gPackager )
				)
				( objectStatus "J1B1.148" )
			)
			( pin "@baseboard_fab2_lib.baseboard_fab2(sch_1):page83_i111:dq(6)"
				( attribute "PN" "10"
					( Origin gPackager )
				)
				( objectStatus "J1B1.10" )
			)
			( pin "@baseboard_fab2_lib.baseboard_fab2(sch_1):page83_i111:dq(7)"
				( attribute "PN" "155"
					( Origin gPackager )
				)
				( objectStatus "J1B1.155" )
			)
			( pin "@baseboard_fab2_lib.baseboard_fab2(sch_1):page83_i111:dq(8)"
				( attribute "PN" "16"
					( Origin gPackager )
				)
				( objectStatus "J1B1.16" )
			)
			( pin "@baseboard_fab2_lib.baseboard_fab2(sch_1):page83_i111:dq(9)"
				( attribute "PN" "161"
					( Origin gPackager )
				)
				( objectStatus "J1B1.161" )
			)
			( pin "@baseboard_fab2_lib.baseboard_fab2(sch_1):page83_i111:dq(10)"
				( attribute "PN" "23"
					( Origin gPackager )
				)
				( objectStatus "J1B1.23" )
			)
			( pin "@baseboard_fab2_lib.baseboard_fab2(sch_1):page83_i111:dq(11)"
				( attribute "PN" "168"
					( Origin gPackager )
				)
				( objectStatus "J1B1.168" )
			)
			( pin "@baseboard_fab2_lib.baseboard_fab2(sch_1):page83_i111:dq(12)"
				( attribute "PN" "14"
					( Origin gPackager )
				)
				( objectStatus "J1B1.14" )
			)
			( pin "@baseboard_fab2_lib.baseboard_fab2(sch_1):page83_i111:dq(13)"
				( attribute "PN" "159"
					( Origin gPackager )
				)
				( objectStatus "J1B1.159" )
			)
			( pin "@baseboard_fab2_lib.baseboard_fab2(sch_1):page83_i111:dq(14)"
				( attribute "PN" "21"
					( Origin gPackager )
				)
				( objectStatus "J1B1.21" )
			)
			( pin "@baseboard_fab2_lib.baseboard_fab2(sch_1):page83_i111:dq(15)"
				( attribute "PN" "166"
					( Origin gPackager )
				)
				( objectStatus "J1B1.166" )
			)
			( pin "@baseboard_fab2_lib.baseboard_fab2(sch_1):page83_i111:dq(16)"
				( attribute "PN" "27"
					( Origin gPackager )
				)
				( objectStatus "J1B1.27" )
			)
			( pin "@baseboard_fab2_lib.baseboard_fab2(sch_1):page83_i111:dq(17)"
				( attribute "PN" "172"
					( Origin gPackager )
				)
				( objectStatus "J1B1.172" )
			)
			( pin "@baseboard_fab2_lib.baseboard_fab2(sch_1):page83_i111:dq(18)"
				( attribute "PN" "34"
					( Origin gPackager )
				)
				( objectStatus "J1B1.34" )
			)
			( pin "@baseboard_fab2_lib.baseboard_fab2(sch_1):page83_i111:dq(19)"
				( attribute "PN" "179"
					( Origin gPackager )
				)
				( objectStatus "J1B1.179" )
			)
			( pin "@baseboard_fab2_lib.baseboard_fab2(sch_1):page83_i111:dq(20)"
				( attribute "PN" "25"
					( Origin gPackager )
				)
				( objectStatus "J1B1.25" )
			)
			( pin "@baseboard_fab2_lib.baseboard_fab2(sch_1):page83_i111:dq(21)"
				( attribute "PN" "170"
					( Origin gPackager )
				)
				( objectStatus "J1B1.170" )
			)
			( pin "@baseboard_fab2_lib.baseboard_fab2(sch_1):page83_i111:dq(22)"
				( attribute "PN" "32"
					( Origin gPackager )
				)
				( objectStatus "J1B1.32" )
			)
			( pin "@baseboard_fab2_lib.baseboard_fab2(sch_1):page83_i111:dq(23)"
				( attribute "PN" "177"
					( Origin gPackager )
				)
				( objectStatus "J1B1.177" )
			)
			( pin "@baseboard_fab2_lib.baseboard_fab2(sch_1):page83_i111:dq(24)"
				( attribute "PN" "38"
					( Origin gPackager )
				)
				( objectStatus "J1B1.38" )
			)
			( pin "@baseboard_fab2_lib.baseboard_fab2(sch_1):page83_i111:dq(25)"
				( attribute "PN" "183"
					( Origin gPackager )
				)
				( objectStatus "J1B1.183" )
			)
			( pin "@baseboard_fab2_lib.baseboard_fab2(sch_1):page83_i111:dq(26)"
				( attribute "PN" "45"
					( Origin gPackager )
				)
				( objectStatus "J1B1.45" )
			)
			( pin "@baseboard_fab2_lib.baseboard_fab2(sch_1):page83_i111:dq(27)"
				( attribute "PN" "190"
					( Origin gPackager )
				)
				( objectStatus "J1B1.190" )
			)
			( pin "@baseboard_fab2_lib.baseboard_fab2(sch_1):page83_i111:dq(28)"
				( attribute "PN" "36"
					( Origin gPackager )
				)
				( objectStatus "J1B1.36" )
			)
			( pin "@baseboard_fab2_lib.baseboard_fab2(sch_1):page83_i111:dq(29)"
				( attribute "PN" "181"
					( Origin gPackager )
				)
				( objectStatus "J1B1.181" )
			)
			( pin "@baseboard_fab2_lib.baseboard_fab2(sch_1):page83_i111:dq(30)"
				( attribute "PN" "43"
					( Origin gPackager )
				)
				( objectStatus "J1B1.43" )
			)
			( pin "@baseboard_fab2_lib.baseboard_fab2(sch_1):page83_i111:dq(31)"
				( attribute "PN" "188"
					( Origin gPackager )
				)
				( objectStatus "J1B1.188" )
			)
			( pin "@baseboard_fab2_lib.baseboard_fab2(sch_1):page83_i111:dq(32)"
				( attribute "PN" "97"
					( Origin gPackager )
				)
				( objectStatus "J1B1.97" )
			)
			( pin "@baseboard_fab2_lib.baseboard_fab2(sch_1):page83_i111:dq(33)"
				( attribute "PN" "242"
					( Origin gPackager )
				)
				( objectStatus "J1B1.242" )
			)
			( pin "@baseboard_fab2_lib.baseboard_fab2(sch_1):page83_i111:dq(34)"
				( attribute "PN" "104"
					( Origin gPackager )
				)
				( objectStatus "J1B1.104" )
			)
			( pin "@baseboard_fab2_lib.baseboard_fab2(sch_1):page83_i111:dq(35)"
				( attribute "PN" "249"
					( Origin gPackager )
				)
				( objectStatus "J1B1.249" )
			)
			( pin "@baseboard_fab2_lib.baseboard_fab2(sch_1):page83_i111:dq(36)"
				( attribute "PN" "95"
					( Origin gPackager )
				)
				( objectStatus "J1B1.95" )
			)
			( pin "@baseboard_fab2_lib.baseboard_fab2(sch_1):page83_i111:dq(37)"
				( attribute "PN" "240"
					( Origin gPackager )
				)
				( objectStatus "J1B1.240" )
			)
			( pin "@baseboard_fab2_lib.baseboard_fab2(sch_1):page83_i111:dq(38)"
				( attribute "PN" "102"
					( Origin gPackager )
				)
				( objectStatus "J1B1.102" )
			)
			( pin "@baseboard_fab2_lib.baseboard_fab2(sch_1):page83_i111:dq(39)"
				( attribute "PN" "247"
					( Origin gPackager )
				)
				( objectStatus "J1B1.247" )
			)
			( pin "@baseboard_fab2_lib.baseboard_fab2(sch_1):page83_i111:dq(40)"
				( attribute "PN" "108"
					( Origin gPackager )
				)
				( objectStatus "J1B1.108" )
			)
			( pin "@baseboard_fab2_lib.baseboard_fab2(sch_1):page83_i111:dq(41)"
				( attribute "PN" "253"
					( Origin gPackager )
				)
				( objectStatus "J1B1.253" )
			)
			( pin "@baseboard_fab2_lib.baseboard_fab2(sch_1):page83_i111:dq(42)"
				( attribute "PN" "115"
					( Origin gPackager )
				)
				( objectStatus "J1B1.115" )
			)
			( pin "@baseboard_fab2_lib.baseboard_fab2(sch_1):page83_i111:dq(43)"
				( attribute "PN" "260"
					( Origin gPackager )
				)
				( objectStatus "J1B1.260" )
			)
			( pin "@baseboard_fab2_lib.baseboard_fab2(sch_1):page83_i111:dq(44)"
				( attribute "PN" "106"
					( Origin gPackager )
				)
				( objectStatus "J1B1.106" )
			)
			( pin "@baseboard_fab2_lib.baseboard_fab2(sch_1):page83_i111:dq(45)"
				( attribute "PN" "251"
					( Origin gPackager )
				)
				( objectStatus "J1B1.251" )
			)
			( pin "@baseboard_fab2_lib.baseboard_fab2(sch_1):page83_i111:dq(46)"
				( attribute "PN" "113"
					( Origin gPackager )
				)
				( objectStatus "J1B1.113" )
			)
			( pin "@baseboard_fab2_lib.baseboard_fab2(sch_1):page83_i111:dq(47)"
				( attribute "PN" "258"
					( Origin gPackager )
				)
				( objectStatus "J1B1.258" )
			)
			( pin "@baseboard_fab2_lib.baseboard_fab2(sch_1):page83_i111:dq(48)"
				( attribute "PN" "119"
					( Origin gPackager )
				)
				( objectStatus "J1B1.119" )
			)
			( pin "@baseboard_fab2_lib.baseboard_fab2(sch_1):page83_i111:dq(49)"
				( attribute "PN" "264"
					( Origin gPackager )
				)
				( objectStatus "J1B1.264" )
			)
			( pin "@baseboard_fab2_lib.baseboard_fab2(sch_1):page83_i111:dq(50)"
				( attribute "PN" "126"
					( Origin gPackager )
				)
				( objectStatus "J1B1.126" )
			)
			( pin "@baseboard_fab2_lib.baseboard_fab2(sch_1):page83_i111:dq(51)"
				( attribute "PN" "271"
					( Origin gPackager )
				)
				( objectStatus "J1B1.271" )
			)
			( pin "@baseboard_fab2_lib.baseboard_fab2(sch_1):page83_i111:dq(52)"
				( attribute "PN" "117"
					( Origin gPackager )
				)
				( objectStatus "J1B1.117" )
			)
			( pin "@baseboard_fab2_lib.baseboard_fab2(sch_1):page83_i111:dq(53)"
				( attribute "PN" "262"
					( Origin gPackager )
				)
				( objectStatus "J1B1.262" )
			)
			( pin "@baseboard_fab2_lib.baseboard_fab2(sch_1):page83_i111:dq(54)"
				( attribute "PN" "124"
					( Origin gPackager )
				)
				( objectStatus "J1B1.124" )
			)
			( pin "@baseboard_fab2_lib.baseboard_fab2(sch_1):page83_i111:dq(55)"
				( attribute "PN" "269"
					( Origin gPackager )
				)
				( objectStatus "J1B1.269" )
			)
			( pin "@baseboard_fab2_lib.baseboard_fab2(sch_1):page83_i111:dq(56)"
				( attribute "PN" "130"
					( Origin gPackager )
				)
				( objectStatus "J1B1.130" )
			)
			( pin "@baseboard_fab2_lib.baseboard_fab2(sch_1):page83_i111:dq(57)"
				( attribute "PN" "275"
					( Origin gPackager )
				)
				( objectStatus "J1B1.275" )
			)
			( pin "@baseboard_fab2_lib.baseboard_fab2(sch_1):page83_i111:dq(58)"
				( attribute "PN" "137"
					( Origin gPackager )
				)
				( objectStatus "J1B1.137" )
			)
			( pin "@baseboard_fab2_lib.baseboard_fab2(sch_1):page83_i111:dq(59)"
				( attribute "PN" "282"
					( Origin gPackager )
				)
				( objectStatus "J1B1.282" )
			)
			( pin "@baseboard_fab2_lib.baseboard_fab2(sch_1):page83_i111:dq(60)"
				( attribute "PN" "128"
					( Origin gPackager )
				)
				( objectStatus "J1B1.128" )
			)
			( pin "@baseboard_fab2_lib.baseboard_fab2(sch_1):page83_i111:dq(61)"
				( attribute "PN" "273"
					( Origin gPackager )
				)
				( objectStatus "J1B1.273" )
			)
			( pin "@baseboard_fab2_lib.baseboard_fab2(sch_1):page83_i111:dq(62)"
				( attribute "PN" "135"
					( Origin gPackager )
				)
				( objectStatus "J1B1.135" )
			)
			( pin "@baseboard_fab2_lib.baseboard_fab2(sch_1):page83_i111:dq(63)"
				( attribute "PN" "280"
					( Origin gPackager )
				)
				( objectStatus "J1B1.280" )
			)
			( pin "@baseboard_fab2_lib.baseboard_fab2(sch_1):page83_i111:event_n"
				( attribute "PN" "78"
					( Origin gPackager )
				)
				( objectStatus "J1B1.78" )
			)
			( pin "@baseboard_fab2_lib.baseboard_fab2(sch_1):page83_i111:odt(0)"
				( attribute "PN" "87"
					( Origin gPackager )
				)
				( objectStatus "J1B1.87" )
			)
			( pin "@baseboard_fab2_lib.baseboard_fab2(sch_1):page83_i111:odt(1)"
				( attribute "PN" "91"
					( Origin gPackager )
				)
				( objectStatus "J1B1.91" )
			)
			( pin "@baseboard_fab2_lib.baseboard_fab2(sch_1):page83_i111:par"
				( attribute "PN" "222"
					( Origin gPackager )
				)
				( objectStatus "J1B1.222" )
			)
			( pin "@baseboard_fab2_lib.baseboard_fab2(sch_1):page83_i111:reset_n"
				( attribute "PN" "58"
					( Origin gPackager )
				)
				( objectStatus "J1B1.58" )
			)
			( pin "@baseboard_fab2_lib.baseboard_fab2(sch_1):page83_i111:rfu(0)"
				( attribute "PN" "205"
					( Origin gPackager )
				)
				( objectStatus "J1B1.205" )
			)
			( pin "@baseboard_fab2_lib.baseboard_fab2(sch_1):page83_i111:rfu(1)"
				( attribute "PN" "227"
					( Origin gPackager )
				)
				( objectStatus "J1B1.227" )
			)
			( pin "@baseboard_fab2_lib.baseboard_fab2(sch_1):page83_i111:rfu(2)"
				( attribute "PN" "144"
					( Origin gPackager )
				)
				( objectStatus "J1B1.144" )
			)
			( pin "@baseboard_fab2_lib.baseboard_fab2(sch_1):page83_i111:s0_n"
				( attribute "PN" "84"
					( Origin gPackager )
				)
				( objectStatus "J1B1.84" )
			)
			( pin "@baseboard_fab2_lib.baseboard_fab2(sch_1):page83_i111:s1_n"
				( attribute "PN" "89"
					( Origin gPackager )
				)
				( objectStatus "J1B1.89" )
			)
			( pin "@baseboard_fab2_lib.baseboard_fab2(sch_1):page83_i111:s2_n_c(0)"
				( attribute "PN" "93"
					( Origin gPackager )
				)
				( objectStatus "J1B1.93" )
			)
			( pin "@baseboard_fab2_lib.baseboard_fab2(sch_1):page83_i111:s3_n_c(1)"
				( attribute "PN" "237"
					( Origin gPackager )
				)
				( objectStatus "J1B1.237" )
			)
			( pin "@baseboard_fab2_lib.baseboard_fab2(sch_1):page83_i111:sa(0)"
				( attribute "PN" "139"
					( Origin gPackager )
				)
				( objectStatus "J1B1.139" )
			)
			( pin "@baseboard_fab2_lib.baseboard_fab2(sch_1):page83_i111:sa(1)"
				( attribute "PN" "140"
					( Origin gPackager )
				)
				( objectStatus "J1B1.140" )
			)
			( pin "@baseboard_fab2_lib.baseboard_fab2(sch_1):page83_i111:sa(2)"
				( attribute "PN" "238"
					( Origin gPackager )
				)
				( objectStatus "J1B1.238" )
			)
			( pin "@baseboard_fab2_lib.baseboard_fab2(sch_1):page83_i111:save_n_nc"
				( attribute "PN" "230"
					( Origin gPackager )
				)
				( objectStatus "J1B1.230" )
			)
			( pin "@baseboard_fab2_lib.baseboard_fab2(sch_1):page83_i111:scl"
				( attribute "PN" "141"
					( Origin gPackager )
				)
				( objectStatus "J1B1.141" )
			)
			( pin "@baseboard_fab2_lib.baseboard_fab2(sch_1):page83_i111:sda"
				( attribute "PN" "285"
					( Origin gPackager )
				)
				( objectStatus "J1B1.285" )
			)
			( pin "@baseboard_fab2_lib.baseboard_fab2(sch_1):page83_i111:vddspd"
				( attribute "PN" "284"
					( Origin gPackager )
				)
				( objectStatus "J1B1.284" )
			)
			( pin "@baseboard_fab2_lib.baseboard_fab2(sch_1):page83_i111:vrefca"
				( attribute "PN" "146"
					( Origin gPackager )
				)
				( objectStatus "J1B1.146" )
			)
			( pin "@baseboard_fab2_lib.baseboard_fab2(sch_1):page83_i167:\12v\(0)"
				( attribute "PN" "145"
					( Origin gPackager )
				)
				( objectStatus "J1B1.145" )
			)
			( pin "@baseboard_fab2_lib.baseboard_fab2(sch_1):page83_i167:\12v\(1)"
				( attribute "PN" "1"
					( Origin gPackager )
				)
				( objectStatus "J1B1.1" )
			)
			( pin "@baseboard_fab2_lib.baseboard_fab2(sch_1):page83_i167:vdd(0)"
				( attribute "PN" "236"
					( Origin gPackager )
				)
				( objectStatus "J1B1.236" )
			)
			( pin "@baseboard_fab2_lib.baseboard_fab2(sch_1):page83_i167:vdd(1)"
				( attribute "PN" "233"
					( Origin gPackager )
				)
				( objectStatus "J1B1.233" )
			)
			( pin "@baseboard_fab2_lib.baseboard_fab2(sch_1):page83_i167:vdd(2)"
				( attribute "PN" "231"
					( Origin gPackager )
				)
				( objectStatus "J1B1.231" )
			)
			( pin "@baseboard_fab2_lib.baseboard_fab2(sch_1):page83_i167:vdd(3)"
				( attribute "PN" "229"
					( Origin gPackager )
				)
				( objectStatus "J1B1.229" )
			)
			( pin "@baseboard_fab2_lib.baseboard_fab2(sch_1):page83_i167:vdd(4)"
				( attribute "PN" "226"
					( Origin gPackager )
				)
				( objectStatus "J1B1.226" )
			)
			( pin "@baseboard_fab2_lib.baseboard_fab2(sch_1):page83_i167:vdd(5)"
				( attribute "PN" "223"
					( Origin gPackager )
				)
				( objectStatus "J1B1.223" )
			)
			( pin "@baseboard_fab2_lib.baseboard_fab2(sch_1):page83_i167:vdd(6)"
				( attribute "PN" "220"
					( Origin gPackager )
				)
				( objectStatus "J1B1.220" )
			)
			( pin "@baseboard_fab2_lib.baseboard_fab2(sch_1):page83_i167:vdd(7)"
				( attribute "PN" "217"
					( Origin gPackager )
				)
				( objectStatus "J1B1.217" )
			)
			( pin "@baseboard_fab2_lib.baseboard_fab2(sch_1):page83_i167:vdd(8)"
				( attribute "PN" "215"
					( Origin gPackager )
				)
				( objectStatus "J1B1.215" )
			)
			( pin "@baseboard_fab2_lib.baseboard_fab2(sch_1):page83_i167:vdd(9)"
				( attribute "PN" "212"
					( Origin gPackager )
				)
				( objectStatus "J1B1.212" )
			)
			( pin "@baseboard_fab2_lib.baseboard_fab2(sch_1):page83_i167:vdd(10)"
				( attribute "PN" "209"
					( Origin gPackager )
				)
				( objectStatus "J1B1.209" )
			)
			( pin "@baseboard_fab2_lib.baseboard_fab2(sch_1):page83_i167:vdd(11)"
				( attribute "PN" "206"
					( Origin gPackager )
				)
				( objectStatus "J1B1.206" )
			)
			( pin "@baseboard_fab2_lib.baseboard_fab2(sch_1):page83_i167:vdd(12)"
				( attribute "PN" "204"
					( Origin gPackager )
				)
				( objectStatus "J1B1.204" )
			)
			( pin "@baseboard_fab2_lib.baseboard_fab2(sch_1):page83_i167:vdd(13)"
				( attribute "PN" "92"
					( Origin gPackager )
				)
				( objectStatus "J1B1.92" )
			)
			( pin "@baseboard_fab2_lib.baseboard_fab2(sch_1):page83_i167:vdd(14)"
				( attribute "PN" "90"
					( Origin gPackager )
				)
				( objectStatus "J1B1.90" )
			)
			( pin "@baseboard_fab2_lib.baseboard_fab2(sch_1):page83_i167:vdd(15)"
				( attribute "PN" "88"
					( Origin gPackager )
				)
				( objectStatus "J1B1.88" )
			)
			( pin "@baseboard_fab2_lib.baseboard_fab2(sch_1):page83_i167:vdd(16)"
				( attribute "PN" "85"
					( Origin gPackager )
				)
				( objectStatus "J1B1.85" )
			)
			( pin "@baseboard_fab2_lib.baseboard_fab2(sch_1):page83_i167:vdd(17)"
				( attribute "PN" "83"
					( Origin gPackager )
				)
				( objectStatus "J1B1.83" )
			)
			( pin "@baseboard_fab2_lib.baseboard_fab2(sch_1):page83_i167:vdd(18)"
				( attribute "PN" "80"
					( Origin gPackager )
				)
				( objectStatus "J1B1.80" )
			)
			( pin "@baseboard_fab2_lib.baseboard_fab2(sch_1):page83_i167:vdd(19)"
				( attribute "PN" "76"
					( Origin gPackager )
				)
				( objectStatus "J1B1.76" )
			)
			( pin "@baseboard_fab2_lib.baseboard_fab2(sch_1):page83_i167:vdd(20)"
				( attribute "PN" "73"
					( Origin gPackager )
				)
				( objectStatus "J1B1.73" )
			)
			( pin "@baseboard_fab2_lib.baseboard_fab2(sch_1):page83_i167:vdd(21)"
				( attribute "PN" "70"
					( Origin gPackager )
				)
				( objectStatus "J1B1.70" )
			)
			( pin "@baseboard_fab2_lib.baseboard_fab2(sch_1):page83_i167:vdd(22)"
				( attribute "PN" "67"
					( Origin gPackager )
				)
				( objectStatus "J1B1.67" )
			)
			( pin "@baseboard_fab2_lib.baseboard_fab2(sch_1):page83_i167:vdd(23)"
				( attribute "PN" "64"
					( Origin gPackager )
				)
				( objectStatus "J1B1.64" )
			)
			( pin "@baseboard_fab2_lib.baseboard_fab2(sch_1):page83_i167:vdd(24)"
				( attribute "PN" "61"
					( Origin gPackager )
				)
				( objectStatus "J1B1.61" )
			)
			( pin "@baseboard_fab2_lib.baseboard_fab2(sch_1):page83_i167:vdd(25)"
				( attribute "PN" "59"
					( Origin gPackager )
				)
				( objectStatus "J1B1.59" )
			)
			( pin "@baseboard_fab2_lib.baseboard_fab2(sch_1):page83_i167:vpp(0)"
				( attribute "PN" "287"
					( Origin gPackager )
				)
				( objectStatus "J1B1.287" )
			)
			( pin "@baseboard_fab2_lib.baseboard_fab2(sch_1):page83_i167:vpp(1)"
				( attribute "PN" "286"
					( Origin gPackager )
				)
				( objectStatus "J1B1.286" )
			)
			( pin "@baseboard_fab2_lib.baseboard_fab2(sch_1):page83_i167:vpp(2)"
				( attribute "PN" "288"
					( Origin gPackager )
				)
				( objectStatus "J1B1.288" )
			)
			( pin "@baseboard_fab2_lib.baseboard_fab2(sch_1):page83_i167:vpp(3)"
				( attribute "PN" "143"
					( Origin gPackager )
				)
				( objectStatus "J1B1.143" )
			)
			( pin "@baseboard_fab2_lib.baseboard_fab2(sch_1):page83_i167:vpp(4)"
				( attribute "PN" "142"
					( Origin gPackager )
				)
				( objectStatus "J1B1.142" )
			)
			( pin "@baseboard_fab2_lib.baseboard_fab2(sch_1):page83_i167:vtt(0)"
				( attribute "PN" "221"
					( Origin gPackager )
				)
				( objectStatus "J1B1.221" )
			)
			( pin "@baseboard_fab2_lib.baseboard_fab2(sch_1):page83_i167:vtt(1)"
				( attribute "PN" "77"
					( Origin gPackager )
				)
				( objectStatus "J1B1.77" )
			)
			( pin "@baseboard_fab2_lib.baseboard_fab2(sch_1):page83_i176:a"
				( attribute "PN" "1"
					( Origin gPackager )
				)
				( objectStatus "C1B9.1" )
			)
			( pin "@baseboard_fab2_lib.baseboard_fab2(sch_1):page83_i176:b"
				( attribute "PN" "2"
					( Origin gPackager )
				)
				( objectStatus "C1B9.2" )
			)
			( pin "@baseboard_fab2_lib.baseboard_fab2(sch_1):page84_i4:a"
				( attribute "PN" "1"
					( Origin gPackager )
				)
				( objectStatus "C9M1.1" )
			)
			( pin "@baseboard_fab2_lib.baseboard_fab2(sch_1):page84_i4:b"
				( attribute "PN" "2"
					( Origin gPackager )
				)
				( objectStatus "C9M1.2" )
			)
			( pin "@baseboard_fab2_lib.baseboard_fab2(sch_1):page84_i14:a0"
				( attribute "PN" "79"
					( Origin gPackager )
				)
				( objectStatus "J9M1.79" )
			)
			( pin "@baseboard_fab2_lib.baseboard_fab2(sch_1):page84_i14:a1"
				( attribute "PN" "72"
					( Origin gPackager )
				)
				( objectStatus "J9M1.72" )
			)
			( pin "@baseboard_fab2_lib.baseboard_fab2(sch_1):page84_i14:a2"
				( attribute "PN" "216"
					( Origin gPackager )
				)
				( objectStatus "J9M1.216" )
			)
			( pin "@baseboard_fab2_lib.baseboard_fab2(sch_1):page84_i14:a3"
				( attribute "PN" "71"
					( Origin gPackager )
				)
				( objectStatus "J9M1.71" )
			)
			( pin "@baseboard_fab2_lib.baseboard_fab2(sch_1):page84_i14:a4"
				( attribute "PN" "214"
					( Origin gPackager )
				)
				( objectStatus "J9M1.214" )
			)
			( pin "@baseboard_fab2_lib.baseboard_fab2(sch_1):page84_i14:a5"
				( attribute "PN" "213"
					( Origin gPackager )
				)
				( objectStatus "J9M1.213" )
			)
			( pin "@baseboard_fab2_lib.baseboard_fab2(sch_1):page84_i14:a6"
				( attribute "PN" "69"
					( Origin gPackager )
				)
				( objectStatus "J9M1.69" )
			)
			( pin "@baseboard_fab2_lib.baseboard_fab2(sch_1):page84_i14:a7"
				( attribute "PN" "211"
					( Origin gPackager )
				)
				( objectStatus "J9M1.211" )
			)
			( pin "@baseboard_fab2_lib.baseboard_fab2(sch_1):page84_i14:a8"
				( attribute "PN" "68"
					( Origin gPackager )
				)
				( objectStatus "J9M1.68" )
			)
			( pin "@baseboard_fab2_lib.baseboard_fab2(sch_1):page84_i14:a9"
				( attribute "PN" "66"
					( Origin gPackager )
				)
				( objectStatus "J9M1.66" )
			)
			( pin "@baseboard_fab2_lib.baseboard_fab2(sch_1):page84_i14:a10"
				( attribute "PN" "225"
					( Origin gPackager )
				)
				( objectStatus "J9M1.225" )
			)
			( pin "@baseboard_fab2_lib.baseboard_fab2(sch_1):page84_i14:a11"
				( attribute "PN" "210"
					( Origin gPackager )
				)
				( objectStatus "J9M1.210" )
			)
			( pin "@baseboard_fab2_lib.baseboard_fab2(sch_1):page84_i14:a12"
				( attribute "PN" "65"
					( Origin gPackager )
				)
				( objectStatus "J9M1.65" )
			)
			( pin "@baseboard_fab2_lib.baseboard_fab2(sch_1):page84_i14:a13"
				( attribute "PN" "232"
					( Origin gPackager )
				)
				( objectStatus "J9M1.232" )
			)
			( pin "@baseboard_fab2_lib.baseboard_fab2(sch_1):page84_i14:a14_we_n"
				( attribute "PN" "228"
					( Origin gPackager )
				)
				( objectStatus "J9M1.228" )
			)
			( pin "@baseboard_fab2_lib.baseboard_fab2(sch_1):page84_i14:a15_cas_n"
				( attribute "PN" "86"
					( Origin gPackager )
				)
				( objectStatus "J9M1.86" )
			)
			( pin "@baseboard_fab2_lib.baseboard_fab2(sch_1):page84_i14:a16_ras_n"
				( attribute "PN" "82"
					( Origin gPackager )
				)
				( objectStatus "J9M1.82" )
			)
			( pin "@baseboard_fab2_lib.baseboard_fab2(sch_1):page84_i14:a17"
				( attribute "PN" "234"
					( Origin gPackager )
				)
				( objectStatus "J9M1.234" )
			)
			( pin "@baseboard_fab2_lib.baseboard_fab2(sch_1):page84_i14:act_n"
				( attribute "PN" "62"
					( Origin gPackager )
				)
				( objectStatus "J9M1.62" )
			)
			( pin "@baseboard_fab2_lib.baseboard_fab2(sch_1):page84_i14:alert_n"
				( attribute "PN" "208"
					( Origin gPackager )
				)
				( objectStatus "J9M1.208" )
			)
			( pin "@baseboard_fab2_lib.baseboard_fab2(sch_1):page84_i14:ba(0)"
				( attribute "PN" "81"
					( Origin gPackager )
				)
				( objectStatus "J9M1.81" )
			)
			( pin "@baseboard_fab2_lib.baseboard_fab2(sch_1):page84_i14:ba(1)"
				( attribute "PN" "224"
					( Origin gPackager )
				)
				( objectStatus "J9M1.224" )
			)
			( pin "@baseboard_fab2_lib.baseboard_fab2(sch_1):page84_i14:bg(0)"
				( attribute "PN" "63"
					( Origin gPackager )
				)
				( objectStatus "J9M1.63" )
			)
			( pin "@baseboard_fab2_lib.baseboard_fab2(sch_1):page84_i14:bg(1)"
				( attribute "PN" "207"
					( Origin gPackager )
				)
				( objectStatus "J9M1.207" )
			)
			( pin "@baseboard_fab2_lib.baseboard_fab2(sch_1):page84_i14:c(2)"
				( attribute "PN" "235"
					( Origin gPackager )
				)
				( objectStatus "J9M1.235" )
			)
			( pin "@baseboard_fab2_lib.baseboard_fab2(sch_1):page84_i14:cb(0)"
				( attribute "PN" "49"
					( Origin gPackager )
				)
				( objectStatus "J9M1.49" )
			)
			( pin "@baseboard_fab2_lib.baseboard_fab2(sch_1):page84_i14:cb(1)"
				( attribute "PN" "194"
					( Origin gPackager )
				)
				( objectStatus "J9M1.194" )
			)
			( pin "@baseboard_fab2_lib.baseboard_fab2(sch_1):page84_i14:cb(2)"
				( attribute "PN" "56"
					( Origin gPackager )
				)
				( objectStatus "J9M1.56" )
			)
			( pin "@baseboard_fab2_lib.baseboard_fab2(sch_1):page84_i14:cb(3)"
				( attribute "PN" "201"
					( Origin gPackager )
				)
				( objectStatus "J9M1.201" )
			)
			( pin "@baseboard_fab2_lib.baseboard_fab2(sch_1):page84_i14:cb(4)"
				( attribute "PN" "47"
					( Origin gPackager )
				)
				( objectStatus "J9M1.47" )
			)
			( pin "@baseboard_fab2_lib.baseboard_fab2(sch_1):page84_i14:cb(5)"
				( attribute "PN" "192"
					( Origin gPackager )
				)
				( objectStatus "J9M1.192" )
			)
			( pin "@baseboard_fab2_lib.baseboard_fab2(sch_1):page84_i14:cb(6)"
				( attribute "PN" "54"
					( Origin gPackager )
				)
				( objectStatus "J9M1.54" )
			)
			( pin "@baseboard_fab2_lib.baseboard_fab2(sch_1):page84_i14:cb(7)"
				( attribute "PN" "199"
					( Origin gPackager )
				)
				( objectStatus "J9M1.199" )
			)
			( pin "@baseboard_fab2_lib.baseboard_fab2(sch_1):page84_i14:ck0n"
				( attribute "PN" "75"
					( Origin gPackager )
				)
				( objectStatus "J9M1.75" )
			)
			( pin "@baseboard_fab2_lib.baseboard_fab2(sch_1):page84_i14:ck0p"
				( attribute "PN" "74"
					( Origin gPackager )
				)
				( objectStatus "J9M1.74" )
			)
			( pin "@baseboard_fab2_lib.baseboard_fab2(sch_1):page84_i14:ck1n"
				( attribute "PN" "219"
					( Origin gPackager )
				)
				( objectStatus "J9M1.219" )
			)
			( pin "@baseboard_fab2_lib.baseboard_fab2(sch_1):page84_i14:ck1p"
				( attribute "PN" "218"
					( Origin gPackager )
				)
				( objectStatus "J9M1.218" )
			)
			( pin "@baseboard_fab2_lib.baseboard_fab2(sch_1):page84_i14:cke(0)"
				( attribute "PN" "60"
					( Origin gPackager )
				)
				( objectStatus "J9M1.60" )
			)
			( pin "@baseboard_fab2_lib.baseboard_fab2(sch_1):page84_i14:cke(1)"
				( attribute "PN" "203"
					( Origin gPackager )
				)
				( objectStatus "J9M1.203" )
			)
			( pin "@baseboard_fab2_lib.baseboard_fab2(sch_1):page84_i14:dq(0)"
				( attribute "PN" "5"
					( Origin gPackager )
				)
				( objectStatus "J9M1.5" )
			)
			( pin "@baseboard_fab2_lib.baseboard_fab2(sch_1):page84_i14:dq(1)"
				( attribute "PN" "150"
					( Origin gPackager )
				)
				( objectStatus "J9M1.150" )
			)
			( pin "@baseboard_fab2_lib.baseboard_fab2(sch_1):page84_i14:dq(2)"
				( attribute "PN" "12"
					( Origin gPackager )
				)
				( objectStatus "J9M1.12" )
			)
			( pin "@baseboard_fab2_lib.baseboard_fab2(sch_1):page84_i14:dq(3)"
				( attribute "PN" "157"
					( Origin gPackager )
				)
				( objectStatus "J9M1.157" )
			)
			( pin "@baseboard_fab2_lib.baseboard_fab2(sch_1):page84_i14:dq(4)"
				( attribute "PN" "3"
					( Origin gPackager )
				)
				( objectStatus "J9M1.3" )
			)
			( pin "@baseboard_fab2_lib.baseboard_fab2(sch_1):page84_i14:dq(5)"
				( attribute "PN" "148"
					( Origin gPackager )
				)
				( objectStatus "J9M1.148" )
			)
			( pin "@baseboard_fab2_lib.baseboard_fab2(sch_1):page84_i14:dq(6)"
				( attribute "PN" "10"
					( Origin gPackager )
				)
				( objectStatus "J9M1.10" )
			)
			( pin "@baseboard_fab2_lib.baseboard_fab2(sch_1):page84_i14:dq(7)"
				( attribute "PN" "155"
					( Origin gPackager )
				)
				( objectStatus "J9M1.155" )
			)
			( pin "@baseboard_fab2_lib.baseboard_fab2(sch_1):page84_i14:dq(8)"
				( attribute "PN" "16"
					( Origin gPackager )
				)
				( objectStatus "J9M1.16" )
			)
			( pin "@baseboard_fab2_lib.baseboard_fab2(sch_1):page84_i14:dq(9)"
				( attribute "PN" "161"
					( Origin gPackager )
				)
				( objectStatus "J9M1.161" )
			)
			( pin "@baseboard_fab2_lib.baseboard_fab2(sch_1):page84_i14:dq(10)"
				( attribute "PN" "23"
					( Origin gPackager )
				)
				( objectStatus "J9M1.23" )
			)
			( pin "@baseboard_fab2_lib.baseboard_fab2(sch_1):page84_i14:dq(11)"
				( attribute "PN" "168"
					( Origin gPackager )
				)
				( objectStatus "J9M1.168" )
			)
			( pin "@baseboard_fab2_lib.baseboard_fab2(sch_1):page84_i14:dq(12)"
				( attribute "PN" "14"
					( Origin gPackager )
				)
				( objectStatus "J9M1.14" )
			)
			( pin "@baseboard_fab2_lib.baseboard_fab2(sch_1):page84_i14:dq(13)"
				( attribute "PN" "159"
					( Origin gPackager )
				)
				( objectStatus "J9M1.159" )
			)
			( pin "@baseboard_fab2_lib.baseboard_fab2(sch_1):page84_i14:dq(14)"
				( attribute "PN" "21"
					( Origin gPackager )
				)
				( objectStatus "J9M1.21" )
			)
			( pin "@baseboard_fab2_lib.baseboard_fab2(sch_1):page84_i14:dq(15)"
				( attribute "PN" "166"
					( Origin gPackager )
				)
				( objectStatus "J9M1.166" )
			)
			( pin "@baseboard_fab2_lib.baseboard_fab2(sch_1):page84_i14:dq(16)"
				( attribute "PN" "27"
					( Origin gPackager )
				)
				( objectStatus "J9M1.27" )
			)
			( pin "@baseboard_fab2_lib.baseboard_fab2(sch_1):page84_i14:dq(17)"
				( attribute "PN" "172"
					( Origin gPackager )
				)
				( objectStatus "J9M1.172" )
			)
			( pin "@baseboard_fab2_lib.baseboard_fab2(sch_1):page84_i14:dq(18)"
				( attribute "PN" "34"
					( Origin gPackager )
				)
				( objectStatus "J9M1.34" )
			)
			( pin "@baseboard_fab2_lib.baseboard_fab2(sch_1):page84_i14:dq(19)"
				( attribute "PN" "179"
					( Origin gPackager )
				)
				( objectStatus "J9M1.179" )
			)
			( pin "@baseboard_fab2_lib.baseboard_fab2(sch_1):page84_i14:dq(20)"
				( attribute "PN" "25"
					( Origin gPackager )
				)
				( objectStatus "J9M1.25" )
			)
			( pin "@baseboard_fab2_lib.baseboard_fab2(sch_1):page84_i14:dq(21)"
				( attribute "PN" "170"
					( Origin gPackager )
				)
				( objectStatus "J9M1.170" )
			)
			( pin "@baseboard_fab2_lib.baseboard_fab2(sch_1):page84_i14:dq(22)"
				( attribute "PN" "32"
					( Origin gPackager )
				)
				( objectStatus "J9M1.32" )
			)
			( pin "@baseboard_fab2_lib.baseboard_fab2(sch_1):page84_i14:dq(23)"
				( attribute "PN" "177"
					( Origin gPackager )
				)
				( objectStatus "J9M1.177" )
			)
			( pin "@baseboard_fab2_lib.baseboard_fab2(sch_1):page84_i14:dq(24)"
				( attribute "PN" "38"
					( Origin gPackager )
				)
				( objectStatus "J9M1.38" )
			)
			( pin "@baseboard_fab2_lib.baseboard_fab2(sch_1):page84_i14:dq(25)"
				( attribute "PN" "183"
					( Origin gPackager )
				)
				( objectStatus "J9M1.183" )
			)
			( pin "@baseboard_fab2_lib.baseboard_fab2(sch_1):page84_i14:dq(26)"
				( attribute "PN" "45"
					( Origin gPackager )
				)
				( objectStatus "J9M1.45" )
			)
			( pin "@baseboard_fab2_lib.baseboard_fab2(sch_1):page84_i14:dq(27)"
				( attribute "PN" "190"
					( Origin gPackager )
				)
				( objectStatus "J9M1.190" )
			)
			( pin "@baseboard_fab2_lib.baseboard_fab2(sch_1):page84_i14:dq(28)"
				( attribute "PN" "36"
					( Origin gPackager )
				)
				( objectStatus "J9M1.36" )
			)
			( pin "@baseboard_fab2_lib.baseboard_fab2(sch_1):page84_i14:dq(29)"
				( attribute "PN" "181"
					( Origin gPackager )
				)
				( objectStatus "J9M1.181" )
			)
			( pin "@baseboard_fab2_lib.baseboard_fab2(sch_1):page84_i14:dq(30)"
				( attribute "PN" "43"
					( Origin gPackager )
				)
				( objectStatus "J9M1.43" )
			)
			( pin "@baseboard_fab2_lib.baseboard_fab2(sch_1):page84_i14:dq(31)"
				( attribute "PN" "188"
					( Origin gPackager )
				)
				( objectStatus "J9M1.188" )
			)
			( pin "@baseboard_fab2_lib.baseboard_fab2(sch_1):page84_i14:dq(32)"
				( attribute "PN" "97"
					( Origin gPackager )
				)
				( objectStatus "J9M1.97" )
			)
			( pin "@baseboard_fab2_lib.baseboard_fab2(sch_1):page84_i14:dq(33)"
				( attribute "PN" "242"
					( Origin gPackager )
				)
				( objectStatus "J9M1.242" )
			)
			( pin "@baseboard_fab2_lib.baseboard_fab2(sch_1):page84_i14:dq(34)"
				( attribute "PN" "104"
					( Origin gPackager )
				)
				( objectStatus "J9M1.104" )
			)
			( pin "@baseboard_fab2_lib.baseboard_fab2(sch_1):page84_i14:dq(35)"
				( attribute "PN" "249"
					( Origin gPackager )
				)
				( objectStatus "J9M1.249" )
			)
			( pin "@baseboard_fab2_lib.baseboard_fab2(sch_1):page84_i14:dq(36)"
				( attribute "PN" "95"
					( Origin gPackager )
				)
				( objectStatus "J9M1.95" )
			)
			( pin "@baseboard_fab2_lib.baseboard_fab2(sch_1):page84_i14:dq(37)"
				( attribute "PN" "240"
					( Origin gPackager )
				)
				( objectStatus "J9M1.240" )
			)
			( pin "@baseboard_fab2_lib.baseboard_fab2(sch_1):page84_i14:dq(38)"
				( attribute "PN" "102"
					( Origin gPackager )
				)
				( objectStatus "J9M1.102" )
			)
			( pin "@baseboard_fab2_lib.baseboard_fab2(sch_1):page84_i14:dq(39)"
				( attribute "PN" "247"
					( Origin gPackager )
				)
				( objectStatus "J9M1.247" )
			)
			( pin "@baseboard_fab2_lib.baseboard_fab2(sch_1):page84_i14:dq(40)"
				( attribute "PN" "108"
					( Origin gPackager )
				)
				( objectStatus "J9M1.108" )
			)
			( pin "@baseboard_fab2_lib.baseboard_fab2(sch_1):page84_i14:dq(41)"
				( attribute "PN" "253"
					( Origin gPackager )
				)
				( objectStatus "J9M1.253" )
			)
			( pin "@baseboard_fab2_lib.baseboard_fab2(sch_1):page84_i14:dq(42)"
				( attribute "PN" "115"
					( Origin gPackager )
				)
				( objectStatus "J9M1.115" )
			)
			( pin "@baseboard_fab2_lib.baseboard_fab2(sch_1):page84_i14:dq(43)"
				( attribute "PN" "260"
					( Origin gPackager )
				)
				( objectStatus "J9M1.260" )
			)
			( pin "@baseboard_fab2_lib.baseboard_fab2(sch_1):page84_i14:dq(44)"
				( attribute "PN" "106"
					( Origin gPackager )
				)
				( objectStatus "J9M1.106" )
			)
			( pin "@baseboard_fab2_lib.baseboard_fab2(sch_1):page84_i14:dq(45)"
				( attribute "PN" "251"
					( Origin gPackager )
				)
				( objectStatus "J9M1.251" )
			)
			( pin "@baseboard_fab2_lib.baseboard_fab2(sch_1):page84_i14:dq(46)"
				( attribute "PN" "113"
					( Origin gPackager )
				)
				( objectStatus "J9M1.113" )
			)
			( pin "@baseboard_fab2_lib.baseboard_fab2(sch_1):page84_i14:dq(47)"
				( attribute "PN" "258"
					( Origin gPackager )
				)
				( objectStatus "J9M1.258" )
			)
			( pin "@baseboard_fab2_lib.baseboard_fab2(sch_1):page84_i14:dq(48)"
				( attribute "PN" "119"
					( Origin gPackager )
				)
				( objectStatus "J9M1.119" )
			)
			( pin "@baseboard_fab2_lib.baseboard_fab2(sch_1):page84_i14:dq(49)"
				( attribute "PN" "264"
					( Origin gPackager )
				)
				( objectStatus "J9M1.264" )
			)
			( pin "@baseboard_fab2_lib.baseboard_fab2(sch_1):page84_i14:dq(50)"
				( attribute "PN" "126"
					( Origin gPackager )
				)
				( objectStatus "J9M1.126" )
			)
			( pin "@baseboard_fab2_lib.baseboard_fab2(sch_1):page84_i14:dq(51)"
				( attribute "PN" "271"
					( Origin gPackager )
				)
				( objectStatus "J9M1.271" )
			)
			( pin "@baseboard_fab2_lib.baseboard_fab2(sch_1):page84_i14:dq(52)"
				( attribute "PN" "117"
					( Origin gPackager )
				)
				( objectStatus "J9M1.117" )
			)
			( pin "@baseboard_fab2_lib.baseboard_fab2(sch_1):page84_i14:dq(53)"
				( attribute "PN" "262"
					( Origin gPackager )
				)
				( objectStatus "J9M1.262" )
			)
			( pin "@baseboard_fab2_lib.baseboard_fab2(sch_1):page84_i14:dq(54)"
				( attribute "PN" "124"
					( Origin gPackager )
				)
				( objectStatus "J9M1.124" )
			)
			( pin "@baseboard_fab2_lib.baseboard_fab2(sch_1):page84_i14:dq(55)"
				( attribute "PN" "269"
					( Origin gPackager )
				)
				( objectStatus "J9M1.269" )
			)
			( pin "@baseboard_fab2_lib.baseboard_fab2(sch_1):page84_i14:dq(56)"
				( attribute "PN" "130"
					( Origin gPackager )
				)
				( objectStatus "J9M1.130" )
			)
			( pin "@baseboard_fab2_lib.baseboard_fab2(sch_1):page84_i14:dq(57)"
				( attribute "PN" "275"
					( Origin gPackager )
				)
				( objectStatus "J9M1.275" )
			)
			( pin "@baseboard_fab2_lib.baseboard_fab2(sch_1):page84_i14:dq(58)"
				( attribute "PN" "137"
					( Origin gPackager )
				)
				( objectStatus "J9M1.137" )
			)
			( pin "@baseboard_fab2_lib.baseboard_fab2(sch_1):page84_i14:dq(59)"
				( attribute "PN" "282"
					( Origin gPackager )
				)
				( objectStatus "J9M1.282" )
			)
			( pin "@baseboard_fab2_lib.baseboard_fab2(sch_1):page84_i14:dq(60)"
				( attribute "PN" "128"
					( Origin gPackager )
				)
				( objectStatus "J9M1.128" )
			)
			( pin "@baseboard_fab2_lib.baseboard_fab2(sch_1):page84_i14:dq(61)"
				( attribute "PN" "273"
					( Origin gPackager )
				)
				( objectStatus "J9M1.273" )
			)
			( pin "@baseboard_fab2_lib.baseboard_fab2(sch_1):page84_i14:dq(62)"
				( attribute "PN" "135"
					( Origin gPackager )
				)
				( objectStatus "J9M1.135" )
			)
			( pin "@baseboard_fab2_lib.baseboard_fab2(sch_1):page84_i14:dq(63)"
				( attribute "PN" "280"
					( Origin gPackager )
				)
				( objectStatus "J9M1.280" )
			)
			( pin "@baseboard_fab2_lib.baseboard_fab2(sch_1):page84_i14:event_n"
				( attribute "PN" "78"
					( Origin gPackager )
				)
				( objectStatus "J9M1.78" )
			)
			( pin "@baseboard_fab2_lib.baseboard_fab2(sch_1):page84_i14:odt(0)"
				( attribute "PN" "87"
					( Origin gPackager )
				)
				( objectStatus "J9M1.87" )
			)
			( pin "@baseboard_fab2_lib.baseboard_fab2(sch_1):page84_i14:odt(1)"
				( attribute "PN" "91"
					( Origin gPackager )
				)
				( objectStatus "J9M1.91" )
			)
			( pin "@baseboard_fab2_lib.baseboard_fab2(sch_1):page84_i14:par"
				( attribute "PN" "222"
					( Origin gPackager )
				)
				( objectStatus "J9M1.222" )
			)
			( pin "@baseboard_fab2_lib.baseboard_fab2(sch_1):page84_i14:reset_n"
				( attribute "PN" "58"
					( Origin gPackager )
				)
				( objectStatus "J9M1.58" )
			)
			( pin "@baseboard_fab2_lib.baseboard_fab2(sch_1):page84_i14:rfu(0)"
				( attribute "PN" "205"
					( Origin gPackager )
				)
				( objectStatus "J9M1.205" )
			)
			( pin "@baseboard_fab2_lib.baseboard_fab2(sch_1):page84_i14:rfu(1)"
				( attribute "PN" "227"
					( Origin gPackager )
				)
				( objectStatus "J9M1.227" )
			)
			( pin "@baseboard_fab2_lib.baseboard_fab2(sch_1):page84_i14:rfu(2)"
				( attribute "PN" "144"
					( Origin gPackager )
				)
				( objectStatus "J9M1.144" )
			)
			( pin "@baseboard_fab2_lib.baseboard_fab2(sch_1):page84_i14:s0_n"
				( attribute "PN" "84"
					( Origin gPackager )
				)
				( objectStatus "J9M1.84" )
			)
			( pin "@baseboard_fab2_lib.baseboard_fab2(sch_1):page84_i14:s1_n"
				( attribute "PN" "89"
					( Origin gPackager )
				)
				( objectStatus "J9M1.89" )
			)
			( pin "@baseboard_fab2_lib.baseboard_fab2(sch_1):page84_i14:s2_n_c(0)"
				( attribute "PN" "93"
					( Origin gPackager )
				)
				( objectStatus "J9M1.93" )
			)
			( pin "@baseboard_fab2_lib.baseboard_fab2(sch_1):page84_i14:s3_n_c(1)"
				( attribute "PN" "237"
					( Origin gPackager )
				)
				( objectStatus "J9M1.237" )
			)
			( pin "@baseboard_fab2_lib.baseboard_fab2(sch_1):page84_i14:sa(0)"
				( attribute "PN" "139"
					( Origin gPackager )
				)
				( objectStatus "J9M1.139" )
			)
			( pin "@baseboard_fab2_lib.baseboard_fab2(sch_1):page84_i14:sa(1)"
				( attribute "PN" "140"
					( Origin gPackager )
				)
				( objectStatus "J9M1.140" )
			)
			( pin "@baseboard_fab2_lib.baseboard_fab2(sch_1):page84_i14:sa(2)"
				( attribute "PN" "238"
					( Origin gPackager )
				)
				( objectStatus "J9M1.238" )
			)
			( pin "@baseboard_fab2_lib.baseboard_fab2(sch_1):page84_i14:save_n_nc"
				( attribute "PN" "230"
					( Origin gPackager )
				)
				( objectStatus "J9M1.230" )
			)
			( pin "@baseboard_fab2_lib.baseboard_fab2(sch_1):page84_i14:scl"
				( attribute "PN" "141"
					( Origin gPackager )
				)
				( objectStatus "J9M1.141" )
			)
			( pin "@baseboard_fab2_lib.baseboard_fab2(sch_1):page84_i14:sda"
				( attribute "PN" "285"
					( Origin gPackager )
				)
				( objectStatus "J9M1.285" )
			)
			( pin "@baseboard_fab2_lib.baseboard_fab2(sch_1):page84_i14:vddspd"
				( attribute "PN" "284"
					( Origin gPackager )
				)
				( objectStatus "J9M1.284" )
			)
			( pin "@baseboard_fab2_lib.baseboard_fab2(sch_1):page84_i14:vrefca"
				( attribute "PN" "146"
					( Origin gPackager )
				)
				( objectStatus "J9M1.146" )
			)
			( pin "@baseboard_fab2_lib.baseboard_fab2(sch_1):page84_i57:\12v\(0)"
				( attribute "PN" "145"
					( Origin gPackager )
				)
				( objectStatus "J9M1.145" )
			)
			( pin "@baseboard_fab2_lib.baseboard_fab2(sch_1):page84_i57:\12v\(1)"
				( attribute "PN" "1"
					( Origin gPackager )
				)
				( objectStatus "J9M1.1" )
			)
			( pin "@baseboard_fab2_lib.baseboard_fab2(sch_1):page84_i57:vdd(0)"
				( attribute "PN" "236"
					( Origin gPackager )
				)
				( objectStatus "J9M1.236" )
			)
			( pin "@baseboard_fab2_lib.baseboard_fab2(sch_1):page84_i57:vdd(1)"
				( attribute "PN" "233"
					( Origin gPackager )
				)
				( objectStatus "J9M1.233" )
			)
			( pin "@baseboard_fab2_lib.baseboard_fab2(sch_1):page84_i57:vdd(2)"
				( attribute "PN" "231"
					( Origin gPackager )
				)
				( objectStatus "J9M1.231" )
			)
			( pin "@baseboard_fab2_lib.baseboard_fab2(sch_1):page84_i57:vdd(3)"
				( attribute "PN" "229"
					( Origin gPackager )
				)
				( objectStatus "J9M1.229" )
			)
			( pin "@baseboard_fab2_lib.baseboard_fab2(sch_1):page84_i57:vdd(4)"
				( attribute "PN" "226"
					( Origin gPackager )
				)
				( objectStatus "J9M1.226" )
			)
			( pin "@baseboard_fab2_lib.baseboard_fab2(sch_1):page84_i57:vdd(5)"
				( attribute "PN" "223"
					( Origin gPackager )
				)
				( objectStatus "J9M1.223" )
			)
			( pin "@baseboard_fab2_lib.baseboard_fab2(sch_1):page84_i57:vdd(6)"
				( attribute "PN" "220"
					( Origin gPackager )
				)
				( objectStatus "J9M1.220" )
			)
			( pin "@baseboard_fab2_lib.baseboard_fab2(sch_1):page84_i57:vdd(7)"
				( attribute "PN" "217"
					( Origin gPackager )
				)
				( objectStatus "J9M1.217" )
			)
			( pin "@baseboard_fab2_lib.baseboard_fab2(sch_1):page84_i57:vdd(8)"
				( attribute "PN" "215"
					( Origin gPackager )
				)
				( objectStatus "J9M1.215" )
			)
			( pin "@baseboard_fab2_lib.baseboard_fab2(sch_1):page84_i57:vdd(9)"
				( attribute "PN" "212"
					( Origin gPackager )
				)
				( objectStatus "J9M1.212" )
			)
			( pin "@baseboard_fab2_lib.baseboard_fab2(sch_1):page84_i57:vdd(10)"
				( attribute "PN" "209"
					( Origin gPackager )
				)
				( objectStatus "J9M1.209" )
			)
			( pin "@baseboard_fab2_lib.baseboard_fab2(sch_1):page84_i57:vdd(11)"
				( attribute "PN" "206"
					( Origin gPackager )
				)
				( objectStatus "J9M1.206" )
			)
			( pin "@baseboard_fab2_lib.baseboard_fab2(sch_1):page84_i57:vdd(12)"
				( attribute "PN" "204"
					( Origin gPackager )
				)
				( objectStatus "J9M1.204" )
			)
			( pin "@baseboard_fab2_lib.baseboard_fab2(sch_1):page84_i57:vdd(13)"
				( attribute "PN" "92"
					( Origin gPackager )
				)
				( objectStatus "J9M1.92" )
			)
			( pin "@baseboard_fab2_lib.baseboard_fab2(sch_1):page84_i57:vdd(14)"
				( attribute "PN" "90"
					( Origin gPackager )
				)
				( objectStatus "J9M1.90" )
			)
			( pin "@baseboard_fab2_lib.baseboard_fab2(sch_1):page84_i57:vdd(15)"
				( attribute "PN" "88"
					( Origin gPackager )
				)
				( objectStatus "J9M1.88" )
			)
			( pin "@baseboard_fab2_lib.baseboard_fab2(sch_1):page84_i57:vdd(16)"
				( attribute "PN" "85"
					( Origin gPackager )
				)
				( objectStatus "J9M1.85" )
			)
			( pin "@baseboard_fab2_lib.baseboard_fab2(sch_1):page84_i57:vdd(17)"
				( attribute "PN" "83"
					( Origin gPackager )
				)
				( objectStatus "J9M1.83" )
			)
			( pin "@baseboard_fab2_lib.baseboard_fab2(sch_1):page84_i57:vdd(18)"
				( attribute "PN" "80"
					( Origin gPackager )
				)
				( objectStatus "J9M1.80" )
			)
			( pin "@baseboard_fab2_lib.baseboard_fab2(sch_1):page84_i57:vdd(19)"
				( attribute "PN" "76"
					( Origin gPackager )
				)
				( objectStatus "J9M1.76" )
			)
			( pin "@baseboard_fab2_lib.baseboard_fab2(sch_1):page84_i57:vdd(20)"
				( attribute "PN" "73"
					( Origin gPackager )
				)
				( objectStatus "J9M1.73" )
			)
			( pin "@baseboard_fab2_lib.baseboard_fab2(sch_1):page84_i57:vdd(21)"
				( attribute "PN" "70"
					( Origin gPackager )
				)
				( objectStatus "J9M1.70" )
			)
			( pin "@baseboard_fab2_lib.baseboard_fab2(sch_1):page84_i57:vdd(22)"
				( attribute "PN" "67"
					( Origin gPackager )
				)
				( objectStatus "J9M1.67" )
			)
			( pin "@baseboard_fab2_lib.baseboard_fab2(sch_1):page84_i57:vdd(23)"
				( attribute "PN" "64"
					( Origin gPackager )
				)
				( objectStatus "J9M1.64" )
			)
			( pin "@baseboard_fab2_lib.baseboard_fab2(sch_1):page84_i57:vdd(24)"
				( attribute "PN" "61"
					( Origin gPackager )
				)
				( objectStatus "J9M1.61" )
			)
			( pin "@baseboard_fab2_lib.baseboard_fab2(sch_1):page84_i57:vdd(25)"
				( attribute "PN" "59"
					( Origin gPackager )
				)
				( objectStatus "J9M1.59" )
			)
			( pin "@baseboard_fab2_lib.baseboard_fab2(sch_1):page84_i57:vpp(0)"
				( attribute "PN" "287"
					( Origin gPackager )
				)
				( objectStatus "J9M1.287" )
			)
			( pin "@baseboard_fab2_lib.baseboard_fab2(sch_1):page84_i57:vpp(1)"
				( attribute "PN" "286"
					( Origin gPackager )
				)
				( objectStatus "J9M1.286" )
			)
			( pin "@baseboard_fab2_lib.baseboard_fab2(sch_1):page84_i57:vpp(2)"
				( attribute "PN" "288"
					( Origin gPackager )
				)
				( objectStatus "J9M1.288" )
			)
			( pin "@baseboard_fab2_lib.baseboard_fab2(sch_1):page84_i57:vpp(3)"
				( attribute "PN" "143"
					( Origin gPackager )
				)
				( objectStatus "J9M1.143" )
			)
			( pin "@baseboard_fab2_lib.baseboard_fab2(sch_1):page84_i57:vpp(4)"
				( attribute "PN" "142"
					( Origin gPackager )
				)
				( objectStatus "J9M1.142" )
			)
			( pin "@baseboard_fab2_lib.baseboard_fab2(sch_1):page84_i57:vtt(0)"
				( attribute "PN" "221"
					( Origin gPackager )
				)
				( objectStatus "J9M1.221" )
			)
			( pin "@baseboard_fab2_lib.baseboard_fab2(sch_1):page84_i57:vtt(1)"
				( attribute "PN" "77"
					( Origin gPackager )
				)
				( objectStatus "J9M1.77" )
			)
			( pin "@baseboard_fab2_lib.baseboard_fab2(sch_1):page84_i102:dqs0n"
				( attribute "PN" "152"
					( Origin gPackager )
				)
				( objectStatus "J9M1.152" )
			)
			( pin "@baseboard_fab2_lib.baseboard_fab2(sch_1):page84_i102:dqs0p"
				( attribute "PN" "153"
					( Origin gPackager )
				)
				( objectStatus "J9M1.153" )
			)
			( pin "@baseboard_fab2_lib.baseboard_fab2(sch_1):page84_i102:dqs1n"
				( attribute "PN" "163"
					( Origin gPackager )
				)
				( objectStatus "J9M1.163" )
			)
			( pin "@baseboard_fab2_lib.baseboard_fab2(sch_1):page84_i102:dqs1p"
				( attribute "PN" "164"
					( Origin gPackager )
				)
				( objectStatus "J9M1.164" )
			)
			( pin "@baseboard_fab2_lib.baseboard_fab2(sch_1):page84_i102:dqs2n"
				( attribute "PN" "174"
					( Origin gPackager )
				)
				( objectStatus "J9M1.174" )
			)
			( pin "@baseboard_fab2_lib.baseboard_fab2(sch_1):page84_i102:dqs2p"
				( attribute "PN" "175"
					( Origin gPackager )
				)
				( objectStatus "J9M1.175" )
			)
			( pin "@baseboard_fab2_lib.baseboard_fab2(sch_1):page84_i102:dqs3n"
				( attribute "PN" "185"
					( Origin gPackager )
				)
				( objectStatus "J9M1.185" )
			)
			( pin "@baseboard_fab2_lib.baseboard_fab2(sch_1):page84_i102:dqs3p"
				( attribute "PN" "186"
					( Origin gPackager )
				)
				( objectStatus "J9M1.186" )
			)
			( pin "@baseboard_fab2_lib.baseboard_fab2(sch_1):page84_i102:dqs4n"
				( attribute "PN" "244"
					( Origin gPackager )
				)
				( objectStatus "J9M1.244" )
			)
			( pin "@baseboard_fab2_lib.baseboard_fab2(sch_1):page84_i102:dqs4p"
				( attribute "PN" "245"
					( Origin gPackager )
				)
				( objectStatus "J9M1.245" )
			)
			( pin "@baseboard_fab2_lib.baseboard_fab2(sch_1):page84_i102:dqs5n"
				( attribute "PN" "255"
					( Origin gPackager )
				)
				( objectStatus "J9M1.255" )
			)
			( pin "@baseboard_fab2_lib.baseboard_fab2(sch_1):page84_i102:dqs5p"
				( attribute "PN" "256"
					( Origin gPackager )
				)
				( objectStatus "J9M1.256" )
			)
			( pin "@baseboard_fab2_lib.baseboard_fab2(sch_1):page84_i102:dqs6n"
				( attribute "PN" "266"
					( Origin gPackager )
				)
				( objectStatus "J9M1.266" )
			)
			( pin "@baseboard_fab2_lib.baseboard_fab2(sch_1):page84_i102:dqs6p"
				( attribute "PN" "267"
					( Origin gPackager )
				)
				( objectStatus "J9M1.267" )
			)
			( pin "@baseboard_fab2_lib.baseboard_fab2(sch_1):page84_i102:dqs7n"
				( attribute "PN" "277"
					( Origin gPackager )
				)
				( objectStatus "J9M1.277" )
			)
			( pin "@baseboard_fab2_lib.baseboard_fab2(sch_1):page84_i102:dqs7p"
				( attribute "PN" "278"
					( Origin gPackager )
				)
				( objectStatus "J9M1.278" )
			)
			( pin "@baseboard_fab2_lib.baseboard_fab2(sch_1):page84_i102:dqs8n"
				( attribute "PN" "196"
					( Origin gPackager )
				)
				( objectStatus "J9M1.196" )
			)
			( pin "@baseboard_fab2_lib.baseboard_fab2(sch_1):page84_i102:dqs8p"
				( attribute "PN" "197"
					( Origin gPackager )
				)
				( objectStatus "J9M1.197" )
			)
			( pin "@baseboard_fab2_lib.baseboard_fab2(sch_1):page84_i102:dqs9n"
				( attribute "PN" "8"
					( Origin gPackager )
				)
				( objectStatus "J9M1.8" )
			)
			( pin "@baseboard_fab2_lib.baseboard_fab2(sch_1):page84_i102:dqs9p"
				( attribute "PN" "7"
					( Origin gPackager )
				)
				( objectStatus "J9M1.7" )
			)
			( pin "@baseboard_fab2_lib.baseboard_fab2(sch_1):page84_i102:dqs10n"
				( attribute "PN" "19"
					( Origin gPackager )
				)
				( objectStatus "J9M1.19" )
			)
			( pin "@baseboard_fab2_lib.baseboard_fab2(sch_1):page84_i102:dqs10p"
				( attribute "PN" "18"
					( Origin gPackager )
				)
				( objectStatus "J9M1.18" )
			)
			( pin "@baseboard_fab2_lib.baseboard_fab2(sch_1):page84_i102:dqs11n"
				( attribute "PN" "30"
					( Origin gPackager )
				)
				( objectStatus "J9M1.30" )
			)
			( pin "@baseboard_fab2_lib.baseboard_fab2(sch_1):page84_i102:dqs11p"
				( attribute "PN" "29"
					( Origin gPackager )
				)
				( objectStatus "J9M1.29" )
			)
			( pin "@baseboard_fab2_lib.baseboard_fab2(sch_1):page84_i102:dqs12n"
				( attribute "PN" "41"
					( Origin gPackager )
				)
				( objectStatus "J9M1.41" )
			)
			( pin "@baseboard_fab2_lib.baseboard_fab2(sch_1):page84_i102:dqs12p"
				( attribute "PN" "40"
					( Origin gPackager )
				)
				( objectStatus "J9M1.40" )
			)
			( pin "@baseboard_fab2_lib.baseboard_fab2(sch_1):page84_i102:dqs13n"
				( attribute "PN" "100"
					( Origin gPackager )
				)
				( objectStatus "J9M1.100" )
			)
			( pin "@baseboard_fab2_lib.baseboard_fab2(sch_1):page84_i102:dqs13p"
				( attribute "PN" "99"
					( Origin gPackager )
				)
				( objectStatus "J9M1.99" )
			)
			( pin "@baseboard_fab2_lib.baseboard_fab2(sch_1):page84_i102:dqs14n"
				( attribute "PN" "111"
					( Origin gPackager )
				)
				( objectStatus "J9M1.111" )
			)
			( pin "@baseboard_fab2_lib.baseboard_fab2(sch_1):page84_i102:dqs14p"
				( attribute "PN" "110"
					( Origin gPackager )
				)
				( objectStatus "J9M1.110" )
			)
			( pin "@baseboard_fab2_lib.baseboard_fab2(sch_1):page84_i102:dqs15n"
				( attribute "PN" "122"
					( Origin gPackager )
				)
				( objectStatus "J9M1.122" )
			)
			( pin "@baseboard_fab2_lib.baseboard_fab2(sch_1):page84_i102:dqs15p"
				( attribute "PN" "121"
					( Origin gPackager )
				)
				( objectStatus "J9M1.121" )
			)
			( pin "@baseboard_fab2_lib.baseboard_fab2(sch_1):page84_i102:dqs16n"
				( attribute "PN" "133"
					( Origin gPackager )
				)
				( objectStatus "J9M1.133" )
			)
			( pin "@baseboard_fab2_lib.baseboard_fab2(sch_1):page84_i102:dqs16p"
				( attribute "PN" "132"
					( Origin gPackager )
				)
				( objectStatus "J9M1.132" )
			)
			( pin "@baseboard_fab2_lib.baseboard_fab2(sch_1):page84_i102:dqs17n"
				( attribute "PN" "52"
					( Origin gPackager )
				)
				( objectStatus "J9M1.52" )
			)
			( pin "@baseboard_fab2_lib.baseboard_fab2(sch_1):page84_i102:dqs17p"
				( attribute "PN" "51"
					( Origin gPackager )
				)
				( objectStatus "J9M1.51" )
			)
			( pin "@baseboard_fab2_lib.baseboard_fab2(sch_1):page84_i138:vss(0)"
				( attribute "PN" "283"
					( Origin gPackager )
				)
				( objectStatus "J9M1.283" )
			)
			( pin "@baseboard_fab2_lib.baseboard_fab2(sch_1):page84_i138:vss(1)"
				( attribute "PN" "281"
					( Origin gPackager )
				)
				( objectStatus "J9M1.281" )
			)
			( pin "@baseboard_fab2_lib.baseboard_fab2(sch_1):page84_i138:vss(2)"
				( attribute "PN" "279"
					( Origin gPackager )
				)
				( objectStatus "J9M1.279" )
			)
			( pin "@baseboard_fab2_lib.baseboard_fab2(sch_1):page84_i138:vss(3)"
				( attribute "PN" "276"
					( Origin gPackager )
				)
				( objectStatus "J9M1.276" )
			)
			( pin "@baseboard_fab2_lib.baseboard_fab2(sch_1):page84_i138:vss(4)"
				( attribute "PN" "274"
					( Origin gPackager )
				)
				( objectStatus "J9M1.274" )
			)
			( pin "@baseboard_fab2_lib.baseboard_fab2(sch_1):page84_i138:vss(5)"
				( attribute "PN" "272"
					( Origin gPackager )
				)
				( objectStatus "J9M1.272" )
			)
			( pin "@baseboard_fab2_lib.baseboard_fab2(sch_1):page84_i138:vss(6)"
				( attribute "PN" "270"
					( Origin gPackager )
				)
				( objectStatus "J9M1.270" )
			)
			( pin "@baseboard_fab2_lib.baseboard_fab2(sch_1):page84_i138:vss(7)"
				( attribute "PN" "268"
					( Origin gPackager )
				)
				( objectStatus "J9M1.268" )
			)
			( pin "@baseboard_fab2_lib.baseboard_fab2(sch_1):page84_i138:vss(8)"
				( attribute "PN" "265"
					( Origin gPackager )
				)
				( objectStatus "J9M1.265" )
			)
			( pin "@baseboard_fab2_lib.baseboard_fab2(sch_1):page84_i138:vss(9)"
				( attribute "PN" "263"
					( Origin gPackager )
				)
				( objectStatus "J9M1.263" )
			)
			( pin "@baseboard_fab2_lib.baseboard_fab2(sch_1):page84_i138:vss(10)"
				( attribute "PN" "261"
					( Origin gPackager )
				)
				( objectStatus "J9M1.261" )
			)
			( pin "@baseboard_fab2_lib.baseboard_fab2(sch_1):page84_i138:vss(11)"
				( attribute "PN" "259"
					( Origin gPackager )
				)
				( objectStatus "J9M1.259" )
			)
			( pin "@baseboard_fab2_lib.baseboard_fab2(sch_1):page84_i138:vss(12)"
				( attribute "PN" "257"
					( Origin gPackager )
				)
				( objectStatus "J9M1.257" )
			)
			( pin "@baseboard_fab2_lib.baseboard_fab2(sch_1):page84_i138:vss(13)"
				( attribute "PN" "254"
					( Origin gPackager )
				)
				( objectStatus "J9M1.254" )
			)
			( pin "@baseboard_fab2_lib.baseboard_fab2(sch_1):page84_i138:vss(14)"
				( attribute "PN" "252"
					( Origin gPackager )
				)
				( objectStatus "J9M1.252" )
			)
			( pin "@baseboard_fab2_lib.baseboard_fab2(sch_1):page84_i138:vss(15)"
				( attribute "PN" "250"
					( Origin gPackager )
				)
				( objectStatus "J9M1.250" )
			)
			( pin "@baseboard_fab2_lib.baseboard_fab2(sch_1):page84_i138:vss(16)"
				( attribute "PN" "248"
					( Origin gPackager )
				)
				( objectStatus "J9M1.248" )
			)
			( pin "@baseboard_fab2_lib.baseboard_fab2(sch_1):page84_i138:vss(17)"
				( attribute "PN" "246"
					( Origin gPackager )
				)
				( objectStatus "J9M1.246" )
			)
			( pin "@baseboard_fab2_lib.baseboard_fab2(sch_1):page84_i138:vss(18)"
				( attribute "PN" "243"
					( Origin gPackager )
				)
				( objectStatus "J9M1.243" )
			)
			( pin "@baseboard_fab2_lib.baseboard_fab2(sch_1):page84_i138:vss(19)"
				( attribute "PN" "241"
					( Origin gPackager )
				)
				( objectStatus "J9M1.241" )
			)
			( pin "@baseboard_fab2_lib.baseboard_fab2(sch_1):page84_i138:vss(20)"
				( attribute "PN" "239"
					( Origin gPackager )
				)
				( objectStatus "J9M1.239" )
			)
			( pin "@baseboard_fab2_lib.baseboard_fab2(sch_1):page84_i138:vss(21)"
				( attribute "PN" "202"
					( Origin gPackager )
				)
				( objectStatus "J9M1.202" )
			)
			( pin "@baseboard_fab2_lib.baseboard_fab2(sch_1):page84_i138:vss(22)"
				( attribute "PN" "200"
					( Origin gPackager )
				)
				( objectStatus "J9M1.200" )
			)
			( pin "@baseboard_fab2_lib.baseboard_fab2(sch_1):page84_i138:vss(23)"
				( attribute "PN" "198"
					( Origin gPackager )
				)
				( objectStatus "J9M1.198" )
			)
			( pin "@baseboard_fab2_lib.baseboard_fab2(sch_1):page84_i138:vss(24)"
				( attribute "PN" "195"
					( Origin gPackager )
				)
				( objectStatus "J9M1.195" )
			)
			( pin "@baseboard_fab2_lib.baseboard_fab2(sch_1):page84_i138:vss(25)"
				( attribute "PN" "193"
					( Origin gPackager )
				)
				( objectStatus "J9M1.193" )
			)
			( pin "@baseboard_fab2_lib.baseboard_fab2(sch_1):page84_i138:vss(26)"
				( attribute "PN" "191"
					( Origin gPackager )
				)
				( objectStatus "J9M1.191" )
			)
			( pin "@baseboard_fab2_lib.baseboard_fab2(sch_1):page84_i138:vss(27)"
				( attribute "PN" "189"
					( Origin gPackager )
				)
				( objectStatus "J9M1.189" )
			)
			( pin "@baseboard_fab2_lib.baseboard_fab2(sch_1):page84_i138:vss(28)"
				( attribute "PN" "187"
					( Origin gPackager )
				)
				( objectStatus "J9M1.187" )
			)
			( pin "@baseboard_fab2_lib.baseboard_fab2(sch_1):page84_i138:vss(29)"
				( attribute "PN" "184"
					( Origin gPackager )
				)
				( objectStatus "J9M1.184" )
			)
			( pin "@baseboard_fab2_lib.baseboard_fab2(sch_1):page84_i138:vss(30)"
				( attribute "PN" "182"
					( Origin gPackager )
				)
				( objectStatus "J9M1.182" )
			)
			( pin "@baseboard_fab2_lib.baseboard_fab2(sch_1):page84_i138:vss(31)"
				( attribute "PN" "180"
					( Origin gPackager )
				)
				( objectStatus "J9M1.180" )
			)
			( pin "@baseboard_fab2_lib.baseboard_fab2(sch_1):page84_i138:vss(32)"
				( attribute "PN" "178"
					( Origin gPackager )
				)
				( objectStatus "J9M1.178" )
			)
			( pin "@baseboard_fab2_lib.baseboard_fab2(sch_1):page84_i138:vss(33)"
				( attribute "PN" "176"
					( Origin gPackager )
				)
				( objectStatus "J9M1.176" )
			)
			( pin "@baseboard_fab2_lib.baseboard_fab2(sch_1):page84_i138:vss(34)"
				( attribute "PN" "173"
					( Origin gPackager )
				)
				( objectStatus "J9M1.173" )
			)
			( pin "@baseboard_fab2_lib.baseboard_fab2(sch_1):page84_i138:vss(35)"
				( attribute "PN" "171"
					( Origin gPackager )
				)
				( objectStatus "J9M1.171" )
			)
			( pin "@baseboard_fab2_lib.baseboard_fab2(sch_1):page84_i138:vss(36)"
				( attribute "PN" "169"
					( Origin gPackager )
				)
				( objectStatus "J9M1.169" )
			)
			( pin "@baseboard_fab2_lib.baseboard_fab2(sch_1):page84_i138:vss(37)"
				( attribute "PN" "167"
					( Origin gPackager )
				)
				( objectStatus "J9M1.167" )
			)
			( pin "@baseboard_fab2_lib.baseboard_fab2(sch_1):page84_i138:vss(38)"
				( attribute "PN" "165"
					( Origin gPackager )
				)
				( objectStatus "J9M1.165" )
			)
			( pin "@baseboard_fab2_lib.baseboard_fab2(sch_1):page84_i138:vss(39)"
				( attribute "PN" "162"
					( Origin gPackager )
				)
				( objectStatus "J9M1.162" )
			)
			( pin "@baseboard_fab2_lib.baseboard_fab2(sch_1):page84_i138:vss(40)"
				( attribute "PN" "160"
					( Origin gPackager )
				)
				( objectStatus "J9M1.160" )
			)
			( pin "@baseboard_fab2_lib.baseboard_fab2(sch_1):page84_i138:vss(41)"
				( attribute "PN" "158"
					( Origin gPackager )
				)
				( objectStatus "J9M1.158" )
			)
			( pin "@baseboard_fab2_lib.baseboard_fab2(sch_1):page84_i138:vss(42)"
				( attribute "PN" "156"
					( Origin gPackager )
				)
				( objectStatus "J9M1.156" )
			)
			( pin "@baseboard_fab2_lib.baseboard_fab2(sch_1):page84_i138:vss(43)"
				( attribute "PN" "154"
					( Origin gPackager )
				)
				( objectStatus "J9M1.154" )
			)
			( pin "@baseboard_fab2_lib.baseboard_fab2(sch_1):page84_i138:vss(44)"
				( attribute "PN" "151"
					( Origin gPackager )
				)
				( objectStatus "J9M1.151" )
			)
			( pin "@baseboard_fab2_lib.baseboard_fab2(sch_1):page84_i138:vss(45)"
				( attribute "PN" "149"
					( Origin gPackager )
				)
				( objectStatus "J9M1.149" )
			)
			( pin "@baseboard_fab2_lib.baseboard_fab2(sch_1):page84_i138:vss(46)"
				( attribute "PN" "147"
					( Origin gPackager )
				)
				( objectStatus "J9M1.147" )
			)
			( pin "@baseboard_fab2_lib.baseboard_fab2(sch_1):page84_i138:vss(47)"
				( attribute "PN" "138"
					( Origin gPackager )
				)
				( objectStatus "J9M1.138" )
			)
			( pin "@baseboard_fab2_lib.baseboard_fab2(sch_1):page84_i138:vss(48)"
				( attribute "PN" "136"
					( Origin gPackager )
				)
				( objectStatus "J9M1.136" )
			)
			( pin "@baseboard_fab2_lib.baseboard_fab2(sch_1):page84_i138:vss(49)"
				( attribute "PN" "134"
					( Origin gPackager )
				)
				( objectStatus "J9M1.134" )
			)
			( pin "@baseboard_fab2_lib.baseboard_fab2(sch_1):page84_i138:vss(50)"
				( attribute "PN" "131"
					( Origin gPackager )
				)
				( objectStatus "J9M1.131" )
			)
			( pin "@baseboard_fab2_lib.baseboard_fab2(sch_1):page84_i138:vss(51)"
				( attribute "PN" "129"
					( Origin gPackager )
				)
				( objectStatus "J9M1.129" )
			)
			( pin "@baseboard_fab2_lib.baseboard_fab2(sch_1):page84_i138:vss(52)"
				( attribute "PN" "127"
					( Origin gPackager )
				)
				( objectStatus "J9M1.127" )
			)
			( pin "@baseboard_fab2_lib.baseboard_fab2(sch_1):page84_i138:vss(53)"
				( attribute "PN" "125"
					( Origin gPackager )
				)
				( objectStatus "J9M1.125" )
			)
			( pin "@baseboard_fab2_lib.baseboard_fab2(sch_1):page84_i138:vss(54)"
				( attribute "PN" "123"
					( Origin gPackager )
				)
				( objectStatus "J9M1.123" )
			)
			( pin "@baseboard_fab2_lib.baseboard_fab2(sch_1):page84_i138:vss(55)"
				( attribute "PN" "120"
					( Origin gPackager )
				)
				( objectStatus "J9M1.120" )
			)
			( pin "@baseboard_fab2_lib.baseboard_fab2(sch_1):page84_i138:vss(56)"
				( attribute "PN" "118"
					( Origin gPackager )
				)
				( objectStatus "J9M1.118" )
			)
			( pin "@baseboard_fab2_lib.baseboard_fab2(sch_1):page84_i138:vss(57)"
				( attribute "PN" "116"
					( Origin gPackager )
				)
				( objectStatus "J9M1.116" )
			)
			( pin "@baseboard_fab2_lib.baseboard_fab2(sch_1):page84_i138:vss(58)"
				( attribute "PN" "114"
					( Origin gPackager )
				)
				( objectStatus "J9M1.114" )
			)
			( pin "@baseboard_fab2_lib.baseboard_fab2(sch_1):page84_i138:vss(59)"
				( attribute "PN" "112"
					( Origin gPackager )
				)
				( objectStatus "J9M1.112" )
			)
			( pin "@baseboard_fab2_lib.baseboard_fab2(sch_1):page84_i138:vss(60)"
				( attribute "PN" "109"
					( Origin gPackager )
				)
				( objectStatus "J9M1.109" )
			)
			( pin "@baseboard_fab2_lib.baseboard_fab2(sch_1):page84_i138:vss(61)"
				( attribute "PN" "107"
					( Origin gPackager )
				)
				( objectStatus "J9M1.107" )
			)
			( pin "@baseboard_fab2_lib.baseboard_fab2(sch_1):page84_i138:vss(62)"
				( attribute "PN" "105"
					( Origin gPackager )
				)
				( objectStatus "J9M1.105" )
			)
			( pin "@baseboard_fab2_lib.baseboard_fab2(sch_1):page84_i138:vss(63)"
				( attribute "PN" "103"
					( Origin gPackager )
				)
				( objectStatus "J9M1.103" )
			)
			( pin "@baseboard_fab2_lib.baseboard_fab2(sch_1):page84_i138:vss(64)"
				( attribute "PN" "101"
					( Origin gPackager )
				)
				( objectStatus "J9M1.101" )
			)
			( pin "@baseboard_fab2_lib.baseboard_fab2(sch_1):page84_i138:vss(65)"
				( attribute "PN" "98"
					( Origin gPackager )
				)
				( objectStatus "J9M1.98" )
			)
			( pin "@baseboard_fab2_lib.baseboard_fab2(sch_1):page84_i138:vss(66)"
				( attribute "PN" "96"
					( Origin gPackager )
				)
				( objectStatus "J9M1.96" )
			)
			( pin "@baseboard_fab2_lib.baseboard_fab2(sch_1):page84_i138:vss(67)"
				( attribute "PN" "94"
					( Origin gPackager )
				)
				( objectStatus "J9M1.94" )
			)
			( pin "@baseboard_fab2_lib.baseboard_fab2(sch_1):page84_i138:vss(68)"
				( attribute "PN" "57"
					( Origin gPackager )
				)
				( objectStatus "J9M1.57" )
			)
			( pin "@baseboard_fab2_lib.baseboard_fab2(sch_1):page84_i138:vss(69)"
				( attribute "PN" "55"
					( Origin gPackager )
				)
				( objectStatus "J9M1.55" )
			)
			( pin "@baseboard_fab2_lib.baseboard_fab2(sch_1):page84_i138:vss(70)"
				( attribute "PN" "53"
					( Origin gPackager )
				)
				( objectStatus "J9M1.53" )
			)
			( pin "@baseboard_fab2_lib.baseboard_fab2(sch_1):page84_i138:vss(71)"
				( attribute "PN" "50"
					( Origin gPackager )
				)
				( objectStatus "J9M1.50" )
			)
			( pin "@baseboard_fab2_lib.baseboard_fab2(sch_1):page84_i138:vss(72)"
				( attribute "PN" "48"
					( Origin gPackager )
				)
				( objectStatus "J9M1.48" )
			)
			( pin "@baseboard_fab2_lib.baseboard_fab2(sch_1):page84_i138:vss(73)"
				( attribute "PN" "46"
					( Origin gPackager )
				)
				( objectStatus "J9M1.46" )
			)
			( pin "@baseboard_fab2_lib.baseboard_fab2(sch_1):page84_i138:vss(74)"
				( attribute "PN" "44"
					( Origin gPackager )
				)
				( objectStatus "J9M1.44" )
			)
			( pin "@baseboard_fab2_lib.baseboard_fab2(sch_1):page84_i138:vss(75)"
				( attribute "PN" "42"
					( Origin gPackager )
				)
				( objectStatus "J9M1.42" )
			)
			( pin "@baseboard_fab2_lib.baseboard_fab2(sch_1):page84_i138:vss(76)"
				( attribute "PN" "39"
					( Origin gPackager )
				)
				( objectStatus "J9M1.39" )
			)
			( pin "@baseboard_fab2_lib.baseboard_fab2(sch_1):page84_i138:vss(77)"
				( attribute "PN" "37"
					( Origin gPackager )
				)
				( objectStatus "J9M1.37" )
			)
			( pin "@baseboard_fab2_lib.baseboard_fab2(sch_1):page84_i138:vss(78)"
				( attribute "PN" "35"
					( Origin gPackager )
				)
				( objectStatus "J9M1.35" )
			)
			( pin "@baseboard_fab2_lib.baseboard_fab2(sch_1):page84_i138:vss(79)"
				( attribute "PN" "33"
					( Origin gPackager )
				)
				( objectStatus "J9M1.33" )
			)
			( pin "@baseboard_fab2_lib.baseboard_fab2(sch_1):page84_i138:vss(80)"
				( attribute "PN" "31"
					( Origin gPackager )
				)
				( objectStatus "J9M1.31" )
			)
			( pin "@baseboard_fab2_lib.baseboard_fab2(sch_1):page84_i138:vss(81)"
				( attribute "PN" "28"
					( Origin gPackager )
				)
				( objectStatus "J9M1.28" )
			)
			( pin "@baseboard_fab2_lib.baseboard_fab2(sch_1):page84_i138:vss(82)"
				( attribute "PN" "26"
					( Origin gPackager )
				)
				( objectStatus "J9M1.26" )
			)
			( pin "@baseboard_fab2_lib.baseboard_fab2(sch_1):page84_i138:vss(83)"
				( attribute "PN" "24"
					( Origin gPackager )
				)
				( objectStatus "J9M1.24" )
			)
			( pin "@baseboard_fab2_lib.baseboard_fab2(sch_1):page84_i138:vss(84)"
				( attribute "PN" "22"
					( Origin gPackager )
				)
				( objectStatus "J9M1.22" )
			)
			( pin "@baseboard_fab2_lib.baseboard_fab2(sch_1):page84_i138:vss(85)"
				( attribute "PN" "20"
					( Origin gPackager )
				)
				( objectStatus "J9M1.20" )
			)
			( pin "@baseboard_fab2_lib.baseboard_fab2(sch_1):page84_i138:vss(86)"
				( attribute "PN" "17"
					( Origin gPackager )
				)
				( objectStatus "J9M1.17" )
			)
			( pin "@baseboard_fab2_lib.baseboard_fab2(sch_1):page84_i138:vss(87)"
				( attribute "PN" "15"
					( Origin gPackager )
				)
				( objectStatus "J9M1.15" )
			)
			( pin "@baseboard_fab2_lib.baseboard_fab2(sch_1):page84_i138:vss(88)"
				( attribute "PN" "13"
					( Origin gPackager )
				)
				( objectStatus "J9M1.13" )
			)
			( pin "@baseboard_fab2_lib.baseboard_fab2(sch_1):page84_i138:vss(89)"
				( attribute "PN" "11"
					( Origin gPackager )
				)
				( objectStatus "J9M1.11" )
			)
			( pin "@baseboard_fab2_lib.baseboard_fab2(sch_1):page84_i138:vss(90)"
				( attribute "PN" "9"
					( Origin gPackager )
				)
				( objectStatus "J9M1.9" )
			)
			( pin "@baseboard_fab2_lib.baseboard_fab2(sch_1):page84_i138:vss(91)"
				( attribute "PN" "6"
					( Origin gPackager )
				)
				( objectStatus "J9M1.6" )
			)
			( pin "@baseboard_fab2_lib.baseboard_fab2(sch_1):page84_i138:vss(92)"
				( attribute "PN" "4"
					( Origin gPackager )
				)
				( objectStatus "J9M1.4" )
			)
			( pin "@baseboard_fab2_lib.baseboard_fab2(sch_1):page84_i138:vss(93)"
				( attribute "PN" "2"
					( Origin gPackager )
				)
				( objectStatus "J9M1.2" )
			)
			( pin "@baseboard_fab2_lib.baseboard_fab2(sch_1):page85_i43:vss(0)"
				( attribute "PN" "283"
					( Origin gPackager )
				)
				( objectStatus "J1A2.283" )
			)
			( pin "@baseboard_fab2_lib.baseboard_fab2(sch_1):page85_i43:vss(1)"
				( attribute "PN" "281"
					( Origin gPackager )
				)
				( objectStatus "J1A2.281" )
			)
			( pin "@baseboard_fab2_lib.baseboard_fab2(sch_1):page85_i43:vss(2)"
				( attribute "PN" "279"
					( Origin gPackager )
				)
				( objectStatus "J1A2.279" )
			)
			( pin "@baseboard_fab2_lib.baseboard_fab2(sch_1):page85_i43:vss(3)"
				( attribute "PN" "276"
					( Origin gPackager )
				)
				( objectStatus "J1A2.276" )
			)
			( pin "@baseboard_fab2_lib.baseboard_fab2(sch_1):page85_i43:vss(4)"
				( attribute "PN" "274"
					( Origin gPackager )
				)
				( objectStatus "J1A2.274" )
			)
			( pin "@baseboard_fab2_lib.baseboard_fab2(sch_1):page85_i43:vss(5)"
				( attribute "PN" "272"
					( Origin gPackager )
				)
				( objectStatus "J1A2.272" )
			)
			( pin "@baseboard_fab2_lib.baseboard_fab2(sch_1):page85_i43:vss(6)"
				( attribute "PN" "270"
					( Origin gPackager )
				)
				( objectStatus "J1A2.270" )
			)
			( pin "@baseboard_fab2_lib.baseboard_fab2(sch_1):page85_i43:vss(7)"
				( attribute "PN" "268"
					( Origin gPackager )
				)
				( objectStatus "J1A2.268" )
			)
			( pin "@baseboard_fab2_lib.baseboard_fab2(sch_1):page85_i43:vss(8)"
				( attribute "PN" "265"
					( Origin gPackager )
				)
				( objectStatus "J1A2.265" )
			)
			( pin "@baseboard_fab2_lib.baseboard_fab2(sch_1):page85_i43:vss(9)"
				( attribute "PN" "263"
					( Origin gPackager )
				)
				( objectStatus "J1A2.263" )
			)
			( pin "@baseboard_fab2_lib.baseboard_fab2(sch_1):page85_i43:vss(10)"
				( attribute "PN" "261"
					( Origin gPackager )
				)
				( objectStatus "J1A2.261" )
			)
			( pin "@baseboard_fab2_lib.baseboard_fab2(sch_1):page85_i43:vss(11)"
				( attribute "PN" "259"
					( Origin gPackager )
				)
				( objectStatus "J1A2.259" )
			)
			( pin "@baseboard_fab2_lib.baseboard_fab2(sch_1):page85_i43:vss(12)"
				( attribute "PN" "257"
					( Origin gPackager )
				)
				( objectStatus "J1A2.257" )
			)
			( pin "@baseboard_fab2_lib.baseboard_fab2(sch_1):page85_i43:vss(13)"
				( attribute "PN" "254"
					( Origin gPackager )
				)
				( objectStatus "J1A2.254" )
			)
			( pin "@baseboard_fab2_lib.baseboard_fab2(sch_1):page85_i43:vss(14)"
				( attribute "PN" "252"
					( Origin gPackager )
				)
				( objectStatus "J1A2.252" )
			)
			( pin "@baseboard_fab2_lib.baseboard_fab2(sch_1):page85_i43:vss(15)"
				( attribute "PN" "250"
					( Origin gPackager )
				)
				( objectStatus "J1A2.250" )
			)
			( pin "@baseboard_fab2_lib.baseboard_fab2(sch_1):page85_i43:vss(16)"
				( attribute "PN" "248"
					( Origin gPackager )
				)
				( objectStatus "J1A2.248" )
			)
			( pin "@baseboard_fab2_lib.baseboard_fab2(sch_1):page85_i43:vss(17)"
				( attribute "PN" "246"
					( Origin gPackager )
				)
				( objectStatus "J1A2.246" )
			)
			( pin "@baseboard_fab2_lib.baseboard_fab2(sch_1):page85_i43:vss(18)"
				( attribute "PN" "243"
					( Origin gPackager )
				)
				( objectStatus "J1A2.243" )
			)
			( pin "@baseboard_fab2_lib.baseboard_fab2(sch_1):page85_i43:vss(19)"
				( attribute "PN" "241"
					( Origin gPackager )
				)
				( objectStatus "J1A2.241" )
			)
			( pin "@baseboard_fab2_lib.baseboard_fab2(sch_1):page85_i43:vss(20)"
				( attribute "PN" "239"
					( Origin gPackager )
				)
				( objectStatus "J1A2.239" )
			)
			( pin "@baseboard_fab2_lib.baseboard_fab2(sch_1):page85_i43:vss(21)"
				( attribute "PN" "202"
					( Origin gPackager )
				)
				( objectStatus "J1A2.202" )
			)
			( pin "@baseboard_fab2_lib.baseboard_fab2(sch_1):page85_i43:vss(22)"
				( attribute "PN" "200"
					( Origin gPackager )
				)
				( objectStatus "J1A2.200" )
			)
			( pin "@baseboard_fab2_lib.baseboard_fab2(sch_1):page85_i43:vss(23)"
				( attribute "PN" "198"
					( Origin gPackager )
				)
				( objectStatus "J1A2.198" )
			)
			( pin "@baseboard_fab2_lib.baseboard_fab2(sch_1):page85_i43:vss(24)"
				( attribute "PN" "195"
					( Origin gPackager )
				)
				( objectStatus "J1A2.195" )
			)
			( pin "@baseboard_fab2_lib.baseboard_fab2(sch_1):page85_i43:vss(25)"
				( attribute "PN" "193"
					( Origin gPackager )
				)
				( objectStatus "J1A2.193" )
			)
			( pin "@baseboard_fab2_lib.baseboard_fab2(sch_1):page85_i43:vss(26)"
				( attribute "PN" "191"
					( Origin gPackager )
				)
				( objectStatus "J1A2.191" )
			)
			( pin "@baseboard_fab2_lib.baseboard_fab2(sch_1):page85_i43:vss(27)"
				( attribute "PN" "189"
					( Origin gPackager )
				)
				( objectStatus "J1A2.189" )
			)
			( pin "@baseboard_fab2_lib.baseboard_fab2(sch_1):page85_i43:vss(28)"
				( attribute "PN" "187"
					( Origin gPackager )
				)
				( objectStatus "J1A2.187" )
			)
			( pin "@baseboard_fab2_lib.baseboard_fab2(sch_1):page85_i43:vss(29)"
				( attribute "PN" "184"
					( Origin gPackager )
				)
				( objectStatus "J1A2.184" )
			)
			( pin "@baseboard_fab2_lib.baseboard_fab2(sch_1):page85_i43:vss(30)"
				( attribute "PN" "182"
					( Origin gPackager )
				)
				( objectStatus "J1A2.182" )
			)
			( pin "@baseboard_fab2_lib.baseboard_fab2(sch_1):page85_i43:vss(31)"
				( attribute "PN" "180"
					( Origin gPackager )
				)
				( objectStatus "J1A2.180" )
			)
			( pin "@baseboard_fab2_lib.baseboard_fab2(sch_1):page85_i43:vss(32)"
				( attribute "PN" "178"
					( Origin gPackager )
				)
				( objectStatus "J1A2.178" )
			)
			( pin "@baseboard_fab2_lib.baseboard_fab2(sch_1):page85_i43:vss(33)"
				( attribute "PN" "176"
					( Origin gPackager )
				)
				( objectStatus "J1A2.176" )
			)
			( pin "@baseboard_fab2_lib.baseboard_fab2(sch_1):page85_i43:vss(34)"
				( attribute "PN" "173"
					( Origin gPackager )
				)
				( objectStatus "J1A2.173" )
			)
			( pin "@baseboard_fab2_lib.baseboard_fab2(sch_1):page85_i43:vss(35)"
				( attribute "PN" "171"
					( Origin gPackager )
				)
				( objectStatus "J1A2.171" )
			)
			( pin "@baseboard_fab2_lib.baseboard_fab2(sch_1):page85_i43:vss(36)"
				( attribute "PN" "169"
					( Origin gPackager )
				)
				( objectStatus "J1A2.169" )
			)
			( pin "@baseboard_fab2_lib.baseboard_fab2(sch_1):page85_i43:vss(37)"
				( attribute "PN" "167"
					( Origin gPackager )
				)
				( objectStatus "J1A2.167" )
			)
			( pin "@baseboard_fab2_lib.baseboard_fab2(sch_1):page85_i43:vss(38)"
				( attribute "PN" "165"
					( Origin gPackager )
				)
				( objectStatus "J1A2.165" )
			)
			( pin "@baseboard_fab2_lib.baseboard_fab2(sch_1):page85_i43:vss(39)"
				( attribute "PN" "162"
					( Origin gPackager )
				)
				( objectStatus "J1A2.162" )
			)
			( pin "@baseboard_fab2_lib.baseboard_fab2(sch_1):page85_i43:vss(40)"
				( attribute "PN" "160"
					( Origin gPackager )
				)
				( objectStatus "J1A2.160" )
			)
			( pin "@baseboard_fab2_lib.baseboard_fab2(sch_1):page85_i43:vss(41)"
				( attribute "PN" "158"
					( Origin gPackager )
				)
				( objectStatus "J1A2.158" )
			)
			( pin "@baseboard_fab2_lib.baseboard_fab2(sch_1):page85_i43:vss(42)"
				( attribute "PN" "156"
					( Origin gPackager )
				)
				( objectStatus "J1A2.156" )
			)
			( pin "@baseboard_fab2_lib.baseboard_fab2(sch_1):page85_i43:vss(43)"
				( attribute "PN" "154"
					( Origin gPackager )
				)
				( objectStatus "J1A2.154" )
			)
			( pin "@baseboard_fab2_lib.baseboard_fab2(sch_1):page85_i43:vss(44)"
				( attribute "PN" "151"
					( Origin gPackager )
				)
				( objectStatus "J1A2.151" )
			)
			( pin "@baseboard_fab2_lib.baseboard_fab2(sch_1):page85_i43:vss(45)"
				( attribute "PN" "149"
					( Origin gPackager )
				)
				( objectStatus "J1A2.149" )
			)
			( pin "@baseboard_fab2_lib.baseboard_fab2(sch_1):page85_i43:vss(46)"
				( attribute "PN" "147"
					( Origin gPackager )
				)
				( objectStatus "J1A2.147" )
			)
			( pin "@baseboard_fab2_lib.baseboard_fab2(sch_1):page85_i43:vss(47)"
				( attribute "PN" "138"
					( Origin gPackager )
				)
				( objectStatus "J1A2.138" )
			)
			( pin "@baseboard_fab2_lib.baseboard_fab2(sch_1):page85_i43:vss(48)"
				( attribute "PN" "136"
					( Origin gPackager )
				)
				( objectStatus "J1A2.136" )
			)
			( pin "@baseboard_fab2_lib.baseboard_fab2(sch_1):page85_i43:vss(49)"
				( attribute "PN" "134"
					( Origin gPackager )
				)
				( objectStatus "J1A2.134" )
			)
			( pin "@baseboard_fab2_lib.baseboard_fab2(sch_1):page85_i43:vss(50)"
				( attribute "PN" "131"
					( Origin gPackager )
				)
				( objectStatus "J1A2.131" )
			)
			( pin "@baseboard_fab2_lib.baseboard_fab2(sch_1):page85_i43:vss(51)"
				( attribute "PN" "129"
					( Origin gPackager )
				)
				( objectStatus "J1A2.129" )
			)
			( pin "@baseboard_fab2_lib.baseboard_fab2(sch_1):page85_i43:vss(52)"
				( attribute "PN" "127"
					( Origin gPackager )
				)
				( objectStatus "J1A2.127" )
			)
			( pin "@baseboard_fab2_lib.baseboard_fab2(sch_1):page85_i43:vss(53)"
				( attribute "PN" "125"
					( Origin gPackager )
				)
				( objectStatus "J1A2.125" )
			)
			( pin "@baseboard_fab2_lib.baseboard_fab2(sch_1):page85_i43:vss(54)"
				( attribute "PN" "123"
					( Origin gPackager )
				)
				( objectStatus "J1A2.123" )
			)
			( pin "@baseboard_fab2_lib.baseboard_fab2(sch_1):page85_i43:vss(55)"
				( attribute "PN" "120"
					( Origin gPackager )
				)
				( objectStatus "J1A2.120" )
			)
			( pin "@baseboard_fab2_lib.baseboard_fab2(sch_1):page85_i43:vss(56)"
				( attribute "PN" "118"
					( Origin gPackager )
				)
				( objectStatus "J1A2.118" )
			)
			( pin "@baseboard_fab2_lib.baseboard_fab2(sch_1):page85_i43:vss(57)"
				( attribute "PN" "116"
					( Origin gPackager )
				)
				( objectStatus "J1A2.116" )
			)
			( pin "@baseboard_fab2_lib.baseboard_fab2(sch_1):page85_i43:vss(58)"
				( attribute "PN" "114"
					( Origin gPackager )
				)
				( objectStatus "J1A2.114" )
			)
			( pin "@baseboard_fab2_lib.baseboard_fab2(sch_1):page85_i43:vss(59)"
				( attribute "PN" "112"
					( Origin gPackager )
				)
				( objectStatus "J1A2.112" )
			)
			( pin "@baseboard_fab2_lib.baseboard_fab2(sch_1):page85_i43:vss(60)"
				( attribute "PN" "109"
					( Origin gPackager )
				)
				( objectStatus "J1A2.109" )
			)
			( pin "@baseboard_fab2_lib.baseboard_fab2(sch_1):page85_i43:vss(61)"
				( attribute "PN" "107"
					( Origin gPackager )
				)
				( objectStatus "J1A2.107" )
			)
			( pin "@baseboard_fab2_lib.baseboard_fab2(sch_1):page85_i43:vss(62)"
				( attribute "PN" "105"
					( Origin gPackager )
				)
				( objectStatus "J1A2.105" )
			)
			( pin "@baseboard_fab2_lib.baseboard_fab2(sch_1):page85_i43:vss(63)"
				( attribute "PN" "103"
					( Origin gPackager )
				)
				( objectStatus "J1A2.103" )
			)
			( pin "@baseboard_fab2_lib.baseboard_fab2(sch_1):page85_i43:vss(64)"
				( attribute "PN" "101"
					( Origin gPackager )
				)
				( objectStatus "J1A2.101" )
			)
			( pin "@baseboard_fab2_lib.baseboard_fab2(sch_1):page85_i43:vss(65)"
				( attribute "PN" "98"
					( Origin gPackager )
				)
				( objectStatus "J1A2.98" )
			)
			( pin "@baseboard_fab2_lib.baseboard_fab2(sch_1):page85_i43:vss(66)"
				( attribute "PN" "96"
					( Origin gPackager )
				)
				( objectStatus "J1A2.96" )
			)
			( pin "@baseboard_fab2_lib.baseboard_fab2(sch_1):page85_i43:vss(67)"
				( attribute "PN" "94"
					( Origin gPackager )
				)
				( objectStatus "J1A2.94" )
			)
			( pin "@baseboard_fab2_lib.baseboard_fab2(sch_1):page85_i43:vss(68)"
				( attribute "PN" "57"
					( Origin gPackager )
				)
				( objectStatus "J1A2.57" )
			)
			( pin "@baseboard_fab2_lib.baseboard_fab2(sch_1):page85_i43:vss(69)"
				( attribute "PN" "55"
					( Origin gPackager )
				)
				( objectStatus "J1A2.55" )
			)
			( pin "@baseboard_fab2_lib.baseboard_fab2(sch_1):page85_i43:vss(70)"
				( attribute "PN" "53"
					( Origin gPackager )
				)
				( objectStatus "J1A2.53" )
			)
			( pin "@baseboard_fab2_lib.baseboard_fab2(sch_1):page85_i43:vss(71)"
				( attribute "PN" "50"
					( Origin gPackager )
				)
				( objectStatus "J1A2.50" )
			)
			( pin "@baseboard_fab2_lib.baseboard_fab2(sch_1):page85_i43:vss(72)"
				( attribute "PN" "48"
					( Origin gPackager )
				)
				( objectStatus "J1A2.48" )
			)
			( pin "@baseboard_fab2_lib.baseboard_fab2(sch_1):page85_i43:vss(73)"
				( attribute "PN" "46"
					( Origin gPackager )
				)
				( objectStatus "J1A2.46" )
			)
			( pin "@baseboard_fab2_lib.baseboard_fab2(sch_1):page85_i43:vss(74)"
				( attribute "PN" "44"
					( Origin gPackager )
				)
				( objectStatus "J1A2.44" )
			)
			( pin "@baseboard_fab2_lib.baseboard_fab2(sch_1):page85_i43:vss(75)"
				( attribute "PN" "42"
					( Origin gPackager )
				)
				( objectStatus "J1A2.42" )
			)
			( pin "@baseboard_fab2_lib.baseboard_fab2(sch_1):page85_i43:vss(76)"
				( attribute "PN" "39"
					( Origin gPackager )
				)
				( objectStatus "J1A2.39" )
			)
			( pin "@baseboard_fab2_lib.baseboard_fab2(sch_1):page85_i43:vss(77)"
				( attribute "PN" "37"
					( Origin gPackager )
				)
				( objectStatus "J1A2.37" )
			)
			( pin "@baseboard_fab2_lib.baseboard_fab2(sch_1):page85_i43:vss(78)"
				( attribute "PN" "35"
					( Origin gPackager )
				)
				( objectStatus "J1A2.35" )
			)
			( pin "@baseboard_fab2_lib.baseboard_fab2(sch_1):page85_i43:vss(79)"
				( attribute "PN" "33"
					( Origin gPackager )
				)
				( objectStatus "J1A2.33" )
			)
			( pin "@baseboard_fab2_lib.baseboard_fab2(sch_1):page85_i43:vss(80)"
				( attribute "PN" "31"
					( Origin gPackager )
				)
				( objectStatus "J1A2.31" )
			)
			( pin "@baseboard_fab2_lib.baseboard_fab2(sch_1):page85_i43:vss(81)"
				( attribute "PN" "28"
					( Origin gPackager )
				)
				( objectStatus "J1A2.28" )
			)
			( pin "@baseboard_fab2_lib.baseboard_fab2(sch_1):page85_i43:vss(82)"
				( attribute "PN" "26"
					( Origin gPackager )
				)
				( objectStatus "J1A2.26" )
			)
			( pin "@baseboard_fab2_lib.baseboard_fab2(sch_1):page85_i43:vss(83)"
				( attribute "PN" "24"
					( Origin gPackager )
				)
				( objectStatus "J1A2.24" )
			)
			( pin "@baseboard_fab2_lib.baseboard_fab2(sch_1):page85_i43:vss(84)"
				( attribute "PN" "22"
					( Origin gPackager )
				)
				( objectStatus "J1A2.22" )
			)
			( pin "@baseboard_fab2_lib.baseboard_fab2(sch_1):page85_i43:vss(85)"
				( attribute "PN" "20"
					( Origin gPackager )
				)
				( objectStatus "J1A2.20" )
			)
			( pin "@baseboard_fab2_lib.baseboard_fab2(sch_1):page85_i43:vss(86)"
				( attribute "PN" "17"
					( Origin gPackager )
				)
				( objectStatus "J1A2.17" )
			)
			( pin "@baseboard_fab2_lib.baseboard_fab2(sch_1):page85_i43:vss(87)"
				( attribute "PN" "15"
					( Origin gPackager )
				)
				( objectStatus "J1A2.15" )
			)
			( pin "@baseboard_fab2_lib.baseboard_fab2(sch_1):page85_i43:vss(88)"
				( attribute "PN" "13"
					( Origin gPackager )
				)
				( objectStatus "J1A2.13" )
			)
			( pin "@baseboard_fab2_lib.baseboard_fab2(sch_1):page85_i43:vss(89)"
				( attribute "PN" "11"
					( Origin gPackager )
				)
				( objectStatus "J1A2.11" )
			)
			( pin "@baseboard_fab2_lib.baseboard_fab2(sch_1):page85_i43:vss(90)"
				( attribute "PN" "9"
					( Origin gPackager )
				)
				( objectStatus "J1A2.9" )
			)
			( pin "@baseboard_fab2_lib.baseboard_fab2(sch_1):page85_i43:vss(91)"
				( attribute "PN" "6"
					( Origin gPackager )
				)
				( objectStatus "J1A2.6" )
			)
			( pin "@baseboard_fab2_lib.baseboard_fab2(sch_1):page85_i43:vss(92)"
				( attribute "PN" "4"
					( Origin gPackager )
				)
				( objectStatus "J1A2.4" )
			)
			( pin "@baseboard_fab2_lib.baseboard_fab2(sch_1):page85_i43:vss(93)"
				( attribute "PN" "2"
					( Origin gPackager )
				)
				( objectStatus "J1A2.2" )
			)
			( pin "@baseboard_fab2_lib.baseboard_fab2(sch_1):page85_i66:dqs0n"
				( attribute "PN" "152"
					( Origin gPackager )
				)
				( objectStatus "J1A2.152" )
			)
			( pin "@baseboard_fab2_lib.baseboard_fab2(sch_1):page85_i66:dqs0p"
				( attribute "PN" "153"
					( Origin gPackager )
				)
				( objectStatus "J1A2.153" )
			)
			( pin "@baseboard_fab2_lib.baseboard_fab2(sch_1):page85_i66:dqs1n"
				( attribute "PN" "163"
					( Origin gPackager )
				)
				( objectStatus "J1A2.163" )
			)
			( pin "@baseboard_fab2_lib.baseboard_fab2(sch_1):page85_i66:dqs1p"
				( attribute "PN" "164"
					( Origin gPackager )
				)
				( objectStatus "J1A2.164" )
			)
			( pin "@baseboard_fab2_lib.baseboard_fab2(sch_1):page85_i66:dqs2n"
				( attribute "PN" "174"
					( Origin gPackager )
				)
				( objectStatus "J1A2.174" )
			)
			( pin "@baseboard_fab2_lib.baseboard_fab2(sch_1):page85_i66:dqs2p"
				( attribute "PN" "175"
					( Origin gPackager )
				)
				( objectStatus "J1A2.175" )
			)
			( pin "@baseboard_fab2_lib.baseboard_fab2(sch_1):page85_i66:dqs3n"
				( attribute "PN" "185"
					( Origin gPackager )
				)
				( objectStatus "J1A2.185" )
			)
			( pin "@baseboard_fab2_lib.baseboard_fab2(sch_1):page85_i66:dqs3p"
				( attribute "PN" "186"
					( Origin gPackager )
				)
				( objectStatus "J1A2.186" )
			)
			( pin "@baseboard_fab2_lib.baseboard_fab2(sch_1):page85_i66:dqs4n"
				( attribute "PN" "244"
					( Origin gPackager )
				)
				( objectStatus "J1A2.244" )
			)
			( pin "@baseboard_fab2_lib.baseboard_fab2(sch_1):page85_i66:dqs4p"
				( attribute "PN" "245"
					( Origin gPackager )
				)
				( objectStatus "J1A2.245" )
			)
			( pin "@baseboard_fab2_lib.baseboard_fab2(sch_1):page85_i66:dqs5n"
				( attribute "PN" "255"
					( Origin gPackager )
				)
				( objectStatus "J1A2.255" )
			)
			( pin "@baseboard_fab2_lib.baseboard_fab2(sch_1):page85_i66:dqs5p"
				( attribute "PN" "256"
					( Origin gPackager )
				)
				( objectStatus "J1A2.256" )
			)
			( pin "@baseboard_fab2_lib.baseboard_fab2(sch_1):page85_i66:dqs6n"
				( attribute "PN" "266"
					( Origin gPackager )
				)
				( objectStatus "J1A2.266" )
			)
			( pin "@baseboard_fab2_lib.baseboard_fab2(sch_1):page85_i66:dqs6p"
				( attribute "PN" "267"
					( Origin gPackager )
				)
				( objectStatus "J1A2.267" )
			)
			( pin "@baseboard_fab2_lib.baseboard_fab2(sch_1):page85_i66:dqs7n"
				( attribute "PN" "277"
					( Origin gPackager )
				)
				( objectStatus "J1A2.277" )
			)
			( pin "@baseboard_fab2_lib.baseboard_fab2(sch_1):page85_i66:dqs7p"
				( attribute "PN" "278"
					( Origin gPackager )
				)
				( objectStatus "J1A2.278" )
			)
			( pin "@baseboard_fab2_lib.baseboard_fab2(sch_1):page85_i66:dqs8n"
				( attribute "PN" "196"
					( Origin gPackager )
				)
				( objectStatus "J1A2.196" )
			)
			( pin "@baseboard_fab2_lib.baseboard_fab2(sch_1):page85_i66:dqs8p"
				( attribute "PN" "197"
					( Origin gPackager )
				)
				( objectStatus "J1A2.197" )
			)
			( pin "@baseboard_fab2_lib.baseboard_fab2(sch_1):page85_i66:dqs9n"
				( attribute "PN" "8"
					( Origin gPackager )
				)
				( objectStatus "J1A2.8" )
			)
			( pin "@baseboard_fab2_lib.baseboard_fab2(sch_1):page85_i66:dqs9p"
				( attribute "PN" "7"
					( Origin gPackager )
				)
				( objectStatus "J1A2.7" )
			)
			( pin "@baseboard_fab2_lib.baseboard_fab2(sch_1):page85_i66:dqs10n"
				( attribute "PN" "19"
					( Origin gPackager )
				)
				( objectStatus "J1A2.19" )
			)
			( pin "@baseboard_fab2_lib.baseboard_fab2(sch_1):page85_i66:dqs10p"
				( attribute "PN" "18"
					( Origin gPackager )
				)
				( objectStatus "J1A2.18" )
			)
			( pin "@baseboard_fab2_lib.baseboard_fab2(sch_1):page85_i66:dqs11n"
				( attribute "PN" "30"
					( Origin gPackager )
				)
				( objectStatus "J1A2.30" )
			)
			( pin "@baseboard_fab2_lib.baseboard_fab2(sch_1):page85_i66:dqs11p"
				( attribute "PN" "29"
					( Origin gPackager )
				)
				( objectStatus "J1A2.29" )
			)
			( pin "@baseboard_fab2_lib.baseboard_fab2(sch_1):page85_i66:dqs12n"
				( attribute "PN" "41"
					( Origin gPackager )
				)
				( objectStatus "J1A2.41" )
			)
			( pin "@baseboard_fab2_lib.baseboard_fab2(sch_1):page85_i66:dqs12p"
				( attribute "PN" "40"
					( Origin gPackager )
				)
				( objectStatus "J1A2.40" )
			)
			( pin "@baseboard_fab2_lib.baseboard_fab2(sch_1):page85_i66:dqs13n"
				( attribute "PN" "100"
					( Origin gPackager )
				)
				( objectStatus "J1A2.100" )
			)
			( pin "@baseboard_fab2_lib.baseboard_fab2(sch_1):page85_i66:dqs13p"
				( attribute "PN" "99"
					( Origin gPackager )
				)
				( objectStatus "J1A2.99" )
			)
			( pin "@baseboard_fab2_lib.baseboard_fab2(sch_1):page85_i66:dqs14n"
				( attribute "PN" "111"
					( Origin gPackager )
				)
				( objectStatus "J1A2.111" )
			)
			( pin "@baseboard_fab2_lib.baseboard_fab2(sch_1):page85_i66:dqs14p"
				( attribute "PN" "110"
					( Origin gPackager )
				)
				( objectStatus "J1A2.110" )
			)
			( pin "@baseboard_fab2_lib.baseboard_fab2(sch_1):page85_i66:dqs15n"
				( attribute "PN" "122"
					( Origin gPackager )
				)
				( objectStatus "J1A2.122" )
			)
			( pin "@baseboard_fab2_lib.baseboard_fab2(sch_1):page85_i66:dqs15p"
				( attribute "PN" "121"
					( Origin gPackager )
				)
				( objectStatus "J1A2.121" )
			)
			( pin "@baseboard_fab2_lib.baseboard_fab2(sch_1):page85_i66:dqs16n"
				( attribute "PN" "133"
					( Origin gPackager )
				)
				( objectStatus "J1A2.133" )
			)
			( pin "@baseboard_fab2_lib.baseboard_fab2(sch_1):page85_i66:dqs16p"
				( attribute "PN" "132"
					( Origin gPackager )
				)
				( objectStatus "J1A2.132" )
			)
			( pin "@baseboard_fab2_lib.baseboard_fab2(sch_1):page85_i66:dqs17n"
				( attribute "PN" "52"
					( Origin gPackager )
				)
				( objectStatus "J1A2.52" )
			)
			( pin "@baseboard_fab2_lib.baseboard_fab2(sch_1):page85_i66:dqs17p"
				( attribute "PN" "51"
					( Origin gPackager )
				)
				( objectStatus "J1A2.51" )
			)
			( pin "@baseboard_fab2_lib.baseboard_fab2(sch_1):page85_i111:a0"
				( attribute "PN" "79"
					( Origin gPackager )
				)
				( objectStatus "J1A2.79" )
			)
			( pin "@baseboard_fab2_lib.baseboard_fab2(sch_1):page85_i111:a1"
				( attribute "PN" "72"
					( Origin gPackager )
				)
				( objectStatus "J1A2.72" )
			)
			( pin "@baseboard_fab2_lib.baseboard_fab2(sch_1):page85_i111:a2"
				( attribute "PN" "216"
					( Origin gPackager )
				)
				( objectStatus "J1A2.216" )
			)
			( pin "@baseboard_fab2_lib.baseboard_fab2(sch_1):page85_i111:a3"
				( attribute "PN" "71"
					( Origin gPackager )
				)
				( objectStatus "J1A2.71" )
			)
			( pin "@baseboard_fab2_lib.baseboard_fab2(sch_1):page85_i111:a4"
				( attribute "PN" "214"
					( Origin gPackager )
				)
				( objectStatus "J1A2.214" )
			)
			( pin "@baseboard_fab2_lib.baseboard_fab2(sch_1):page85_i111:a5"
				( attribute "PN" "213"
					( Origin gPackager )
				)
				( objectStatus "J1A2.213" )
			)
			( pin "@baseboard_fab2_lib.baseboard_fab2(sch_1):page85_i111:a6"
				( attribute "PN" "69"
					( Origin gPackager )
				)
				( objectStatus "J1A2.69" )
			)
			( pin "@baseboard_fab2_lib.baseboard_fab2(sch_1):page85_i111:a7"
				( attribute "PN" "211"
					( Origin gPackager )
				)
				( objectStatus "J1A2.211" )
			)
			( pin "@baseboard_fab2_lib.baseboard_fab2(sch_1):page85_i111:a8"
				( attribute "PN" "68"
					( Origin gPackager )
				)
				( objectStatus "J1A2.68" )
			)
			( pin "@baseboard_fab2_lib.baseboard_fab2(sch_1):page85_i111:a9"
				( attribute "PN" "66"
					( Origin gPackager )
				)
				( objectStatus "J1A2.66" )
			)
			( pin "@baseboard_fab2_lib.baseboard_fab2(sch_1):page85_i111:a10"
				( attribute "PN" "225"
					( Origin gPackager )
				)
				( objectStatus "J1A2.225" )
			)
			( pin "@baseboard_fab2_lib.baseboard_fab2(sch_1):page85_i111:a11"
				( attribute "PN" "210"
					( Origin gPackager )
				)
				( objectStatus "J1A2.210" )
			)
			( pin "@baseboard_fab2_lib.baseboard_fab2(sch_1):page85_i111:a12"
				( attribute "PN" "65"
					( Origin gPackager )
				)
				( objectStatus "J1A2.65" )
			)
			( pin "@baseboard_fab2_lib.baseboard_fab2(sch_1):page85_i111:a13"
				( attribute "PN" "232"
					( Origin gPackager )
				)
				( objectStatus "J1A2.232" )
			)
			( pin "@baseboard_fab2_lib.baseboard_fab2(sch_1):page85_i111:a14_we_n"
				( attribute "PN" "228"
					( Origin gPackager )
				)
				( objectStatus "J1A2.228" )
			)
			( pin "@baseboard_fab2_lib.baseboard_fab2(sch_1):page85_i111:a15_cas_n"
				( attribute "PN" "86"
					( Origin gPackager )
				)
				( objectStatus "J1A2.86" )
			)
			( pin "@baseboard_fab2_lib.baseboard_fab2(sch_1):page85_i111:a16_ras_n"
				( attribute "PN" "82"
					( Origin gPackager )
				)
				( objectStatus "J1A2.82" )
			)
			( pin "@baseboard_fab2_lib.baseboard_fab2(sch_1):page85_i111:a17"
				( attribute "PN" "234"
					( Origin gPackager )
				)
				( objectStatus "J1A2.234" )
			)
			( pin "@baseboard_fab2_lib.baseboard_fab2(sch_1):page85_i111:act_n"
				( attribute "PN" "62"
					( Origin gPackager )
				)
				( objectStatus "J1A2.62" )
			)
			( pin "@baseboard_fab2_lib.baseboard_fab2(sch_1):page85_i111:alert_n"
				( attribute "PN" "208"
					( Origin gPackager )
				)
				( objectStatus "J1A2.208" )
			)
			( pin "@baseboard_fab2_lib.baseboard_fab2(sch_1):page85_i111:ba(0)"
				( attribute "PN" "81"
					( Origin gPackager )
				)
				( objectStatus "J1A2.81" )
			)
			( pin "@baseboard_fab2_lib.baseboard_fab2(sch_1):page85_i111:ba(1)"
				( attribute "PN" "224"
					( Origin gPackager )
				)
				( objectStatus "J1A2.224" )
			)
			( pin "@baseboard_fab2_lib.baseboard_fab2(sch_1):page85_i111:bg(0)"
				( attribute "PN" "63"
					( Origin gPackager )
				)
				( objectStatus "J1A2.63" )
			)
			( pin "@baseboard_fab2_lib.baseboard_fab2(sch_1):page85_i111:bg(1)"
				( attribute "PN" "207"
					( Origin gPackager )
				)
				( objectStatus "J1A2.207" )
			)
			( pin "@baseboard_fab2_lib.baseboard_fab2(sch_1):page85_i111:c(2)"
				( attribute "PN" "235"
					( Origin gPackager )
				)
				( objectStatus "J1A2.235" )
			)
			( pin "@baseboard_fab2_lib.baseboard_fab2(sch_1):page85_i111:cb(0)"
				( attribute "PN" "49"
					( Origin gPackager )
				)
				( objectStatus "J1A2.49" )
			)
			( pin "@baseboard_fab2_lib.baseboard_fab2(sch_1):page85_i111:cb(1)"
				( attribute "PN" "194"
					( Origin gPackager )
				)
				( objectStatus "J1A2.194" )
			)
			( pin "@baseboard_fab2_lib.baseboard_fab2(sch_1):page85_i111:cb(2)"
				( attribute "PN" "56"
					( Origin gPackager )
				)
				( objectStatus "J1A2.56" )
			)
			( pin "@baseboard_fab2_lib.baseboard_fab2(sch_1):page85_i111:cb(3)"
				( attribute "PN" "201"
					( Origin gPackager )
				)
				( objectStatus "J1A2.201" )
			)
			( pin "@baseboard_fab2_lib.baseboard_fab2(sch_1):page85_i111:cb(4)"
				( attribute "PN" "47"
					( Origin gPackager )
				)
				( objectStatus "J1A2.47" )
			)
			( pin "@baseboard_fab2_lib.baseboard_fab2(sch_1):page85_i111:cb(5)"
				( attribute "PN" "192"
					( Origin gPackager )
				)
				( objectStatus "J1A2.192" )
			)
			( pin "@baseboard_fab2_lib.baseboard_fab2(sch_1):page85_i111:cb(6)"
				( attribute "PN" "54"
					( Origin gPackager )
				)
				( objectStatus "J1A2.54" )
			)
			( pin "@baseboard_fab2_lib.baseboard_fab2(sch_1):page85_i111:cb(7)"
				( attribute "PN" "199"
					( Origin gPackager )
				)
				( objectStatus "J1A2.199" )
			)
			( pin "@baseboard_fab2_lib.baseboard_fab2(sch_1):page85_i111:ck0n"
				( attribute "PN" "75"
					( Origin gPackager )
				)
				( objectStatus "J1A2.75" )
			)
			( pin "@baseboard_fab2_lib.baseboard_fab2(sch_1):page85_i111:ck0p"
				( attribute "PN" "74"
					( Origin gPackager )
				)
				( objectStatus "J1A2.74" )
			)
			( pin "@baseboard_fab2_lib.baseboard_fab2(sch_1):page85_i111:ck1n"
				( attribute "PN" "219"
					( Origin gPackager )
				)
				( objectStatus "J1A2.219" )
			)
			( pin "@baseboard_fab2_lib.baseboard_fab2(sch_1):page85_i111:ck1p"
				( attribute "PN" "218"
					( Origin gPackager )
				)
				( objectStatus "J1A2.218" )
			)
			( pin "@baseboard_fab2_lib.baseboard_fab2(sch_1):page85_i111:cke(0)"
				( attribute "PN" "60"
					( Origin gPackager )
				)
				( objectStatus "J1A2.60" )
			)
			( pin "@baseboard_fab2_lib.baseboard_fab2(sch_1):page85_i111:cke(1)"
				( attribute "PN" "203"
					( Origin gPackager )
				)
				( objectStatus "J1A2.203" )
			)
			( pin "@baseboard_fab2_lib.baseboard_fab2(sch_1):page85_i111:dq(0)"
				( attribute "PN" "5"
					( Origin gPackager )
				)
				( objectStatus "J1A2.5" )
			)
			( pin "@baseboard_fab2_lib.baseboard_fab2(sch_1):page85_i111:dq(1)"
				( attribute "PN" "150"
					( Origin gPackager )
				)
				( objectStatus "J1A2.150" )
			)
			( pin "@baseboard_fab2_lib.baseboard_fab2(sch_1):page85_i111:dq(2)"
				( attribute "PN" "12"
					( Origin gPackager )
				)
				( objectStatus "J1A2.12" )
			)
			( pin "@baseboard_fab2_lib.baseboard_fab2(sch_1):page85_i111:dq(3)"
				( attribute "PN" "157"
					( Origin gPackager )
				)
				( objectStatus "J1A2.157" )
			)
			( pin "@baseboard_fab2_lib.baseboard_fab2(sch_1):page85_i111:dq(4)"
				( attribute "PN" "3"
					( Origin gPackager )
				)
				( objectStatus "J1A2.3" )
			)
			( pin "@baseboard_fab2_lib.baseboard_fab2(sch_1):page85_i111:dq(5)"
				( attribute "PN" "148"
					( Origin gPackager )
				)
				( objectStatus "J1A2.148" )
			)
			( pin "@baseboard_fab2_lib.baseboard_fab2(sch_1):page85_i111:dq(6)"
				( attribute "PN" "10"
					( Origin gPackager )
				)
				( objectStatus "J1A2.10" )
			)
			( pin "@baseboard_fab2_lib.baseboard_fab2(sch_1):page85_i111:dq(7)"
				( attribute "PN" "155"
					( Origin gPackager )
				)
				( objectStatus "J1A2.155" )
			)
			( pin "@baseboard_fab2_lib.baseboard_fab2(sch_1):page85_i111:dq(8)"
				( attribute "PN" "16"
					( Origin gPackager )
				)
				( objectStatus "J1A2.16" )
			)
			( pin "@baseboard_fab2_lib.baseboard_fab2(sch_1):page85_i111:dq(9)"
				( attribute "PN" "161"
					( Origin gPackager )
				)
				( objectStatus "J1A2.161" )
			)
			( pin "@baseboard_fab2_lib.baseboard_fab2(sch_1):page85_i111:dq(10)"
				( attribute "PN" "23"
					( Origin gPackager )
				)
				( objectStatus "J1A2.23" )
			)
			( pin "@baseboard_fab2_lib.baseboard_fab2(sch_1):page85_i111:dq(11)"
				( attribute "PN" "168"
					( Origin gPackager )
				)
				( objectStatus "J1A2.168" )
			)
			( pin "@baseboard_fab2_lib.baseboard_fab2(sch_1):page85_i111:dq(12)"
				( attribute "PN" "14"
					( Origin gPackager )
				)
				( objectStatus "J1A2.14" )
			)
			( pin "@baseboard_fab2_lib.baseboard_fab2(sch_1):page85_i111:dq(13)"
				( attribute "PN" "159"
					( Origin gPackager )
				)
				( objectStatus "J1A2.159" )
			)
			( pin "@baseboard_fab2_lib.baseboard_fab2(sch_1):page85_i111:dq(14)"
				( attribute "PN" "21"
					( Origin gPackager )
				)
				( objectStatus "J1A2.21" )
			)
			( pin "@baseboard_fab2_lib.baseboard_fab2(sch_1):page85_i111:dq(15)"
				( attribute "PN" "166"
					( Origin gPackager )
				)
				( objectStatus "J1A2.166" )
			)
			( pin "@baseboard_fab2_lib.baseboard_fab2(sch_1):page85_i111:dq(16)"
				( attribute "PN" "27"
					( Origin gPackager )
				)
				( objectStatus "J1A2.27" )
			)
			( pin "@baseboard_fab2_lib.baseboard_fab2(sch_1):page85_i111:dq(17)"
				( attribute "PN" "172"
					( Origin gPackager )
				)
				( objectStatus "J1A2.172" )
			)
			( pin "@baseboard_fab2_lib.baseboard_fab2(sch_1):page85_i111:dq(18)"
				( attribute "PN" "34"
					( Origin gPackager )
				)
				( objectStatus "J1A2.34" )
			)
			( pin "@baseboard_fab2_lib.baseboard_fab2(sch_1):page85_i111:dq(19)"
				( attribute "PN" "179"
					( Origin gPackager )
				)
				( objectStatus "J1A2.179" )
			)
			( pin "@baseboard_fab2_lib.baseboard_fab2(sch_1):page85_i111:dq(20)"
				( attribute "PN" "25"
					( Origin gPackager )
				)
				( objectStatus "J1A2.25" )
			)
			( pin "@baseboard_fab2_lib.baseboard_fab2(sch_1):page85_i111:dq(21)"
				( attribute "PN" "170"
					( Origin gPackager )
				)
				( objectStatus "J1A2.170" )
			)
			( pin "@baseboard_fab2_lib.baseboard_fab2(sch_1):page85_i111:dq(22)"
				( attribute "PN" "32"
					( Origin gPackager )
				)
				( objectStatus "J1A2.32" )
			)
			( pin "@baseboard_fab2_lib.baseboard_fab2(sch_1):page85_i111:dq(23)"
				( attribute "PN" "177"
					( Origin gPackager )
				)
				( objectStatus "J1A2.177" )
			)
			( pin "@baseboard_fab2_lib.baseboard_fab2(sch_1):page85_i111:dq(24)"
				( attribute "PN" "38"
					( Origin gPackager )
				)
				( objectStatus "J1A2.38" )
			)
			( pin "@baseboard_fab2_lib.baseboard_fab2(sch_1):page85_i111:dq(25)"
				( attribute "PN" "183"
					( Origin gPackager )
				)
				( objectStatus "J1A2.183" )
			)
			( pin "@baseboard_fab2_lib.baseboard_fab2(sch_1):page85_i111:dq(26)"
				( attribute "PN" "45"
					( Origin gPackager )
				)
				( objectStatus "J1A2.45" )
			)
			( pin "@baseboard_fab2_lib.baseboard_fab2(sch_1):page85_i111:dq(27)"
				( attribute "PN" "190"
					( Origin gPackager )
				)
				( objectStatus "J1A2.190" )
			)
			( pin "@baseboard_fab2_lib.baseboard_fab2(sch_1):page85_i111:dq(28)"
				( attribute "PN" "36"
					( Origin gPackager )
				)
				( objectStatus "J1A2.36" )
			)
			( pin "@baseboard_fab2_lib.baseboard_fab2(sch_1):page85_i111:dq(29)"
				( attribute "PN" "181"
					( Origin gPackager )
				)
				( objectStatus "J1A2.181" )
			)
			( pin "@baseboard_fab2_lib.baseboard_fab2(sch_1):page85_i111:dq(30)"
				( attribute "PN" "43"
					( Origin gPackager )
				)
				( objectStatus "J1A2.43" )
			)
			( pin "@baseboard_fab2_lib.baseboard_fab2(sch_1):page85_i111:dq(31)"
				( attribute "PN" "188"
					( Origin gPackager )
				)
				( objectStatus "J1A2.188" )
			)
			( pin "@baseboard_fab2_lib.baseboard_fab2(sch_1):page85_i111:dq(32)"
				( attribute "PN" "97"
					( Origin gPackager )
				)
				( objectStatus "J1A2.97" )
			)
			( pin "@baseboard_fab2_lib.baseboard_fab2(sch_1):page85_i111:dq(33)"
				( attribute "PN" "242"
					( Origin gPackager )
				)
				( objectStatus "J1A2.242" )
			)
			( pin "@baseboard_fab2_lib.baseboard_fab2(sch_1):page85_i111:dq(34)"
				( attribute "PN" "104"
					( Origin gPackager )
				)
				( objectStatus "J1A2.104" )
			)
			( pin "@baseboard_fab2_lib.baseboard_fab2(sch_1):page85_i111:dq(35)"
				( attribute "PN" "249"
					( Origin gPackager )
				)
				( objectStatus "J1A2.249" )
			)
			( pin "@baseboard_fab2_lib.baseboard_fab2(sch_1):page85_i111:dq(36)"
				( attribute "PN" "95"
					( Origin gPackager )
				)
				( objectStatus "J1A2.95" )
			)
			( pin "@baseboard_fab2_lib.baseboard_fab2(sch_1):page85_i111:dq(37)"
				( attribute "PN" "240"
					( Origin gPackager )
				)
				( objectStatus "J1A2.240" )
			)
			( pin "@baseboard_fab2_lib.baseboard_fab2(sch_1):page85_i111:dq(38)"
				( attribute "PN" "102"
					( Origin gPackager )
				)
				( objectStatus "J1A2.102" )
			)
			( pin "@baseboard_fab2_lib.baseboard_fab2(sch_1):page85_i111:dq(39)"
				( attribute "PN" "247"
					( Origin gPackager )
				)
				( objectStatus "J1A2.247" )
			)
			( pin "@baseboard_fab2_lib.baseboard_fab2(sch_1):page85_i111:dq(40)"
				( attribute "PN" "108"
					( Origin gPackager )
				)
				( objectStatus "J1A2.108" )
			)
			( pin "@baseboard_fab2_lib.baseboard_fab2(sch_1):page85_i111:dq(41)"
				( attribute "PN" "253"
					( Origin gPackager )
				)
				( objectStatus "J1A2.253" )
			)
			( pin "@baseboard_fab2_lib.baseboard_fab2(sch_1):page85_i111:dq(42)"
				( attribute "PN" "115"
					( Origin gPackager )
				)
				( objectStatus "J1A2.115" )
			)
			( pin "@baseboard_fab2_lib.baseboard_fab2(sch_1):page85_i111:dq(43)"
				( attribute "PN" "260"
					( Origin gPackager )
				)
				( objectStatus "J1A2.260" )
			)
			( pin "@baseboard_fab2_lib.baseboard_fab2(sch_1):page85_i111:dq(44)"
				( attribute "PN" "106"
					( Origin gPackager )
				)
				( objectStatus "J1A2.106" )
			)
			( pin "@baseboard_fab2_lib.baseboard_fab2(sch_1):page85_i111:dq(45)"
				( attribute "PN" "251"
					( Origin gPackager )
				)
				( objectStatus "J1A2.251" )
			)
			( pin "@baseboard_fab2_lib.baseboard_fab2(sch_1):page85_i111:dq(46)"
				( attribute "PN" "113"
					( Origin gPackager )
				)
				( objectStatus "J1A2.113" )
			)
			( pin "@baseboard_fab2_lib.baseboard_fab2(sch_1):page85_i111:dq(47)"
				( attribute "PN" "258"
					( Origin gPackager )
				)
				( objectStatus "J1A2.258" )
			)
			( pin "@baseboard_fab2_lib.baseboard_fab2(sch_1):page85_i111:dq(48)"
				( attribute "PN" "119"
					( Origin gPackager )
				)
				( objectStatus "J1A2.119" )
			)
			( pin "@baseboard_fab2_lib.baseboard_fab2(sch_1):page85_i111:dq(49)"
				( attribute "PN" "264"
					( Origin gPackager )
				)
				( objectStatus "J1A2.264" )
			)
			( pin "@baseboard_fab2_lib.baseboard_fab2(sch_1):page85_i111:dq(50)"
				( attribute "PN" "126"
					( Origin gPackager )
				)
				( objectStatus "J1A2.126" )
			)
			( pin "@baseboard_fab2_lib.baseboard_fab2(sch_1):page85_i111:dq(51)"
				( attribute "PN" "271"
					( Origin gPackager )
				)
				( objectStatus "J1A2.271" )
			)
			( pin "@baseboard_fab2_lib.baseboard_fab2(sch_1):page85_i111:dq(52)"
				( attribute "PN" "117"
					( Origin gPackager )
				)
				( objectStatus "J1A2.117" )
			)
			( pin "@baseboard_fab2_lib.baseboard_fab2(sch_1):page85_i111:dq(53)"
				( attribute "PN" "262"
					( Origin gPackager )
				)
				( objectStatus "J1A2.262" )
			)
			( pin "@baseboard_fab2_lib.baseboard_fab2(sch_1):page85_i111:dq(54)"
				( attribute "PN" "124"
					( Origin gPackager )
				)
				( objectStatus "J1A2.124" )
			)
			( pin "@baseboard_fab2_lib.baseboard_fab2(sch_1):page85_i111:dq(55)"
				( attribute "PN" "269"
					( Origin gPackager )
				)
				( objectStatus "J1A2.269" )
			)
			( pin "@baseboard_fab2_lib.baseboard_fab2(sch_1):page85_i111:dq(56)"
				( attribute "PN" "130"
					( Origin gPackager )
				)
				( objectStatus "J1A2.130" )
			)
			( pin "@baseboard_fab2_lib.baseboard_fab2(sch_1):page85_i111:dq(57)"
				( attribute "PN" "275"
					( Origin gPackager )
				)
				( objectStatus "J1A2.275" )
			)
			( pin "@baseboard_fab2_lib.baseboard_fab2(sch_1):page85_i111:dq(58)"
				( attribute "PN" "137"
					( Origin gPackager )
				)
				( objectStatus "J1A2.137" )
			)
			( pin "@baseboard_fab2_lib.baseboard_fab2(sch_1):page85_i111:dq(59)"
				( attribute "PN" "282"
					( Origin gPackager )
				)
				( objectStatus "J1A2.282" )
			)
			( pin "@baseboard_fab2_lib.baseboard_fab2(sch_1):page85_i111:dq(60)"
				( attribute "PN" "128"
					( Origin gPackager )
				)
				( objectStatus "J1A2.128" )
			)
			( pin "@baseboard_fab2_lib.baseboard_fab2(sch_1):page85_i111:dq(61)"
				( attribute "PN" "273"
					( Origin gPackager )
				)
				( objectStatus "J1A2.273" )
			)
			( pin "@baseboard_fab2_lib.baseboard_fab2(sch_1):page85_i111:dq(62)"
				( attribute "PN" "135"
					( Origin gPackager )
				)
				( objectStatus "J1A2.135" )
			)
			( pin "@baseboard_fab2_lib.baseboard_fab2(sch_1):page85_i111:dq(63)"
				( attribute "PN" "280"
					( Origin gPackager )
				)
				( objectStatus "J1A2.280" )
			)
			( pin "@baseboard_fab2_lib.baseboard_fab2(sch_1):page85_i111:event_n"
				( attribute "PN" "78"
					( Origin gPackager )
				)
				( objectStatus "J1A2.78" )
			)
			( pin "@baseboard_fab2_lib.baseboard_fab2(sch_1):page85_i111:odt(0)"
				( attribute "PN" "87"
					( Origin gPackager )
				)
				( objectStatus "J1A2.87" )
			)
			( pin "@baseboard_fab2_lib.baseboard_fab2(sch_1):page85_i111:odt(1)"
				( attribute "PN" "91"
					( Origin gPackager )
				)
				( objectStatus "J1A2.91" )
			)
			( pin "@baseboard_fab2_lib.baseboard_fab2(sch_1):page85_i111:par"
				( attribute "PN" "222"
					( Origin gPackager )
				)
				( objectStatus "J1A2.222" )
			)
			( pin "@baseboard_fab2_lib.baseboard_fab2(sch_1):page85_i111:reset_n"
				( attribute "PN" "58"
					( Origin gPackager )
				)
				( objectStatus "J1A2.58" )
			)
			( pin "@baseboard_fab2_lib.baseboard_fab2(sch_1):page85_i111:rfu(0)"
				( attribute "PN" "205"
					( Origin gPackager )
				)
				( objectStatus "J1A2.205" )
			)
			( pin "@baseboard_fab2_lib.baseboard_fab2(sch_1):page85_i111:rfu(1)"
				( attribute "PN" "227"
					( Origin gPackager )
				)
				( objectStatus "J1A2.227" )
			)
			( pin "@baseboard_fab2_lib.baseboard_fab2(sch_1):page85_i111:rfu(2)"
				( attribute "PN" "144"
					( Origin gPackager )
				)
				( objectStatus "J1A2.144" )
			)
			( pin "@baseboard_fab2_lib.baseboard_fab2(sch_1):page85_i111:s0_n"
				( attribute "PN" "84"
					( Origin gPackager )
				)
				( objectStatus "J1A2.84" )
			)
			( pin "@baseboard_fab2_lib.baseboard_fab2(sch_1):page85_i111:s1_n"
				( attribute "PN" "89"
					( Origin gPackager )
				)
				( objectStatus "J1A2.89" )
			)
			( pin "@baseboard_fab2_lib.baseboard_fab2(sch_1):page85_i111:s2_n_c(0)"
				( attribute "PN" "93"
					( Origin gPackager )
				)
				( objectStatus "J1A2.93" )
			)
			( pin "@baseboard_fab2_lib.baseboard_fab2(sch_1):page85_i111:s3_n_c(1)"
				( attribute "PN" "237"
					( Origin gPackager )
				)
				( objectStatus "J1A2.237" )
			)
			( pin "@baseboard_fab2_lib.baseboard_fab2(sch_1):page85_i111:sa(0)"
				( attribute "PN" "139"
					( Origin gPackager )
				)
				( objectStatus "J1A2.139" )
			)
			( pin "@baseboard_fab2_lib.baseboard_fab2(sch_1):page85_i111:sa(1)"
				( attribute "PN" "140"
					( Origin gPackager )
				)
				( objectStatus "J1A2.140" )
			)
			( pin "@baseboard_fab2_lib.baseboard_fab2(sch_1):page85_i111:sa(2)"
				( attribute "PN" "238"
					( Origin gPackager )
				)
				( objectStatus "J1A2.238" )
			)
			( pin "@baseboard_fab2_lib.baseboard_fab2(sch_1):page85_i111:save_n_nc"
				( attribute "PN" "230"
					( Origin gPackager )
				)
				( objectStatus "J1A2.230" )
			)
			( pin "@baseboard_fab2_lib.baseboard_fab2(sch_1):page85_i111:scl"
				( attribute "PN" "141"
					( Origin gPackager )
				)
				( objectStatus "J1A2.141" )
			)
			( pin "@baseboard_fab2_lib.baseboard_fab2(sch_1):page85_i111:sda"
				( attribute "PN" "285"
					( Origin gPackager )
				)
				( objectStatus "J1A2.285" )
			)
			( pin "@baseboard_fab2_lib.baseboard_fab2(sch_1):page85_i111:vddspd"
				( attribute "PN" "284"
					( Origin gPackager )
				)
				( objectStatus "J1A2.284" )
			)
			( pin "@baseboard_fab2_lib.baseboard_fab2(sch_1):page85_i111:vrefca"
				( attribute "PN" "146"
					( Origin gPackager )
				)
				( objectStatus "J1A2.146" )
			)
			( pin "@baseboard_fab2_lib.baseboard_fab2(sch_1):page85_i172:\12v\(0)"
				( attribute "PN" "145"
					( Origin gPackager )
				)
				( objectStatus "J1A2.145" )
			)
			( pin "@baseboard_fab2_lib.baseboard_fab2(sch_1):page85_i172:\12v\(1)"
				( attribute "PN" "1"
					( Origin gPackager )
				)
				( objectStatus "J1A2.1" )
			)
			( pin "@baseboard_fab2_lib.baseboard_fab2(sch_1):page85_i172:vdd(0)"
				( attribute "PN" "236"
					( Origin gPackager )
				)
				( objectStatus "J1A2.236" )
			)
			( pin "@baseboard_fab2_lib.baseboard_fab2(sch_1):page85_i172:vdd(1)"
				( attribute "PN" "233"
					( Origin gPackager )
				)
				( objectStatus "J1A2.233" )
			)
			( pin "@baseboard_fab2_lib.baseboard_fab2(sch_1):page85_i172:vdd(2)"
				( attribute "PN" "231"
					( Origin gPackager )
				)
				( objectStatus "J1A2.231" )
			)
			( pin "@baseboard_fab2_lib.baseboard_fab2(sch_1):page85_i172:vdd(3)"
				( attribute "PN" "229"
					( Origin gPackager )
				)
				( objectStatus "J1A2.229" )
			)
			( pin "@baseboard_fab2_lib.baseboard_fab2(sch_1):page85_i172:vdd(4)"
				( attribute "PN" "226"
					( Origin gPackager )
				)
				( objectStatus "J1A2.226" )
			)
			( pin "@baseboard_fab2_lib.baseboard_fab2(sch_1):page85_i172:vdd(5)"
				( attribute "PN" "223"
					( Origin gPackager )
				)
				( objectStatus "J1A2.223" )
			)
			( pin "@baseboard_fab2_lib.baseboard_fab2(sch_1):page85_i172:vdd(6)"
				( attribute "PN" "220"
					( Origin gPackager )
				)
				( objectStatus "J1A2.220" )
			)
			( pin "@baseboard_fab2_lib.baseboard_fab2(sch_1):page85_i172:vdd(7)"
				( attribute "PN" "217"
					( Origin gPackager )
				)
				( objectStatus "J1A2.217" )
			)
			( pin "@baseboard_fab2_lib.baseboard_fab2(sch_1):page85_i172:vdd(8)"
				( attribute "PN" "215"
					( Origin gPackager )
				)
				( objectStatus "J1A2.215" )
			)
			( pin "@baseboard_fab2_lib.baseboard_fab2(sch_1):page85_i172:vdd(9)"
				( attribute "PN" "212"
					( Origin gPackager )
				)
				( objectStatus "J1A2.212" )
			)
			( pin "@baseboard_fab2_lib.baseboard_fab2(sch_1):page85_i172:vdd(10)"
				( attribute "PN" "209"
					( Origin gPackager )
				)
				( objectStatus "J1A2.209" )
			)
			( pin "@baseboard_fab2_lib.baseboard_fab2(sch_1):page85_i172:vdd(11)"
				( attribute "PN" "206"
					( Origin gPackager )
				)
				( objectStatus "J1A2.206" )
			)
			( pin "@baseboard_fab2_lib.baseboard_fab2(sch_1):page85_i172:vdd(12)"
				( attribute "PN" "204"
					( Origin gPackager )
				)
				( objectStatus "J1A2.204" )
			)
			( pin "@baseboard_fab2_lib.baseboard_fab2(sch_1):page85_i172:vdd(13)"
				( attribute "PN" "92"
					( Origin gPackager )
				)
				( objectStatus "J1A2.92" )
			)
			( pin "@baseboard_fab2_lib.baseboard_fab2(sch_1):page85_i172:vdd(14)"
				( attribute "PN" "90"
					( Origin gPackager )
				)
				( objectStatus "J1A2.90" )
			)
			( pin "@baseboard_fab2_lib.baseboard_fab2(sch_1):page85_i172:vdd(15)"
				( attribute "PN" "88"
					( Origin gPackager )
				)
				( objectStatus "J1A2.88" )
			)
			( pin "@baseboard_fab2_lib.baseboard_fab2(sch_1):page85_i172:vdd(16)"
				( attribute "PN" "85"
					( Origin gPackager )
				)
				( objectStatus "J1A2.85" )
			)
			( pin "@baseboard_fab2_lib.baseboard_fab2(sch_1):page85_i172:vdd(17)"
				( attribute "PN" "83"
					( Origin gPackager )
				)
				( objectStatus "J1A2.83" )
			)
			( pin "@baseboard_fab2_lib.baseboard_fab2(sch_1):page85_i172:vdd(18)"
				( attribute "PN" "80"
					( Origin gPackager )
				)
				( objectStatus "J1A2.80" )
			)
			( pin "@baseboard_fab2_lib.baseboard_fab2(sch_1):page85_i172:vdd(19)"
				( attribute "PN" "76"
					( Origin gPackager )
				)
				( objectStatus "J1A2.76" )
			)
			( pin "@baseboard_fab2_lib.baseboard_fab2(sch_1):page85_i172:vdd(20)"
				( attribute "PN" "73"
					( Origin gPackager )
				)
				( objectStatus "J1A2.73" )
			)
			( pin "@baseboard_fab2_lib.baseboard_fab2(sch_1):page85_i172:vdd(21)"
				( attribute "PN" "70"
					( Origin gPackager )
				)
				( objectStatus "J1A2.70" )
			)
			( pin "@baseboard_fab2_lib.baseboard_fab2(sch_1):page85_i172:vdd(22)"
				( attribute "PN" "67"
					( Origin gPackager )
				)
				( objectStatus "J1A2.67" )
			)
			( pin "@baseboard_fab2_lib.baseboard_fab2(sch_1):page85_i172:vdd(23)"
				( attribute "PN" "64"
					( Origin gPackager )
				)
				( objectStatus "J1A2.64" )
			)
			( pin "@baseboard_fab2_lib.baseboard_fab2(sch_1):page85_i172:vdd(24)"
				( attribute "PN" "61"
					( Origin gPackager )
				)
				( objectStatus "J1A2.61" )
			)
			( pin "@baseboard_fab2_lib.baseboard_fab2(sch_1):page85_i172:vdd(25)"
				( attribute "PN" "59"
					( Origin gPackager )
				)
				( objectStatus "J1A2.59" )
			)
			( pin "@baseboard_fab2_lib.baseboard_fab2(sch_1):page85_i172:vpp(0)"
				( attribute "PN" "287"
					( Origin gPackager )
				)
				( objectStatus "J1A2.287" )
			)
			( pin "@baseboard_fab2_lib.baseboard_fab2(sch_1):page85_i172:vpp(1)"
				( attribute "PN" "286"
					( Origin gPackager )
				)
				( objectStatus "J1A2.286" )
			)
			( pin "@baseboard_fab2_lib.baseboard_fab2(sch_1):page85_i172:vpp(2)"
				( attribute "PN" "288"
					( Origin gPackager )
				)
				( objectStatus "J1A2.288" )
			)
			( pin "@baseboard_fab2_lib.baseboard_fab2(sch_1):page85_i172:vpp(3)"
				( attribute "PN" "143"
					( Origin gPackager )
				)
				( objectStatus "J1A2.143" )
			)
			( pin "@baseboard_fab2_lib.baseboard_fab2(sch_1):page85_i172:vpp(4)"
				( attribute "PN" "142"
					( Origin gPackager )
				)
				( objectStatus "J1A2.142" )
			)
			( pin "@baseboard_fab2_lib.baseboard_fab2(sch_1):page85_i172:vtt(0)"
				( attribute "PN" "221"
					( Origin gPackager )
				)
				( objectStatus "J1A2.221" )
			)
			( pin "@baseboard_fab2_lib.baseboard_fab2(sch_1):page85_i172:vtt(1)"
				( attribute "PN" "77"
					( Origin gPackager )
				)
				( objectStatus "J1A2.77" )
			)
			( pin "@baseboard_fab2_lib.baseboard_fab2(sch_1):page85_i181:a"
				( attribute "PN" "1"
					( Origin gPackager )
				)
				( objectStatus "C9L7.1" )
			)
			( pin "@baseboard_fab2_lib.baseboard_fab2(sch_1):page85_i181:b"
				( attribute "PN" "2"
					( Origin gPackager )
				)
				( objectStatus "C9L7.2" )
			)
			( pin "@baseboard_fab2_lib.baseboard_fab2(sch_1):page86_i12:a0"
				( attribute "PN" "79"
					( Origin gPackager )
				)
				( objectStatus "J9L2.79" )
			)
			( pin "@baseboard_fab2_lib.baseboard_fab2(sch_1):page86_i12:a1"
				( attribute "PN" "72"
					( Origin gPackager )
				)
				( objectStatus "J9L2.72" )
			)
			( pin "@baseboard_fab2_lib.baseboard_fab2(sch_1):page86_i12:a2"
				( attribute "PN" "216"
					( Origin gPackager )
				)
				( objectStatus "J9L2.216" )
			)
			( pin "@baseboard_fab2_lib.baseboard_fab2(sch_1):page86_i12:a3"
				( attribute "PN" "71"
					( Origin gPackager )
				)
				( objectStatus "J9L2.71" )
			)
			( pin "@baseboard_fab2_lib.baseboard_fab2(sch_1):page86_i12:a4"
				( attribute "PN" "214"
					( Origin gPackager )
				)
				( objectStatus "J9L2.214" )
			)
			( pin "@baseboard_fab2_lib.baseboard_fab2(sch_1):page86_i12:a5"
				( attribute "PN" "213"
					( Origin gPackager )
				)
				( objectStatus "J9L2.213" )
			)
			( pin "@baseboard_fab2_lib.baseboard_fab2(sch_1):page86_i12:a6"
				( attribute "PN" "69"
					( Origin gPackager )
				)
				( objectStatus "J9L2.69" )
			)
			( pin "@baseboard_fab2_lib.baseboard_fab2(sch_1):page86_i12:a7"
				( attribute "PN" "211"
					( Origin gPackager )
				)
				( objectStatus "J9L2.211" )
			)
			( pin "@baseboard_fab2_lib.baseboard_fab2(sch_1):page86_i12:a8"
				( attribute "PN" "68"
					( Origin gPackager )
				)
				( objectStatus "J9L2.68" )
			)
			( pin "@baseboard_fab2_lib.baseboard_fab2(sch_1):page86_i12:a9"
				( attribute "PN" "66"
					( Origin gPackager )
				)
				( objectStatus "J9L2.66" )
			)
			( pin "@baseboard_fab2_lib.baseboard_fab2(sch_1):page86_i12:a10"
				( attribute "PN" "225"
					( Origin gPackager )
				)
				( objectStatus "J9L2.225" )
			)
			( pin "@baseboard_fab2_lib.baseboard_fab2(sch_1):page86_i12:a11"
				( attribute "PN" "210"
					( Origin gPackager )
				)
				( objectStatus "J9L2.210" )
			)
			( pin "@baseboard_fab2_lib.baseboard_fab2(sch_1):page86_i12:a12"
				( attribute "PN" "65"
					( Origin gPackager )
				)
				( objectStatus "J9L2.65" )
			)
			( pin "@baseboard_fab2_lib.baseboard_fab2(sch_1):page86_i12:a13"
				( attribute "PN" "232"
					( Origin gPackager )
				)
				( objectStatus "J9L2.232" )
			)
			( pin "@baseboard_fab2_lib.baseboard_fab2(sch_1):page86_i12:a14_we_n"
				( attribute "PN" "228"
					( Origin gPackager )
				)
				( objectStatus "J9L2.228" )
			)
			( pin "@baseboard_fab2_lib.baseboard_fab2(sch_1):page86_i12:a15_cas_n"
				( attribute "PN" "86"
					( Origin gPackager )
				)
				( objectStatus "J9L2.86" )
			)
			( pin "@baseboard_fab2_lib.baseboard_fab2(sch_1):page86_i12:a16_ras_n"
				( attribute "PN" "82"
					( Origin gPackager )
				)
				( objectStatus "J9L2.82" )
			)
			( pin "@baseboard_fab2_lib.baseboard_fab2(sch_1):page86_i12:a17"
				( attribute "PN" "234"
					( Origin gPackager )
				)
				( objectStatus "J9L2.234" )
			)
			( pin "@baseboard_fab2_lib.baseboard_fab2(sch_1):page86_i12:act_n"
				( attribute "PN" "62"
					( Origin gPackager )
				)
				( objectStatus "J9L2.62" )
			)
			( pin "@baseboard_fab2_lib.baseboard_fab2(sch_1):page86_i12:alert_n"
				( attribute "PN" "208"
					( Origin gPackager )
				)
				( objectStatus "J9L2.208" )
			)
			( pin "@baseboard_fab2_lib.baseboard_fab2(sch_1):page86_i12:ba(0)"
				( attribute "PN" "81"
					( Origin gPackager )
				)
				( objectStatus "J9L2.81" )
			)
			( pin "@baseboard_fab2_lib.baseboard_fab2(sch_1):page86_i12:ba(1)"
				( attribute "PN" "224"
					( Origin gPackager )
				)
				( objectStatus "J9L2.224" )
			)
			( pin "@baseboard_fab2_lib.baseboard_fab2(sch_1):page86_i12:bg(0)"
				( attribute "PN" "63"
					( Origin gPackager )
				)
				( objectStatus "J9L2.63" )
			)
			( pin "@baseboard_fab2_lib.baseboard_fab2(sch_1):page86_i12:bg(1)"
				( attribute "PN" "207"
					( Origin gPackager )
				)
				( objectStatus "J9L2.207" )
			)
			( pin "@baseboard_fab2_lib.baseboard_fab2(sch_1):page86_i12:c(2)"
				( attribute "PN" "235"
					( Origin gPackager )
				)
				( objectStatus "J9L2.235" )
			)
			( pin "@baseboard_fab2_lib.baseboard_fab2(sch_1):page86_i12:cb(0)"
				( attribute "PN" "49"
					( Origin gPackager )
				)
				( objectStatus "J9L2.49" )
			)
			( pin "@baseboard_fab2_lib.baseboard_fab2(sch_1):page86_i12:cb(1)"
				( attribute "PN" "194"
					( Origin gPackager )
				)
				( objectStatus "J9L2.194" )
			)
			( pin "@baseboard_fab2_lib.baseboard_fab2(sch_1):page86_i12:cb(2)"
				( attribute "PN" "56"
					( Origin gPackager )
				)
				( objectStatus "J9L2.56" )
			)
			( pin "@baseboard_fab2_lib.baseboard_fab2(sch_1):page86_i12:cb(3)"
				( attribute "PN" "201"
					( Origin gPackager )
				)
				( objectStatus "J9L2.201" )
			)
			( pin "@baseboard_fab2_lib.baseboard_fab2(sch_1):page86_i12:cb(4)"
				( attribute "PN" "47"
					( Origin gPackager )
				)
				( objectStatus "J9L2.47" )
			)
			( pin "@baseboard_fab2_lib.baseboard_fab2(sch_1):page86_i12:cb(5)"
				( attribute "PN" "192"
					( Origin gPackager )
				)
				( objectStatus "J9L2.192" )
			)
			( pin "@baseboard_fab2_lib.baseboard_fab2(sch_1):page86_i12:cb(6)"
				( attribute "PN" "54"
					( Origin gPackager )
				)
				( objectStatus "J9L2.54" )
			)
			( pin "@baseboard_fab2_lib.baseboard_fab2(sch_1):page86_i12:cb(7)"
				( attribute "PN" "199"
					( Origin gPackager )
				)
				( objectStatus "J9L2.199" )
			)
			( pin "@baseboard_fab2_lib.baseboard_fab2(sch_1):page86_i12:ck0n"
				( attribute "PN" "75"
					( Origin gPackager )
				)
				( objectStatus "J9L2.75" )
			)
			( pin "@baseboard_fab2_lib.baseboard_fab2(sch_1):page86_i12:ck0p"
				( attribute "PN" "74"
					( Origin gPackager )
				)
				( objectStatus "J9L2.74" )
			)
			( pin "@baseboard_fab2_lib.baseboard_fab2(sch_1):page86_i12:ck1n"
				( attribute "PN" "219"
					( Origin gPackager )
				)
				( objectStatus "J9L2.219" )
			)
			( pin "@baseboard_fab2_lib.baseboard_fab2(sch_1):page86_i12:ck1p"
				( attribute "PN" "218"
					( Origin gPackager )
				)
				( objectStatus "J9L2.218" )
			)
			( pin "@baseboard_fab2_lib.baseboard_fab2(sch_1):page86_i12:cke(0)"
				( attribute "PN" "60"
					( Origin gPackager )
				)
				( objectStatus "J9L2.60" )
			)
			( pin "@baseboard_fab2_lib.baseboard_fab2(sch_1):page86_i12:cke(1)"
				( attribute "PN" "203"
					( Origin gPackager )
				)
				( objectStatus "J9L2.203" )
			)
			( pin "@baseboard_fab2_lib.baseboard_fab2(sch_1):page86_i12:dq(0)"
				( attribute "PN" "5"
					( Origin gPackager )
				)
				( objectStatus "J9L2.5" )
			)
			( pin "@baseboard_fab2_lib.baseboard_fab2(sch_1):page86_i12:dq(1)"
				( attribute "PN" "150"
					( Origin gPackager )
				)
				( objectStatus "J9L2.150" )
			)
			( pin "@baseboard_fab2_lib.baseboard_fab2(sch_1):page86_i12:dq(2)"
				( attribute "PN" "12"
					( Origin gPackager )
				)
				( objectStatus "J9L2.12" )
			)
			( pin "@baseboard_fab2_lib.baseboard_fab2(sch_1):page86_i12:dq(3)"
				( attribute "PN" "157"
					( Origin gPackager )
				)
				( objectStatus "J9L2.157" )
			)
			( pin "@baseboard_fab2_lib.baseboard_fab2(sch_1):page86_i12:dq(4)"
				( attribute "PN" "3"
					( Origin gPackager )
				)
				( objectStatus "J9L2.3" )
			)
			( pin "@baseboard_fab2_lib.baseboard_fab2(sch_1):page86_i12:dq(5)"
				( attribute "PN" "148"
					( Origin gPackager )
				)
				( objectStatus "J9L2.148" )
			)
			( pin "@baseboard_fab2_lib.baseboard_fab2(sch_1):page86_i12:dq(6)"
				( attribute "PN" "10"
					( Origin gPackager )
				)
				( objectStatus "J9L2.10" )
			)
			( pin "@baseboard_fab2_lib.baseboard_fab2(sch_1):page86_i12:dq(7)"
				( attribute "PN" "155"
					( Origin gPackager )
				)
				( objectStatus "J9L2.155" )
			)
			( pin "@baseboard_fab2_lib.baseboard_fab2(sch_1):page86_i12:dq(8)"
				( attribute "PN" "16"
					( Origin gPackager )
				)
				( objectStatus "J9L2.16" )
			)
			( pin "@baseboard_fab2_lib.baseboard_fab2(sch_1):page86_i12:dq(9)"
				( attribute "PN" "161"
					( Origin gPackager )
				)
				( objectStatus "J9L2.161" )
			)
			( pin "@baseboard_fab2_lib.baseboard_fab2(sch_1):page86_i12:dq(10)"
				( attribute "PN" "23"
					( Origin gPackager )
				)
				( objectStatus "J9L2.23" )
			)
			( pin "@baseboard_fab2_lib.baseboard_fab2(sch_1):page86_i12:dq(11)"
				( attribute "PN" "168"
					( Origin gPackager )
				)
				( objectStatus "J9L2.168" )
			)
			( pin "@baseboard_fab2_lib.baseboard_fab2(sch_1):page86_i12:dq(12)"
				( attribute "PN" "14"
					( Origin gPackager )
				)
				( objectStatus "J9L2.14" )
			)
			( pin "@baseboard_fab2_lib.baseboard_fab2(sch_1):page86_i12:dq(13)"
				( attribute "PN" "159"
					( Origin gPackager )
				)
				( objectStatus "J9L2.159" )
			)
			( pin "@baseboard_fab2_lib.baseboard_fab2(sch_1):page86_i12:dq(14)"
				( attribute "PN" "21"
					( Origin gPackager )
				)
				( objectStatus "J9L2.21" )
			)
			( pin "@baseboard_fab2_lib.baseboard_fab2(sch_1):page86_i12:dq(15)"
				( attribute "PN" "166"
					( Origin gPackager )
				)
				( objectStatus "J9L2.166" )
			)
			( pin "@baseboard_fab2_lib.baseboard_fab2(sch_1):page86_i12:dq(16)"
				( attribute "PN" "27"
					( Origin gPackager )
				)
				( objectStatus "J9L2.27" )
			)
			( pin "@baseboard_fab2_lib.baseboard_fab2(sch_1):page86_i12:dq(17)"
				( attribute "PN" "172"
					( Origin gPackager )
				)
				( objectStatus "J9L2.172" )
			)
			( pin "@baseboard_fab2_lib.baseboard_fab2(sch_1):page86_i12:dq(18)"
				( attribute "PN" "34"
					( Origin gPackager )
				)
				( objectStatus "J9L2.34" )
			)
			( pin "@baseboard_fab2_lib.baseboard_fab2(sch_1):page86_i12:dq(19)"
				( attribute "PN" "179"
					( Origin gPackager )
				)
				( objectStatus "J9L2.179" )
			)
			( pin "@baseboard_fab2_lib.baseboard_fab2(sch_1):page86_i12:dq(20)"
				( attribute "PN" "25"
					( Origin gPackager )
				)
				( objectStatus "J9L2.25" )
			)
			( pin "@baseboard_fab2_lib.baseboard_fab2(sch_1):page86_i12:dq(21)"
				( attribute "PN" "170"
					( Origin gPackager )
				)
				( objectStatus "J9L2.170" )
			)
			( pin "@baseboard_fab2_lib.baseboard_fab2(sch_1):page86_i12:dq(22)"
				( attribute "PN" "32"
					( Origin gPackager )
				)
				( objectStatus "J9L2.32" )
			)
			( pin "@baseboard_fab2_lib.baseboard_fab2(sch_1):page86_i12:dq(23)"
				( attribute "PN" "177"
					( Origin gPackager )
				)
				( objectStatus "J9L2.177" )
			)
			( pin "@baseboard_fab2_lib.baseboard_fab2(sch_1):page86_i12:dq(24)"
				( attribute "PN" "38"
					( Origin gPackager )
				)
				( objectStatus "J9L2.38" )
			)
			( pin "@baseboard_fab2_lib.baseboard_fab2(sch_1):page86_i12:dq(25)"
				( attribute "PN" "183"
					( Origin gPackager )
				)
				( objectStatus "J9L2.183" )
			)
			( pin "@baseboard_fab2_lib.baseboard_fab2(sch_1):page86_i12:dq(26)"
				( attribute "PN" "45"
					( Origin gPackager )
				)
				( objectStatus "J9L2.45" )
			)
			( pin "@baseboard_fab2_lib.baseboard_fab2(sch_1):page86_i12:dq(27)"
				( attribute "PN" "190"
					( Origin gPackager )
				)
				( objectStatus "J9L2.190" )
			)
			( pin "@baseboard_fab2_lib.baseboard_fab2(sch_1):page86_i12:dq(28)"
				( attribute "PN" "36"
					( Origin gPackager )
				)
				( objectStatus "J9L2.36" )
			)
			( pin "@baseboard_fab2_lib.baseboard_fab2(sch_1):page86_i12:dq(29)"
				( attribute "PN" "181"
					( Origin gPackager )
				)
				( objectStatus "J9L2.181" )
			)
			( pin "@baseboard_fab2_lib.baseboard_fab2(sch_1):page86_i12:dq(30)"
				( attribute "PN" "43"
					( Origin gPackager )
				)
				( objectStatus "J9L2.43" )
			)
			( pin "@baseboard_fab2_lib.baseboard_fab2(sch_1):page86_i12:dq(31)"
				( attribute "PN" "188"
					( Origin gPackager )
				)
				( objectStatus "J9L2.188" )
			)
			( pin "@baseboard_fab2_lib.baseboard_fab2(sch_1):page86_i12:dq(32)"
				( attribute "PN" "97"
					( Origin gPackager )
				)
				( objectStatus "J9L2.97" )
			)
			( pin "@baseboard_fab2_lib.baseboard_fab2(sch_1):page86_i12:dq(33)"
				( attribute "PN" "242"
					( Origin gPackager )
				)
				( objectStatus "J9L2.242" )
			)
			( pin "@baseboard_fab2_lib.baseboard_fab2(sch_1):page86_i12:dq(34)"
				( attribute "PN" "104"
					( Origin gPackager )
				)
				( objectStatus "J9L2.104" )
			)
			( pin "@baseboard_fab2_lib.baseboard_fab2(sch_1):page86_i12:dq(35)"
				( attribute "PN" "249"
					( Origin gPackager )
				)
				( objectStatus "J9L2.249" )
			)
			( pin "@baseboard_fab2_lib.baseboard_fab2(sch_1):page86_i12:dq(36)"
				( attribute "PN" "95"
					( Origin gPackager )
				)
				( objectStatus "J9L2.95" )
			)
			( pin "@baseboard_fab2_lib.baseboard_fab2(sch_1):page86_i12:dq(37)"
				( attribute "PN" "240"
					( Origin gPackager )
				)
				( objectStatus "J9L2.240" )
			)
			( pin "@baseboard_fab2_lib.baseboard_fab2(sch_1):page86_i12:dq(38)"
				( attribute "PN" "102"
					( Origin gPackager )
				)
				( objectStatus "J9L2.102" )
			)
			( pin "@baseboard_fab2_lib.baseboard_fab2(sch_1):page86_i12:dq(39)"
				( attribute "PN" "247"
					( Origin gPackager )
				)
				( objectStatus "J9L2.247" )
			)
			( pin "@baseboard_fab2_lib.baseboard_fab2(sch_1):page86_i12:dq(40)"
				( attribute "PN" "108"
					( Origin gPackager )
				)
				( objectStatus "J9L2.108" )
			)
			( pin "@baseboard_fab2_lib.baseboard_fab2(sch_1):page86_i12:dq(41)"
				( attribute "PN" "253"
					( Origin gPackager )
				)
				( objectStatus "J9L2.253" )
			)
			( pin "@baseboard_fab2_lib.baseboard_fab2(sch_1):page86_i12:dq(42)"
				( attribute "PN" "115"
					( Origin gPackager )
				)
				( objectStatus "J9L2.115" )
			)
			( pin "@baseboard_fab2_lib.baseboard_fab2(sch_1):page86_i12:dq(43)"
				( attribute "PN" "260"
					( Origin gPackager )
				)
				( objectStatus "J9L2.260" )
			)
			( pin "@baseboard_fab2_lib.baseboard_fab2(sch_1):page86_i12:dq(44)"
				( attribute "PN" "106"
					( Origin gPackager )
				)
				( objectStatus "J9L2.106" )
			)
			( pin "@baseboard_fab2_lib.baseboard_fab2(sch_1):page86_i12:dq(45)"
				( attribute "PN" "251"
					( Origin gPackager )
				)
				( objectStatus "J9L2.251" )
			)
			( pin "@baseboard_fab2_lib.baseboard_fab2(sch_1):page86_i12:dq(46)"
				( attribute "PN" "113"
					( Origin gPackager )
				)
				( objectStatus "J9L2.113" )
			)
			( pin "@baseboard_fab2_lib.baseboard_fab2(sch_1):page86_i12:dq(47)"
				( attribute "PN" "258"
					( Origin gPackager )
				)
				( objectStatus "J9L2.258" )
			)
			( pin "@baseboard_fab2_lib.baseboard_fab2(sch_1):page86_i12:dq(48)"
				( attribute "PN" "119"
					( Origin gPackager )
				)
				( objectStatus "J9L2.119" )
			)
			( pin "@baseboard_fab2_lib.baseboard_fab2(sch_1):page86_i12:dq(49)"
				( attribute "PN" "264"
					( Origin gPackager )
				)
				( objectStatus "J9L2.264" )
			)
			( pin "@baseboard_fab2_lib.baseboard_fab2(sch_1):page86_i12:dq(50)"
				( attribute "PN" "126"
					( Origin gPackager )
				)
				( objectStatus "J9L2.126" )
			)
			( pin "@baseboard_fab2_lib.baseboard_fab2(sch_1):page86_i12:dq(51)"
				( attribute "PN" "271"
					( Origin gPackager )
				)
				( objectStatus "J9L2.271" )
			)
			( pin "@baseboard_fab2_lib.baseboard_fab2(sch_1):page86_i12:dq(52)"
				( attribute "PN" "117"
					( Origin gPackager )
				)
				( objectStatus "J9L2.117" )
			)
			( pin "@baseboard_fab2_lib.baseboard_fab2(sch_1):page86_i12:dq(53)"
				( attribute "PN" "262"
					( Origin gPackager )
				)
				( objectStatus "J9L2.262" )
			)
			( pin "@baseboard_fab2_lib.baseboard_fab2(sch_1):page86_i12:dq(54)"
				( attribute "PN" "124"
					( Origin gPackager )
				)
				( objectStatus "J9L2.124" )
			)
			( pin "@baseboard_fab2_lib.baseboard_fab2(sch_1):page86_i12:dq(55)"
				( attribute "PN" "269"
					( Origin gPackager )
				)
				( objectStatus "J9L2.269" )
			)
			( pin "@baseboard_fab2_lib.baseboard_fab2(sch_1):page86_i12:dq(56)"
				( attribute "PN" "130"
					( Origin gPackager )
				)
				( objectStatus "J9L2.130" )
			)
			( pin "@baseboard_fab2_lib.baseboard_fab2(sch_1):page86_i12:dq(57)"
				( attribute "PN" "275"
					( Origin gPackager )
				)
				( objectStatus "J9L2.275" )
			)
			( pin "@baseboard_fab2_lib.baseboard_fab2(sch_1):page86_i12:dq(58)"
				( attribute "PN" "137"
					( Origin gPackager )
				)
				( objectStatus "J9L2.137" )
			)
			( pin "@baseboard_fab2_lib.baseboard_fab2(sch_1):page86_i12:dq(59)"
				( attribute "PN" "282"
					( Origin gPackager )
				)
				( objectStatus "J9L2.282" )
			)
			( pin "@baseboard_fab2_lib.baseboard_fab2(sch_1):page86_i12:dq(60)"
				( attribute "PN" "128"
					( Origin gPackager )
				)
				( objectStatus "J9L2.128" )
			)
			( pin "@baseboard_fab2_lib.baseboard_fab2(sch_1):page86_i12:dq(61)"
				( attribute "PN" "273"
					( Origin gPackager )
				)
				( objectStatus "J9L2.273" )
			)
			( pin "@baseboard_fab2_lib.baseboard_fab2(sch_1):page86_i12:dq(62)"
				( attribute "PN" "135"
					( Origin gPackager )
				)
				( objectStatus "J9L2.135" )
			)
			( pin "@baseboard_fab2_lib.baseboard_fab2(sch_1):page86_i12:dq(63)"
				( attribute "PN" "280"
					( Origin gPackager )
				)
				( objectStatus "J9L2.280" )
			)
			( pin "@baseboard_fab2_lib.baseboard_fab2(sch_1):page86_i12:event_n"
				( attribute "PN" "78"
					( Origin gPackager )
				)
				( objectStatus "J9L2.78" )
			)
			( pin "@baseboard_fab2_lib.baseboard_fab2(sch_1):page86_i12:odt(0)"
				( attribute "PN" "87"
					( Origin gPackager )
				)
				( objectStatus "J9L2.87" )
			)
			( pin "@baseboard_fab2_lib.baseboard_fab2(sch_1):page86_i12:odt(1)"
				( attribute "PN" "91"
					( Origin gPackager )
				)
				( objectStatus "J9L2.91" )
			)
			( pin "@baseboard_fab2_lib.baseboard_fab2(sch_1):page86_i12:par"
				( attribute "PN" "222"
					( Origin gPackager )
				)
				( objectStatus "J9L2.222" )
			)
			( pin "@baseboard_fab2_lib.baseboard_fab2(sch_1):page86_i12:reset_n"
				( attribute "PN" "58"
					( Origin gPackager )
				)
				( objectStatus "J9L2.58" )
			)
			( pin "@baseboard_fab2_lib.baseboard_fab2(sch_1):page86_i12:rfu(0)"
				( attribute "PN" "205"
					( Origin gPackager )
				)
				( objectStatus "J9L2.205" )
			)
			( pin "@baseboard_fab2_lib.baseboard_fab2(sch_1):page86_i12:rfu(1)"
				( attribute "PN" "227"
					( Origin gPackager )
				)
				( objectStatus "J9L2.227" )
			)
			( pin "@baseboard_fab2_lib.baseboard_fab2(sch_1):page86_i12:rfu(2)"
				( attribute "PN" "144"
					( Origin gPackager )
				)
				( objectStatus "J9L2.144" )
			)
			( pin "@baseboard_fab2_lib.baseboard_fab2(sch_1):page86_i12:s0_n"
				( attribute "PN" "84"
					( Origin gPackager )
				)
				( objectStatus "J9L2.84" )
			)
			( pin "@baseboard_fab2_lib.baseboard_fab2(sch_1):page86_i12:s1_n"
				( attribute "PN" "89"
					( Origin gPackager )
				)
				( objectStatus "J9L2.89" )
			)
			( pin "@baseboard_fab2_lib.baseboard_fab2(sch_1):page86_i12:s2_n_c(0)"
				( attribute "PN" "93"
					( Origin gPackager )
				)
				( objectStatus "J9L2.93" )
			)
			( pin "@baseboard_fab2_lib.baseboard_fab2(sch_1):page86_i12:s3_n_c(1)"
				( attribute "PN" "237"
					( Origin gPackager )
				)
				( objectStatus "J9L2.237" )
			)
			( pin "@baseboard_fab2_lib.baseboard_fab2(sch_1):page86_i12:sa(0)"
				( attribute "PN" "139"
					( Origin gPackager )
				)
				( objectStatus "J9L2.139" )
			)
			( pin "@baseboard_fab2_lib.baseboard_fab2(sch_1):page86_i12:sa(1)"
				( attribute "PN" "140"
					( Origin gPackager )
				)
				( objectStatus "J9L2.140" )
			)
			( pin "@baseboard_fab2_lib.baseboard_fab2(sch_1):page86_i12:sa(2)"
				( attribute "PN" "238"
					( Origin gPackager )
				)
				( objectStatus "J9L2.238" )
			)
			( pin "@baseboard_fab2_lib.baseboard_fab2(sch_1):page86_i12:save_n_nc"
				( attribute "PN" "230"
					( Origin gPackager )
				)
				( objectStatus "J9L2.230" )
			)
			( pin "@baseboard_fab2_lib.baseboard_fab2(sch_1):page86_i12:scl"
				( attribute "PN" "141"
					( Origin gPackager )
				)
				( objectStatus "J9L2.141" )
			)
			( pin "@baseboard_fab2_lib.baseboard_fab2(sch_1):page86_i12:sda"
				( attribute "PN" "285"
					( Origin gPackager )
				)
				( objectStatus "J9L2.285" )
			)
			( pin "@baseboard_fab2_lib.baseboard_fab2(sch_1):page86_i12:vddspd"
				( attribute "PN" "284"
					( Origin gPackager )
				)
				( objectStatus "J9L2.284" )
			)
			( pin "@baseboard_fab2_lib.baseboard_fab2(sch_1):page86_i12:vrefca"
				( attribute "PN" "146"
					( Origin gPackager )
				)
				( objectStatus "J9L2.146" )
			)
			( pin "@baseboard_fab2_lib.baseboard_fab2(sch_1):page86_i55:\12v\(0)"
				( attribute "PN" "145"
					( Origin gPackager )
				)
				( objectStatus "J9L2.145" )
			)
			( pin "@baseboard_fab2_lib.baseboard_fab2(sch_1):page86_i55:\12v\(1)"
				( attribute "PN" "1"
					( Origin gPackager )
				)
				( objectStatus "J9L2.1" )
			)
			( pin "@baseboard_fab2_lib.baseboard_fab2(sch_1):page86_i55:vdd(0)"
				( attribute "PN" "236"
					( Origin gPackager )
				)
				( objectStatus "J9L2.236" )
			)
			( pin "@baseboard_fab2_lib.baseboard_fab2(sch_1):page86_i55:vdd(1)"
				( attribute "PN" "233"
					( Origin gPackager )
				)
				( objectStatus "J9L2.233" )
			)
			( pin "@baseboard_fab2_lib.baseboard_fab2(sch_1):page86_i55:vdd(2)"
				( attribute "PN" "231"
					( Origin gPackager )
				)
				( objectStatus "J9L2.231" )
			)
			( pin "@baseboard_fab2_lib.baseboard_fab2(sch_1):page86_i55:vdd(3)"
				( attribute "PN" "229"
					( Origin gPackager )
				)
				( objectStatus "J9L2.229" )
			)
			( pin "@baseboard_fab2_lib.baseboard_fab2(sch_1):page86_i55:vdd(4)"
				( attribute "PN" "226"
					( Origin gPackager )
				)
				( objectStatus "J9L2.226" )
			)
			( pin "@baseboard_fab2_lib.baseboard_fab2(sch_1):page86_i55:vdd(5)"
				( attribute "PN" "223"
					( Origin gPackager )
				)
				( objectStatus "J9L2.223" )
			)
			( pin "@baseboard_fab2_lib.baseboard_fab2(sch_1):page86_i55:vdd(6)"
				( attribute "PN" "220"
					( Origin gPackager )
				)
				( objectStatus "J9L2.220" )
			)
			( pin "@baseboard_fab2_lib.baseboard_fab2(sch_1):page86_i55:vdd(7)"
				( attribute "PN" "217"
					( Origin gPackager )
				)
				( objectStatus "J9L2.217" )
			)
			( pin "@baseboard_fab2_lib.baseboard_fab2(sch_1):page86_i55:vdd(8)"
				( attribute "PN" "215"
					( Origin gPackager )
				)
				( objectStatus "J9L2.215" )
			)
			( pin "@baseboard_fab2_lib.baseboard_fab2(sch_1):page86_i55:vdd(9)"
				( attribute "PN" "212"
					( Origin gPackager )
				)
				( objectStatus "J9L2.212" )
			)
			( pin "@baseboard_fab2_lib.baseboard_fab2(sch_1):page86_i55:vdd(10)"
				( attribute "PN" "209"
					( Origin gPackager )
				)
				( objectStatus "J9L2.209" )
			)
			( pin "@baseboard_fab2_lib.baseboard_fab2(sch_1):page86_i55:vdd(11)"
				( attribute "PN" "206"
					( Origin gPackager )
				)
				( objectStatus "J9L2.206" )
			)
			( pin "@baseboard_fab2_lib.baseboard_fab2(sch_1):page86_i55:vdd(12)"
				( attribute "PN" "204"
					( Origin gPackager )
				)
				( objectStatus "J9L2.204" )
			)
			( pin "@baseboard_fab2_lib.baseboard_fab2(sch_1):page86_i55:vdd(13)"
				( attribute "PN" "92"
					( Origin gPackager )
				)
				( objectStatus "J9L2.92" )
			)
			( pin "@baseboard_fab2_lib.baseboard_fab2(sch_1):page86_i55:vdd(14)"
				( attribute "PN" "90"
					( Origin gPackager )
				)
				( objectStatus "J9L2.90" )
			)
			( pin "@baseboard_fab2_lib.baseboard_fab2(sch_1):page86_i55:vdd(15)"
				( attribute "PN" "88"
					( Origin gPackager )
				)
				( objectStatus "J9L2.88" )
			)
			( pin "@baseboard_fab2_lib.baseboard_fab2(sch_1):page86_i55:vdd(16)"
				( attribute "PN" "85"
					( Origin gPackager )
				)
				( objectStatus "J9L2.85" )
			)
			( pin "@baseboard_fab2_lib.baseboard_fab2(sch_1):page86_i55:vdd(17)"
				( attribute "PN" "83"
					( Origin gPackager )
				)
				( objectStatus "J9L2.83" )
			)
			( pin "@baseboard_fab2_lib.baseboard_fab2(sch_1):page86_i55:vdd(18)"
				( attribute "PN" "80"
					( Origin gPackager )
				)
				( objectStatus "J9L2.80" )
			)
			( pin "@baseboard_fab2_lib.baseboard_fab2(sch_1):page86_i55:vdd(19)"
				( attribute "PN" "76"
					( Origin gPackager )
				)
				( objectStatus "J9L2.76" )
			)
			( pin "@baseboard_fab2_lib.baseboard_fab2(sch_1):page86_i55:vdd(20)"
				( attribute "PN" "73"
					( Origin gPackager )
				)
				( objectStatus "J9L2.73" )
			)
			( pin "@baseboard_fab2_lib.baseboard_fab2(sch_1):page86_i55:vdd(21)"
				( attribute "PN" "70"
					( Origin gPackager )
				)
				( objectStatus "J9L2.70" )
			)
			( pin "@baseboard_fab2_lib.baseboard_fab2(sch_1):page86_i55:vdd(22)"
				( attribute "PN" "67"
					( Origin gPackager )
				)
				( objectStatus "J9L2.67" )
			)
			( pin "@baseboard_fab2_lib.baseboard_fab2(sch_1):page86_i55:vdd(23)"
				( attribute "PN" "64"
					( Origin gPackager )
				)
				( objectStatus "J9L2.64" )
			)
			( pin "@baseboard_fab2_lib.baseboard_fab2(sch_1):page86_i55:vdd(24)"
				( attribute "PN" "61"
					( Origin gPackager )
				)
				( objectStatus "J9L2.61" )
			)
			( pin "@baseboard_fab2_lib.baseboard_fab2(sch_1):page86_i55:vdd(25)"
				( attribute "PN" "59"
					( Origin gPackager )
				)
				( objectStatus "J9L2.59" )
			)
			( pin "@baseboard_fab2_lib.baseboard_fab2(sch_1):page86_i55:vpp(0)"
				( attribute "PN" "287"
					( Origin gPackager )
				)
				( objectStatus "J9L2.287" )
			)
			( pin "@baseboard_fab2_lib.baseboard_fab2(sch_1):page86_i55:vpp(1)"
				( attribute "PN" "286"
					( Origin gPackager )
				)
				( objectStatus "J9L2.286" )
			)
			( pin "@baseboard_fab2_lib.baseboard_fab2(sch_1):page86_i55:vpp(2)"
				( attribute "PN" "288"
					( Origin gPackager )
				)
				( objectStatus "J9L2.288" )
			)
			( pin "@baseboard_fab2_lib.baseboard_fab2(sch_1):page86_i55:vpp(3)"
				( attribute "PN" "143"
					( Origin gPackager )
				)
				( objectStatus "J9L2.143" )
			)
			( pin "@baseboard_fab2_lib.baseboard_fab2(sch_1):page86_i55:vpp(4)"
				( attribute "PN" "142"
					( Origin gPackager )
				)
				( objectStatus "J9L2.142" )
			)
			( pin "@baseboard_fab2_lib.baseboard_fab2(sch_1):page86_i55:vtt(0)"
				( attribute "PN" "221"
					( Origin gPackager )
				)
				( objectStatus "J9L2.221" )
			)
			( pin "@baseboard_fab2_lib.baseboard_fab2(sch_1):page86_i55:vtt(1)"
				( attribute "PN" "77"
					( Origin gPackager )
				)
				( objectStatus "J9L2.77" )
			)
			( pin "@baseboard_fab2_lib.baseboard_fab2(sch_1):page86_i100:dqs0n"
				( attribute "PN" "152"
					( Origin gPackager )
				)
				( objectStatus "J9L2.152" )
			)
			( pin "@baseboard_fab2_lib.baseboard_fab2(sch_1):page86_i100:dqs0p"
				( attribute "PN" "153"
					( Origin gPackager )
				)
				( objectStatus "J9L2.153" )
			)
			( pin "@baseboard_fab2_lib.baseboard_fab2(sch_1):page86_i100:dqs1n"
				( attribute "PN" "163"
					( Origin gPackager )
				)
				( objectStatus "J9L2.163" )
			)
			( pin "@baseboard_fab2_lib.baseboard_fab2(sch_1):page86_i100:dqs1p"
				( attribute "PN" "164"
					( Origin gPackager )
				)
				( objectStatus "J9L2.164" )
			)
			( pin "@baseboard_fab2_lib.baseboard_fab2(sch_1):page86_i100:dqs2n"
				( attribute "PN" "174"
					( Origin gPackager )
				)
				( objectStatus "J9L2.174" )
			)
			( pin "@baseboard_fab2_lib.baseboard_fab2(sch_1):page86_i100:dqs2p"
				( attribute "PN" "175"
					( Origin gPackager )
				)
				( objectStatus "J9L2.175" )
			)
			( pin "@baseboard_fab2_lib.baseboard_fab2(sch_1):page86_i100:dqs3n"
				( attribute "PN" "185"
					( Origin gPackager )
				)
				( objectStatus "J9L2.185" )
			)
			( pin "@baseboard_fab2_lib.baseboard_fab2(sch_1):page86_i100:dqs3p"
				( attribute "PN" "186"
					( Origin gPackager )
				)
				( objectStatus "J9L2.186" )
			)
			( pin "@baseboard_fab2_lib.baseboard_fab2(sch_1):page86_i100:dqs4n"
				( attribute "PN" "244"
					( Origin gPackager )
				)
				( objectStatus "J9L2.244" )
			)
			( pin "@baseboard_fab2_lib.baseboard_fab2(sch_1):page86_i100:dqs4p"
				( attribute "PN" "245"
					( Origin gPackager )
				)
				( objectStatus "J9L2.245" )
			)
			( pin "@baseboard_fab2_lib.baseboard_fab2(sch_1):page86_i100:dqs5n"
				( attribute "PN" "255"
					( Origin gPackager )
				)
				( objectStatus "J9L2.255" )
			)
			( pin "@baseboard_fab2_lib.baseboard_fab2(sch_1):page86_i100:dqs5p"
				( attribute "PN" "256"
					( Origin gPackager )
				)
				( objectStatus "J9L2.256" )
			)
			( pin "@baseboard_fab2_lib.baseboard_fab2(sch_1):page86_i100:dqs6n"
				( attribute "PN" "266"
					( Origin gPackager )
				)
				( objectStatus "J9L2.266" )
			)
			( pin "@baseboard_fab2_lib.baseboard_fab2(sch_1):page86_i100:dqs6p"
				( attribute "PN" "267"
					( Origin gPackager )
				)
				( objectStatus "J9L2.267" )
			)
			( pin "@baseboard_fab2_lib.baseboard_fab2(sch_1):page86_i100:dqs7n"
				( attribute "PN" "277"
					( Origin gPackager )
				)
				( objectStatus "J9L2.277" )
			)
			( pin "@baseboard_fab2_lib.baseboard_fab2(sch_1):page86_i100:dqs7p"
				( attribute "PN" "278"
					( Origin gPackager )
				)
				( objectStatus "J9L2.278" )
			)
			( pin "@baseboard_fab2_lib.baseboard_fab2(sch_1):page86_i100:dqs8n"
				( attribute "PN" "196"
					( Origin gPackager )
				)
				( objectStatus "J9L2.196" )
			)
			( pin "@baseboard_fab2_lib.baseboard_fab2(sch_1):page86_i100:dqs8p"
				( attribute "PN" "197"
					( Origin gPackager )
				)
				( objectStatus "J9L2.197" )
			)
			( pin "@baseboard_fab2_lib.baseboard_fab2(sch_1):page86_i100:dqs9n"
				( attribute "PN" "8"
					( Origin gPackager )
				)
				( objectStatus "J9L2.8" )
			)
			( pin "@baseboard_fab2_lib.baseboard_fab2(sch_1):page86_i100:dqs9p"
				( attribute "PN" "7"
					( Origin gPackager )
				)
				( objectStatus "J9L2.7" )
			)
			( pin "@baseboard_fab2_lib.baseboard_fab2(sch_1):page86_i100:dqs10n"
				( attribute "PN" "19"
					( Origin gPackager )
				)
				( objectStatus "J9L2.19" )
			)
			( pin "@baseboard_fab2_lib.baseboard_fab2(sch_1):page86_i100:dqs10p"
				( attribute "PN" "18"
					( Origin gPackager )
				)
				( objectStatus "J9L2.18" )
			)
			( pin "@baseboard_fab2_lib.baseboard_fab2(sch_1):page86_i100:dqs11n"
				( attribute "PN" "30"
					( Origin gPackager )
				)
				( objectStatus "J9L2.30" )
			)
			( pin "@baseboard_fab2_lib.baseboard_fab2(sch_1):page86_i100:dqs11p"
				( attribute "PN" "29"
					( Origin gPackager )
				)
				( objectStatus "J9L2.29" )
			)
			( pin "@baseboard_fab2_lib.baseboard_fab2(sch_1):page86_i100:dqs12n"
				( attribute "PN" "41"
					( Origin gPackager )
				)
				( objectStatus "J9L2.41" )
			)
			( pin "@baseboard_fab2_lib.baseboard_fab2(sch_1):page86_i100:dqs12p"
				( attribute "PN" "40"
					( Origin gPackager )
				)
				( objectStatus "J9L2.40" )
			)
			( pin "@baseboard_fab2_lib.baseboard_fab2(sch_1):page86_i100:dqs13n"
				( attribute "PN" "100"
					( Origin gPackager )
				)
				( objectStatus "J9L2.100" )
			)
			( pin "@baseboard_fab2_lib.baseboard_fab2(sch_1):page86_i100:dqs13p"
				( attribute "PN" "99"
					( Origin gPackager )
				)
				( objectStatus "J9L2.99" )
			)
			( pin "@baseboard_fab2_lib.baseboard_fab2(sch_1):page86_i100:dqs14n"
				( attribute "PN" "111"
					( Origin gPackager )
				)
				( objectStatus "J9L2.111" )
			)
			( pin "@baseboard_fab2_lib.baseboard_fab2(sch_1):page86_i100:dqs14p"
				( attribute "PN" "110"
					( Origin gPackager )
				)
				( objectStatus "J9L2.110" )
			)
			( pin "@baseboard_fab2_lib.baseboard_fab2(sch_1):page86_i100:dqs15n"
				( attribute "PN" "122"
					( Origin gPackager )
				)
				( objectStatus "J9L2.122" )
			)
			( pin "@baseboard_fab2_lib.baseboard_fab2(sch_1):page86_i100:dqs15p"
				( attribute "PN" "121"
					( Origin gPackager )
				)
				( objectStatus "J9L2.121" )
			)
			( pin "@baseboard_fab2_lib.baseboard_fab2(sch_1):page86_i100:dqs16n"
				( attribute "PN" "133"
					( Origin gPackager )
				)
				( objectStatus "J9L2.133" )
			)
			( pin "@baseboard_fab2_lib.baseboard_fab2(sch_1):page86_i100:dqs16p"
				( attribute "PN" "132"
					( Origin gPackager )
				)
				( objectStatus "J9L2.132" )
			)
			( pin "@baseboard_fab2_lib.baseboard_fab2(sch_1):page86_i100:dqs17n"
				( attribute "PN" "52"
					( Origin gPackager )
				)
				( objectStatus "J9L2.52" )
			)
			( pin "@baseboard_fab2_lib.baseboard_fab2(sch_1):page86_i100:dqs17p"
				( attribute "PN" "51"
					( Origin gPackager )
				)
				( objectStatus "J9L2.51" )
			)
			( pin "@baseboard_fab2_lib.baseboard_fab2(sch_1):page86_i138:vss(0)"
				( attribute "PN" "283"
					( Origin gPackager )
				)
				( objectStatus "J9L2.283" )
			)
			( pin "@baseboard_fab2_lib.baseboard_fab2(sch_1):page86_i138:vss(1)"
				( attribute "PN" "281"
					( Origin gPackager )
				)
				( objectStatus "J9L2.281" )
			)
			( pin "@baseboard_fab2_lib.baseboard_fab2(sch_1):page86_i138:vss(2)"
				( attribute "PN" "279"
					( Origin gPackager )
				)
				( objectStatus "J9L2.279" )
			)
			( pin "@baseboard_fab2_lib.baseboard_fab2(sch_1):page86_i138:vss(3)"
				( attribute "PN" "276"
					( Origin gPackager )
				)
				( objectStatus "J9L2.276" )
			)
			( pin "@baseboard_fab2_lib.baseboard_fab2(sch_1):page86_i138:vss(4)"
				( attribute "PN" "274"
					( Origin gPackager )
				)
				( objectStatus "J9L2.274" )
			)
			( pin "@baseboard_fab2_lib.baseboard_fab2(sch_1):page86_i138:vss(5)"
				( attribute "PN" "272"
					( Origin gPackager )
				)
				( objectStatus "J9L2.272" )
			)
			( pin "@baseboard_fab2_lib.baseboard_fab2(sch_1):page86_i138:vss(6)"
				( attribute "PN" "270"
					( Origin gPackager )
				)
				( objectStatus "J9L2.270" )
			)
			( pin "@baseboard_fab2_lib.baseboard_fab2(sch_1):page86_i138:vss(7)"
				( attribute "PN" "268"
					( Origin gPackager )
				)
				( objectStatus "J9L2.268" )
			)
			( pin "@baseboard_fab2_lib.baseboard_fab2(sch_1):page86_i138:vss(8)"
				( attribute "PN" "265"
					( Origin gPackager )
				)
				( objectStatus "J9L2.265" )
			)
			( pin "@baseboard_fab2_lib.baseboard_fab2(sch_1):page86_i138:vss(9)"
				( attribute "PN" "263"
					( Origin gPackager )
				)
				( objectStatus "J9L2.263" )
			)
			( pin "@baseboard_fab2_lib.baseboard_fab2(sch_1):page86_i138:vss(10)"
				( attribute "PN" "261"
					( Origin gPackager )
				)
				( objectStatus "J9L2.261" )
			)
			( pin "@baseboard_fab2_lib.baseboard_fab2(sch_1):page86_i138:vss(11)"
				( attribute "PN" "259"
					( Origin gPackager )
				)
				( objectStatus "J9L2.259" )
			)
			( pin "@baseboard_fab2_lib.baseboard_fab2(sch_1):page86_i138:vss(12)"
				( attribute "PN" "257"
					( Origin gPackager )
				)
				( objectStatus "J9L2.257" )
			)
			( pin "@baseboard_fab2_lib.baseboard_fab2(sch_1):page86_i138:vss(13)"
				( attribute "PN" "254"
					( Origin gPackager )
				)
				( objectStatus "J9L2.254" )
			)
			( pin "@baseboard_fab2_lib.baseboard_fab2(sch_1):page86_i138:vss(14)"
				( attribute "PN" "252"
					( Origin gPackager )
				)
				( objectStatus "J9L2.252" )
			)
			( pin "@baseboard_fab2_lib.baseboard_fab2(sch_1):page86_i138:vss(15)"
				( attribute "PN" "250"
					( Origin gPackager )
				)
				( objectStatus "J9L2.250" )
			)
			( pin "@baseboard_fab2_lib.baseboard_fab2(sch_1):page86_i138:vss(16)"
				( attribute "PN" "248"
					( Origin gPackager )
				)
				( objectStatus "J9L2.248" )
			)
			( pin "@baseboard_fab2_lib.baseboard_fab2(sch_1):page86_i138:vss(17)"
				( attribute "PN" "246"
					( Origin gPackager )
				)
				( objectStatus "J9L2.246" )
			)
			( pin "@baseboard_fab2_lib.baseboard_fab2(sch_1):page86_i138:vss(18)"
				( attribute "PN" "243"
					( Origin gPackager )
				)
				( objectStatus "J9L2.243" )
			)
			( pin "@baseboard_fab2_lib.baseboard_fab2(sch_1):page86_i138:vss(19)"
				( attribute "PN" "241"
					( Origin gPackager )
				)
				( objectStatus "J9L2.241" )
			)
			( pin "@baseboard_fab2_lib.baseboard_fab2(sch_1):page86_i138:vss(20)"
				( attribute "PN" "239"
					( Origin gPackager )
				)
				( objectStatus "J9L2.239" )
			)
			( pin "@baseboard_fab2_lib.baseboard_fab2(sch_1):page86_i138:vss(21)"
				( attribute "PN" "202"
					( Origin gPackager )
				)
				( objectStatus "J9L2.202" )
			)
			( pin "@baseboard_fab2_lib.baseboard_fab2(sch_1):page86_i138:vss(22)"
				( attribute "PN" "200"
					( Origin gPackager )
				)
				( objectStatus "J9L2.200" )
			)
			( pin "@baseboard_fab2_lib.baseboard_fab2(sch_1):page86_i138:vss(23)"
				( attribute "PN" "198"
					( Origin gPackager )
				)
				( objectStatus "J9L2.198" )
			)
			( pin "@baseboard_fab2_lib.baseboard_fab2(sch_1):page86_i138:vss(24)"
				( attribute "PN" "195"
					( Origin gPackager )
				)
				( objectStatus "J9L2.195" )
			)
			( pin "@baseboard_fab2_lib.baseboard_fab2(sch_1):page86_i138:vss(25)"
				( attribute "PN" "193"
					( Origin gPackager )
				)
				( objectStatus "J9L2.193" )
			)
			( pin "@baseboard_fab2_lib.baseboard_fab2(sch_1):page86_i138:vss(26)"
				( attribute "PN" "191"
					( Origin gPackager )
				)
				( objectStatus "J9L2.191" )
			)
			( pin "@baseboard_fab2_lib.baseboard_fab2(sch_1):page86_i138:vss(27)"
				( attribute "PN" "189"
					( Origin gPackager )
				)
				( objectStatus "J9L2.189" )
			)
			( pin "@baseboard_fab2_lib.baseboard_fab2(sch_1):page86_i138:vss(28)"
				( attribute "PN" "187"
					( Origin gPackager )
				)
				( objectStatus "J9L2.187" )
			)
			( pin "@baseboard_fab2_lib.baseboard_fab2(sch_1):page86_i138:vss(29)"
				( attribute "PN" "184"
					( Origin gPackager )
				)
				( objectStatus "J9L2.184" )
			)
			( pin "@baseboard_fab2_lib.baseboard_fab2(sch_1):page86_i138:vss(30)"
				( attribute "PN" "182"
					( Origin gPackager )
				)
				( objectStatus "J9L2.182" )
			)
			( pin "@baseboard_fab2_lib.baseboard_fab2(sch_1):page86_i138:vss(31)"
				( attribute "PN" "180"
					( Origin gPackager )
				)
				( objectStatus "J9L2.180" )
			)
			( pin "@baseboard_fab2_lib.baseboard_fab2(sch_1):page86_i138:vss(32)"
				( attribute "PN" "178"
					( Origin gPackager )
				)
				( objectStatus "J9L2.178" )
			)
			( pin "@baseboard_fab2_lib.baseboard_fab2(sch_1):page86_i138:vss(33)"
				( attribute "PN" "176"
					( Origin gPackager )
				)
				( objectStatus "J9L2.176" )
			)
			( pin "@baseboard_fab2_lib.baseboard_fab2(sch_1):page86_i138:vss(34)"
				( attribute "PN" "173"
					( Origin gPackager )
				)
				( objectStatus "J9L2.173" )
			)
			( pin "@baseboard_fab2_lib.baseboard_fab2(sch_1):page86_i138:vss(35)"
				( attribute "PN" "171"
					( Origin gPackager )
				)
				( objectStatus "J9L2.171" )
			)
			( pin "@baseboard_fab2_lib.baseboard_fab2(sch_1):page86_i138:vss(36)"
				( attribute "PN" "169"
					( Origin gPackager )
				)
				( objectStatus "J9L2.169" )
			)
			( pin "@baseboard_fab2_lib.baseboard_fab2(sch_1):page86_i138:vss(37)"
				( attribute "PN" "167"
					( Origin gPackager )
				)
				( objectStatus "J9L2.167" )
			)
			( pin "@baseboard_fab2_lib.baseboard_fab2(sch_1):page86_i138:vss(38)"
				( attribute "PN" "165"
					( Origin gPackager )
				)
				( objectStatus "J9L2.165" )
			)
			( pin "@baseboard_fab2_lib.baseboard_fab2(sch_1):page86_i138:vss(39)"
				( attribute "PN" "162"
					( Origin gPackager )
				)
				( objectStatus "J9L2.162" )
			)
			( pin "@baseboard_fab2_lib.baseboard_fab2(sch_1):page86_i138:vss(40)"
				( attribute "PN" "160"
					( Origin gPackager )
				)
				( objectStatus "J9L2.160" )
			)
			( pin "@baseboard_fab2_lib.baseboard_fab2(sch_1):page86_i138:vss(41)"
				( attribute "PN" "158"
					( Origin gPackager )
				)
				( objectStatus "J9L2.158" )
			)
			( pin "@baseboard_fab2_lib.baseboard_fab2(sch_1):page86_i138:vss(42)"
				( attribute "PN" "156"
					( Origin gPackager )
				)
				( objectStatus "J9L2.156" )
			)
			( pin "@baseboard_fab2_lib.baseboard_fab2(sch_1):page86_i138:vss(43)"
				( attribute "PN" "154"
					( Origin gPackager )
				)
				( objectStatus "J9L2.154" )
			)
			( pin "@baseboard_fab2_lib.baseboard_fab2(sch_1):page86_i138:vss(44)"
				( attribute "PN" "151"
					( Origin gPackager )
				)
				( objectStatus "J9L2.151" )
			)
			( pin "@baseboard_fab2_lib.baseboard_fab2(sch_1):page86_i138:vss(45)"
				( attribute "PN" "149"
					( Origin gPackager )
				)
				( objectStatus "J9L2.149" )
			)
			( pin "@baseboard_fab2_lib.baseboard_fab2(sch_1):page86_i138:vss(46)"
				( attribute "PN" "147"
					( Origin gPackager )
				)
				( objectStatus "J9L2.147" )
			)
			( pin "@baseboard_fab2_lib.baseboard_fab2(sch_1):page86_i138:vss(47)"
				( attribute "PN" "138"
					( Origin gPackager )
				)
				( objectStatus "J9L2.138" )
			)
			( pin "@baseboard_fab2_lib.baseboard_fab2(sch_1):page86_i138:vss(48)"
				( attribute "PN" "136"
					( Origin gPackager )
				)
				( objectStatus "J9L2.136" )
			)
			( pin "@baseboard_fab2_lib.baseboard_fab2(sch_1):page86_i138:vss(49)"
				( attribute "PN" "134"
					( Origin gPackager )
				)
				( objectStatus "J9L2.134" )
			)
			( pin "@baseboard_fab2_lib.baseboard_fab2(sch_1):page86_i138:vss(50)"
				( attribute "PN" "131"
					( Origin gPackager )
				)
				( objectStatus "J9L2.131" )
			)
			( pin "@baseboard_fab2_lib.baseboard_fab2(sch_1):page86_i138:vss(51)"
				( attribute "PN" "129"
					( Origin gPackager )
				)
				( objectStatus "J9L2.129" )
			)
			( pin "@baseboard_fab2_lib.baseboard_fab2(sch_1):page86_i138:vss(52)"
				( attribute "PN" "127"
					( Origin gPackager )
				)
				( objectStatus "J9L2.127" )
			)
			( pin "@baseboard_fab2_lib.baseboard_fab2(sch_1):page86_i138:vss(53)"
				( attribute "PN" "125"
					( Origin gPackager )
				)
				( objectStatus "J9L2.125" )
			)
			( pin "@baseboard_fab2_lib.baseboard_fab2(sch_1):page86_i138:vss(54)"
				( attribute "PN" "123"
					( Origin gPackager )
				)
				( objectStatus "J9L2.123" )
			)
			( pin "@baseboard_fab2_lib.baseboard_fab2(sch_1):page86_i138:vss(55)"
				( attribute "PN" "120"
					( Origin gPackager )
				)
				( objectStatus "J9L2.120" )
			)
			( pin "@baseboard_fab2_lib.baseboard_fab2(sch_1):page86_i138:vss(56)"
				( attribute "PN" "118"
					( Origin gPackager )
				)
				( objectStatus "J9L2.118" )
			)
			( pin "@baseboard_fab2_lib.baseboard_fab2(sch_1):page86_i138:vss(57)"
				( attribute "PN" "116"
					( Origin gPackager )
				)
				( objectStatus "J9L2.116" )
			)
			( pin "@baseboard_fab2_lib.baseboard_fab2(sch_1):page86_i138:vss(58)"
				( attribute "PN" "114"
					( Origin gPackager )
				)
				( objectStatus "J9L2.114" )
			)
			( pin "@baseboard_fab2_lib.baseboard_fab2(sch_1):page86_i138:vss(59)"
				( attribute "PN" "112"
					( Origin gPackager )
				)
				( objectStatus "J9L2.112" )
			)
			( pin "@baseboard_fab2_lib.baseboard_fab2(sch_1):page86_i138:vss(60)"
				( attribute "PN" "109"
					( Origin gPackager )
				)
				( objectStatus "J9L2.109" )
			)
			( pin "@baseboard_fab2_lib.baseboard_fab2(sch_1):page86_i138:vss(61)"
				( attribute "PN" "107"
					( Origin gPackager )
				)
				( objectStatus "J9L2.107" )
			)
			( pin "@baseboard_fab2_lib.baseboard_fab2(sch_1):page86_i138:vss(62)"
				( attribute "PN" "105"
					( Origin gPackager )
				)
				( objectStatus "J9L2.105" )
			)
			( pin "@baseboard_fab2_lib.baseboard_fab2(sch_1):page86_i138:vss(63)"
				( attribute "PN" "103"
					( Origin gPackager )
				)
				( objectStatus "J9L2.103" )
			)
			( pin "@baseboard_fab2_lib.baseboard_fab2(sch_1):page86_i138:vss(64)"
				( attribute "PN" "101"
					( Origin gPackager )
				)
				( objectStatus "J9L2.101" )
			)
			( pin "@baseboard_fab2_lib.baseboard_fab2(sch_1):page86_i138:vss(65)"
				( attribute "PN" "98"
					( Origin gPackager )
				)
				( objectStatus "J9L2.98" )
			)
			( pin "@baseboard_fab2_lib.baseboard_fab2(sch_1):page86_i138:vss(66)"
				( attribute "PN" "96"
					( Origin gPackager )
				)
				( objectStatus "J9L2.96" )
			)
			( pin "@baseboard_fab2_lib.baseboard_fab2(sch_1):page86_i138:vss(67)"
				( attribute "PN" "94"
					( Origin gPackager )
				)
				( objectStatus "J9L2.94" )
			)
			( pin "@baseboard_fab2_lib.baseboard_fab2(sch_1):page86_i138:vss(68)"
				( attribute "PN" "57"
					( Origin gPackager )
				)
				( objectStatus "J9L2.57" )
			)
			( pin "@baseboard_fab2_lib.baseboard_fab2(sch_1):page86_i138:vss(69)"
				( attribute "PN" "55"
					( Origin gPackager )
				)
				( objectStatus "J9L2.55" )
			)
			( pin "@baseboard_fab2_lib.baseboard_fab2(sch_1):page86_i138:vss(70)"
				( attribute "PN" "53"
					( Origin gPackager )
				)
				( objectStatus "J9L2.53" )
			)
			( pin "@baseboard_fab2_lib.baseboard_fab2(sch_1):page86_i138:vss(71)"
				( attribute "PN" "50"
					( Origin gPackager )
				)
				( objectStatus "J9L2.50" )
			)
			( pin "@baseboard_fab2_lib.baseboard_fab2(sch_1):page86_i138:vss(72)"
				( attribute "PN" "48"
					( Origin gPackager )
				)
				( objectStatus "J9L2.48" )
			)
			( pin "@baseboard_fab2_lib.baseboard_fab2(sch_1):page86_i138:vss(73)"
				( attribute "PN" "46"
					( Origin gPackager )
				)
				( objectStatus "J9L2.46" )
			)
			( pin "@baseboard_fab2_lib.baseboard_fab2(sch_1):page86_i138:vss(74)"
				( attribute "PN" "44"
					( Origin gPackager )
				)
				( objectStatus "J9L2.44" )
			)
			( pin "@baseboard_fab2_lib.baseboard_fab2(sch_1):page86_i138:vss(75)"
				( attribute "PN" "42"
					( Origin gPackager )
				)
				( objectStatus "J9L2.42" )
			)
			( pin "@baseboard_fab2_lib.baseboard_fab2(sch_1):page86_i138:vss(76)"
				( attribute "PN" "39"
					( Origin gPackager )
				)
				( objectStatus "J9L2.39" )
			)
			( pin "@baseboard_fab2_lib.baseboard_fab2(sch_1):page86_i138:vss(77)"
				( attribute "PN" "37"
					( Origin gPackager )
				)
				( objectStatus "J9L2.37" )
			)
			( pin "@baseboard_fab2_lib.baseboard_fab2(sch_1):page86_i138:vss(78)"
				( attribute "PN" "35"
					( Origin gPackager )
				)
				( objectStatus "J9L2.35" )
			)
			( pin "@baseboard_fab2_lib.baseboard_fab2(sch_1):page86_i138:vss(79)"
				( attribute "PN" "33"
					( Origin gPackager )
				)
				( objectStatus "J9L2.33" )
			)
			( pin "@baseboard_fab2_lib.baseboard_fab2(sch_1):page86_i138:vss(80)"
				( attribute "PN" "31"
					( Origin gPackager )
				)
				( objectStatus "J9L2.31" )
			)
			( pin "@baseboard_fab2_lib.baseboard_fab2(sch_1):page86_i138:vss(81)"
				( attribute "PN" "28"
					( Origin gPackager )
				)
				( objectStatus "J9L2.28" )
			)
			( pin "@baseboard_fab2_lib.baseboard_fab2(sch_1):page86_i138:vss(82)"
				( attribute "PN" "26"
					( Origin gPackager )
				)
				( objectStatus "J9L2.26" )
			)
			( pin "@baseboard_fab2_lib.baseboard_fab2(sch_1):page86_i138:vss(83)"
				( attribute "PN" "24"
					( Origin gPackager )
				)
				( objectStatus "J9L2.24" )
			)
			( pin "@baseboard_fab2_lib.baseboard_fab2(sch_1):page86_i138:vss(84)"
				( attribute "PN" "22"
					( Origin gPackager )
				)
				( objectStatus "J9L2.22" )
			)
			( pin "@baseboard_fab2_lib.baseboard_fab2(sch_1):page86_i138:vss(85)"
				( attribute "PN" "20"
					( Origin gPackager )
				)
				( objectStatus "J9L2.20" )
			)
			( pin "@baseboard_fab2_lib.baseboard_fab2(sch_1):page86_i138:vss(86)"
				( attribute "PN" "17"
					( Origin gPackager )
				)
				( objectStatus "J9L2.17" )
			)
			( pin "@baseboard_fab2_lib.baseboard_fab2(sch_1):page86_i138:vss(87)"
				( attribute "PN" "15"
					( Origin gPackager )
				)
				( objectStatus "J9L2.15" )
			)
			( pin "@baseboard_fab2_lib.baseboard_fab2(sch_1):page86_i138:vss(88)"
				( attribute "PN" "13"
					( Origin gPackager )
				)
				( objectStatus "J9L2.13" )
			)
			( pin "@baseboard_fab2_lib.baseboard_fab2(sch_1):page86_i138:vss(89)"
				( attribute "PN" "11"
					( Origin gPackager )
				)
				( objectStatus "J9L2.11" )
			)
			( pin "@baseboard_fab2_lib.baseboard_fab2(sch_1):page86_i138:vss(90)"
				( attribute "PN" "9"
					( Origin gPackager )
				)
				( objectStatus "J9L2.9" )
			)
			( pin "@baseboard_fab2_lib.baseboard_fab2(sch_1):page86_i138:vss(91)"
				( attribute "PN" "6"
					( Origin gPackager )
				)
				( objectStatus "J9L2.6" )
			)
			( pin "@baseboard_fab2_lib.baseboard_fab2(sch_1):page86_i138:vss(92)"
				( attribute "PN" "4"
					( Origin gPackager )
				)
				( objectStatus "J9L2.4" )
			)
			( pin "@baseboard_fab2_lib.baseboard_fab2(sch_1):page86_i138:vss(93)"
				( attribute "PN" "2"
					( Origin gPackager )
				)
				( objectStatus "J9L2.2" )
			)
			( pin "@baseboard_fab2_lib.baseboard_fab2(sch_1):page86_i182:a"
				( attribute "PN" "1"
					( Origin gPackager )
				)
				( objectStatus "C1A17.1" )
			)
			( pin "@baseboard_fab2_lib.baseboard_fab2(sch_1):page86_i182:b"
				( attribute "PN" "2"
					( Origin gPackager )
				)
				( objectStatus "C1A17.2" )
			)
			( pin "@baseboard_fab2_lib.baseboard_fab2(sch_1):page87_i169:\12v\(0)"
				( attribute "PN" "145"
					( Origin gPackager )
				)
				( objectStatus "J1A1.145" )
			)
			( pin "@baseboard_fab2_lib.baseboard_fab2(sch_1):page87_i169:\12v\(1)"
				( attribute "PN" "1"
					( Origin gPackager )
				)
				( objectStatus "J1A1.1" )
			)
			( pin "@baseboard_fab2_lib.baseboard_fab2(sch_1):page87_i169:vdd(0)"
				( attribute "PN" "236"
					( Origin gPackager )
				)
				( objectStatus "J1A1.236" )
			)
			( pin "@baseboard_fab2_lib.baseboard_fab2(sch_1):page87_i169:vdd(1)"
				( attribute "PN" "233"
					( Origin gPackager )
				)
				( objectStatus "J1A1.233" )
			)
			( pin "@baseboard_fab2_lib.baseboard_fab2(sch_1):page87_i169:vdd(2)"
				( attribute "PN" "231"
					( Origin gPackager )
				)
				( objectStatus "J1A1.231" )
			)
			( pin "@baseboard_fab2_lib.baseboard_fab2(sch_1):page87_i169:vdd(3)"
				( attribute "PN" "229"
					( Origin gPackager )
				)
				( objectStatus "J1A1.229" )
			)
			( pin "@baseboard_fab2_lib.baseboard_fab2(sch_1):page87_i169:vdd(4)"
				( attribute "PN" "226"
					( Origin gPackager )
				)
				( objectStatus "J1A1.226" )
			)
			( pin "@baseboard_fab2_lib.baseboard_fab2(sch_1):page87_i169:vdd(5)"
				( attribute "PN" "223"
					( Origin gPackager )
				)
				( objectStatus "J1A1.223" )
			)
			( pin "@baseboard_fab2_lib.baseboard_fab2(sch_1):page87_i169:vdd(6)"
				( attribute "PN" "220"
					( Origin gPackager )
				)
				( objectStatus "J1A1.220" )
			)
			( pin "@baseboard_fab2_lib.baseboard_fab2(sch_1):page87_i169:vdd(7)"
				( attribute "PN" "217"
					( Origin gPackager )
				)
				( objectStatus "J1A1.217" )
			)
			( pin "@baseboard_fab2_lib.baseboard_fab2(sch_1):page87_i169:vdd(8)"
				( attribute "PN" "215"
					( Origin gPackager )
				)
				( objectStatus "J1A1.215" )
			)
			( pin "@baseboard_fab2_lib.baseboard_fab2(sch_1):page87_i169:vdd(9)"
				( attribute "PN" "212"
					( Origin gPackager )
				)
				( objectStatus "J1A1.212" )
			)
			( pin "@baseboard_fab2_lib.baseboard_fab2(sch_1):page87_i169:vdd(10)"
				( attribute "PN" "209"
					( Origin gPackager )
				)
				( objectStatus "J1A1.209" )
			)
			( pin "@baseboard_fab2_lib.baseboard_fab2(sch_1):page87_i169:vdd(11)"
				( attribute "PN" "206"
					( Origin gPackager )
				)
				( objectStatus "J1A1.206" )
			)
			( pin "@baseboard_fab2_lib.baseboard_fab2(sch_1):page87_i169:vdd(12)"
				( attribute "PN" "204"
					( Origin gPackager )
				)
				( objectStatus "J1A1.204" )
			)
			( pin "@baseboard_fab2_lib.baseboard_fab2(sch_1):page87_i169:vdd(13)"
				( attribute "PN" "92"
					( Origin gPackager )
				)
				( objectStatus "J1A1.92" )
			)
			( pin "@baseboard_fab2_lib.baseboard_fab2(sch_1):page87_i169:vdd(14)"
				( attribute "PN" "90"
					( Origin gPackager )
				)
				( objectStatus "J1A1.90" )
			)
			( pin "@baseboard_fab2_lib.baseboard_fab2(sch_1):page87_i169:vdd(15)"
				( attribute "PN" "88"
					( Origin gPackager )
				)
				( objectStatus "J1A1.88" )
			)
			( pin "@baseboard_fab2_lib.baseboard_fab2(sch_1):page87_i169:vdd(16)"
				( attribute "PN" "85"
					( Origin gPackager )
				)
				( objectStatus "J1A1.85" )
			)
			( pin "@baseboard_fab2_lib.baseboard_fab2(sch_1):page87_i169:vdd(17)"
				( attribute "PN" "83"
					( Origin gPackager )
				)
				( objectStatus "J1A1.83" )
			)
			( pin "@baseboard_fab2_lib.baseboard_fab2(sch_1):page87_i169:vdd(18)"
				( attribute "PN" "80"
					( Origin gPackager )
				)
				( objectStatus "J1A1.80" )
			)
			( pin "@baseboard_fab2_lib.baseboard_fab2(sch_1):page87_i169:vdd(19)"
				( attribute "PN" "76"
					( Origin gPackager )
				)
				( objectStatus "J1A1.76" )
			)
			( pin "@baseboard_fab2_lib.baseboard_fab2(sch_1):page87_i169:vdd(20)"
				( attribute "PN" "73"
					( Origin gPackager )
				)
				( objectStatus "J1A1.73" )
			)
			( pin "@baseboard_fab2_lib.baseboard_fab2(sch_1):page87_i169:vdd(21)"
				( attribute "PN" "70"
					( Origin gPackager )
				)
				( objectStatus "J1A1.70" )
			)
			( pin "@baseboard_fab2_lib.baseboard_fab2(sch_1):page87_i169:vdd(22)"
				( attribute "PN" "67"
					( Origin gPackager )
				)
				( objectStatus "J1A1.67" )
			)
			( pin "@baseboard_fab2_lib.baseboard_fab2(sch_1):page87_i169:vdd(23)"
				( attribute "PN" "64"
					( Origin gPackager )
				)
				( objectStatus "J1A1.64" )
			)
			( pin "@baseboard_fab2_lib.baseboard_fab2(sch_1):page87_i169:vdd(24)"
				( attribute "PN" "61"
					( Origin gPackager )
				)
				( objectStatus "J1A1.61" )
			)
			( pin "@baseboard_fab2_lib.baseboard_fab2(sch_1):page87_i169:vdd(25)"
				( attribute "PN" "59"
					( Origin gPackager )
				)
				( objectStatus "J1A1.59" )
			)
			( pin "@baseboard_fab2_lib.baseboard_fab2(sch_1):page87_i169:vpp(0)"
				( attribute "PN" "287"
					( Origin gPackager )
				)
				( objectStatus "J1A1.287" )
			)
			( pin "@baseboard_fab2_lib.baseboard_fab2(sch_1):page87_i169:vpp(1)"
				( attribute "PN" "286"
					( Origin gPackager )
				)
				( objectStatus "J1A1.286" )
			)
			( pin "@baseboard_fab2_lib.baseboard_fab2(sch_1):page87_i169:vpp(2)"
				( attribute "PN" "288"
					( Origin gPackager )
				)
				( objectStatus "J1A1.288" )
			)
			( pin "@baseboard_fab2_lib.baseboard_fab2(sch_1):page87_i169:vpp(3)"
				( attribute "PN" "143"
					( Origin gPackager )
				)
				( objectStatus "J1A1.143" )
			)
			( pin "@baseboard_fab2_lib.baseboard_fab2(sch_1):page87_i169:vpp(4)"
				( attribute "PN" "142"
					( Origin gPackager )
				)
				( objectStatus "J1A1.142" )
			)
			( pin "@baseboard_fab2_lib.baseboard_fab2(sch_1):page87_i169:vtt(0)"
				( attribute "PN" "221"
					( Origin gPackager )
				)
				( objectStatus "J1A1.221" )
			)
			( pin "@baseboard_fab2_lib.baseboard_fab2(sch_1):page87_i169:vtt(1)"
				( attribute "PN" "77"
					( Origin gPackager )
				)
				( objectStatus "J1A1.77" )
			)
			( pin "@baseboard_fab2_lib.baseboard_fab2(sch_1):page87_i178:a"
				( attribute "PN" "1"
					( Origin gPackager )
				)
				( objectStatus "C1A5.1" )
			)
			( pin "@baseboard_fab2_lib.baseboard_fab2(sch_1):page87_i178:b"
				( attribute "PN" "2"
					( Origin gPackager )
				)
				( objectStatus "C1A5.2" )
			)
			( pin "@baseboard_fab2_lib.baseboard_fab2(sch_1):page87_i185:vss(0)"
				( attribute "PN" "283"
					( Origin gPackager )
				)
				( objectStatus "J1A1.283" )
			)
			( pin "@baseboard_fab2_lib.baseboard_fab2(sch_1):page87_i185:vss(1)"
				( attribute "PN" "281"
					( Origin gPackager )
				)
				( objectStatus "J1A1.281" )
			)
			( pin "@baseboard_fab2_lib.baseboard_fab2(sch_1):page87_i185:vss(2)"
				( attribute "PN" "279"
					( Origin gPackager )
				)
				( objectStatus "J1A1.279" )
			)
			( pin "@baseboard_fab2_lib.baseboard_fab2(sch_1):page87_i185:vss(3)"
				( attribute "PN" "276"
					( Origin gPackager )
				)
				( objectStatus "J1A1.276" )
			)
			( pin "@baseboard_fab2_lib.baseboard_fab2(sch_1):page87_i185:vss(4)"
				( attribute "PN" "274"
					( Origin gPackager )
				)
				( objectStatus "J1A1.274" )
			)
			( pin "@baseboard_fab2_lib.baseboard_fab2(sch_1):page87_i185:vss(5)"
				( attribute "PN" "272"
					( Origin gPackager )
				)
				( objectStatus "J1A1.272" )
			)
			( pin "@baseboard_fab2_lib.baseboard_fab2(sch_1):page87_i185:vss(6)"
				( attribute "PN" "270"
					( Origin gPackager )
				)
				( objectStatus "J1A1.270" )
			)
			( pin "@baseboard_fab2_lib.baseboard_fab2(sch_1):page87_i185:vss(7)"
				( attribute "PN" "268"
					( Origin gPackager )
				)
				( objectStatus "J1A1.268" )
			)
			( pin "@baseboard_fab2_lib.baseboard_fab2(sch_1):page87_i185:vss(8)"
				( attribute "PN" "265"
					( Origin gPackager )
				)
				( objectStatus "J1A1.265" )
			)
			( pin "@baseboard_fab2_lib.baseboard_fab2(sch_1):page87_i185:vss(9)"
				( attribute "PN" "263"
					( Origin gPackager )
				)
				( objectStatus "J1A1.263" )
			)
			( pin "@baseboard_fab2_lib.baseboard_fab2(sch_1):page87_i185:vss(10)"
				( attribute "PN" "261"
					( Origin gPackager )
				)
				( objectStatus "J1A1.261" )
			)
			( pin "@baseboard_fab2_lib.baseboard_fab2(sch_1):page87_i185:vss(11)"
				( attribute "PN" "259"
					( Origin gPackager )
				)
				( objectStatus "J1A1.259" )
			)
			( pin "@baseboard_fab2_lib.baseboard_fab2(sch_1):page87_i185:vss(12)"
				( attribute "PN" "257"
					( Origin gPackager )
				)
				( objectStatus "J1A1.257" )
			)
			( pin "@baseboard_fab2_lib.baseboard_fab2(sch_1):page87_i185:vss(13)"
				( attribute "PN" "254"
					( Origin gPackager )
				)
				( objectStatus "J1A1.254" )
			)
			( pin "@baseboard_fab2_lib.baseboard_fab2(sch_1):page87_i185:vss(14)"
				( attribute "PN" "252"
					( Origin gPackager )
				)
				( objectStatus "J1A1.252" )
			)
			( pin "@baseboard_fab2_lib.baseboard_fab2(sch_1):page87_i185:vss(15)"
				( attribute "PN" "250"
					( Origin gPackager )
				)
				( objectStatus "J1A1.250" )
			)
			( pin "@baseboard_fab2_lib.baseboard_fab2(sch_1):page87_i185:vss(16)"
				( attribute "PN" "248"
					( Origin gPackager )
				)
				( objectStatus "J1A1.248" )
			)
			( pin "@baseboard_fab2_lib.baseboard_fab2(sch_1):page87_i185:vss(17)"
				( attribute "PN" "246"
					( Origin gPackager )
				)
				( objectStatus "J1A1.246" )
			)
			( pin "@baseboard_fab2_lib.baseboard_fab2(sch_1):page87_i185:vss(18)"
				( attribute "PN" "243"
					( Origin gPackager )
				)
				( objectStatus "J1A1.243" )
			)
			( pin "@baseboard_fab2_lib.baseboard_fab2(sch_1):page87_i185:vss(19)"
				( attribute "PN" "241"
					( Origin gPackager )
				)
				( objectStatus "J1A1.241" )
			)
			( pin "@baseboard_fab2_lib.baseboard_fab2(sch_1):page87_i185:vss(20)"
				( attribute "PN" "239"
					( Origin gPackager )
				)
				( objectStatus "J1A1.239" )
			)
			( pin "@baseboard_fab2_lib.baseboard_fab2(sch_1):page87_i185:vss(21)"
				( attribute "PN" "202"
					( Origin gPackager )
				)
				( objectStatus "J1A1.202" )
			)
			( pin "@baseboard_fab2_lib.baseboard_fab2(sch_1):page87_i185:vss(22)"
				( attribute "PN" "200"
					( Origin gPackager )
				)
				( objectStatus "J1A1.200" )
			)
			( pin "@baseboard_fab2_lib.baseboard_fab2(sch_1):page87_i185:vss(23)"
				( attribute "PN" "198"
					( Origin gPackager )
				)
				( objectStatus "J1A1.198" )
			)
			( pin "@baseboard_fab2_lib.baseboard_fab2(sch_1):page87_i185:vss(24)"
				( attribute "PN" "195"
					( Origin gPackager )
				)
				( objectStatus "J1A1.195" )
			)
			( pin "@baseboard_fab2_lib.baseboard_fab2(sch_1):page87_i185:vss(25)"
				( attribute "PN" "193"
					( Origin gPackager )
				)
				( objectStatus "J1A1.193" )
			)
			( pin "@baseboard_fab2_lib.baseboard_fab2(sch_1):page87_i185:vss(26)"
				( attribute "PN" "191"
					( Origin gPackager )
				)
				( objectStatus "J1A1.191" )
			)
			( pin "@baseboard_fab2_lib.baseboard_fab2(sch_1):page87_i185:vss(27)"
				( attribute "PN" "189"
					( Origin gPackager )
				)
				( objectStatus "J1A1.189" )
			)
			( pin "@baseboard_fab2_lib.baseboard_fab2(sch_1):page87_i185:vss(28)"
				( attribute "PN" "187"
					( Origin gPackager )
				)
				( objectStatus "J1A1.187" )
			)
			( pin "@baseboard_fab2_lib.baseboard_fab2(sch_1):page87_i185:vss(29)"
				( attribute "PN" "184"
					( Origin gPackager )
				)
				( objectStatus "J1A1.184" )
			)
			( pin "@baseboard_fab2_lib.baseboard_fab2(sch_1):page87_i185:vss(30)"
				( attribute "PN" "182"
					( Origin gPackager )
				)
				( objectStatus "J1A1.182" )
			)
			( pin "@baseboard_fab2_lib.baseboard_fab2(sch_1):page87_i185:vss(31)"
				( attribute "PN" "180"
					( Origin gPackager )
				)
				( objectStatus "J1A1.180" )
			)
			( pin "@baseboard_fab2_lib.baseboard_fab2(sch_1):page87_i185:vss(32)"
				( attribute "PN" "178"
					( Origin gPackager )
				)
				( objectStatus "J1A1.178" )
			)
			( pin "@baseboard_fab2_lib.baseboard_fab2(sch_1):page87_i185:vss(33)"
				( attribute "PN" "176"
					( Origin gPackager )
				)
				( objectStatus "J1A1.176" )
			)
			( pin "@baseboard_fab2_lib.baseboard_fab2(sch_1):page87_i185:vss(34)"
				( attribute "PN" "173"
					( Origin gPackager )
				)
				( objectStatus "J1A1.173" )
			)
			( pin "@baseboard_fab2_lib.baseboard_fab2(sch_1):page87_i185:vss(35)"
				( attribute "PN" "171"
					( Origin gPackager )
				)
				( objectStatus "J1A1.171" )
			)
			( pin "@baseboard_fab2_lib.baseboard_fab2(sch_1):page87_i185:vss(36)"
				( attribute "PN" "169"
					( Origin gPackager )
				)
				( objectStatus "J1A1.169" )
			)
			( pin "@baseboard_fab2_lib.baseboard_fab2(sch_1):page87_i185:vss(37)"
				( attribute "PN" "167"
					( Origin gPackager )
				)
				( objectStatus "J1A1.167" )
			)
			( pin "@baseboard_fab2_lib.baseboard_fab2(sch_1):page87_i185:vss(38)"
				( attribute "PN" "165"
					( Origin gPackager )
				)
				( objectStatus "J1A1.165" )
			)
			( pin "@baseboard_fab2_lib.baseboard_fab2(sch_1):page87_i185:vss(39)"
				( attribute "PN" "162"
					( Origin gPackager )
				)
				( objectStatus "J1A1.162" )
			)
			( pin "@baseboard_fab2_lib.baseboard_fab2(sch_1):page87_i185:vss(40)"
				( attribute "PN" "160"
					( Origin gPackager )
				)
				( objectStatus "J1A1.160" )
			)
			( pin "@baseboard_fab2_lib.baseboard_fab2(sch_1):page87_i185:vss(41)"
				( attribute "PN" "158"
					( Origin gPackager )
				)
				( objectStatus "J1A1.158" )
			)
			( pin "@baseboard_fab2_lib.baseboard_fab2(sch_1):page87_i185:vss(42)"
				( attribute "PN" "156"
					( Origin gPackager )
				)
				( objectStatus "J1A1.156" )
			)
			( pin "@baseboard_fab2_lib.baseboard_fab2(sch_1):page87_i185:vss(43)"
				( attribute "PN" "154"
					( Origin gPackager )
				)
				( objectStatus "J1A1.154" )
			)
			( pin "@baseboard_fab2_lib.baseboard_fab2(sch_1):page87_i185:vss(44)"
				( attribute "PN" "151"
					( Origin gPackager )
				)
				( objectStatus "J1A1.151" )
			)
			( pin "@baseboard_fab2_lib.baseboard_fab2(sch_1):page87_i185:vss(45)"
				( attribute "PN" "149"
					( Origin gPackager )
				)
				( objectStatus "J1A1.149" )
			)
			( pin "@baseboard_fab2_lib.baseboard_fab2(sch_1):page87_i185:vss(46)"
				( attribute "PN" "147"
					( Origin gPackager )
				)
				( objectStatus "J1A1.147" )
			)
			( pin "@baseboard_fab2_lib.baseboard_fab2(sch_1):page87_i185:vss(47)"
				( attribute "PN" "138"
					( Origin gPackager )
				)
				( objectStatus "J1A1.138" )
			)
			( pin "@baseboard_fab2_lib.baseboard_fab2(sch_1):page87_i185:vss(48)"
				( attribute "PN" "136"
					( Origin gPackager )
				)
				( objectStatus "J1A1.136" )
			)
			( pin "@baseboard_fab2_lib.baseboard_fab2(sch_1):page87_i185:vss(49)"
				( attribute "PN" "134"
					( Origin gPackager )
				)
				( objectStatus "J1A1.134" )
			)
			( pin "@baseboard_fab2_lib.baseboard_fab2(sch_1):page87_i185:vss(50)"
				( attribute "PN" "131"
					( Origin gPackager )
				)
				( objectStatus "J1A1.131" )
			)
			( pin "@baseboard_fab2_lib.baseboard_fab2(sch_1):page87_i185:vss(51)"
				( attribute "PN" "129"
					( Origin gPackager )
				)
				( objectStatus "J1A1.129" )
			)
			( pin "@baseboard_fab2_lib.baseboard_fab2(sch_1):page87_i185:vss(52)"
				( attribute "PN" "127"
					( Origin gPackager )
				)
				( objectStatus "J1A1.127" )
			)
			( pin "@baseboard_fab2_lib.baseboard_fab2(sch_1):page87_i185:vss(53)"
				( attribute "PN" "125"
					( Origin gPackager )
				)
				( objectStatus "J1A1.125" )
			)
			( pin "@baseboard_fab2_lib.baseboard_fab2(sch_1):page87_i185:vss(54)"
				( attribute "PN" "123"
					( Origin gPackager )
				)
				( objectStatus "J1A1.123" )
			)
			( pin "@baseboard_fab2_lib.baseboard_fab2(sch_1):page87_i185:vss(55)"
				( attribute "PN" "120"
					( Origin gPackager )
				)
				( objectStatus "J1A1.120" )
			)
			( pin "@baseboard_fab2_lib.baseboard_fab2(sch_1):page87_i185:vss(56)"
				( attribute "PN" "118"
					( Origin gPackager )
				)
				( objectStatus "J1A1.118" )
			)
			( pin "@baseboard_fab2_lib.baseboard_fab2(sch_1):page87_i185:vss(57)"
				( attribute "PN" "116"
					( Origin gPackager )
				)
				( objectStatus "J1A1.116" )
			)
			( pin "@baseboard_fab2_lib.baseboard_fab2(sch_1):page87_i185:vss(58)"
				( attribute "PN" "114"
					( Origin gPackager )
				)
				( objectStatus "J1A1.114" )
			)
			( pin "@baseboard_fab2_lib.baseboard_fab2(sch_1):page87_i185:vss(59)"
				( attribute "PN" "112"
					( Origin gPackager )
				)
				( objectStatus "J1A1.112" )
			)
			( pin "@baseboard_fab2_lib.baseboard_fab2(sch_1):page87_i185:vss(60)"
				( attribute "PN" "109"
					( Origin gPackager )
				)
				( objectStatus "J1A1.109" )
			)
			( pin "@baseboard_fab2_lib.baseboard_fab2(sch_1):page87_i185:vss(61)"
				( attribute "PN" "107"
					( Origin gPackager )
				)
				( objectStatus "J1A1.107" )
			)
			( pin "@baseboard_fab2_lib.baseboard_fab2(sch_1):page87_i185:vss(62)"
				( attribute "PN" "105"
					( Origin gPackager )
				)
				( objectStatus "J1A1.105" )
			)
			( pin "@baseboard_fab2_lib.baseboard_fab2(sch_1):page87_i185:vss(63)"
				( attribute "PN" "103"
					( Origin gPackager )
				)
				( objectStatus "J1A1.103" )
			)
			( pin "@baseboard_fab2_lib.baseboard_fab2(sch_1):page87_i185:vss(64)"
				( attribute "PN" "101"
					( Origin gPackager )
				)
				( objectStatus "J1A1.101" )
			)
			( pin "@baseboard_fab2_lib.baseboard_fab2(sch_1):page87_i185:vss(65)"
				( attribute "PN" "98"
					( Origin gPackager )
				)
				( objectStatus "J1A1.98" )
			)
			( pin "@baseboard_fab2_lib.baseboard_fab2(sch_1):page87_i185:vss(66)"
				( attribute "PN" "96"
					( Origin gPackager )
				)
				( objectStatus "J1A1.96" )
			)
			( pin "@baseboard_fab2_lib.baseboard_fab2(sch_1):page87_i185:vss(67)"
				( attribute "PN" "94"
					( Origin gPackager )
				)
				( objectStatus "J1A1.94" )
			)
			( pin "@baseboard_fab2_lib.baseboard_fab2(sch_1):page87_i185:vss(68)"
				( attribute "PN" "57"
					( Origin gPackager )
				)
				( objectStatus "J1A1.57" )
			)
			( pin "@baseboard_fab2_lib.baseboard_fab2(sch_1):page87_i185:vss(69)"
				( attribute "PN" "55"
					( Origin gPackager )
				)
				( objectStatus "J1A1.55" )
			)
			( pin "@baseboard_fab2_lib.baseboard_fab2(sch_1):page87_i185:vss(70)"
				( attribute "PN" "53"
					( Origin gPackager )
				)
				( objectStatus "J1A1.53" )
			)
			( pin "@baseboard_fab2_lib.baseboard_fab2(sch_1):page87_i185:vss(71)"
				( attribute "PN" "50"
					( Origin gPackager )
				)
				( objectStatus "J1A1.50" )
			)
			( pin "@baseboard_fab2_lib.baseboard_fab2(sch_1):page87_i185:vss(72)"
				( attribute "PN" "48"
					( Origin gPackager )
				)
				( objectStatus "J1A1.48" )
			)
			( pin "@baseboard_fab2_lib.baseboard_fab2(sch_1):page87_i185:vss(73)"
				( attribute "PN" "46"
					( Origin gPackager )
				)
				( objectStatus "J1A1.46" )
			)
			( pin "@baseboard_fab2_lib.baseboard_fab2(sch_1):page87_i185:vss(74)"
				( attribute "PN" "44"
					( Origin gPackager )
				)
				( objectStatus "J1A1.44" )
			)
			( pin "@baseboard_fab2_lib.baseboard_fab2(sch_1):page87_i185:vss(75)"
				( attribute "PN" "42"
					( Origin gPackager )
				)
				( objectStatus "J1A1.42" )
			)
			( pin "@baseboard_fab2_lib.baseboard_fab2(sch_1):page87_i185:vss(76)"
				( attribute "PN" "39"
					( Origin gPackager )
				)
				( objectStatus "J1A1.39" )
			)
			( pin "@baseboard_fab2_lib.baseboard_fab2(sch_1):page87_i185:vss(77)"
				( attribute "PN" "37"
					( Origin gPackager )
				)
				( objectStatus "J1A1.37" )
			)
			( pin "@baseboard_fab2_lib.baseboard_fab2(sch_1):page87_i185:vss(78)"
				( attribute "PN" "35"
					( Origin gPackager )
				)
				( objectStatus "J1A1.35" )
			)
			( pin "@baseboard_fab2_lib.baseboard_fab2(sch_1):page87_i185:vss(79)"
				( attribute "PN" "33"
					( Origin gPackager )
				)
				( objectStatus "J1A1.33" )
			)
			( pin "@baseboard_fab2_lib.baseboard_fab2(sch_1):page87_i185:vss(80)"
				( attribute "PN" "31"
					( Origin gPackager )
				)
				( objectStatus "J1A1.31" )
			)
			( pin "@baseboard_fab2_lib.baseboard_fab2(sch_1):page87_i185:vss(81)"
				( attribute "PN" "28"
					( Origin gPackager )
				)
				( objectStatus "J1A1.28" )
			)
			( pin "@baseboard_fab2_lib.baseboard_fab2(sch_1):page87_i185:vss(82)"
				( attribute "PN" "26"
					( Origin gPackager )
				)
				( objectStatus "J1A1.26" )
			)
			( pin "@baseboard_fab2_lib.baseboard_fab2(sch_1):page87_i185:vss(83)"
				( attribute "PN" "24"
					( Origin gPackager )
				)
				( objectStatus "J1A1.24" )
			)
			( pin "@baseboard_fab2_lib.baseboard_fab2(sch_1):page87_i185:vss(84)"
				( attribute "PN" "22"
					( Origin gPackager )
				)
				( objectStatus "J1A1.22" )
			)
			( pin "@baseboard_fab2_lib.baseboard_fab2(sch_1):page87_i185:vss(85)"
				( attribute "PN" "20"
					( Origin gPackager )
				)
				( objectStatus "J1A1.20" )
			)
			( pin "@baseboard_fab2_lib.baseboard_fab2(sch_1):page87_i185:vss(86)"
				( attribute "PN" "17"
					( Origin gPackager )
				)
				( objectStatus "J1A1.17" )
			)
			( pin "@baseboard_fab2_lib.baseboard_fab2(sch_1):page87_i185:vss(87)"
				( attribute "PN" "15"
					( Origin gPackager )
				)
				( objectStatus "J1A1.15" )
			)
			( pin "@baseboard_fab2_lib.baseboard_fab2(sch_1):page87_i185:vss(88)"
				( attribute "PN" "13"
					( Origin gPackager )
				)
				( objectStatus "J1A1.13" )
			)
			( pin "@baseboard_fab2_lib.baseboard_fab2(sch_1):page87_i185:vss(89)"
				( attribute "PN" "11"
					( Origin gPackager )
				)
				( objectStatus "J1A1.11" )
			)
			( pin "@baseboard_fab2_lib.baseboard_fab2(sch_1):page87_i185:vss(90)"
				( attribute "PN" "9"
					( Origin gPackager )
				)
				( objectStatus "J1A1.9" )
			)
			( pin "@baseboard_fab2_lib.baseboard_fab2(sch_1):page87_i185:vss(91)"
				( attribute "PN" "6"
					( Origin gPackager )
				)
				( objectStatus "J1A1.6" )
			)
			( pin "@baseboard_fab2_lib.baseboard_fab2(sch_1):page87_i185:vss(92)"
				( attribute "PN" "4"
					( Origin gPackager )
				)
				( objectStatus "J1A1.4" )
			)
			( pin "@baseboard_fab2_lib.baseboard_fab2(sch_1):page87_i185:vss(93)"
				( attribute "PN" "2"
					( Origin gPackager )
				)
				( objectStatus "J1A1.2" )
			)
			( pin "@baseboard_fab2_lib.baseboard_fab2(sch_1):page87_i186:a0"
				( attribute "PN" "79"
					( Origin gPackager )
				)
				( objectStatus "J1A1.79" )
			)
			( pin "@baseboard_fab2_lib.baseboard_fab2(sch_1):page87_i186:a1"
				( attribute "PN" "72"
					( Origin gPackager )
				)
				( objectStatus "J1A1.72" )
			)
			( pin "@baseboard_fab2_lib.baseboard_fab2(sch_1):page87_i186:a2"
				( attribute "PN" "216"
					( Origin gPackager )
				)
				( objectStatus "J1A1.216" )
			)
			( pin "@baseboard_fab2_lib.baseboard_fab2(sch_1):page87_i186:a3"
				( attribute "PN" "71"
					( Origin gPackager )
				)
				( objectStatus "J1A1.71" )
			)
			( pin "@baseboard_fab2_lib.baseboard_fab2(sch_1):page87_i186:a4"
				( attribute "PN" "214"
					( Origin gPackager )
				)
				( objectStatus "J1A1.214" )
			)
			( pin "@baseboard_fab2_lib.baseboard_fab2(sch_1):page87_i186:a5"
				( attribute "PN" "213"
					( Origin gPackager )
				)
				( objectStatus "J1A1.213" )
			)
			( pin "@baseboard_fab2_lib.baseboard_fab2(sch_1):page87_i186:a6"
				( attribute "PN" "69"
					( Origin gPackager )
				)
				( objectStatus "J1A1.69" )
			)
			( pin "@baseboard_fab2_lib.baseboard_fab2(sch_1):page87_i186:a7"
				( attribute "PN" "211"
					( Origin gPackager )
				)
				( objectStatus "J1A1.211" )
			)
			( pin "@baseboard_fab2_lib.baseboard_fab2(sch_1):page87_i186:a8"
				( attribute "PN" "68"
					( Origin gPackager )
				)
				( objectStatus "J1A1.68" )
			)
			( pin "@baseboard_fab2_lib.baseboard_fab2(sch_1):page87_i186:a9"
				( attribute "PN" "66"
					( Origin gPackager )
				)
				( objectStatus "J1A1.66" )
			)
			( pin "@baseboard_fab2_lib.baseboard_fab2(sch_1):page87_i186:a10"
				( attribute "PN" "225"
					( Origin gPackager )
				)
				( objectStatus "J1A1.225" )
			)
			( pin "@baseboard_fab2_lib.baseboard_fab2(sch_1):page87_i186:a11"
				( attribute "PN" "210"
					( Origin gPackager )
				)
				( objectStatus "J1A1.210" )
			)
			( pin "@baseboard_fab2_lib.baseboard_fab2(sch_1):page87_i186:a12"
				( attribute "PN" "65"
					( Origin gPackager )
				)
				( objectStatus "J1A1.65" )
			)
			( pin "@baseboard_fab2_lib.baseboard_fab2(sch_1):page87_i186:a13"
				( attribute "PN" "232"
					( Origin gPackager )
				)
				( objectStatus "J1A1.232" )
			)
			( pin "@baseboard_fab2_lib.baseboard_fab2(sch_1):page87_i186:a14_we_n"
				( attribute "PN" "228"
					( Origin gPackager )
				)
				( objectStatus "J1A1.228" )
			)
			( pin "@baseboard_fab2_lib.baseboard_fab2(sch_1):page87_i186:a15_cas_n"
				( attribute "PN" "86"
					( Origin gPackager )
				)
				( objectStatus "J1A1.86" )
			)
			( pin "@baseboard_fab2_lib.baseboard_fab2(sch_1):page87_i186:a16_ras_n"
				( attribute "PN" "82"
					( Origin gPackager )
				)
				( objectStatus "J1A1.82" )
			)
			( pin "@baseboard_fab2_lib.baseboard_fab2(sch_1):page87_i186:a17"
				( attribute "PN" "234"
					( Origin gPackager )
				)
				( objectStatus "J1A1.234" )
			)
			( pin "@baseboard_fab2_lib.baseboard_fab2(sch_1):page87_i186:act_n"
				( attribute "PN" "62"
					( Origin gPackager )
				)
				( objectStatus "J1A1.62" )
			)
			( pin "@baseboard_fab2_lib.baseboard_fab2(sch_1):page87_i186:alert_n"
				( attribute "PN" "208"
					( Origin gPackager )
				)
				( objectStatus "J1A1.208" )
			)
			( pin "@baseboard_fab2_lib.baseboard_fab2(sch_1):page87_i186:ba(0)"
				( attribute "PN" "81"
					( Origin gPackager )
				)
				( objectStatus "J1A1.81" )
			)
			( pin "@baseboard_fab2_lib.baseboard_fab2(sch_1):page87_i186:ba(1)"
				( attribute "PN" "224"
					( Origin gPackager )
				)
				( objectStatus "J1A1.224" )
			)
			( pin "@baseboard_fab2_lib.baseboard_fab2(sch_1):page87_i186:bg(0)"
				( attribute "PN" "63"
					( Origin gPackager )
				)
				( objectStatus "J1A1.63" )
			)
			( pin "@baseboard_fab2_lib.baseboard_fab2(sch_1):page87_i186:bg(1)"
				( attribute "PN" "207"
					( Origin gPackager )
				)
				( objectStatus "J1A1.207" )
			)
			( pin "@baseboard_fab2_lib.baseboard_fab2(sch_1):page87_i186:c(2)"
				( attribute "PN" "235"
					( Origin gPackager )
				)
				( objectStatus "J1A1.235" )
			)
			( pin "@baseboard_fab2_lib.baseboard_fab2(sch_1):page87_i186:cb(0)"
				( attribute "PN" "49"
					( Origin gPackager )
				)
				( objectStatus "J1A1.49" )
			)
			( pin "@baseboard_fab2_lib.baseboard_fab2(sch_1):page87_i186:cb(1)"
				( attribute "PN" "194"
					( Origin gPackager )
				)
				( objectStatus "J1A1.194" )
			)
			( pin "@baseboard_fab2_lib.baseboard_fab2(sch_1):page87_i186:cb(2)"
				( attribute "PN" "56"
					( Origin gPackager )
				)
				( objectStatus "J1A1.56" )
			)
			( pin "@baseboard_fab2_lib.baseboard_fab2(sch_1):page87_i186:cb(3)"
				( attribute "PN" "201"
					( Origin gPackager )
				)
				( objectStatus "J1A1.201" )
			)
			( pin "@baseboard_fab2_lib.baseboard_fab2(sch_1):page87_i186:cb(4)"
				( attribute "PN" "47"
					( Origin gPackager )
				)
				( objectStatus "J1A1.47" )
			)
			( pin "@baseboard_fab2_lib.baseboard_fab2(sch_1):page87_i186:cb(5)"
				( attribute "PN" "192"
					( Origin gPackager )
				)
				( objectStatus "J1A1.192" )
			)
			( pin "@baseboard_fab2_lib.baseboard_fab2(sch_1):page87_i186:cb(6)"
				( attribute "PN" "54"
					( Origin gPackager )
				)
				( objectStatus "J1A1.54" )
			)
			( pin "@baseboard_fab2_lib.baseboard_fab2(sch_1):page87_i186:cb(7)"
				( attribute "PN" "199"
					( Origin gPackager )
				)
				( objectStatus "J1A1.199" )
			)
			( pin "@baseboard_fab2_lib.baseboard_fab2(sch_1):page87_i186:ck0n"
				( attribute "PN" "75"
					( Origin gPackager )
				)
				( objectStatus "J1A1.75" )
			)
			( pin "@baseboard_fab2_lib.baseboard_fab2(sch_1):page87_i186:ck0p"
				( attribute "PN" "74"
					( Origin gPackager )
				)
				( objectStatus "J1A1.74" )
			)
			( pin "@baseboard_fab2_lib.baseboard_fab2(sch_1):page87_i186:ck1n"
				( attribute "PN" "219"
					( Origin gPackager )
				)
				( objectStatus "J1A1.219" )
			)
			( pin "@baseboard_fab2_lib.baseboard_fab2(sch_1):page87_i186:ck1p"
				( attribute "PN" "218"
					( Origin gPackager )
				)
				( objectStatus "J1A1.218" )
			)
			( pin "@baseboard_fab2_lib.baseboard_fab2(sch_1):page87_i186:cke(0)"
				( attribute "PN" "60"
					( Origin gPackager )
				)
				( objectStatus "J1A1.60" )
			)
			( pin "@baseboard_fab2_lib.baseboard_fab2(sch_1):page87_i186:cke(1)"
				( attribute "PN" "203"
					( Origin gPackager )
				)
				( objectStatus "J1A1.203" )
			)
			( pin "@baseboard_fab2_lib.baseboard_fab2(sch_1):page87_i186:dq(0)"
				( attribute "PN" "5"
					( Origin gPackager )
				)
				( objectStatus "J1A1.5" )
			)
			( pin "@baseboard_fab2_lib.baseboard_fab2(sch_1):page87_i186:dq(1)"
				( attribute "PN" "150"
					( Origin gPackager )
				)
				( objectStatus "J1A1.150" )
			)
			( pin "@baseboard_fab2_lib.baseboard_fab2(sch_1):page87_i186:dq(2)"
				( attribute "PN" "12"
					( Origin gPackager )
				)
				( objectStatus "J1A1.12" )
			)
			( pin "@baseboard_fab2_lib.baseboard_fab2(sch_1):page87_i186:dq(3)"
				( attribute "PN" "157"
					( Origin gPackager )
				)
				( objectStatus "J1A1.157" )
			)
			( pin "@baseboard_fab2_lib.baseboard_fab2(sch_1):page87_i186:dq(4)"
				( attribute "PN" "3"
					( Origin gPackager )
				)
				( objectStatus "J1A1.3" )
			)
			( pin "@baseboard_fab2_lib.baseboard_fab2(sch_1):page87_i186:dq(5)"
				( attribute "PN" "148"
					( Origin gPackager )
				)
				( objectStatus "J1A1.148" )
			)
			( pin "@baseboard_fab2_lib.baseboard_fab2(sch_1):page87_i186:dq(6)"
				( attribute "PN" "10"
					( Origin gPackager )
				)
				( objectStatus "J1A1.10" )
			)
			( pin "@baseboard_fab2_lib.baseboard_fab2(sch_1):page87_i186:dq(7)"
				( attribute "PN" "155"
					( Origin gPackager )
				)
				( objectStatus "J1A1.155" )
			)
			( pin "@baseboard_fab2_lib.baseboard_fab2(sch_1):page87_i186:dq(8)"
				( attribute "PN" "16"
					( Origin gPackager )
				)
				( objectStatus "J1A1.16" )
			)
			( pin "@baseboard_fab2_lib.baseboard_fab2(sch_1):page87_i186:dq(9)"
				( attribute "PN" "161"
					( Origin gPackager )
				)
				( objectStatus "J1A1.161" )
			)
			( pin "@baseboard_fab2_lib.baseboard_fab2(sch_1):page87_i186:dq(10)"
				( attribute "PN" "23"
					( Origin gPackager )
				)
				( objectStatus "J1A1.23" )
			)
			( pin "@baseboard_fab2_lib.baseboard_fab2(sch_1):page87_i186:dq(11)"
				( attribute "PN" "168"
					( Origin gPackager )
				)
				( objectStatus "J1A1.168" )
			)
			( pin "@baseboard_fab2_lib.baseboard_fab2(sch_1):page87_i186:dq(12)"
				( attribute "PN" "14"
					( Origin gPackager )
				)
				( objectStatus "J1A1.14" )
			)
			( pin "@baseboard_fab2_lib.baseboard_fab2(sch_1):page87_i186:dq(13)"
				( attribute "PN" "159"
					( Origin gPackager )
				)
				( objectStatus "J1A1.159" )
			)
			( pin "@baseboard_fab2_lib.baseboard_fab2(sch_1):page87_i186:dq(14)"
				( attribute "PN" "21"
					( Origin gPackager )
				)
				( objectStatus "J1A1.21" )
			)
			( pin "@baseboard_fab2_lib.baseboard_fab2(sch_1):page87_i186:dq(15)"
				( attribute "PN" "166"
					( Origin gPackager )
				)
				( objectStatus "J1A1.166" )
			)
			( pin "@baseboard_fab2_lib.baseboard_fab2(sch_1):page87_i186:dq(16)"
				( attribute "PN" "27"
					( Origin gPackager )
				)
				( objectStatus "J1A1.27" )
			)
			( pin "@baseboard_fab2_lib.baseboard_fab2(sch_1):page87_i186:dq(17)"
				( attribute "PN" "172"
					( Origin gPackager )
				)
				( objectStatus "J1A1.172" )
			)
			( pin "@baseboard_fab2_lib.baseboard_fab2(sch_1):page87_i186:dq(18)"
				( attribute "PN" "34"
					( Origin gPackager )
				)
				( objectStatus "J1A1.34" )
			)
			( pin "@baseboard_fab2_lib.baseboard_fab2(sch_1):page87_i186:dq(19)"
				( attribute "PN" "179"
					( Origin gPackager )
				)
				( objectStatus "J1A1.179" )
			)
			( pin "@baseboard_fab2_lib.baseboard_fab2(sch_1):page87_i186:dq(20)"
				( attribute "PN" "25"
					( Origin gPackager )
				)
				( objectStatus "J1A1.25" )
			)
			( pin "@baseboard_fab2_lib.baseboard_fab2(sch_1):page87_i186:dq(21)"
				( attribute "PN" "170"
					( Origin gPackager )
				)
				( objectStatus "J1A1.170" )
			)
			( pin "@baseboard_fab2_lib.baseboard_fab2(sch_1):page87_i186:dq(22)"
				( attribute "PN" "32"
					( Origin gPackager )
				)
				( objectStatus "J1A1.32" )
			)
			( pin "@baseboard_fab2_lib.baseboard_fab2(sch_1):page87_i186:dq(23)"
				( attribute "PN" "177"
					( Origin gPackager )
				)
				( objectStatus "J1A1.177" )
			)
			( pin "@baseboard_fab2_lib.baseboard_fab2(sch_1):page87_i186:dq(24)"
				( attribute "PN" "38"
					( Origin gPackager )
				)
				( objectStatus "J1A1.38" )
			)
			( pin "@baseboard_fab2_lib.baseboard_fab2(sch_1):page87_i186:dq(25)"
				( attribute "PN" "183"
					( Origin gPackager )
				)
				( objectStatus "J1A1.183" )
			)
			( pin "@baseboard_fab2_lib.baseboard_fab2(sch_1):page87_i186:dq(26)"
				( attribute "PN" "45"
					( Origin gPackager )
				)
				( objectStatus "J1A1.45" )
			)
			( pin "@baseboard_fab2_lib.baseboard_fab2(sch_1):page87_i186:dq(27)"
				( attribute "PN" "190"
					( Origin gPackager )
				)
				( objectStatus "J1A1.190" )
			)
			( pin "@baseboard_fab2_lib.baseboard_fab2(sch_1):page87_i186:dq(28)"
				( attribute "PN" "36"
					( Origin gPackager )
				)
				( objectStatus "J1A1.36" )
			)
			( pin "@baseboard_fab2_lib.baseboard_fab2(sch_1):page87_i186:dq(29)"
				( attribute "PN" "181"
					( Origin gPackager )
				)
				( objectStatus "J1A1.181" )
			)
			( pin "@baseboard_fab2_lib.baseboard_fab2(sch_1):page87_i186:dq(30)"
				( attribute "PN" "43"
					( Origin gPackager )
				)
				( objectStatus "J1A1.43" )
			)
			( pin "@baseboard_fab2_lib.baseboard_fab2(sch_1):page87_i186:dq(31)"
				( attribute "PN" "188"
					( Origin gPackager )
				)
				( objectStatus "J1A1.188" )
			)
			( pin "@baseboard_fab2_lib.baseboard_fab2(sch_1):page87_i186:dq(32)"
				( attribute "PN" "97"
					( Origin gPackager )
				)
				( objectStatus "J1A1.97" )
			)
			( pin "@baseboard_fab2_lib.baseboard_fab2(sch_1):page87_i186:dq(33)"
				( attribute "PN" "242"
					( Origin gPackager )
				)
				( objectStatus "J1A1.242" )
			)
			( pin "@baseboard_fab2_lib.baseboard_fab2(sch_1):page87_i186:dq(34)"
				( attribute "PN" "104"
					( Origin gPackager )
				)
				( objectStatus "J1A1.104" )
			)
			( pin "@baseboard_fab2_lib.baseboard_fab2(sch_1):page87_i186:dq(35)"
				( attribute "PN" "249"
					( Origin gPackager )
				)
				( objectStatus "J1A1.249" )
			)
			( pin "@baseboard_fab2_lib.baseboard_fab2(sch_1):page87_i186:dq(36)"
				( attribute "PN" "95"
					( Origin gPackager )
				)
				( objectStatus "J1A1.95" )
			)
			( pin "@baseboard_fab2_lib.baseboard_fab2(sch_1):page87_i186:dq(37)"
				( attribute "PN" "240"
					( Origin gPackager )
				)
				( objectStatus "J1A1.240" )
			)
			( pin "@baseboard_fab2_lib.baseboard_fab2(sch_1):page87_i186:dq(38)"
				( attribute "PN" "102"
					( Origin gPackager )
				)
				( objectStatus "J1A1.102" )
			)
			( pin "@baseboard_fab2_lib.baseboard_fab2(sch_1):page87_i186:dq(39)"
				( attribute "PN" "247"
					( Origin gPackager )
				)
				( objectStatus "J1A1.247" )
			)
			( pin "@baseboard_fab2_lib.baseboard_fab2(sch_1):page87_i186:dq(40)"
				( attribute "PN" "108"
					( Origin gPackager )
				)
				( objectStatus "J1A1.108" )
			)
			( pin "@baseboard_fab2_lib.baseboard_fab2(sch_1):page87_i186:dq(41)"
				( attribute "PN" "253"
					( Origin gPackager )
				)
				( objectStatus "J1A1.253" )
			)
			( pin "@baseboard_fab2_lib.baseboard_fab2(sch_1):page87_i186:dq(42)"
				( attribute "PN" "115"
					( Origin gPackager )
				)
				( objectStatus "J1A1.115" )
			)
			( pin "@baseboard_fab2_lib.baseboard_fab2(sch_1):page87_i186:dq(43)"
				( attribute "PN" "260"
					( Origin gPackager )
				)
				( objectStatus "J1A1.260" )
			)
			( pin "@baseboard_fab2_lib.baseboard_fab2(sch_1):page87_i186:dq(44)"
				( attribute "PN" "106"
					( Origin gPackager )
				)
				( objectStatus "J1A1.106" )
			)
			( pin "@baseboard_fab2_lib.baseboard_fab2(sch_1):page87_i186:dq(45)"
				( attribute "PN" "251"
					( Origin gPackager )
				)
				( objectStatus "J1A1.251" )
			)
			( pin "@baseboard_fab2_lib.baseboard_fab2(sch_1):page87_i186:dq(46)"
				( attribute "PN" "113"
					( Origin gPackager )
				)
				( objectStatus "J1A1.113" )
			)
			( pin "@baseboard_fab2_lib.baseboard_fab2(sch_1):page87_i186:dq(47)"
				( attribute "PN" "258"
					( Origin gPackager )
				)
				( objectStatus "J1A1.258" )
			)
			( pin "@baseboard_fab2_lib.baseboard_fab2(sch_1):page87_i186:dq(48)"
				( attribute "PN" "119"
					( Origin gPackager )
				)
				( objectStatus "J1A1.119" )
			)
			( pin "@baseboard_fab2_lib.baseboard_fab2(sch_1):page87_i186:dq(49)"
				( attribute "PN" "264"
					( Origin gPackager )
				)
				( objectStatus "J1A1.264" )
			)
			( pin "@baseboard_fab2_lib.baseboard_fab2(sch_1):page87_i186:dq(50)"
				( attribute "PN" "126"
					( Origin gPackager )
				)
				( objectStatus "J1A1.126" )
			)
			( pin "@baseboard_fab2_lib.baseboard_fab2(sch_1):page87_i186:dq(51)"
				( attribute "PN" "271"
					( Origin gPackager )
				)
				( objectStatus "J1A1.271" )
			)
			( pin "@baseboard_fab2_lib.baseboard_fab2(sch_1):page87_i186:dq(52)"
				( attribute "PN" "117"
					( Origin gPackager )
				)
				( objectStatus "J1A1.117" )
			)
			( pin "@baseboard_fab2_lib.baseboard_fab2(sch_1):page87_i186:dq(53)"
				( attribute "PN" "262"
					( Origin gPackager )
				)
				( objectStatus "J1A1.262" )
			)
			( pin "@baseboard_fab2_lib.baseboard_fab2(sch_1):page87_i186:dq(54)"
				( attribute "PN" "124"
					( Origin gPackager )
				)
				( objectStatus "J1A1.124" )
			)
			( pin "@baseboard_fab2_lib.baseboard_fab2(sch_1):page87_i186:dq(55)"
				( attribute "PN" "269"
					( Origin gPackager )
				)
				( objectStatus "J1A1.269" )
			)
			( pin "@baseboard_fab2_lib.baseboard_fab2(sch_1):page87_i186:dq(56)"
				( attribute "PN" "130"
					( Origin gPackager )
				)
				( objectStatus "J1A1.130" )
			)
			( pin "@baseboard_fab2_lib.baseboard_fab2(sch_1):page87_i186:dq(57)"
				( attribute "PN" "275"
					( Origin gPackager )
				)
				( objectStatus "J1A1.275" )
			)
			( pin "@baseboard_fab2_lib.baseboard_fab2(sch_1):page87_i186:dq(58)"
				( attribute "PN" "137"
					( Origin gPackager )
				)
				( objectStatus "J1A1.137" )
			)
			( pin "@baseboard_fab2_lib.baseboard_fab2(sch_1):page87_i186:dq(59)"
				( attribute "PN" "282"
					( Origin gPackager )
				)
				( objectStatus "J1A1.282" )
			)
			( pin "@baseboard_fab2_lib.baseboard_fab2(sch_1):page87_i186:dq(60)"
				( attribute "PN" "128"
					( Origin gPackager )
				)
				( objectStatus "J1A1.128" )
			)
			( pin "@baseboard_fab2_lib.baseboard_fab2(sch_1):page87_i186:dq(61)"
				( attribute "PN" "273"
					( Origin gPackager )
				)
				( objectStatus "J1A1.273" )
			)
			( pin "@baseboard_fab2_lib.baseboard_fab2(sch_1):page87_i186:dq(62)"
				( attribute "PN" "135"
					( Origin gPackager )
				)
				( objectStatus "J1A1.135" )
			)
			( pin "@baseboard_fab2_lib.baseboard_fab2(sch_1):page87_i186:dq(63)"
				( attribute "PN" "280"
					( Origin gPackager )
				)
				( objectStatus "J1A1.280" )
			)
			( pin "@baseboard_fab2_lib.baseboard_fab2(sch_1):page87_i186:event_n"
				( attribute "PN" "78"
					( Origin gPackager )
				)
				( objectStatus "J1A1.78" )
			)
			( pin "@baseboard_fab2_lib.baseboard_fab2(sch_1):page87_i186:odt(0)"
				( attribute "PN" "87"
					( Origin gPackager )
				)
				( objectStatus "J1A1.87" )
			)
			( pin "@baseboard_fab2_lib.baseboard_fab2(sch_1):page87_i186:odt(1)"
				( attribute "PN" "91"
					( Origin gPackager )
				)
				( objectStatus "J1A1.91" )
			)
			( pin "@baseboard_fab2_lib.baseboard_fab2(sch_1):page87_i186:par"
				( attribute "PN" "222"
					( Origin gPackager )
				)
				( objectStatus "J1A1.222" )
			)
			( pin "@baseboard_fab2_lib.baseboard_fab2(sch_1):page87_i186:reset_n"
				( attribute "PN" "58"
					( Origin gPackager )
				)
				( objectStatus "J1A1.58" )
			)
			( pin "@baseboard_fab2_lib.baseboard_fab2(sch_1):page87_i186:rfu(0)"
				( attribute "PN" "205"
					( Origin gPackager )
				)
				( objectStatus "J1A1.205" )
			)
			( pin "@baseboard_fab2_lib.baseboard_fab2(sch_1):page87_i186:rfu(1)"
				( attribute "PN" "227"
					( Origin gPackager )
				)
				( objectStatus "J1A1.227" )
			)
			( pin "@baseboard_fab2_lib.baseboard_fab2(sch_1):page87_i186:rfu(2)"
				( attribute "PN" "144"
					( Origin gPackager )
				)
				( objectStatus "J1A1.144" )
			)
			( pin "@baseboard_fab2_lib.baseboard_fab2(sch_1):page87_i186:s0_n"
				( attribute "PN" "84"
					( Origin gPackager )
				)
				( objectStatus "J1A1.84" )
			)
			( pin "@baseboard_fab2_lib.baseboard_fab2(sch_1):page87_i186:s1_n"
				( attribute "PN" "89"
					( Origin gPackager )
				)
				( objectStatus "J1A1.89" )
			)
			( pin "@baseboard_fab2_lib.baseboard_fab2(sch_1):page87_i186:s2_n_c(0)"
				( attribute "PN" "93"
					( Origin gPackager )
				)
				( objectStatus "J1A1.93" )
			)
			( pin "@baseboard_fab2_lib.baseboard_fab2(sch_1):page87_i186:s3_n_c(1)"
				( attribute "PN" "237"
					( Origin gPackager )
				)
				( objectStatus "J1A1.237" )
			)
			( pin "@baseboard_fab2_lib.baseboard_fab2(sch_1):page87_i186:sa(0)"
				( attribute "PN" "139"
					( Origin gPackager )
				)
				( objectStatus "J1A1.139" )
			)
			( pin "@baseboard_fab2_lib.baseboard_fab2(sch_1):page87_i186:sa(1)"
				( attribute "PN" "140"
					( Origin gPackager )
				)
				( objectStatus "J1A1.140" )
			)
			( pin "@baseboard_fab2_lib.baseboard_fab2(sch_1):page87_i186:sa(2)"
				( attribute "PN" "238"
					( Origin gPackager )
				)
				( objectStatus "J1A1.238" )
			)
			( pin "@baseboard_fab2_lib.baseboard_fab2(sch_1):page87_i186:save_n_nc"
				( attribute "PN" "230"
					( Origin gPackager )
				)
				( objectStatus "J1A1.230" )
			)
			( pin "@baseboard_fab2_lib.baseboard_fab2(sch_1):page87_i186:scl"
				( attribute "PN" "141"
					( Origin gPackager )
				)
				( objectStatus "J1A1.141" )
			)
			( pin "@baseboard_fab2_lib.baseboard_fab2(sch_1):page87_i186:sda"
				( attribute "PN" "285"
					( Origin gPackager )
				)
				( objectStatus "J1A1.285" )
			)
			( pin "@baseboard_fab2_lib.baseboard_fab2(sch_1):page87_i186:vddspd"
				( attribute "PN" "284"
					( Origin gPackager )
				)
				( objectStatus "J1A1.284" )
			)
			( pin "@baseboard_fab2_lib.baseboard_fab2(sch_1):page87_i186:vrefca"
				( attribute "PN" "146"
					( Origin gPackager )
				)
				( objectStatus "J1A1.146" )
			)
			( pin "@baseboard_fab2_lib.baseboard_fab2(sch_1):page87_i187:dqs0n"
				( attribute "PN" "152"
					( Origin gPackager )
				)
				( objectStatus "J1A1.152" )
			)
			( pin "@baseboard_fab2_lib.baseboard_fab2(sch_1):page87_i187:dqs0p"
				( attribute "PN" "153"
					( Origin gPackager )
				)
				( objectStatus "J1A1.153" )
			)
			( pin "@baseboard_fab2_lib.baseboard_fab2(sch_1):page87_i187:dqs1n"
				( attribute "PN" "163"
					( Origin gPackager )
				)
				( objectStatus "J1A1.163" )
			)
			( pin "@baseboard_fab2_lib.baseboard_fab2(sch_1):page87_i187:dqs1p"
				( attribute "PN" "164"
					( Origin gPackager )
				)
				( objectStatus "J1A1.164" )
			)
			( pin "@baseboard_fab2_lib.baseboard_fab2(sch_1):page87_i187:dqs2n"
				( attribute "PN" "174"
					( Origin gPackager )
				)
				( objectStatus "J1A1.174" )
			)
			( pin "@baseboard_fab2_lib.baseboard_fab2(sch_1):page87_i187:dqs2p"
				( attribute "PN" "175"
					( Origin gPackager )
				)
				( objectStatus "J1A1.175" )
			)
			( pin "@baseboard_fab2_lib.baseboard_fab2(sch_1):page87_i187:dqs3n"
				( attribute "PN" "185"
					( Origin gPackager )
				)
				( objectStatus "J1A1.185" )
			)
			( pin "@baseboard_fab2_lib.baseboard_fab2(sch_1):page87_i187:dqs3p"
				( attribute "PN" "186"
					( Origin gPackager )
				)
				( objectStatus "J1A1.186" )
			)
			( pin "@baseboard_fab2_lib.baseboard_fab2(sch_1):page87_i187:dqs4n"
				( attribute "PN" "244"
					( Origin gPackager )
				)
				( objectStatus "J1A1.244" )
			)
			( pin "@baseboard_fab2_lib.baseboard_fab2(sch_1):page87_i187:dqs4p"
				( attribute "PN" "245"
					( Origin gPackager )
				)
				( objectStatus "J1A1.245" )
			)
			( pin "@baseboard_fab2_lib.baseboard_fab2(sch_1):page87_i187:dqs5n"
				( attribute "PN" "255"
					( Origin gPackager )
				)
				( objectStatus "J1A1.255" )
			)
			( pin "@baseboard_fab2_lib.baseboard_fab2(sch_1):page87_i187:dqs5p"
				( attribute "PN" "256"
					( Origin gPackager )
				)
				( objectStatus "J1A1.256" )
			)
			( pin "@baseboard_fab2_lib.baseboard_fab2(sch_1):page87_i187:dqs6n"
				( attribute "PN" "266"
					( Origin gPackager )
				)
				( objectStatus "J1A1.266" )
			)
			( pin "@baseboard_fab2_lib.baseboard_fab2(sch_1):page87_i187:dqs6p"
				( attribute "PN" "267"
					( Origin gPackager )
				)
				( objectStatus "J1A1.267" )
			)
			( pin "@baseboard_fab2_lib.baseboard_fab2(sch_1):page87_i187:dqs7n"
				( attribute "PN" "277"
					( Origin gPackager )
				)
				( objectStatus "J1A1.277" )
			)
			( pin "@baseboard_fab2_lib.baseboard_fab2(sch_1):page87_i187:dqs7p"
				( attribute "PN" "278"
					( Origin gPackager )
				)
				( objectStatus "J1A1.278" )
			)
			( pin "@baseboard_fab2_lib.baseboard_fab2(sch_1):page87_i187:dqs8n"
				( attribute "PN" "196"
					( Origin gPackager )
				)
				( objectStatus "J1A1.196" )
			)
			( pin "@baseboard_fab2_lib.baseboard_fab2(sch_1):page87_i187:dqs8p"
				( attribute "PN" "197"
					( Origin gPackager )
				)
				( objectStatus "J1A1.197" )
			)
			( pin "@baseboard_fab2_lib.baseboard_fab2(sch_1):page87_i187:dqs9n"
				( attribute "PN" "8"
					( Origin gPackager )
				)
				( objectStatus "J1A1.8" )
			)
			( pin "@baseboard_fab2_lib.baseboard_fab2(sch_1):page87_i187:dqs9p"
				( attribute "PN" "7"
					( Origin gPackager )
				)
				( objectStatus "J1A1.7" )
			)
			( pin "@baseboard_fab2_lib.baseboard_fab2(sch_1):page87_i187:dqs10n"
				( attribute "PN" "19"
					( Origin gPackager )
				)
				( objectStatus "J1A1.19" )
			)
			( pin "@baseboard_fab2_lib.baseboard_fab2(sch_1):page87_i187:dqs10p"
				( attribute "PN" "18"
					( Origin gPackager )
				)
				( objectStatus "J1A1.18" )
			)
			( pin "@baseboard_fab2_lib.baseboard_fab2(sch_1):page87_i187:dqs11n"
				( attribute "PN" "30"
					( Origin gPackager )
				)
				( objectStatus "J1A1.30" )
			)
			( pin "@baseboard_fab2_lib.baseboard_fab2(sch_1):page87_i187:dqs11p"
				( attribute "PN" "29"
					( Origin gPackager )
				)
				( objectStatus "J1A1.29" )
			)
			( pin "@baseboard_fab2_lib.baseboard_fab2(sch_1):page87_i187:dqs12n"
				( attribute "PN" "41"
					( Origin gPackager )
				)
				( objectStatus "J1A1.41" )
			)
			( pin "@baseboard_fab2_lib.baseboard_fab2(sch_1):page87_i187:dqs12p"
				( attribute "PN" "40"
					( Origin gPackager )
				)
				( objectStatus "J1A1.40" )
			)
			( pin "@baseboard_fab2_lib.baseboard_fab2(sch_1):page87_i187:dqs13n"
				( attribute "PN" "100"
					( Origin gPackager )
				)
				( objectStatus "J1A1.100" )
			)
			( pin "@baseboard_fab2_lib.baseboard_fab2(sch_1):page87_i187:dqs13p"
				( attribute "PN" "99"
					( Origin gPackager )
				)
				( objectStatus "J1A1.99" )
			)
			( pin "@baseboard_fab2_lib.baseboard_fab2(sch_1):page87_i187:dqs14n"
				( attribute "PN" "111"
					( Origin gPackager )
				)
				( objectStatus "J1A1.111" )
			)
			( pin "@baseboard_fab2_lib.baseboard_fab2(sch_1):page87_i187:dqs14p"
				( attribute "PN" "110"
					( Origin gPackager )
				)
				( objectStatus "J1A1.110" )
			)
			( pin "@baseboard_fab2_lib.baseboard_fab2(sch_1):page87_i187:dqs15n"
				( attribute "PN" "122"
					( Origin gPackager )
				)
				( objectStatus "J1A1.122" )
			)
			( pin "@baseboard_fab2_lib.baseboard_fab2(sch_1):page87_i187:dqs15p"
				( attribute "PN" "121"
					( Origin gPackager )
				)
				( objectStatus "J1A1.121" )
			)
			( pin "@baseboard_fab2_lib.baseboard_fab2(sch_1):page87_i187:dqs16n"
				( attribute "PN" "133"
					( Origin gPackager )
				)
				( objectStatus "J1A1.133" )
			)
			( pin "@baseboard_fab2_lib.baseboard_fab2(sch_1):page87_i187:dqs16p"
				( attribute "PN" "132"
					( Origin gPackager )
				)
				( objectStatus "J1A1.132" )
			)
			( pin "@baseboard_fab2_lib.baseboard_fab2(sch_1):page87_i187:dqs17n"
				( attribute "PN" "52"
					( Origin gPackager )
				)
				( objectStatus "J1A1.52" )
			)
			( pin "@baseboard_fab2_lib.baseboard_fab2(sch_1):page87_i187:dqs17p"
				( attribute "PN" "51"
					( Origin gPackager )
				)
				( objectStatus "J1A1.51" )
			)
			( pin "@baseboard_fab2_lib.baseboard_fab2(sch_1):page88_i25:vss(0)"
				( attribute "PN" "283"
					( Origin gPackager )
				)
				( objectStatus "J9L1.283" )
			)
			( pin "@baseboard_fab2_lib.baseboard_fab2(sch_1):page88_i25:vss(1)"
				( attribute "PN" "281"
					( Origin gPackager )
				)
				( objectStatus "J9L1.281" )
			)
			( pin "@baseboard_fab2_lib.baseboard_fab2(sch_1):page88_i25:vss(2)"
				( attribute "PN" "279"
					( Origin gPackager )
				)
				( objectStatus "J9L1.279" )
			)
			( pin "@baseboard_fab2_lib.baseboard_fab2(sch_1):page88_i25:vss(3)"
				( attribute "PN" "276"
					( Origin gPackager )
				)
				( objectStatus "J9L1.276" )
			)
			( pin "@baseboard_fab2_lib.baseboard_fab2(sch_1):page88_i25:vss(4)"
				( attribute "PN" "274"
					( Origin gPackager )
				)
				( objectStatus "J9L1.274" )
			)
			( pin "@baseboard_fab2_lib.baseboard_fab2(sch_1):page88_i25:vss(5)"
				( attribute "PN" "272"
					( Origin gPackager )
				)
				( objectStatus "J9L1.272" )
			)
			( pin "@baseboard_fab2_lib.baseboard_fab2(sch_1):page88_i25:vss(6)"
				( attribute "PN" "270"
					( Origin gPackager )
				)
				( objectStatus "J9L1.270" )
			)
			( pin "@baseboard_fab2_lib.baseboard_fab2(sch_1):page88_i25:vss(7)"
				( attribute "PN" "268"
					( Origin gPackager )
				)
				( objectStatus "J9L1.268" )
			)
			( pin "@baseboard_fab2_lib.baseboard_fab2(sch_1):page88_i25:vss(8)"
				( attribute "PN" "265"
					( Origin gPackager )
				)
				( objectStatus "J9L1.265" )
			)
			( pin "@baseboard_fab2_lib.baseboard_fab2(sch_1):page88_i25:vss(9)"
				( attribute "PN" "263"
					( Origin gPackager )
				)
				( objectStatus "J9L1.263" )
			)
			( pin "@baseboard_fab2_lib.baseboard_fab2(sch_1):page88_i25:vss(10)"
				( attribute "PN" "261"
					( Origin gPackager )
				)
				( objectStatus "J9L1.261" )
			)
			( pin "@baseboard_fab2_lib.baseboard_fab2(sch_1):page88_i25:vss(11)"
				( attribute "PN" "259"
					( Origin gPackager )
				)
				( objectStatus "J9L1.259" )
			)
			( pin "@baseboard_fab2_lib.baseboard_fab2(sch_1):page88_i25:vss(12)"
				( attribute "PN" "257"
					( Origin gPackager )
				)
				( objectStatus "J9L1.257" )
			)
			( pin "@baseboard_fab2_lib.baseboard_fab2(sch_1):page88_i25:vss(13)"
				( attribute "PN" "254"
					( Origin gPackager )
				)
				( objectStatus "J9L1.254" )
			)
			( pin "@baseboard_fab2_lib.baseboard_fab2(sch_1):page88_i25:vss(14)"
				( attribute "PN" "252"
					( Origin gPackager )
				)
				( objectStatus "J9L1.252" )
			)
			( pin "@baseboard_fab2_lib.baseboard_fab2(sch_1):page88_i25:vss(15)"
				( attribute "PN" "250"
					( Origin gPackager )
				)
				( objectStatus "J9L1.250" )
			)
			( pin "@baseboard_fab2_lib.baseboard_fab2(sch_1):page88_i25:vss(16)"
				( attribute "PN" "248"
					( Origin gPackager )
				)
				( objectStatus "J9L1.248" )
			)
			( pin "@baseboard_fab2_lib.baseboard_fab2(sch_1):page88_i25:vss(17)"
				( attribute "PN" "246"
					( Origin gPackager )
				)
				( objectStatus "J9L1.246" )
			)
			( pin "@baseboard_fab2_lib.baseboard_fab2(sch_1):page88_i25:vss(18)"
				( attribute "PN" "243"
					( Origin gPackager )
				)
				( objectStatus "J9L1.243" )
			)
			( pin "@baseboard_fab2_lib.baseboard_fab2(sch_1):page88_i25:vss(19)"
				( attribute "PN" "241"
					( Origin gPackager )
				)
				( objectStatus "J9L1.241" )
			)
			( pin "@baseboard_fab2_lib.baseboard_fab2(sch_1):page88_i25:vss(20)"
				( attribute "PN" "239"
					( Origin gPackager )
				)
				( objectStatus "J9L1.239" )
			)
			( pin "@baseboard_fab2_lib.baseboard_fab2(sch_1):page88_i25:vss(21)"
				( attribute "PN" "202"
					( Origin gPackager )
				)
				( objectStatus "J9L1.202" )
			)
			( pin "@baseboard_fab2_lib.baseboard_fab2(sch_1):page88_i25:vss(22)"
				( attribute "PN" "200"
					( Origin gPackager )
				)
				( objectStatus "J9L1.200" )
			)
			( pin "@baseboard_fab2_lib.baseboard_fab2(sch_1):page88_i25:vss(23)"
				( attribute "PN" "198"
					( Origin gPackager )
				)
				( objectStatus "J9L1.198" )
			)
			( pin "@baseboard_fab2_lib.baseboard_fab2(sch_1):page88_i25:vss(24)"
				( attribute "PN" "195"
					( Origin gPackager )
				)
				( objectStatus "J9L1.195" )
			)
			( pin "@baseboard_fab2_lib.baseboard_fab2(sch_1):page88_i25:vss(25)"
				( attribute "PN" "193"
					( Origin gPackager )
				)
				( objectStatus "J9L1.193" )
			)
			( pin "@baseboard_fab2_lib.baseboard_fab2(sch_1):page88_i25:vss(26)"
				( attribute "PN" "191"
					( Origin gPackager )
				)
				( objectStatus "J9L1.191" )
			)
			( pin "@baseboard_fab2_lib.baseboard_fab2(sch_1):page88_i25:vss(27)"
				( attribute "PN" "189"
					( Origin gPackager )
				)
				( objectStatus "J9L1.189" )
			)
			( pin "@baseboard_fab2_lib.baseboard_fab2(sch_1):page88_i25:vss(28)"
				( attribute "PN" "187"
					( Origin gPackager )
				)
				( objectStatus "J9L1.187" )
			)
			( pin "@baseboard_fab2_lib.baseboard_fab2(sch_1):page88_i25:vss(29)"
				( attribute "PN" "184"
					( Origin gPackager )
				)
				( objectStatus "J9L1.184" )
			)
			( pin "@baseboard_fab2_lib.baseboard_fab2(sch_1):page88_i25:vss(30)"
				( attribute "PN" "182"
					( Origin gPackager )
				)
				( objectStatus "J9L1.182" )
			)
			( pin "@baseboard_fab2_lib.baseboard_fab2(sch_1):page88_i25:vss(31)"
				( attribute "PN" "180"
					( Origin gPackager )
				)
				( objectStatus "J9L1.180" )
			)
			( pin "@baseboard_fab2_lib.baseboard_fab2(sch_1):page88_i25:vss(32)"
				( attribute "PN" "178"
					( Origin gPackager )
				)
				( objectStatus "J9L1.178" )
			)
			( pin "@baseboard_fab2_lib.baseboard_fab2(sch_1):page88_i25:vss(33)"
				( attribute "PN" "176"
					( Origin gPackager )
				)
				( objectStatus "J9L1.176" )
			)
			( pin "@baseboard_fab2_lib.baseboard_fab2(sch_1):page88_i25:vss(34)"
				( attribute "PN" "173"
					( Origin gPackager )
				)
				( objectStatus "J9L1.173" )
			)
			( pin "@baseboard_fab2_lib.baseboard_fab2(sch_1):page88_i25:vss(35)"
				( attribute "PN" "171"
					( Origin gPackager )
				)
				( objectStatus "J9L1.171" )
			)
			( pin "@baseboard_fab2_lib.baseboard_fab2(sch_1):page88_i25:vss(36)"
				( attribute "PN" "169"
					( Origin gPackager )
				)
				( objectStatus "J9L1.169" )
			)
			( pin "@baseboard_fab2_lib.baseboard_fab2(sch_1):page88_i25:vss(37)"
				( attribute "PN" "167"
					( Origin gPackager )
				)
				( objectStatus "J9L1.167" )
			)
			( pin "@baseboard_fab2_lib.baseboard_fab2(sch_1):page88_i25:vss(38)"
				( attribute "PN" "165"
					( Origin gPackager )
				)
				( objectStatus "J9L1.165" )
			)
			( pin "@baseboard_fab2_lib.baseboard_fab2(sch_1):page88_i25:vss(39)"
				( attribute "PN" "162"
					( Origin gPackager )
				)
				( objectStatus "J9L1.162" )
			)
			( pin "@baseboard_fab2_lib.baseboard_fab2(sch_1):page88_i25:vss(40)"
				( attribute "PN" "160"
					( Origin gPackager )
				)
				( objectStatus "J9L1.160" )
			)
			( pin "@baseboard_fab2_lib.baseboard_fab2(sch_1):page88_i25:vss(41)"
				( attribute "PN" "158"
					( Origin gPackager )
				)
				( objectStatus "J9L1.158" )
			)
			( pin "@baseboard_fab2_lib.baseboard_fab2(sch_1):page88_i25:vss(42)"
				( attribute "PN" "156"
					( Origin gPackager )
				)
				( objectStatus "J9L1.156" )
			)
			( pin "@baseboard_fab2_lib.baseboard_fab2(sch_1):page88_i25:vss(43)"
				( attribute "PN" "154"
					( Origin gPackager )
				)
				( objectStatus "J9L1.154" )
			)
			( pin "@baseboard_fab2_lib.baseboard_fab2(sch_1):page88_i25:vss(44)"
				( attribute "PN" "151"
					( Origin gPackager )
				)
				( objectStatus "J9L1.151" )
			)
			( pin "@baseboard_fab2_lib.baseboard_fab2(sch_1):page88_i25:vss(45)"
				( attribute "PN" "149"
					( Origin gPackager )
				)
				( objectStatus "J9L1.149" )
			)
			( pin "@baseboard_fab2_lib.baseboard_fab2(sch_1):page88_i25:vss(46)"
				( attribute "PN" "147"
					( Origin gPackager )
				)
				( objectStatus "J9L1.147" )
			)
			( pin "@baseboard_fab2_lib.baseboard_fab2(sch_1):page88_i25:vss(47)"
				( attribute "PN" "138"
					( Origin gPackager )
				)
				( objectStatus "J9L1.138" )
			)
			( pin "@baseboard_fab2_lib.baseboard_fab2(sch_1):page88_i25:vss(48)"
				( attribute "PN" "136"
					( Origin gPackager )
				)
				( objectStatus "J9L1.136" )
			)
			( pin "@baseboard_fab2_lib.baseboard_fab2(sch_1):page88_i25:vss(49)"
				( attribute "PN" "134"
					( Origin gPackager )
				)
				( objectStatus "J9L1.134" )
			)
			( pin "@baseboard_fab2_lib.baseboard_fab2(sch_1):page88_i25:vss(50)"
				( attribute "PN" "131"
					( Origin gPackager )
				)
				( objectStatus "J9L1.131" )
			)
			( pin "@baseboard_fab2_lib.baseboard_fab2(sch_1):page88_i25:vss(51)"
				( attribute "PN" "129"
					( Origin gPackager )
				)
				( objectStatus "J9L1.129" )
			)
			( pin "@baseboard_fab2_lib.baseboard_fab2(sch_1):page88_i25:vss(52)"
				( attribute "PN" "127"
					( Origin gPackager )
				)
				( objectStatus "J9L1.127" )
			)
			( pin "@baseboard_fab2_lib.baseboard_fab2(sch_1):page88_i25:vss(53)"
				( attribute "PN" "125"
					( Origin gPackager )
				)
				( objectStatus "J9L1.125" )
			)
			( pin "@baseboard_fab2_lib.baseboard_fab2(sch_1):page88_i25:vss(54)"
				( attribute "PN" "123"
					( Origin gPackager )
				)
				( objectStatus "J9L1.123" )
			)
			( pin "@baseboard_fab2_lib.baseboard_fab2(sch_1):page88_i25:vss(55)"
				( attribute "PN" "120"
					( Origin gPackager )
				)
				( objectStatus "J9L1.120" )
			)
			( pin "@baseboard_fab2_lib.baseboard_fab2(sch_1):page88_i25:vss(56)"
				( attribute "PN" "118"
					( Origin gPackager )
				)
				( objectStatus "J9L1.118" )
			)
			( pin "@baseboard_fab2_lib.baseboard_fab2(sch_1):page88_i25:vss(57)"
				( attribute "PN" "116"
					( Origin gPackager )
				)
				( objectStatus "J9L1.116" )
			)
			( pin "@baseboard_fab2_lib.baseboard_fab2(sch_1):page88_i25:vss(58)"
				( attribute "PN" "114"
					( Origin gPackager )
				)
				( objectStatus "J9L1.114" )
			)
			( pin "@baseboard_fab2_lib.baseboard_fab2(sch_1):page88_i25:vss(59)"
				( attribute "PN" "112"
					( Origin gPackager )
				)
				( objectStatus "J9L1.112" )
			)
			( pin "@baseboard_fab2_lib.baseboard_fab2(sch_1):page88_i25:vss(60)"
				( attribute "PN" "109"
					( Origin gPackager )
				)
				( objectStatus "J9L1.109" )
			)
			( pin "@baseboard_fab2_lib.baseboard_fab2(sch_1):page88_i25:vss(61)"
				( attribute "PN" "107"
					( Origin gPackager )
				)
				( objectStatus "J9L1.107" )
			)
			( pin "@baseboard_fab2_lib.baseboard_fab2(sch_1):page88_i25:vss(62)"
				( attribute "PN" "105"
					( Origin gPackager )
				)
				( objectStatus "J9L1.105" )
			)
			( pin "@baseboard_fab2_lib.baseboard_fab2(sch_1):page88_i25:vss(63)"
				( attribute "PN" "103"
					( Origin gPackager )
				)
				( objectStatus "J9L1.103" )
			)
			( pin "@baseboard_fab2_lib.baseboard_fab2(sch_1):page88_i25:vss(64)"
				( attribute "PN" "101"
					( Origin gPackager )
				)
				( objectStatus "J9L1.101" )
			)
			( pin "@baseboard_fab2_lib.baseboard_fab2(sch_1):page88_i25:vss(65)"
				( attribute "PN" "98"
					( Origin gPackager )
				)
				( objectStatus "J9L1.98" )
			)
			( pin "@baseboard_fab2_lib.baseboard_fab2(sch_1):page88_i25:vss(66)"
				( attribute "PN" "96"
					( Origin gPackager )
				)
				( objectStatus "J9L1.96" )
			)
			( pin "@baseboard_fab2_lib.baseboard_fab2(sch_1):page88_i25:vss(67)"
				( attribute "PN" "94"
					( Origin gPackager )
				)
				( objectStatus "J9L1.94" )
			)
			( pin "@baseboard_fab2_lib.baseboard_fab2(sch_1):page88_i25:vss(68)"
				( attribute "PN" "57"
					( Origin gPackager )
				)
				( objectStatus "J9L1.57" )
			)
			( pin "@baseboard_fab2_lib.baseboard_fab2(sch_1):page88_i25:vss(69)"
				( attribute "PN" "55"
					( Origin gPackager )
				)
				( objectStatus "J9L1.55" )
			)
			( pin "@baseboard_fab2_lib.baseboard_fab2(sch_1):page88_i25:vss(70)"
				( attribute "PN" "53"
					( Origin gPackager )
				)
				( objectStatus "J9L1.53" )
			)
			( pin "@baseboard_fab2_lib.baseboard_fab2(sch_1):page88_i25:vss(71)"
				( attribute "PN" "50"
					( Origin gPackager )
				)
				( objectStatus "J9L1.50" )
			)
			( pin "@baseboard_fab2_lib.baseboard_fab2(sch_1):page88_i25:vss(72)"
				( attribute "PN" "48"
					( Origin gPackager )
				)
				( objectStatus "J9L1.48" )
			)
			( pin "@baseboard_fab2_lib.baseboard_fab2(sch_1):page88_i25:vss(73)"
				( attribute "PN" "46"
					( Origin gPackager )
				)
				( objectStatus "J9L1.46" )
			)
			( pin "@baseboard_fab2_lib.baseboard_fab2(sch_1):page88_i25:vss(74)"
				( attribute "PN" "44"
					( Origin gPackager )
				)
				( objectStatus "J9L1.44" )
			)
			( pin "@baseboard_fab2_lib.baseboard_fab2(sch_1):page88_i25:vss(75)"
				( attribute "PN" "42"
					( Origin gPackager )
				)
				( objectStatus "J9L1.42" )
			)
			( pin "@baseboard_fab2_lib.baseboard_fab2(sch_1):page88_i25:vss(76)"
				( attribute "PN" "39"
					( Origin gPackager )
				)
				( objectStatus "J9L1.39" )
			)
			( pin "@baseboard_fab2_lib.baseboard_fab2(sch_1):page88_i25:vss(77)"
				( attribute "PN" "37"
					( Origin gPackager )
				)
				( objectStatus "J9L1.37" )
			)
			( pin "@baseboard_fab2_lib.baseboard_fab2(sch_1):page88_i25:vss(78)"
				( attribute "PN" "35"
					( Origin gPackager )
				)
				( objectStatus "J9L1.35" )
			)
			( pin "@baseboard_fab2_lib.baseboard_fab2(sch_1):page88_i25:vss(79)"
				( attribute "PN" "33"
					( Origin gPackager )
				)
				( objectStatus "J9L1.33" )
			)
			( pin "@baseboard_fab2_lib.baseboard_fab2(sch_1):page88_i25:vss(80)"
				( attribute "PN" "31"
					( Origin gPackager )
				)
				( objectStatus "J9L1.31" )
			)
			( pin "@baseboard_fab2_lib.baseboard_fab2(sch_1):page88_i25:vss(81)"
				( attribute "PN" "28"
					( Origin gPackager )
				)
				( objectStatus "J9L1.28" )
			)
			( pin "@baseboard_fab2_lib.baseboard_fab2(sch_1):page88_i25:vss(82)"
				( attribute "PN" "26"
					( Origin gPackager )
				)
				( objectStatus "J9L1.26" )
			)
			( pin "@baseboard_fab2_lib.baseboard_fab2(sch_1):page88_i25:vss(83)"
				( attribute "PN" "24"
					( Origin gPackager )
				)
				( objectStatus "J9L1.24" )
			)
			( pin "@baseboard_fab2_lib.baseboard_fab2(sch_1):page88_i25:vss(84)"
				( attribute "PN" "22"
					( Origin gPackager )
				)
				( objectStatus "J9L1.22" )
			)
			( pin "@baseboard_fab2_lib.baseboard_fab2(sch_1):page88_i25:vss(85)"
				( attribute "PN" "20"
					( Origin gPackager )
				)
				( objectStatus "J9L1.20" )
			)
			( pin "@baseboard_fab2_lib.baseboard_fab2(sch_1):page88_i25:vss(86)"
				( attribute "PN" "17"
					( Origin gPackager )
				)
				( objectStatus "J9L1.17" )
			)
			( pin "@baseboard_fab2_lib.baseboard_fab2(sch_1):page88_i25:vss(87)"
				( attribute "PN" "15"
					( Origin gPackager )
				)
				( objectStatus "J9L1.15" )
			)
			( pin "@baseboard_fab2_lib.baseboard_fab2(sch_1):page88_i25:vss(88)"
				( attribute "PN" "13"
					( Origin gPackager )
				)
				( objectStatus "J9L1.13" )
			)
			( pin "@baseboard_fab2_lib.baseboard_fab2(sch_1):page88_i25:vss(89)"
				( attribute "PN" "11"
					( Origin gPackager )
				)
				( objectStatus "J9L1.11" )
			)
			( pin "@baseboard_fab2_lib.baseboard_fab2(sch_1):page88_i25:vss(90)"
				( attribute "PN" "9"
					( Origin gPackager )
				)
				( objectStatus "J9L1.9" )
			)
			( pin "@baseboard_fab2_lib.baseboard_fab2(sch_1):page88_i25:vss(91)"
				( attribute "PN" "6"
					( Origin gPackager )
				)
				( objectStatus "J9L1.6" )
			)
			( pin "@baseboard_fab2_lib.baseboard_fab2(sch_1):page88_i25:vss(92)"
				( attribute "PN" "4"
					( Origin gPackager )
				)
				( objectStatus "J9L1.4" )
			)
			( pin "@baseboard_fab2_lib.baseboard_fab2(sch_1):page88_i25:vss(93)"
				( attribute "PN" "2"
					( Origin gPackager )
				)
				( objectStatus "J9L1.2" )
			)
			( pin "@baseboard_fab2_lib.baseboard_fab2(sch_1):page88_i87:dqs0n"
				( attribute "PN" "152"
					( Origin gPackager )
				)
				( objectStatus "J9L1.152" )
			)
			( pin "@baseboard_fab2_lib.baseboard_fab2(sch_1):page88_i87:dqs0p"
				( attribute "PN" "153"
					( Origin gPackager )
				)
				( objectStatus "J9L1.153" )
			)
			( pin "@baseboard_fab2_lib.baseboard_fab2(sch_1):page88_i87:dqs1n"
				( attribute "PN" "163"
					( Origin gPackager )
				)
				( objectStatus "J9L1.163" )
			)
			( pin "@baseboard_fab2_lib.baseboard_fab2(sch_1):page88_i87:dqs1p"
				( attribute "PN" "164"
					( Origin gPackager )
				)
				( objectStatus "J9L1.164" )
			)
			( pin "@baseboard_fab2_lib.baseboard_fab2(sch_1):page88_i87:dqs2n"
				( attribute "PN" "174"
					( Origin gPackager )
				)
				( objectStatus "J9L1.174" )
			)
			( pin "@baseboard_fab2_lib.baseboard_fab2(sch_1):page88_i87:dqs2p"
				( attribute "PN" "175"
					( Origin gPackager )
				)
				( objectStatus "J9L1.175" )
			)
			( pin "@baseboard_fab2_lib.baseboard_fab2(sch_1):page88_i87:dqs3n"
				( attribute "PN" "185"
					( Origin gPackager )
				)
				( objectStatus "J9L1.185" )
			)
			( pin "@baseboard_fab2_lib.baseboard_fab2(sch_1):page88_i87:dqs3p"
				( attribute "PN" "186"
					( Origin gPackager )
				)
				( objectStatus "J9L1.186" )
			)
			( pin "@baseboard_fab2_lib.baseboard_fab2(sch_1):page88_i87:dqs4n"
				( attribute "PN" "244"
					( Origin gPackager )
				)
				( objectStatus "J9L1.244" )
			)
			( pin "@baseboard_fab2_lib.baseboard_fab2(sch_1):page88_i87:dqs4p"
				( attribute "PN" "245"
					( Origin gPackager )
				)
				( objectStatus "J9L1.245" )
			)
			( pin "@baseboard_fab2_lib.baseboard_fab2(sch_1):page88_i87:dqs5n"
				( attribute "PN" "255"
					( Origin gPackager )
				)
				( objectStatus "J9L1.255" )
			)
			( pin "@baseboard_fab2_lib.baseboard_fab2(sch_1):page88_i87:dqs5p"
				( attribute "PN" "256"
					( Origin gPackager )
				)
				( objectStatus "J9L1.256" )
			)
			( pin "@baseboard_fab2_lib.baseboard_fab2(sch_1):page88_i87:dqs6n"
				( attribute "PN" "266"
					( Origin gPackager )
				)
				( objectStatus "J9L1.266" )
			)
			( pin "@baseboard_fab2_lib.baseboard_fab2(sch_1):page88_i87:dqs6p"
				( attribute "PN" "267"
					( Origin gPackager )
				)
				( objectStatus "J9L1.267" )
			)
			( pin "@baseboard_fab2_lib.baseboard_fab2(sch_1):page88_i87:dqs7n"
				( attribute "PN" "277"
					( Origin gPackager )
				)
				( objectStatus "J9L1.277" )
			)
			( pin "@baseboard_fab2_lib.baseboard_fab2(sch_1):page88_i87:dqs7p"
				( attribute "PN" "278"
					( Origin gPackager )
				)
				( objectStatus "J9L1.278" )
			)
			( pin "@baseboard_fab2_lib.baseboard_fab2(sch_1):page88_i87:dqs8n"
				( attribute "PN" "196"
					( Origin gPackager )
				)
				( objectStatus "J9L1.196" )
			)
			( pin "@baseboard_fab2_lib.baseboard_fab2(sch_1):page88_i87:dqs8p"
				( attribute "PN" "197"
					( Origin gPackager )
				)
				( objectStatus "J9L1.197" )
			)
			( pin "@baseboard_fab2_lib.baseboard_fab2(sch_1):page88_i87:dqs9n"
				( attribute "PN" "8"
					( Origin gPackager )
				)
				( objectStatus "J9L1.8" )
			)
			( pin "@baseboard_fab2_lib.baseboard_fab2(sch_1):page88_i87:dqs9p"
				( attribute "PN" "7"
					( Origin gPackager )
				)
				( objectStatus "J9L1.7" )
			)
			( pin "@baseboard_fab2_lib.baseboard_fab2(sch_1):page88_i87:dqs10n"
				( attribute "PN" "19"
					( Origin gPackager )
				)
				( objectStatus "J9L1.19" )
			)
			( pin "@baseboard_fab2_lib.baseboard_fab2(sch_1):page88_i87:dqs10p"
				( attribute "PN" "18"
					( Origin gPackager )
				)
				( objectStatus "J9L1.18" )
			)
			( pin "@baseboard_fab2_lib.baseboard_fab2(sch_1):page88_i87:dqs11n"
				( attribute "PN" "30"
					( Origin gPackager )
				)
				( objectStatus "J9L1.30" )
			)
			( pin "@baseboard_fab2_lib.baseboard_fab2(sch_1):page88_i87:dqs11p"
				( attribute "PN" "29"
					( Origin gPackager )
				)
				( objectStatus "J9L1.29" )
			)
			( pin "@baseboard_fab2_lib.baseboard_fab2(sch_1):page88_i87:dqs12n"
				( attribute "PN" "41"
					( Origin gPackager )
				)
				( objectStatus "J9L1.41" )
			)
			( pin "@baseboard_fab2_lib.baseboard_fab2(sch_1):page88_i87:dqs12p"
				( attribute "PN" "40"
					( Origin gPackager )
				)
				( objectStatus "J9L1.40" )
			)
			( pin "@baseboard_fab2_lib.baseboard_fab2(sch_1):page88_i87:dqs13n"
				( attribute "PN" "100"
					( Origin gPackager )
				)
				( objectStatus "J9L1.100" )
			)
			( pin "@baseboard_fab2_lib.baseboard_fab2(sch_1):page88_i87:dqs13p"
				( attribute "PN" "99"
					( Origin gPackager )
				)
				( objectStatus "J9L1.99" )
			)
			( pin "@baseboard_fab2_lib.baseboard_fab2(sch_1):page88_i87:dqs14n"
				( attribute "PN" "111"
					( Origin gPackager )
				)
				( objectStatus "J9L1.111" )
			)
			( pin "@baseboard_fab2_lib.baseboard_fab2(sch_1):page88_i87:dqs14p"
				( attribute "PN" "110"
					( Origin gPackager )
				)
				( objectStatus "J9L1.110" )
			)
			( pin "@baseboard_fab2_lib.baseboard_fab2(sch_1):page88_i87:dqs15n"
				( attribute "PN" "122"
					( Origin gPackager )
				)
				( objectStatus "J9L1.122" )
			)
			( pin "@baseboard_fab2_lib.baseboard_fab2(sch_1):page88_i87:dqs15p"
				( attribute "PN" "121"
					( Origin gPackager )
				)
				( objectStatus "J9L1.121" )
			)
			( pin "@baseboard_fab2_lib.baseboard_fab2(sch_1):page88_i87:dqs16n"
				( attribute "PN" "133"
					( Origin gPackager )
				)
				( objectStatus "J9L1.133" )
			)
			( pin "@baseboard_fab2_lib.baseboard_fab2(sch_1):page88_i87:dqs16p"
				( attribute "PN" "132"
					( Origin gPackager )
				)
				( objectStatus "J9L1.132" )
			)
			( pin "@baseboard_fab2_lib.baseboard_fab2(sch_1):page88_i87:dqs17n"
				( attribute "PN" "52"
					( Origin gPackager )
				)
				( objectStatus "J9L1.52" )
			)
			( pin "@baseboard_fab2_lib.baseboard_fab2(sch_1):page88_i87:dqs17p"
				( attribute "PN" "51"
					( Origin gPackager )
				)
				( objectStatus "J9L1.51" )
			)
			( pin "@baseboard_fab2_lib.baseboard_fab2(sch_1):page88_i111:a0"
				( attribute "PN" "79"
					( Origin gPackager )
				)
				( objectStatus "J9L1.79" )
			)
			( pin "@baseboard_fab2_lib.baseboard_fab2(sch_1):page88_i111:a1"
				( attribute "PN" "72"
					( Origin gPackager )
				)
				( objectStatus "J9L1.72" )
			)
			( pin "@baseboard_fab2_lib.baseboard_fab2(sch_1):page88_i111:a2"
				( attribute "PN" "216"
					( Origin gPackager )
				)
				( objectStatus "J9L1.216" )
			)
			( pin "@baseboard_fab2_lib.baseboard_fab2(sch_1):page88_i111:a3"
				( attribute "PN" "71"
					( Origin gPackager )
				)
				( objectStatus "J9L1.71" )
			)
			( pin "@baseboard_fab2_lib.baseboard_fab2(sch_1):page88_i111:a4"
				( attribute "PN" "214"
					( Origin gPackager )
				)
				( objectStatus "J9L1.214" )
			)
			( pin "@baseboard_fab2_lib.baseboard_fab2(sch_1):page88_i111:a5"
				( attribute "PN" "213"
					( Origin gPackager )
				)
				( objectStatus "J9L1.213" )
			)
			( pin "@baseboard_fab2_lib.baseboard_fab2(sch_1):page88_i111:a6"
				( attribute "PN" "69"
					( Origin gPackager )
				)
				( objectStatus "J9L1.69" )
			)
			( pin "@baseboard_fab2_lib.baseboard_fab2(sch_1):page88_i111:a7"
				( attribute "PN" "211"
					( Origin gPackager )
				)
				( objectStatus "J9L1.211" )
			)
			( pin "@baseboard_fab2_lib.baseboard_fab2(sch_1):page88_i111:a8"
				( attribute "PN" "68"
					( Origin gPackager )
				)
				( objectStatus "J9L1.68" )
			)
			( pin "@baseboard_fab2_lib.baseboard_fab2(sch_1):page88_i111:a9"
				( attribute "PN" "66"
					( Origin gPackager )
				)
				( objectStatus "J9L1.66" )
			)
			( pin "@baseboard_fab2_lib.baseboard_fab2(sch_1):page88_i111:a10"
				( attribute "PN" "225"
					( Origin gPackager )
				)
				( objectStatus "J9L1.225" )
			)
			( pin "@baseboard_fab2_lib.baseboard_fab2(sch_1):page88_i111:a11"
				( attribute "PN" "210"
					( Origin gPackager )
				)
				( objectStatus "J9L1.210" )
			)
			( pin "@baseboard_fab2_lib.baseboard_fab2(sch_1):page88_i111:a12"
				( attribute "PN" "65"
					( Origin gPackager )
				)
				( objectStatus "J9L1.65" )
			)
			( pin "@baseboard_fab2_lib.baseboard_fab2(sch_1):page88_i111:a13"
				( attribute "PN" "232"
					( Origin gPackager )
				)
				( objectStatus "J9L1.232" )
			)
			( pin "@baseboard_fab2_lib.baseboard_fab2(sch_1):page88_i111:a14_we_n"
				( attribute "PN" "228"
					( Origin gPackager )
				)
				( objectStatus "J9L1.228" )
			)
			( pin "@baseboard_fab2_lib.baseboard_fab2(sch_1):page88_i111:a15_cas_n"
				( attribute "PN" "86"
					( Origin gPackager )
				)
				( objectStatus "J9L1.86" )
			)
			( pin "@baseboard_fab2_lib.baseboard_fab2(sch_1):page88_i111:a16_ras_n"
				( attribute "PN" "82"
					( Origin gPackager )
				)
				( objectStatus "J9L1.82" )
			)
			( pin "@baseboard_fab2_lib.baseboard_fab2(sch_1):page88_i111:a17"
				( attribute "PN" "234"
					( Origin gPackager )
				)
				( objectStatus "J9L1.234" )
			)
			( pin "@baseboard_fab2_lib.baseboard_fab2(sch_1):page88_i111:act_n"
				( attribute "PN" "62"
					( Origin gPackager )
				)
				( objectStatus "J9L1.62" )
			)
			( pin "@baseboard_fab2_lib.baseboard_fab2(sch_1):page88_i111:alert_n"
				( attribute "PN" "208"
					( Origin gPackager )
				)
				( objectStatus "J9L1.208" )
			)
			( pin "@baseboard_fab2_lib.baseboard_fab2(sch_1):page88_i111:ba(0)"
				( attribute "PN" "81"
					( Origin gPackager )
				)
				( objectStatus "J9L1.81" )
			)
			( pin "@baseboard_fab2_lib.baseboard_fab2(sch_1):page88_i111:ba(1)"
				( attribute "PN" "224"
					( Origin gPackager )
				)
				( objectStatus "J9L1.224" )
			)
			( pin "@baseboard_fab2_lib.baseboard_fab2(sch_1):page88_i111:bg(0)"
				( attribute "PN" "63"
					( Origin gPackager )
				)
				( objectStatus "J9L1.63" )
			)
			( pin "@baseboard_fab2_lib.baseboard_fab2(sch_1):page88_i111:bg(1)"
				( attribute "PN" "207"
					( Origin gPackager )
				)
				( objectStatus "J9L1.207" )
			)
			( pin "@baseboard_fab2_lib.baseboard_fab2(sch_1):page88_i111:c(2)"
				( attribute "PN" "235"
					( Origin gPackager )
				)
				( objectStatus "J9L1.235" )
			)
			( pin "@baseboard_fab2_lib.baseboard_fab2(sch_1):page88_i111:cb(0)"
				( attribute "PN" "49"
					( Origin gPackager )
				)
				( objectStatus "J9L1.49" )
			)
			( pin "@baseboard_fab2_lib.baseboard_fab2(sch_1):page88_i111:cb(1)"
				( attribute "PN" "194"
					( Origin gPackager )
				)
				( objectStatus "J9L1.194" )
			)
			( pin "@baseboard_fab2_lib.baseboard_fab2(sch_1):page88_i111:cb(2)"
				( attribute "PN" "56"
					( Origin gPackager )
				)
				( objectStatus "J9L1.56" )
			)
			( pin "@baseboard_fab2_lib.baseboard_fab2(sch_1):page88_i111:cb(3)"
				( attribute "PN" "201"
					( Origin gPackager )
				)
				( objectStatus "J9L1.201" )
			)
			( pin "@baseboard_fab2_lib.baseboard_fab2(sch_1):page88_i111:cb(4)"
				( attribute "PN" "47"
					( Origin gPackager )
				)
				( objectStatus "J9L1.47" )
			)
			( pin "@baseboard_fab2_lib.baseboard_fab2(sch_1):page88_i111:cb(5)"
				( attribute "PN" "192"
					( Origin gPackager )
				)
				( objectStatus "J9L1.192" )
			)
			( pin "@baseboard_fab2_lib.baseboard_fab2(sch_1):page88_i111:cb(6)"
				( attribute "PN" "54"
					( Origin gPackager )
				)
				( objectStatus "J9L1.54" )
			)
			( pin "@baseboard_fab2_lib.baseboard_fab2(sch_1):page88_i111:cb(7)"
				( attribute "PN" "199"
					( Origin gPackager )
				)
				( objectStatus "J9L1.199" )
			)
			( pin "@baseboard_fab2_lib.baseboard_fab2(sch_1):page88_i111:ck0n"
				( attribute "PN" "75"
					( Origin gPackager )
				)
				( objectStatus "J9L1.75" )
			)
			( pin "@baseboard_fab2_lib.baseboard_fab2(sch_1):page88_i111:ck0p"
				( attribute "PN" "74"
					( Origin gPackager )
				)
				( objectStatus "J9L1.74" )
			)
			( pin "@baseboard_fab2_lib.baseboard_fab2(sch_1):page88_i111:ck1n"
				( attribute "PN" "219"
					( Origin gPackager )
				)
				( objectStatus "J9L1.219" )
			)
			( pin "@baseboard_fab2_lib.baseboard_fab2(sch_1):page88_i111:ck1p"
				( attribute "PN" "218"
					( Origin gPackager )
				)
				( objectStatus "J9L1.218" )
			)
			( pin "@baseboard_fab2_lib.baseboard_fab2(sch_1):page88_i111:cke(0)"
				( attribute "PN" "60"
					( Origin gPackager )
				)
				( objectStatus "J9L1.60" )
			)
			( pin "@baseboard_fab2_lib.baseboard_fab2(sch_1):page88_i111:cke(1)"
				( attribute "PN" "203"
					( Origin gPackager )
				)
				( objectStatus "J9L1.203" )
			)
			( pin "@baseboard_fab2_lib.baseboard_fab2(sch_1):page88_i111:dq(0)"
				( attribute "PN" "5"
					( Origin gPackager )
				)
				( objectStatus "J9L1.5" )
			)
			( pin "@baseboard_fab2_lib.baseboard_fab2(sch_1):page88_i111:dq(1)"
				( attribute "PN" "150"
					( Origin gPackager )
				)
				( objectStatus "J9L1.150" )
			)
			( pin "@baseboard_fab2_lib.baseboard_fab2(sch_1):page88_i111:dq(2)"
				( attribute "PN" "12"
					( Origin gPackager )
				)
				( objectStatus "J9L1.12" )
			)
			( pin "@baseboard_fab2_lib.baseboard_fab2(sch_1):page88_i111:dq(3)"
				( attribute "PN" "157"
					( Origin gPackager )
				)
				( objectStatus "J9L1.157" )
			)
			( pin "@baseboard_fab2_lib.baseboard_fab2(sch_1):page88_i111:dq(4)"
				( attribute "PN" "3"
					( Origin gPackager )
				)
				( objectStatus "J9L1.3" )
			)
			( pin "@baseboard_fab2_lib.baseboard_fab2(sch_1):page88_i111:dq(5)"
				( attribute "PN" "148"
					( Origin gPackager )
				)
				( objectStatus "J9L1.148" )
			)
			( pin "@baseboard_fab2_lib.baseboard_fab2(sch_1):page88_i111:dq(6)"
				( attribute "PN" "10"
					( Origin gPackager )
				)
				( objectStatus "J9L1.10" )
			)
			( pin "@baseboard_fab2_lib.baseboard_fab2(sch_1):page88_i111:dq(7)"
				( attribute "PN" "155"
					( Origin gPackager )
				)
				( objectStatus "J9L1.155" )
			)
			( pin "@baseboard_fab2_lib.baseboard_fab2(sch_1):page88_i111:dq(8)"
				( attribute "PN" "16"
					( Origin gPackager )
				)
				( objectStatus "J9L1.16" )
			)
			( pin "@baseboard_fab2_lib.baseboard_fab2(sch_1):page88_i111:dq(9)"
				( attribute "PN" "161"
					( Origin gPackager )
				)
				( objectStatus "J9L1.161" )
			)
			( pin "@baseboard_fab2_lib.baseboard_fab2(sch_1):page88_i111:dq(10)"
				( attribute "PN" "23"
					( Origin gPackager )
				)
				( objectStatus "J9L1.23" )
			)
			( pin "@baseboard_fab2_lib.baseboard_fab2(sch_1):page88_i111:dq(11)"
				( attribute "PN" "168"
					( Origin gPackager )
				)
				( objectStatus "J9L1.168" )
			)
			( pin "@baseboard_fab2_lib.baseboard_fab2(sch_1):page88_i111:dq(12)"
				( attribute "PN" "14"
					( Origin gPackager )
				)
				( objectStatus "J9L1.14" )
			)
			( pin "@baseboard_fab2_lib.baseboard_fab2(sch_1):page88_i111:dq(13)"
				( attribute "PN" "159"
					( Origin gPackager )
				)
				( objectStatus "J9L1.159" )
			)
			( pin "@baseboard_fab2_lib.baseboard_fab2(sch_1):page88_i111:dq(14)"
				( attribute "PN" "21"
					( Origin gPackager )
				)
				( objectStatus "J9L1.21" )
			)
			( pin "@baseboard_fab2_lib.baseboard_fab2(sch_1):page88_i111:dq(15)"
				( attribute "PN" "166"
					( Origin gPackager )
				)
				( objectStatus "J9L1.166" )
			)
			( pin "@baseboard_fab2_lib.baseboard_fab2(sch_1):page88_i111:dq(16)"
				( attribute "PN" "27"
					( Origin gPackager )
				)
				( objectStatus "J9L1.27" )
			)
			( pin "@baseboard_fab2_lib.baseboard_fab2(sch_1):page88_i111:dq(17)"
				( attribute "PN" "172"
					( Origin gPackager )
				)
				( objectStatus "J9L1.172" )
			)
			( pin "@baseboard_fab2_lib.baseboard_fab2(sch_1):page88_i111:dq(18)"
				( attribute "PN" "34"
					( Origin gPackager )
				)
				( objectStatus "J9L1.34" )
			)
			( pin "@baseboard_fab2_lib.baseboard_fab2(sch_1):page88_i111:dq(19)"
				( attribute "PN" "179"
					( Origin gPackager )
				)
				( objectStatus "J9L1.179" )
			)
			( pin "@baseboard_fab2_lib.baseboard_fab2(sch_1):page88_i111:dq(20)"
				( attribute "PN" "25"
					( Origin gPackager )
				)
				( objectStatus "J9L1.25" )
			)
			( pin "@baseboard_fab2_lib.baseboard_fab2(sch_1):page88_i111:dq(21)"
				( attribute "PN" "170"
					( Origin gPackager )
				)
				( objectStatus "J9L1.170" )
			)
			( pin "@baseboard_fab2_lib.baseboard_fab2(sch_1):page88_i111:dq(22)"
				( attribute "PN" "32"
					( Origin gPackager )
				)
				( objectStatus "J9L1.32" )
			)
			( pin "@baseboard_fab2_lib.baseboard_fab2(sch_1):page88_i111:dq(23)"
				( attribute "PN" "177"
					( Origin gPackager )
				)
				( objectStatus "J9L1.177" )
			)
			( pin "@baseboard_fab2_lib.baseboard_fab2(sch_1):page88_i111:dq(24)"
				( attribute "PN" "38"
					( Origin gPackager )
				)
				( objectStatus "J9L1.38" )
			)
			( pin "@baseboard_fab2_lib.baseboard_fab2(sch_1):page88_i111:dq(25)"
				( attribute "PN" "183"
					( Origin gPackager )
				)
				( objectStatus "J9L1.183" )
			)
			( pin "@baseboard_fab2_lib.baseboard_fab2(sch_1):page88_i111:dq(26)"
				( attribute "PN" "45"
					( Origin gPackager )
				)
				( objectStatus "J9L1.45" )
			)
			( pin "@baseboard_fab2_lib.baseboard_fab2(sch_1):page88_i111:dq(27)"
				( attribute "PN" "190"
					( Origin gPackager )
				)
				( objectStatus "J9L1.190" )
			)
			( pin "@baseboard_fab2_lib.baseboard_fab2(sch_1):page88_i111:dq(28)"
				( attribute "PN" "36"
					( Origin gPackager )
				)
				( objectStatus "J9L1.36" )
			)
			( pin "@baseboard_fab2_lib.baseboard_fab2(sch_1):page88_i111:dq(29)"
				( attribute "PN" "181"
					( Origin gPackager )
				)
				( objectStatus "J9L1.181" )
			)
			( pin "@baseboard_fab2_lib.baseboard_fab2(sch_1):page88_i111:dq(30)"
				( attribute "PN" "43"
					( Origin gPackager )
				)
				( objectStatus "J9L1.43" )
			)
			( pin "@baseboard_fab2_lib.baseboard_fab2(sch_1):page88_i111:dq(31)"
				( attribute "PN" "188"
					( Origin gPackager )
				)
				( objectStatus "J9L1.188" )
			)
			( pin "@baseboard_fab2_lib.baseboard_fab2(sch_1):page88_i111:dq(32)"
				( attribute "PN" "97"
					( Origin gPackager )
				)
				( objectStatus "J9L1.97" )
			)
			( pin "@baseboard_fab2_lib.baseboard_fab2(sch_1):page88_i111:dq(33)"
				( attribute "PN" "242"
					( Origin gPackager )
				)
				( objectStatus "J9L1.242" )
			)
			( pin "@baseboard_fab2_lib.baseboard_fab2(sch_1):page88_i111:dq(34)"
				( attribute "PN" "104"
					( Origin gPackager )
				)
				( objectStatus "J9L1.104" )
			)
			( pin "@baseboard_fab2_lib.baseboard_fab2(sch_1):page88_i111:dq(35)"
				( attribute "PN" "249"
					( Origin gPackager )
				)
				( objectStatus "J9L1.249" )
			)
			( pin "@baseboard_fab2_lib.baseboard_fab2(sch_1):page88_i111:dq(36)"
				( attribute "PN" "95"
					( Origin gPackager )
				)
				( objectStatus "J9L1.95" )
			)
			( pin "@baseboard_fab2_lib.baseboard_fab2(sch_1):page88_i111:dq(37)"
				( attribute "PN" "240"
					( Origin gPackager )
				)
				( objectStatus "J9L1.240" )
			)
			( pin "@baseboard_fab2_lib.baseboard_fab2(sch_1):page88_i111:dq(38)"
				( attribute "PN" "102"
					( Origin gPackager )
				)
				( objectStatus "J9L1.102" )
			)
			( pin "@baseboard_fab2_lib.baseboard_fab2(sch_1):page88_i111:dq(39)"
				( attribute "PN" "247"
					( Origin gPackager )
				)
				( objectStatus "J9L1.247" )
			)
			( pin "@baseboard_fab2_lib.baseboard_fab2(sch_1):page88_i111:dq(40)"
				( attribute "PN" "108"
					( Origin gPackager )
				)
				( objectStatus "J9L1.108" )
			)
			( pin "@baseboard_fab2_lib.baseboard_fab2(sch_1):page88_i111:dq(41)"
				( attribute "PN" "253"
					( Origin gPackager )
				)
				( objectStatus "J9L1.253" )
			)
			( pin "@baseboard_fab2_lib.baseboard_fab2(sch_1):page88_i111:dq(42)"
				( attribute "PN" "115"
					( Origin gPackager )
				)
				( objectStatus "J9L1.115" )
			)
			( pin "@baseboard_fab2_lib.baseboard_fab2(sch_1):page88_i111:dq(43)"
				( attribute "PN" "260"
					( Origin gPackager )
				)
				( objectStatus "J9L1.260" )
			)
			( pin "@baseboard_fab2_lib.baseboard_fab2(sch_1):page88_i111:dq(44)"
				( attribute "PN" "106"
					( Origin gPackager )
				)
				( objectStatus "J9L1.106" )
			)
			( pin "@baseboard_fab2_lib.baseboard_fab2(sch_1):page88_i111:dq(45)"
				( attribute "PN" "251"
					( Origin gPackager )
				)
				( objectStatus "J9L1.251" )
			)
			( pin "@baseboard_fab2_lib.baseboard_fab2(sch_1):page88_i111:dq(46)"
				( attribute "PN" "113"
					( Origin gPackager )
				)
				( objectStatus "J9L1.113" )
			)
			( pin "@baseboard_fab2_lib.baseboard_fab2(sch_1):page88_i111:dq(47)"
				( attribute "PN" "258"
					( Origin gPackager )
				)
				( objectStatus "J9L1.258" )
			)
			( pin "@baseboard_fab2_lib.baseboard_fab2(sch_1):page88_i111:dq(48)"
				( attribute "PN" "119"
					( Origin gPackager )
				)
				( objectStatus "J9L1.119" )
			)
			( pin "@baseboard_fab2_lib.baseboard_fab2(sch_1):page88_i111:dq(49)"
				( attribute "PN" "264"
					( Origin gPackager )
				)
				( objectStatus "J9L1.264" )
			)
			( pin "@baseboard_fab2_lib.baseboard_fab2(sch_1):page88_i111:dq(50)"
				( attribute "PN" "126"
					( Origin gPackager )
				)
				( objectStatus "J9L1.126" )
			)
			( pin "@baseboard_fab2_lib.baseboard_fab2(sch_1):page88_i111:dq(51)"
				( attribute "PN" "271"
					( Origin gPackager )
				)
				( objectStatus "J9L1.271" )
			)
			( pin "@baseboard_fab2_lib.baseboard_fab2(sch_1):page88_i111:dq(52)"
				( attribute "PN" "117"
					( Origin gPackager )
				)
				( objectStatus "J9L1.117" )
			)
			( pin "@baseboard_fab2_lib.baseboard_fab2(sch_1):page88_i111:dq(53)"
				( attribute "PN" "262"
					( Origin gPackager )
				)
				( objectStatus "J9L1.262" )
			)
			( pin "@baseboard_fab2_lib.baseboard_fab2(sch_1):page88_i111:dq(54)"
				( attribute "PN" "124"
					( Origin gPackager )
				)
				( objectStatus "J9L1.124" )
			)
			( pin "@baseboard_fab2_lib.baseboard_fab2(sch_1):page88_i111:dq(55)"
				( attribute "PN" "269"
					( Origin gPackager )
				)
				( objectStatus "J9L1.269" )
			)
			( pin "@baseboard_fab2_lib.baseboard_fab2(sch_1):page88_i111:dq(56)"
				( attribute "PN" "130"
					( Origin gPackager )
				)
				( objectStatus "J9L1.130" )
			)
			( pin "@baseboard_fab2_lib.baseboard_fab2(sch_1):page88_i111:dq(57)"
				( attribute "PN" "275"
					( Origin gPackager )
				)
				( objectStatus "J9L1.275" )
			)
			( pin "@baseboard_fab2_lib.baseboard_fab2(sch_1):page88_i111:dq(58)"
				( attribute "PN" "137"
					( Origin gPackager )
				)
				( objectStatus "J9L1.137" )
			)
			( pin "@baseboard_fab2_lib.baseboard_fab2(sch_1):page88_i111:dq(59)"
				( attribute "PN" "282"
					( Origin gPackager )
				)
				( objectStatus "J9L1.282" )
			)
			( pin "@baseboard_fab2_lib.baseboard_fab2(sch_1):page88_i111:dq(60)"
				( attribute "PN" "128"
					( Origin gPackager )
				)
				( objectStatus "J9L1.128" )
			)
			( pin "@baseboard_fab2_lib.baseboard_fab2(sch_1):page88_i111:dq(61)"
				( attribute "PN" "273"
					( Origin gPackager )
				)
				( objectStatus "J9L1.273" )
			)
			( pin "@baseboard_fab2_lib.baseboard_fab2(sch_1):page88_i111:dq(62)"
				( attribute "PN" "135"
					( Origin gPackager )
				)
				( objectStatus "J9L1.135" )
			)
			( pin "@baseboard_fab2_lib.baseboard_fab2(sch_1):page88_i111:dq(63)"
				( attribute "PN" "280"
					( Origin gPackager )
				)
				( objectStatus "J9L1.280" )
			)
			( pin "@baseboard_fab2_lib.baseboard_fab2(sch_1):page88_i111:event_n"
				( attribute "PN" "78"
					( Origin gPackager )
				)
				( objectStatus "J9L1.78" )
			)
			( pin "@baseboard_fab2_lib.baseboard_fab2(sch_1):page88_i111:odt(0)"
				( attribute "PN" "87"
					( Origin gPackager )
				)
				( objectStatus "J9L1.87" )
			)
			( pin "@baseboard_fab2_lib.baseboard_fab2(sch_1):page88_i111:odt(1)"
				( attribute "PN" "91"
					( Origin gPackager )
				)
				( objectStatus "J9L1.91" )
			)
			( pin "@baseboard_fab2_lib.baseboard_fab2(sch_1):page88_i111:par"
				( attribute "PN" "222"
					( Origin gPackager )
				)
				( objectStatus "J9L1.222" )
			)
			( pin "@baseboard_fab2_lib.baseboard_fab2(sch_1):page88_i111:reset_n"
				( attribute "PN" "58"
					( Origin gPackager )
				)
				( objectStatus "J9L1.58" )
			)
			( pin "@baseboard_fab2_lib.baseboard_fab2(sch_1):page88_i111:rfu(0)"
				( attribute "PN" "205"
					( Origin gPackager )
				)
				( objectStatus "J9L1.205" )
			)
			( pin "@baseboard_fab2_lib.baseboard_fab2(sch_1):page88_i111:rfu(1)"
				( attribute "PN" "227"
					( Origin gPackager )
				)
				( objectStatus "J9L1.227" )
			)
			( pin "@baseboard_fab2_lib.baseboard_fab2(sch_1):page88_i111:rfu(2)"
				( attribute "PN" "144"
					( Origin gPackager )
				)
				( objectStatus "J9L1.144" )
			)
			( pin "@baseboard_fab2_lib.baseboard_fab2(sch_1):page88_i111:s0_n"
				( attribute "PN" "84"
					( Origin gPackager )
				)
				( objectStatus "J9L1.84" )
			)
			( pin "@baseboard_fab2_lib.baseboard_fab2(sch_1):page88_i111:s1_n"
				( attribute "PN" "89"
					( Origin gPackager )
				)
				( objectStatus "J9L1.89" )
			)
			( pin "@baseboard_fab2_lib.baseboard_fab2(sch_1):page88_i111:s2_n_c(0)"
				( attribute "PN" "93"
					( Origin gPackager )
				)
				( objectStatus "J9L1.93" )
			)
			( pin "@baseboard_fab2_lib.baseboard_fab2(sch_1):page88_i111:s3_n_c(1)"
				( attribute "PN" "237"
					( Origin gPackager )
				)
				( objectStatus "J9L1.237" )
			)
			( pin "@baseboard_fab2_lib.baseboard_fab2(sch_1):page88_i111:sa(0)"
				( attribute "PN" "139"
					( Origin gPackager )
				)
				( objectStatus "J9L1.139" )
			)
			( pin "@baseboard_fab2_lib.baseboard_fab2(sch_1):page88_i111:sa(1)"
				( attribute "PN" "140"
					( Origin gPackager )
				)
				( objectStatus "J9L1.140" )
			)
			( pin "@baseboard_fab2_lib.baseboard_fab2(sch_1):page88_i111:sa(2)"
				( attribute "PN" "238"
					( Origin gPackager )
				)
				( objectStatus "J9L1.238" )
			)
			( pin "@baseboard_fab2_lib.baseboard_fab2(sch_1):page88_i111:save_n_nc"
				( attribute "PN" "230"
					( Origin gPackager )
				)
				( objectStatus "J9L1.230" )
			)
			( pin "@baseboard_fab2_lib.baseboard_fab2(sch_1):page88_i111:scl"
				( attribute "PN" "141"
					( Origin gPackager )
				)
				( objectStatus "J9L1.141" )
			)
			( pin "@baseboard_fab2_lib.baseboard_fab2(sch_1):page88_i111:sda"
				( attribute "PN" "285"
					( Origin gPackager )
				)
				( objectStatus "J9L1.285" )
			)
			( pin "@baseboard_fab2_lib.baseboard_fab2(sch_1):page88_i111:vddspd"
				( attribute "PN" "284"
					( Origin gPackager )
				)
				( objectStatus "J9L1.284" )
			)
			( pin "@baseboard_fab2_lib.baseboard_fab2(sch_1):page88_i111:vrefca"
				( attribute "PN" "146"
					( Origin gPackager )
				)
				( objectStatus "J9L1.146" )
			)
			( pin "@baseboard_fab2_lib.baseboard_fab2(sch_1):page88_i168:\12v\(0)"
				( attribute "PN" "145"
					( Origin gPackager )
				)
				( objectStatus "J9L1.145" )
			)
			( pin "@baseboard_fab2_lib.baseboard_fab2(sch_1):page88_i168:\12v\(1)"
				( attribute "PN" "1"
					( Origin gPackager )
				)
				( objectStatus "J9L1.1" )
			)
			( pin "@baseboard_fab2_lib.baseboard_fab2(sch_1):page88_i168:vdd(0)"
				( attribute "PN" "236"
					( Origin gPackager )
				)
				( objectStatus "J9L1.236" )
			)
			( pin "@baseboard_fab2_lib.baseboard_fab2(sch_1):page88_i168:vdd(1)"
				( attribute "PN" "233"
					( Origin gPackager )
				)
				( objectStatus "J9L1.233" )
			)
			( pin "@baseboard_fab2_lib.baseboard_fab2(sch_1):page88_i168:vdd(2)"
				( attribute "PN" "231"
					( Origin gPackager )
				)
				( objectStatus "J9L1.231" )
			)
			( pin "@baseboard_fab2_lib.baseboard_fab2(sch_1):page88_i168:vdd(3)"
				( attribute "PN" "229"
					( Origin gPackager )
				)
				( objectStatus "J9L1.229" )
			)
			( pin "@baseboard_fab2_lib.baseboard_fab2(sch_1):page88_i168:vdd(4)"
				( attribute "PN" "226"
					( Origin gPackager )
				)
				( objectStatus "J9L1.226" )
			)
			( pin "@baseboard_fab2_lib.baseboard_fab2(sch_1):page88_i168:vdd(5)"
				( attribute "PN" "223"
					( Origin gPackager )
				)
				( objectStatus "J9L1.223" )
			)
			( pin "@baseboard_fab2_lib.baseboard_fab2(sch_1):page88_i168:vdd(6)"
				( attribute "PN" "220"
					( Origin gPackager )
				)
				( objectStatus "J9L1.220" )
			)
			( pin "@baseboard_fab2_lib.baseboard_fab2(sch_1):page88_i168:vdd(7)"
				( attribute "PN" "217"
					( Origin gPackager )
				)
				( objectStatus "J9L1.217" )
			)
			( pin "@baseboard_fab2_lib.baseboard_fab2(sch_1):page88_i168:vdd(8)"
				( attribute "PN" "215"
					( Origin gPackager )
				)
				( objectStatus "J9L1.215" )
			)
			( pin "@baseboard_fab2_lib.baseboard_fab2(sch_1):page88_i168:vdd(9)"
				( attribute "PN" "212"
					( Origin gPackager )
				)
				( objectStatus "J9L1.212" )
			)
			( pin "@baseboard_fab2_lib.baseboard_fab2(sch_1):page88_i168:vdd(10)"
				( attribute "PN" "209"
					( Origin gPackager )
				)
				( objectStatus "J9L1.209" )
			)
			( pin "@baseboard_fab2_lib.baseboard_fab2(sch_1):page88_i168:vdd(11)"
				( attribute "PN" "206"
					( Origin gPackager )
				)
				( objectStatus "J9L1.206" )
			)
			( pin "@baseboard_fab2_lib.baseboard_fab2(sch_1):page88_i168:vdd(12)"
				( attribute "PN" "204"
					( Origin gPackager )
				)
				( objectStatus "J9L1.204" )
			)
			( pin "@baseboard_fab2_lib.baseboard_fab2(sch_1):page88_i168:vdd(13)"
				( attribute "PN" "92"
					( Origin gPackager )
				)
				( objectStatus "J9L1.92" )
			)
			( pin "@baseboard_fab2_lib.baseboard_fab2(sch_1):page88_i168:vdd(14)"
				( attribute "PN" "90"
					( Origin gPackager )
				)
				( objectStatus "J9L1.90" )
			)
			( pin "@baseboard_fab2_lib.baseboard_fab2(sch_1):page88_i168:vdd(15)"
				( attribute "PN" "88"
					( Origin gPackager )
				)
				( objectStatus "J9L1.88" )
			)
			( pin "@baseboard_fab2_lib.baseboard_fab2(sch_1):page88_i168:vdd(16)"
				( attribute "PN" "85"
					( Origin gPackager )
				)
				( objectStatus "J9L1.85" )
			)
			( pin "@baseboard_fab2_lib.baseboard_fab2(sch_1):page88_i168:vdd(17)"
				( attribute "PN" "83"
					( Origin gPackager )
				)
				( objectStatus "J9L1.83" )
			)
			( pin "@baseboard_fab2_lib.baseboard_fab2(sch_1):page88_i168:vdd(18)"
				( attribute "PN" "80"
					( Origin gPackager )
				)
				( objectStatus "J9L1.80" )
			)
			( pin "@baseboard_fab2_lib.baseboard_fab2(sch_1):page88_i168:vdd(19)"
				( attribute "PN" "76"
					( Origin gPackager )
				)
				( objectStatus "J9L1.76" )
			)
			( pin "@baseboard_fab2_lib.baseboard_fab2(sch_1):page88_i168:vdd(20)"
				( attribute "PN" "73"
					( Origin gPackager )
				)
				( objectStatus "J9L1.73" )
			)
			( pin "@baseboard_fab2_lib.baseboard_fab2(sch_1):page88_i168:vdd(21)"
				( attribute "PN" "70"
					( Origin gPackager )
				)
				( objectStatus "J9L1.70" )
			)
			( pin "@baseboard_fab2_lib.baseboard_fab2(sch_1):page88_i168:vdd(22)"
				( attribute "PN" "67"
					( Origin gPackager )
				)
				( objectStatus "J9L1.67" )
			)
			( pin "@baseboard_fab2_lib.baseboard_fab2(sch_1):page88_i168:vdd(23)"
				( attribute "PN" "64"
					( Origin gPackager )
				)
				( objectStatus "J9L1.64" )
			)
			( pin "@baseboard_fab2_lib.baseboard_fab2(sch_1):page88_i168:vdd(24)"
				( attribute "PN" "61"
					( Origin gPackager )
				)
				( objectStatus "J9L1.61" )
			)
			( pin "@baseboard_fab2_lib.baseboard_fab2(sch_1):page88_i168:vdd(25)"
				( attribute "PN" "59"
					( Origin gPackager )
				)
				( objectStatus "J9L1.59" )
			)
			( pin "@baseboard_fab2_lib.baseboard_fab2(sch_1):page88_i168:vpp(0)"
				( attribute "PN" "287"
					( Origin gPackager )
				)
				( objectStatus "J9L1.287" )
			)
			( pin "@baseboard_fab2_lib.baseboard_fab2(sch_1):page88_i168:vpp(1)"
				( attribute "PN" "286"
					( Origin gPackager )
				)
				( objectStatus "J9L1.286" )
			)
			( pin "@baseboard_fab2_lib.baseboard_fab2(sch_1):page88_i168:vpp(2)"
				( attribute "PN" "288"
					( Origin gPackager )
				)
				( objectStatus "J9L1.288" )
			)
			( pin "@baseboard_fab2_lib.baseboard_fab2(sch_1):page88_i168:vpp(3)"
				( attribute "PN" "143"
					( Origin gPackager )
				)
				( objectStatus "J9L1.143" )
			)
			( pin "@baseboard_fab2_lib.baseboard_fab2(sch_1):page88_i168:vpp(4)"
				( attribute "PN" "142"
					( Origin gPackager )
				)
				( objectStatus "J9L1.142" )
			)
			( pin "@baseboard_fab2_lib.baseboard_fab2(sch_1):page88_i168:vtt(0)"
				( attribute "PN" "221"
					( Origin gPackager )
				)
				( objectStatus "J9L1.221" )
			)
			( pin "@baseboard_fab2_lib.baseboard_fab2(sch_1):page88_i168:vtt(1)"
				( attribute "PN" "77"
					( Origin gPackager )
				)
				( objectStatus "J9L1.77" )
			)
			( pin "@baseboard_fab2_lib.baseboard_fab2(sch_1):page88_i177:a"
				( attribute "PN" "1"
					( Origin gPackager )
				)
				( objectStatus "C9L1.1" )
			)
			( pin "@baseboard_fab2_lib.baseboard_fab2(sch_1):page88_i177:b"
				( attribute "PN" "2"
					( Origin gPackager )
				)
				( objectStatus "C9L1.2" )
			)
			( pin "@baseboard_fab2_lib.baseboard_fab2(sch_1):page89_i1:a"
				( attribute "PN" "1"
					( Origin gPackager )
				)
				( objectStatus "R4T2.1" )
			)
			( pin "@baseboard_fab2_lib.baseboard_fab2(sch_1):page89_i1:b"
				( attribute "PN" "2"
					( Origin gPackager )
				)
				( objectStatus "R4T2.2" )
			)
			( pin "@baseboard_fab2_lib.baseboard_fab2(sch_1):page89_i2:a"
				( attribute "PN" "1"
					( Origin gPackager )
				)
				( objectStatus "R4T1.1" )
			)
			( pin "@baseboard_fab2_lib.baseboard_fab2(sch_1):page89_i2:b"
				( attribute "PN" "2"
					( Origin gPackager )
				)
				( objectStatus "R4T1.2" )
			)
			( pin "@baseboard_fab2_lib.baseboard_fab2(sch_1):page89_i3:a"
				( attribute "PN" "1"
					( Origin gPackager )
				)
				( objectStatus "R6F4.1" )
			)
			( pin "@baseboard_fab2_lib.baseboard_fab2(sch_1):page89_i3:b"
				( attribute "PN" "2"
					( Origin gPackager )
				)
				( objectStatus "R6F4.2" )
			)
			( pin "@baseboard_fab2_lib.baseboard_fab2(sch_1):page89_i4:a"
				( attribute "PN" "1"
					( Origin gPackager )
				)
				( objectStatus "R6F1.1" )
			)
			( pin "@baseboard_fab2_lib.baseboard_fab2(sch_1):page89_i4:b"
				( attribute "PN" "2"
					( Origin gPackager )
				)
				( objectStatus "R6F1.2" )
			)
			( pin "@baseboard_fab2_lib.baseboard_fab2(sch_1):page89_i5:a"
				( attribute "PN" "1"
					( Origin gPackager )
				)
				( objectStatus "R6F5.1" )
			)
			( pin "@baseboard_fab2_lib.baseboard_fab2(sch_1):page89_i5:b"
				( attribute "PN" "2"
					( Origin gPackager )
				)
				( objectStatus "R6F5.2" )
			)
			( pin "@baseboard_fab2_lib.baseboard_fab2(sch_1):page89_i6:a"
				( attribute "PN" "1"
					( Origin gPackager )
				)
				( objectStatus "R6F2.1" )
			)
			( pin "@baseboard_fab2_lib.baseboard_fab2(sch_1):page89_i6:b"
				( attribute "PN" "2"
					( Origin gPackager )
				)
				( objectStatus "R6F2.2" )
			)
			( pin "@baseboard_fab2_lib.baseboard_fab2(sch_1):page89_i7:a"
				( attribute "PN" "1"
					( Origin gPackager )
				)
				( objectStatus "R6F3.1" )
			)
			( pin "@baseboard_fab2_lib.baseboard_fab2(sch_1):page89_i7:b"
				( attribute "PN" "2"
					( Origin gPackager )
				)
				( objectStatus "R6F3.2" )
			)
			( pin "@baseboard_fab2_lib.baseboard_fab2(sch_1):page196_i129:drn"
				( attribute "PN" "3"
					( Origin gPackager )
				)
				( objectStatus "Q1P2.3" )
			)
			( pin "@baseboard_fab2_lib.baseboard_fab2(sch_1):page196_i129:gate"
				( attribute "PN" "1"
					( Origin gPackager )
				)
				( objectStatus "Q1P2.1" )
			)
			( pin "@baseboard_fab2_lib.baseboard_fab2(sch_1):page196_i129:src"
				( attribute "PN" "2"
					( Origin gPackager )
				)
				( objectStatus "Q1P2.2" )
			)
			( pin "@baseboard_fab2_lib.baseboard_fab2(sch_1):page89_i23:a"
				( attribute "PN" "1"
					( Origin gPackager )
				)
				( objectStatus "R2P12.1" )
			)
			( pin "@baseboard_fab2_lib.baseboard_fab2(sch_1):page89_i23:b"
				( attribute "PN" "2"
					( Origin gPackager )
				)
				( objectStatus "R2P12.2" )
			)
			( pin "@baseboard_fab2_lib.baseboard_fab2(sch_1):page89_i26:a"
				( attribute "PN" "1"
					( Origin gPackager )
				)
				( objectStatus "R8D29.1" )
			)
			( pin "@baseboard_fab2_lib.baseboard_fab2(sch_1):page89_i26:b"
				( attribute "PN" "2"
					( Origin gPackager )
				)
				( objectStatus "R8D29.2" )
			)
			( pin "@baseboard_fab2_lib.baseboard_fab2(sch_1):page89_i27:a"
				( attribute "PN" "1"
					( Origin gPackager )
				)
				( objectStatus "R8D31.1" )
			)
			( pin "@baseboard_fab2_lib.baseboard_fab2(sch_1):page89_i27:b"
				( attribute "PN" "2"
					( Origin gPackager )
				)
				( objectStatus "R8D31.2" )
			)
			( pin "@baseboard_fab2_lib.baseboard_fab2(sch_1):page89_i34:a"
				( attribute "PN" "1"
					( Origin gPackager )
				)
				( objectStatus "R8D30.1" )
			)
			( pin "@baseboard_fab2_lib.baseboard_fab2(sch_1):page89_i34:b"
				( attribute "PN" "2"
					( Origin gPackager )
				)
				( objectStatus "R8D30.2" )
			)
			( pin "@baseboard_fab2_lib.baseboard_fab2(sch_1):page89_i35:b(0)"
				( attribute "PN" "5"
					( Origin gPackager )
				)
				( objectStatus "Q8D1.5" )
			)
			( pin "@baseboard_fab2_lib.baseboard_fab2(sch_1):page89_i35:c(0)"
				( attribute "PN" "3"
					( Origin gPackager )
				)
				( objectStatus "Q8D1.3" )
			)
			( pin "@baseboard_fab2_lib.baseboard_fab2(sch_1):page89_i35:e(0)"
				( attribute "PN" "4"
					( Origin gPackager )
				)
				( objectStatus "Q8D1.4" )
			)
			( pin "@baseboard_fab2_lib.baseboard_fab2(sch_1):page90_i17:a"
				( attribute "PN" "1"
					( Origin gPackager )
				)
				( objectStatus "R3D22.1" )
			)
			( pin "@baseboard_fab2_lib.baseboard_fab2(sch_1):page90_i17:b"
				( attribute "PN" "2"
					( Origin gPackager )
				)
				( objectStatus "R3D22.2" )
			)
			( pin "@baseboard_fab2_lib.baseboard_fab2(sch_1):page90_i24:a"
				( attribute "PN" "1"
					( Origin gPackager )
				)
				( objectStatus "R3D16.1" )
			)
			( pin "@baseboard_fab2_lib.baseboard_fab2(sch_1):page90_i24:b"
				( attribute "PN" "2"
					( Origin gPackager )
				)
				( objectStatus "R3D16.2" )
			)
			( pin "@baseboard_fab2_lib.baseboard_fab2(sch_1):page90_i25:a"
				( attribute "PN" "1"
					( Origin gPackager )
				)
				( objectStatus "R3D23.1" )
			)
			( pin "@baseboard_fab2_lib.baseboard_fab2(sch_1):page90_i25:b"
				( attribute "PN" "2"
					( Origin gPackager )
				)
				( objectStatus "R3D23.2" )
			)
			( pin "@baseboard_fab2_lib.baseboard_fab2(sch_1):page90_i28:a"
				( attribute "PN" "1"
					( Origin gPackager )
				)
				( objectStatus "R3D26.1" )
			)
			( pin "@baseboard_fab2_lib.baseboard_fab2(sch_1):page90_i28:b"
				( attribute "PN" "2"
					( Origin gPackager )
				)
				( objectStatus "R3D26.2" )
			)
			( pin "@baseboard_fab2_lib.baseboard_fab2(sch_1):page90_i29:a"
				( attribute "PN" "1"
					( Origin gPackager )
				)
				( objectStatus "R5D3.1" )
			)
			( pin "@baseboard_fab2_lib.baseboard_fab2(sch_1):page90_i29:b"
				( attribute "PN" "2"
					( Origin gPackager )
				)
				( objectStatus "R5D3.2" )
			)
			( pin "@baseboard_fab2_lib.baseboard_fab2(sch_1):page90_i31:a"
				( attribute "PN" "1"
					( Origin gPackager )
				)
				( objectStatus "R6D7.1" )
			)
			( pin "@baseboard_fab2_lib.baseboard_fab2(sch_1):page90_i31:b"
				( attribute "PN" "2"
					( Origin gPackager )
				)
				( objectStatus "R6D7.2" )
			)
			( pin "@baseboard_fab2_lib.baseboard_fab2(sch_1):page90_i33:a"
				( attribute "PN" "1"
					( Origin gPackager )
				)
				( objectStatus "R6D13.1" )
			)
			( pin "@baseboard_fab2_lib.baseboard_fab2(sch_1):page90_i33:b"
				( attribute "PN" "2"
					( Origin gPackager )
				)
				( objectStatus "R6D13.2" )
			)
			( pin "@baseboard_fab2_lib.baseboard_fab2(sch_1):page90_i48:a"
				( attribute "PN" "1"
					( Origin gPackager )
				)
				( objectStatus "R6D15.1" )
			)
			( pin "@baseboard_fab2_lib.baseboard_fab2(sch_1):page90_i48:b"
				( attribute "PN" "2"
					( Origin gPackager )
				)
				( objectStatus "R6D15.2" )
			)
			( pin "@baseboard_fab2_lib.baseboard_fab2(sch_1):page90_i49:a"
				( attribute "PN" "1"
					( Origin gPackager )
				)
				( objectStatus "R6D10.1" )
			)
			( pin "@baseboard_fab2_lib.baseboard_fab2(sch_1):page90_i49:b"
				( attribute "PN" "2"
					( Origin gPackager )
				)
				( objectStatus "R6D10.2" )
			)
			( pin "@baseboard_fab2_lib.baseboard_fab2(sch_1):page90_i52:a"
				( attribute "PN" "1"
					( Origin gPackager )
				)
				( objectStatus "R6D14.1" )
			)
			( pin "@baseboard_fab2_lib.baseboard_fab2(sch_1):page90_i52:b"
				( attribute "PN" "2"
					( Origin gPackager )
				)
				( objectStatus "R6D14.2" )
			)
			( pin "@baseboard_fab2_lib.baseboard_fab2(sch_1):page90_i53:a"
				( attribute "PN" "1"
					( Origin gPackager )
				)
				( objectStatus "R4P14.1" )
			)
			( pin "@baseboard_fab2_lib.baseboard_fab2(sch_1):page90_i53:b"
				( attribute "PN" "2"
					( Origin gPackager )
				)
				( objectStatus "R4P14.2" )
			)
			( pin "@baseboard_fab2_lib.baseboard_fab2(sch_1):page90_i59:a"
				( attribute "PN" "1"
					( Origin gPackager )
				)
				( objectStatus "R3D24.1" )
			)
			( pin "@baseboard_fab2_lib.baseboard_fab2(sch_1):page90_i59:b"
				( attribute "PN" "2"
					( Origin gPackager )
				)
				( objectStatus "R3D24.2" )
			)
			( pin "@baseboard_fab2_lib.baseboard_fab2(sch_1):page90_i60:a"
				( attribute "PN" "1"
					( Origin gPackager )
				)
				( objectStatus "R3D17.1" )
			)
			( pin "@baseboard_fab2_lib.baseboard_fab2(sch_1):page90_i60:b"
				( attribute "PN" "2"
					( Origin gPackager )
				)
				( objectStatus "R3D17.2" )
			)
			( pin "@baseboard_fab2_lib.baseboard_fab2(sch_1):page90_i66:a"
				( attribute "PN" "1"
					( Origin gPackager )
				)
				( objectStatus "R3D25.1" )
			)
			( pin "@baseboard_fab2_lib.baseboard_fab2(sch_1):page90_i66:b"
				( attribute "PN" "2"
					( Origin gPackager )
				)
				( objectStatus "R3D25.2" )
			)
			( pin "@baseboard_fab2_lib.baseboard_fab2(sch_1):page90_i68:a"
				( attribute "PN" "1"
					( Origin gPackager )
				)
				( objectStatus "R4P6.1" )
			)
			( pin "@baseboard_fab2_lib.baseboard_fab2(sch_1):page90_i68:b"
				( attribute "PN" "2"
					( Origin gPackager )
				)
				( objectStatus "R4P6.2" )
			)
			( pin "@baseboard_fab2_lib.baseboard_fab2(sch_1):page125_i88:a"
				( attribute "PN" "1"
					( Origin gPackager )
				)
				( objectStatus "R2U30.1" )
			)
			( pin "@baseboard_fab2_lib.baseboard_fab2(sch_1):page125_i88:b"
				( attribute "PN" "2"
					( Origin gPackager )
				)
				( objectStatus "R2U30.2" )
			)
			( pin "@baseboard_fab2_lib.baseboard_fab2(sch_1):page90_i72:a"
				( attribute "PN" "1"
					( Origin gPackager )
				)
				( objectStatus "R4P7.1" )
			)
			( pin "@baseboard_fab2_lib.baseboard_fab2(sch_1):page90_i72:b"
				( attribute "PN" "2"
					( Origin gPackager )
				)
				( objectStatus "R4P7.2" )
			)
			( pin "@baseboard_fab2_lib.baseboard_fab2(sch_1):page90_i74:a"
				( attribute "PN" "1"
					( Origin gPackager )
				)
				( objectStatus "R7P15.1" )
			)
			( pin "@baseboard_fab2_lib.baseboard_fab2(sch_1):page90_i74:b"
				( attribute "PN" "2"
					( Origin gPackager )
				)
				( objectStatus "R7P15.2" )
			)
			( pin "@baseboard_fab2_lib.baseboard_fab2(sch_1):page90_i76:a"
				( attribute "PN" "1"
					( Origin gPackager )
				)
				( objectStatus "R7P22.1" )
			)
			( pin "@baseboard_fab2_lib.baseboard_fab2(sch_1):page90_i76:b"
				( attribute "PN" "2"
					( Origin gPackager )
				)
				( objectStatus "R7P22.2" )
			)
			( pin "@baseboard_fab2_lib.baseboard_fab2(sch_1):page90_i79:a"
				( attribute "PN" "1"
					( Origin gPackager )
				)
				( objectStatus "R5P2.1" )
			)
			( pin "@baseboard_fab2_lib.baseboard_fab2(sch_1):page90_i79:b"
				( attribute "PN" "2"
					( Origin gPackager )
				)
				( objectStatus "R5P2.2" )
			)
			( pin "@baseboard_fab2_lib.baseboard_fab2(sch_1):page90_i80:a"
				( attribute "PN" "1"
					( Origin gPackager )
				)
				( objectStatus "R5P3.1" )
			)
			( pin "@baseboard_fab2_lib.baseboard_fab2(sch_1):page90_i80:b"
				( attribute "PN" "2"
					( Origin gPackager )
				)
				( objectStatus "R5P3.2" )
			)
			( pin "@baseboard_fab2_lib.baseboard_fab2(sch_1):page90_i81:a"
				( attribute "PN" "1"
					( Origin gPackager )
				)
				( objectStatus "R6D5.1" )
			)
			( pin "@baseboard_fab2_lib.baseboard_fab2(sch_1):page90_i81:b"
				( attribute "PN" "2"
					( Origin gPackager )
				)
				( objectStatus "R6D5.2" )
			)
			( pin "@baseboard_fab2_lib.baseboard_fab2(sch_1):page90_i85:a"
				( attribute "PN" "1"
					( Origin gPackager )
				)
				( objectStatus "R8P1.1" )
			)
			( pin "@baseboard_fab2_lib.baseboard_fab2(sch_1):page90_i85:b"
				( attribute "PN" "2"
					( Origin gPackager )
				)
				( objectStatus "R8P1.2" )
			)
			( pin "@baseboard_fab2_lib.baseboard_fab2(sch_1):page90_i86:a"
				( attribute "PN" "1"
					( Origin gPackager )
				)
				( objectStatus "R8P2.1" )
			)
			( pin "@baseboard_fab2_lib.baseboard_fab2(sch_1):page90_i86:b"
				( attribute "PN" "2"
					( Origin gPackager )
				)
				( objectStatus "R8P2.2" )
			)
			( pin "@baseboard_fab2_lib.baseboard_fab2(sch_1):page90_i88:a"
				( attribute "PN" "1"
					( Origin gPackager )
				)
				( objectStatus "R3D9.1" )
			)
			( pin "@baseboard_fab2_lib.baseboard_fab2(sch_1):page90_i88:b"
				( attribute "PN" "2"
					( Origin gPackager )
				)
				( objectStatus "R3D9.2" )
			)
			( pin "@baseboard_fab2_lib.baseboard_fab2(sch_1):page91_i1:io1"
				( attribute "PN" "1"
					( Origin gPackager )
				)
				( objectStatus "J8B1.1" )
			)
			( pin "@baseboard_fab2_lib.baseboard_fab2(sch_1):page91_i1:io2"
				( attribute "PN" "2"
					( Origin gPackager )
				)
				( objectStatus "J8B1.2" )
			)
			( pin "@baseboard_fab2_lib.baseboard_fab2(sch_1):page91_i1:io3"
				( attribute "PN" "3"
					( Origin gPackager )
				)
				( objectStatus "J8B1.3" )
			)
			( pin "@baseboard_fab2_lib.baseboard_fab2(sch_1):page91_i1:io4"
				( attribute "PN" "4"
					( Origin gPackager )
				)
				( objectStatus "J8B1.4" )
			)
			( pin "@baseboard_fab2_lib.baseboard_fab2(sch_1):page91_i1:io5"
				( attribute "PN" "5"
					( Origin gPackager )
				)
				( objectStatus "J8B1.5" )
			)
			( pin "@baseboard_fab2_lib.baseboard_fab2(sch_1):page91_i1:io6"
				( attribute "PN" "6"
					( Origin gPackager )
				)
				( objectStatus "J8B1.6" )
			)
			( pin "@baseboard_fab2_lib.baseboard_fab2(sch_1):page91_i1:io7"
				( attribute "PN" "7"
					( Origin gPackager )
				)
				( objectStatus "J8B1.7" )
			)
			( pin "@baseboard_fab2_lib.baseboard_fab2(sch_1):page91_i1:io8"
				( attribute "PN" "8"
					( Origin gPackager )
				)
				( objectStatus "J8B1.8" )
			)
			( pin "@baseboard_fab2_lib.baseboard_fab2(sch_1):page91_i1:io9"
				( attribute "PN" "9"
					( Origin gPackager )
				)
				( objectStatus "J8B1.9" )
			)
			( pin "@baseboard_fab2_lib.baseboard_fab2(sch_1):page91_i1:io10"
				( attribute "PN" "10"
					( Origin gPackager )
				)
				( objectStatus "J8B1.10" )
			)
			( pin "@baseboard_fab2_lib.baseboard_fab2(sch_1):page91_i1:io11"
				( attribute "PN" "11"
					( Origin gPackager )
				)
				( objectStatus "J8B1.11" )
			)
			( pin "@baseboard_fab2_lib.baseboard_fab2(sch_1):page91_i1:io12"
				( attribute "PN" "12"
					( Origin gPackager )
				)
				( objectStatus "J8B1.12" )
			)
			( pin "@baseboard_fab2_lib.baseboard_fab2(sch_1):page91_i1:io13"
				( attribute "PN" "13"
					( Origin gPackager )
				)
				( objectStatus "J8B1.13" )
			)
			( pin "@baseboard_fab2_lib.baseboard_fab2(sch_1):page91_i1:io14"
				( attribute "PN" "14"
					( Origin gPackager )
				)
				( objectStatus "J8B1.14" )
			)
			( pin "@baseboard_fab2_lib.baseboard_fab2(sch_1):page91_i1:io15"
				( attribute "PN" "15"
					( Origin gPackager )
				)
				( objectStatus "J8B1.15" )
			)
			( pin "@baseboard_fab2_lib.baseboard_fab2(sch_1):page91_i1:io16"
				( attribute "PN" "16"
					( Origin gPackager )
				)
				( objectStatus "J8B1.16" )
			)
			( pin "@baseboard_fab2_lib.baseboard_fab2(sch_1):page91_i1:io17"
				( attribute "PN" "17"
					( Origin gPackager )
				)
				( objectStatus "J8B1.17" )
			)
			( pin "@baseboard_fab2_lib.baseboard_fab2(sch_1):page91_i1:io18"
				( attribute "PN" "18"
					( Origin gPackager )
				)
				( objectStatus "J8B1.18" )
			)
			( pin "@baseboard_fab2_lib.baseboard_fab2(sch_1):page91_i1:io19"
				( attribute "PN" "19"
					( Origin gPackager )
				)
				( objectStatus "J8B1.19" )
			)
			( pin "@baseboard_fab2_lib.baseboard_fab2(sch_1):page91_i1:io20"
				( attribute "PN" "20"
					( Origin gPackager )
				)
				( objectStatus "J8B1.20" )
			)
			( pin "@baseboard_fab2_lib.baseboard_fab2(sch_1):page91_i1:io21"
				( attribute "PN" "21"
					( Origin gPackager )
				)
				( objectStatus "J8B1.21" )
			)
			( pin "@baseboard_fab2_lib.baseboard_fab2(sch_1):page91_i1:io22"
				( attribute "PN" "22"
					( Origin gPackager )
				)
				( objectStatus "J8B1.22" )
			)
			( pin "@baseboard_fab2_lib.baseboard_fab2(sch_1):page91_i1:io23"
				( attribute "PN" "23"
					( Origin gPackager )
				)
				( objectStatus "J8B1.23" )
			)
			( pin "@baseboard_fab2_lib.baseboard_fab2(sch_1):page91_i1:io24"
				( attribute "PN" "24"
					( Origin gPackager )
				)
				( objectStatus "J8B1.24" )
			)
			( pin "@baseboard_fab2_lib.baseboard_fab2(sch_1):page91_i1:mp1"
				( attribute "PN" "MP1"
					( Origin gPackager )
				)
				( objectStatus "J8B1.MP1" )
			)
			( pin "@baseboard_fab2_lib.baseboard_fab2(sch_1):page91_i1:mp2"
				( attribute "PN" "MP2"
					( Origin gPackager )
				)
				( objectStatus "J8B1.MP2" )
			)
			( pin "@baseboard_fab2_lib.baseboard_fab2(sch_1):page91_i14:a"
				( attribute "PN" "1"
					( Origin gPackager )
				)
				( objectStatus "R8B8.1" )
			)
			( pin "@baseboard_fab2_lib.baseboard_fab2(sch_1):page91_i14:b"
				( attribute "PN" "2"
					( Origin gPackager )
				)
				( objectStatus "R8B8.2" )
			)
			( pin "@baseboard_fab2_lib.baseboard_fab2(sch_1):page91_i16:a"
				( attribute "PN" "1"
					( Origin gPackager )
				)
				( objectStatus "R8B10.1" )
			)
			( pin "@baseboard_fab2_lib.baseboard_fab2(sch_1):page91_i16:b"
				( attribute "PN" "2"
					( Origin gPackager )
				)
				( objectStatus "R8B10.2" )
			)
			( pin "@baseboard_fab2_lib.baseboard_fab2(sch_1):page91_i17:a"
				( attribute "PN" "1"
					( Origin gPackager )
				)
				( objectStatus "R8B16.1" )
			)
			( pin "@baseboard_fab2_lib.baseboard_fab2(sch_1):page91_i17:b"
				( attribute "PN" "2"
					( Origin gPackager )
				)
				( objectStatus "R8B16.2" )
			)
			( pin "@baseboard_fab2_lib.baseboard_fab2(sch_1):page91_i18:a"
				( attribute "PN" "1"
					( Origin gPackager )
				)
				( objectStatus "R8B17.1" )
			)
			( pin "@baseboard_fab2_lib.baseboard_fab2(sch_1):page91_i18:b"
				( attribute "PN" "2"
					( Origin gPackager )
				)
				( objectStatus "R8B17.2" )
			)
			( pin "@baseboard_fab2_lib.baseboard_fab2(sch_1):page91_i20:a"
				( attribute "PN" "1"
					( Origin gPackager )
				)
				( objectStatus "R8B18.1" )
			)
			( pin "@baseboard_fab2_lib.baseboard_fab2(sch_1):page91_i20:b"
				( attribute "PN" "2"
					( Origin gPackager )
				)
				( objectStatus "R8B18.2" )
			)
			( pin "@baseboard_fab2_lib.baseboard_fab2(sch_1):page91_i21:a"
				( attribute "PN" "1"
					( Origin gPackager )
				)
				( objectStatus "R8B19.1" )
			)
			( pin "@baseboard_fab2_lib.baseboard_fab2(sch_1):page91_i21:b"
				( attribute "PN" "2"
					( Origin gPackager )
				)
				( objectStatus "R8B19.2" )
			)
			( pin "@baseboard_fab2_lib.baseboard_fab2(sch_1):page91_i22:a"
				( attribute "PN" "1"
					( Origin gPackager )
				)
				( objectStatus "R8B5.1" )
			)
			( pin "@baseboard_fab2_lib.baseboard_fab2(sch_1):page91_i22:b"
				( attribute "PN" "2"
					( Origin gPackager )
				)
				( objectStatus "R8B5.2" )
			)
			( pin "@baseboard_fab2_lib.baseboard_fab2(sch_1):page91_i24:a"
				( attribute "PN" "1"
					( Origin gPackager )
				)
				( objectStatus "R8B3.1" )
			)
			( pin "@baseboard_fab2_lib.baseboard_fab2(sch_1):page91_i24:b"
				( attribute "PN" "2"
					( Origin gPackager )
				)
				( objectStatus "R8B3.2" )
			)
			( pin "@baseboard_fab2_lib.baseboard_fab2(sch_1):page91_i34:a"
				( attribute "PN" "1"
					( Origin gPackager )
				)
				( objectStatus "R8B13.1" )
			)
			( pin "@baseboard_fab2_lib.baseboard_fab2(sch_1):page91_i34:b"
				( attribute "PN" "2"
					( Origin gPackager )
				)
				( objectStatus "R8B13.2" )
			)
			( pin "@baseboard_fab2_lib.baseboard_fab2(sch_1):page91_i35:a"
				( attribute "PN" "1"
					( Origin gPackager )
				)
				( objectStatus "R8B11.1" )
			)
			( pin "@baseboard_fab2_lib.baseboard_fab2(sch_1):page91_i35:b"
				( attribute "PN" "2"
					( Origin gPackager )
				)
				( objectStatus "R8B11.2" )
			)
			( pin "@baseboard_fab2_lib.baseboard_fab2(sch_1):page91_i36:a"
				( attribute "PN" "1"
					( Origin gPackager )
				)
				( objectStatus "R8B7.1" )
			)
			( pin "@baseboard_fab2_lib.baseboard_fab2(sch_1):page91_i36:b"
				( attribute "PN" "2"
					( Origin gPackager )
				)
				( objectStatus "R8B7.2" )
			)
			( pin "@baseboard_fab2_lib.baseboard_fab2(sch_1):page91_i37:a"
				( attribute "PN" "1"
					( Origin gPackager )
				)
				( objectStatus "R8B6.1" )
			)
			( pin "@baseboard_fab2_lib.baseboard_fab2(sch_1):page91_i37:b"
				( attribute "PN" "2"
					( Origin gPackager )
				)
				( objectStatus "R8B6.2" )
			)
			( pin "@baseboard_fab2_lib.baseboard_fab2(sch_1):page92_i1:a0"
				( attribute "PN" "13"
					( Origin gPackager )
				)
				( objectStatus "U3P2.13" )
			)
			( pin "@baseboard_fab2_lib.baseboard_fab2(sch_1):page92_i1:a1"
				( attribute "PN" "12"
					( Origin gPackager )
				)
				( objectStatus "U3P2.12" )
			)
			( pin "@baseboard_fab2_lib.baseboard_fab2(sch_1):page92_i1:a2"
				( attribute "PN" "10"
					( Origin gPackager )
				)
				( objectStatus "U3P2.10" )
			)
			( pin "@baseboard_fab2_lib.baseboard_fab2(sch_1):page92_i1:a3"
				( attribute "PN" "9"
					( Origin gPackager )
				)
				( objectStatus "U3P2.9" )
			)
			( pin "@baseboard_fab2_lib.baseboard_fab2(sch_1):page92_i1:b0"
				( attribute "PN" "2"
					( Origin gPackager )
				)
				( objectStatus "U3P2.2" )
			)
			( pin "@baseboard_fab2_lib.baseboard_fab2(sch_1):page92_i1:b1"
				( attribute "PN" "3"
					( Origin gPackager )
				)
				( objectStatus "U3P2.3" )
			)
			( pin "@baseboard_fab2_lib.baseboard_fab2(sch_1):page92_i1:b2"
				( attribute "PN" "5"
					( Origin gPackager )
				)
				( objectStatus "U3P2.5" )
			)
			( pin "@baseboard_fab2_lib.baseboard_fab2(sch_1):page92_i1:b3"
				( attribute "PN" "6"
					( Origin gPackager )
				)
				( objectStatus "U3P2.6" )
			)
			( pin "@baseboard_fab2_lib.baseboard_fab2(sch_1):page92_i1:dir"
				( attribute "PN" "1"
					( Origin gPackager )
				)
				( objectStatus "U3P2.1" )
			)
			( pin "@baseboard_fab2_lib.baseboard_fab2(sch_1):page92_i1:gnd(0)"
				( attribute "PN" "7"
					( Origin gPackager )
				)
				( objectStatus "U3P2.7" )
			)
			( pin "@baseboard_fab2_lib.baseboard_fab2(sch_1):page92_i1:gnd(1)"
				( attribute "PN" "8"
					( Origin gPackager )
				)
				( objectStatus "U3P2.8" )
			)
			( pin "@baseboard_fab2_lib.baseboard_fab2(sch_1):page92_i1:gnd(2)"
				( attribute "PN" "11"
					( Origin gPackager )
				)
				( objectStatus "U3P2.11" )
			)
			( pin "@baseboard_fab2_lib.baseboard_fab2(sch_1):page92_i1:vcc"
				( attribute "PN" "14"
					( Origin gPackager )
				)
				( objectStatus "U3P2.14" )
			)
			( pin "@baseboard_fab2_lib.baseboard_fab2(sch_1):page92_i1:vref"
				( attribute "PN" "4"
					( Origin gPackager )
				)
				( objectStatus "U3P2.4" )
			)
			( pin "@baseboard_fab2_lib.baseboard_fab2(sch_1):page92_i9:a"
				( attribute "PN" "1"
					( Origin gPackager )
				)
				( objectStatus "R3P41.1" )
			)
			( pin "@baseboard_fab2_lib.baseboard_fab2(sch_1):page92_i9:b"
				( attribute "PN" "2"
					( Origin gPackager )
				)
				( objectStatus "R3P41.2" )
			)
			( pin "@baseboard_fab2_lib.baseboard_fab2(sch_1):page92_i12:a"
				( attribute "PN" "1"
					( Origin gPackager )
				)
				( objectStatus "R3P46.1" )
			)
			( pin "@baseboard_fab2_lib.baseboard_fab2(sch_1):page92_i12:b"
				( attribute "PN" "2"
					( Origin gPackager )
				)
				( objectStatus "R3P46.2" )
			)
			( pin "@baseboard_fab2_lib.baseboard_fab2(sch_1):page92_i13:a"
				( attribute "PN" "1"
					( Origin gPackager )
				)
				( objectStatus "R3P43.1" )
			)
			( pin "@baseboard_fab2_lib.baseboard_fab2(sch_1):page92_i13:b"
				( attribute "PN" "2"
					( Origin gPackager )
				)
				( objectStatus "R3P43.2" )
			)
			( pin "@baseboard_fab2_lib.baseboard_fab2(sch_1):page92_i14:a"
				( attribute "PN" "1"
					( Origin gPackager )
				)
				( objectStatus "R3P42.1" )
			)
			( pin "@baseboard_fab2_lib.baseboard_fab2(sch_1):page92_i14:b"
				( attribute "PN" "2"
					( Origin gPackager )
				)
				( objectStatus "R3P42.2" )
			)
			( pin "@baseboard_fab2_lib.baseboard_fab2(sch_1):page92_i19:a"
				( attribute "PN" "1"
					( Origin gPackager )
				)
				( objectStatus "R7E2.1" )
			)
			( pin "@baseboard_fab2_lib.baseboard_fab2(sch_1):page92_i19:b"
				( attribute "PN" "2"
					( Origin gPackager )
				)
				( objectStatus "R7E2.2" )
			)
			( pin "@baseboard_fab2_lib.baseboard_fab2(sch_1):page92_i24:a"
				( attribute "PN" "1"
					( Origin gPackager )
				)
				( objectStatus "R7D34.1" )
			)
			( pin "@baseboard_fab2_lib.baseboard_fab2(sch_1):page92_i24:b"
				( attribute "PN" "2"
					( Origin gPackager )
				)
				( objectStatus "R7D34.2" )
			)
			( pin "@baseboard_fab2_lib.baseboard_fab2(sch_1):page92_i29:a"
				( attribute "PN" "1"
					( Origin gPackager )
				)
				( objectStatus "R7D31.1" )
			)
			( pin "@baseboard_fab2_lib.baseboard_fab2(sch_1):page92_i29:b"
				( attribute "PN" "2"
					( Origin gPackager )
				)
				( objectStatus "R7D31.2" )
			)
			( pin "@baseboard_fab2_lib.baseboard_fab2(sch_1):page92_i30:a"
				( attribute "PN" "1"
					( Origin gPackager )
				)
				( objectStatus "R7D29.1" )
			)
			( pin "@baseboard_fab2_lib.baseboard_fab2(sch_1):page92_i30:b"
				( attribute "PN" "2"
					( Origin gPackager )
				)
				( objectStatus "R7D29.2" )
			)
			( pin "@baseboard_fab2_lib.baseboard_fab2(sch_1):page92_i32:a0"
				( attribute "PN" "13"
					( Origin gPackager )
				)
				( objectStatus "U7D2.13" )
			)
			( pin "@baseboard_fab2_lib.baseboard_fab2(sch_1):page92_i32:a1"
				( attribute "PN" "12"
					( Origin gPackager )
				)
				( objectStatus "U7D2.12" )
			)
			( pin "@baseboard_fab2_lib.baseboard_fab2(sch_1):page92_i32:a2"
				( attribute "PN" "10"
					( Origin gPackager )
				)
				( objectStatus "U7D2.10" )
			)
			( pin "@baseboard_fab2_lib.baseboard_fab2(sch_1):page92_i32:a3"
				( attribute "PN" "9"
					( Origin gPackager )
				)
				( objectStatus "U7D2.9" )
			)
			( pin "@baseboard_fab2_lib.baseboard_fab2(sch_1):page92_i32:b0"
				( attribute "PN" "2"
					( Origin gPackager )
				)
				( objectStatus "U7D2.2" )
			)
			( pin "@baseboard_fab2_lib.baseboard_fab2(sch_1):page92_i32:b1"
				( attribute "PN" "3"
					( Origin gPackager )
				)
				( objectStatus "U7D2.3" )
			)
			( pin "@baseboard_fab2_lib.baseboard_fab2(sch_1):page92_i32:b2"
				( attribute "PN" "5"
					( Origin gPackager )
				)
				( objectStatus "U7D2.5" )
			)
			( pin "@baseboard_fab2_lib.baseboard_fab2(sch_1):page92_i32:b3"
				( attribute "PN" "6"
					( Origin gPackager )
				)
				( objectStatus "U7D2.6" )
			)
			( pin "@baseboard_fab2_lib.baseboard_fab2(sch_1):page92_i32:dir"
				( attribute "PN" "1"
					( Origin gPackager )
				)
				( objectStatus "U7D2.1" )
			)
			( pin "@baseboard_fab2_lib.baseboard_fab2(sch_1):page92_i32:gnd(0)"
				( attribute "PN" "7"
					( Origin gPackager )
				)
				( objectStatus "U7D2.7" )
			)
			( pin "@baseboard_fab2_lib.baseboard_fab2(sch_1):page92_i32:gnd(1)"
				( attribute "PN" "8"
					( Origin gPackager )
				)
				( objectStatus "U7D2.8" )
			)
			( pin "@baseboard_fab2_lib.baseboard_fab2(sch_1):page92_i32:gnd(2)"
				( attribute "PN" "11"
					( Origin gPackager )
				)
				( objectStatus "U7D2.11" )
			)
			( pin "@baseboard_fab2_lib.baseboard_fab2(sch_1):page92_i32:vcc"
				( attribute "PN" "14"
					( Origin gPackager )
				)
				( objectStatus "U7D2.14" )
			)
			( pin "@baseboard_fab2_lib.baseboard_fab2(sch_1):page92_i32:vref"
				( attribute "PN" "4"
					( Origin gPackager )
				)
				( objectStatus "U7D2.4" )
			)
			( pin "@baseboard_fab2_lib.baseboard_fab2(sch_1):page92_i37:a"
				( attribute "PN" "1"
					( Origin gPackager )
				)
				( objectStatus "C3P49.1" )
			)
			( pin "@baseboard_fab2_lib.baseboard_fab2(sch_1):page92_i37:b"
				( attribute "PN" "2"
					( Origin gPackager )
				)
				( objectStatus "C3P49.2" )
			)
			( pin "@baseboard_fab2_lib.baseboard_fab2(sch_1):page92_i38:a"
				( attribute "PN" "1"
					( Origin gPackager )
				)
				( objectStatus "R3P49.1" )
			)
			( pin "@baseboard_fab2_lib.baseboard_fab2(sch_1):page92_i38:b"
				( attribute "PN" "2"
					( Origin gPackager )
				)
				( objectStatus "R3P49.2" )
			)
			( pin "@baseboard_fab2_lib.baseboard_fab2(sch_1):page176_i175:a"
				( attribute "PN" "1"
					( Origin gPackager )
				)
				( objectStatus "R1W39.1" )
			)
			( pin "@baseboard_fab2_lib.baseboard_fab2(sch_1):page176_i175:b"
				( attribute "PN" "2"
					( Origin gPackager )
				)
				( objectStatus "R1W39.2" )
			)
			( pin "@baseboard_fab2_lib.baseboard_fab2(sch_1):page92_i46:a"
				( attribute "PN" "1"
					( Origin gPackager )
				)
				( objectStatus "R3R1.1" )
			)
			( pin "@baseboard_fab2_lib.baseboard_fab2(sch_1):page92_i46:b"
				( attribute "PN" "2"
					( Origin gPackager )
				)
				( objectStatus "R3R1.2" )
			)
			( pin "@baseboard_fab2_lib.baseboard_fab2(sch_1):page92_i48:a"
				( attribute "PN" "1"
					( Origin gPackager )
				)
				( objectStatus "R7D32.1" )
			)
			( pin "@baseboard_fab2_lib.baseboard_fab2(sch_1):page92_i48:b"
				( attribute "PN" "2"
					( Origin gPackager )
				)
				( objectStatus "R7D32.2" )
			)
			( pin "@baseboard_fab2_lib.baseboard_fab2(sch_1):page93_i148:\1\"
				( attribute "PN" "1"
					( Origin gPackager )
				)
				( objectStatus "R2T36.1" )
			)
			( pin "@baseboard_fab2_lib.baseboard_fab2(sch_1):page93_i148:\2\"
				( attribute "PN" "2"
					( Origin gPackager )
				)
				( objectStatus "R2T36.2" )
			)
			( pin "@baseboard_fab2_lib.baseboard_fab2(sch_1):page92_i52:a"
				( attribute "PN" "1"
					( Origin gPackager )
				)
				( objectStatus "C7D5.1" )
			)
			( pin "@baseboard_fab2_lib.baseboard_fab2(sch_1):page92_i52:b"
				( attribute "PN" "2"
					( Origin gPackager )
				)
				( objectStatus "C7D5.2" )
			)
			( pin "@baseboard_fab2_lib.baseboard_fab2(sch_1):page92_i54:a"
				( attribute "PN" "1"
					( Origin gPackager )
				)
				( objectStatus "R7D26.1" )
			)
			( pin "@baseboard_fab2_lib.baseboard_fab2(sch_1):page92_i54:b"
				( attribute "PN" "2"
					( Origin gPackager )
				)
				( objectStatus "R7D26.2" )
			)
			( pin "@baseboard_fab2_lib.baseboard_fab2(sch_1):page92_i61:a"
				( attribute "PN" "1"
					( Origin gPackager )
				)
				( objectStatus "R3R3.1" )
			)
			( pin "@baseboard_fab2_lib.baseboard_fab2(sch_1):page92_i61:b"
				( attribute "PN" "2"
					( Origin gPackager )
				)
				( objectStatus "R3R3.2" )
			)
			( pin "@baseboard_fab2_lib.baseboard_fab2(sch_1):page92_i64:a"
				( attribute "PN" "1"
					( Origin gPackager )
				)
				( objectStatus "R6D9.1" )
			)
			( pin "@baseboard_fab2_lib.baseboard_fab2(sch_1):page92_i64:b"
				( attribute "PN" "2"
					( Origin gPackager )
				)
				( objectStatus "R6D9.2" )
			)
			( pin "@baseboard_fab2_lib.baseboard_fab2(sch_1):page92_i65:a"
				( attribute "PN" "1"
					( Origin gPackager )
				)
				( objectStatus "R7P27.1" )
			)
			( pin "@baseboard_fab2_lib.baseboard_fab2(sch_1):page92_i65:b"
				( attribute "PN" "2"
					( Origin gPackager )
				)
				( objectStatus "R7P27.2" )
			)
			( pin "@baseboard_fab2_lib.baseboard_fab2(sch_1):page92_i67:a"
				( attribute "PN" "1"
					( Origin gPackager )
				)
				( objectStatus "R7D28.1" )
			)
			( pin "@baseboard_fab2_lib.baseboard_fab2(sch_1):page92_i67:b"
				( attribute "PN" "2"
					( Origin gPackager )
				)
				( objectStatus "R7D28.2" )
			)
			( pin "@baseboard_fab2_lib.baseboard_fab2(sch_1):page92_i68:a"
				( attribute "PN" "1"
					( Origin gPackager )
				)
				( objectStatus "R7D27.1" )
			)
			( pin "@baseboard_fab2_lib.baseboard_fab2(sch_1):page92_i68:b"
				( attribute "PN" "2"
					( Origin gPackager )
				)
				( objectStatus "R7D27.2" )
			)
			( pin "@baseboard_fab2_lib.baseboard_fab2(sch_1):page92_i70:a"
				( attribute "PN" "1"
					( Origin gPackager )
				)
				( objectStatus "R7D25.1" )
			)
			( pin "@baseboard_fab2_lib.baseboard_fab2(sch_1):page92_i70:b"
				( attribute "PN" "2"
					( Origin gPackager )
				)
				( objectStatus "R7D25.2" )
			)
			( pin "@baseboard_fab2_lib.baseboard_fab2(sch_1):page92_i75:a"
				( attribute "PN" "1"
					( Origin gPackager )
				)
				( objectStatus "R3R2.1" )
			)
			( pin "@baseboard_fab2_lib.baseboard_fab2(sch_1):page92_i75:b"
				( attribute "PN" "2"
					( Origin gPackager )
				)
				( objectStatus "R3R2.2" )
			)
			( pin "@baseboard_fab2_lib.baseboard_fab2(sch_1):page92_i79:a"
				( attribute "PN" "1"
					( Origin gPackager )
				)
				( objectStatus "C7D4.1" )
			)
			( pin "@baseboard_fab2_lib.baseboard_fab2(sch_1):page92_i79:b"
				( attribute "PN" "2"
					( Origin gPackager )
				)
				( objectStatus "C7D4.2" )
			)
			( pin "@baseboard_fab2_lib.baseboard_fab2(sch_1):page92_i84:a"
				( attribute "PN" "1"
					( Origin gPackager )
				)
				( objectStatus "C3P50.1" )
			)
			( pin "@baseboard_fab2_lib.baseboard_fab2(sch_1):page92_i84:b"
				( attribute "PN" "2"
					( Origin gPackager )
				)
				( objectStatus "C3P50.2" )
			)
			( pin "@baseboard_fab2_lib.baseboard_fab2(sch_1):page92_i92:a"
				( attribute "PN" "1"
					( Origin gPackager )
				)
				( objectStatus "R2T44.1" )
			)
			( pin "@baseboard_fab2_lib.baseboard_fab2(sch_1):page92_i92:b"
				( attribute "PN" "2"
					( Origin gPackager )
				)
				( objectStatus "R2T44.2" )
			)
			( pin "@baseboard_fab2_lib.baseboard_fab2(sch_1):page92_i93:a"
				( attribute "PN" "1"
					( Origin gPackager )
				)
				( objectStatus "R2T40.1" )
			)
			( pin "@baseboard_fab2_lib.baseboard_fab2(sch_1):page92_i93:b"
				( attribute "PN" "2"
					( Origin gPackager )
				)
				( objectStatus "R2T40.2" )
			)
			( pin "@baseboard_fab2_lib.baseboard_fab2(sch_1):page92_i94:a"
				( attribute "PN" "1"
					( Origin gPackager )
				)
				( objectStatus "R2T37.1" )
			)
			( pin "@baseboard_fab2_lib.baseboard_fab2(sch_1):page92_i94:b"
				( attribute "PN" "2"
					( Origin gPackager )
				)
				( objectStatus "R2T37.2" )
			)
			( pin "@baseboard_fab2_lib.baseboard_fab2(sch_1):page92_i96:a"
				( attribute "PN" "1"
					( Origin gPackager )
				)
				( objectStatus "R2T43.1" )
			)
			( pin "@baseboard_fab2_lib.baseboard_fab2(sch_1):page92_i96:b"
				( attribute "PN" "2"
					( Origin gPackager )
				)
				( objectStatus "R2T43.2" )
			)
			( pin "@baseboard_fab2_lib.baseboard_fab2(sch_1):page92_i97:a"
				( attribute "PN" "1"
					( Origin gPackager )
				)
				( objectStatus "R3P59.1" )
			)
			( pin "@baseboard_fab2_lib.baseboard_fab2(sch_1):page92_i97:b"
				( attribute "PN" "2"
					( Origin gPackager )
				)
				( objectStatus "R3P59.2" )
			)
			( pin "@baseboard_fab2_lib.baseboard_fab2(sch_1):page92_i98:a"
				( attribute "PN" "1"
					( Origin gPackager )
				)
				( objectStatus "R3P58.1" )
			)
			( pin "@baseboard_fab2_lib.baseboard_fab2(sch_1):page92_i98:b"
				( attribute "PN" "2"
					( Origin gPackager )
				)
				( objectStatus "R3P58.2" )
			)
			( pin "@baseboard_fab2_lib.baseboard_fab2(sch_1):page92_i100:a"
				( attribute "PN" "1"
					( Origin gPackager )
				)
				( objectStatus "R7P18.1" )
			)
			( pin "@baseboard_fab2_lib.baseboard_fab2(sch_1):page92_i100:b"
				( attribute "PN" "2"
					( Origin gPackager )
				)
				( objectStatus "R7P18.2" )
			)
			( pin "@baseboard_fab2_lib.baseboard_fab2(sch_1):page92_i101:a"
				( attribute "PN" "1"
					( Origin gPackager )
				)
				( objectStatus "R4R2.1" )
			)
			( pin "@baseboard_fab2_lib.baseboard_fab2(sch_1):page92_i101:b"
				( attribute "PN" "2"
					( Origin gPackager )
				)
				( objectStatus "R4R2.2" )
			)
			( pin "@baseboard_fab2_lib.baseboard_fab2(sch_1):page93_i13:a"
				( attribute "PN" "1"
					( Origin gPackager )
				)
				( objectStatus "R2T27.1" )
			)
			( pin "@baseboard_fab2_lib.baseboard_fab2(sch_1):page93_i13:b"
				( attribute "PN" "2"
					( Origin gPackager )
				)
				( objectStatus "R2T27.2" )
			)
			( pin "@baseboard_fab2_lib.baseboard_fab2(sch_1):page93_i15:a"
				( attribute "PN" "1"
					( Origin gPackager )
				)
				( objectStatus "R2T32.1" )
			)
			( pin "@baseboard_fab2_lib.baseboard_fab2(sch_1):page93_i15:b"
				( attribute "PN" "2"
					( Origin gPackager )
				)
				( objectStatus "R2T32.2" )
			)
			( pin "@baseboard_fab2_lib.baseboard_fab2(sch_1):page93_i16:a"
				( attribute "PN" "1"
					( Origin gPackager )
				)
				( objectStatus "R2T20.1" )
			)
			( pin "@baseboard_fab2_lib.baseboard_fab2(sch_1):page93_i16:b"
				( attribute "PN" "2"
					( Origin gPackager )
				)
				( objectStatus "R2T20.2" )
			)
			( pin "@baseboard_fab2_lib.baseboard_fab2(sch_1):page93_i23:a"
				( attribute "PN" "1"
					( Origin gPackager )
				)
				( objectStatus "R2T17.1" )
			)
			( pin "@baseboard_fab2_lib.baseboard_fab2(sch_1):page93_i23:b"
				( attribute "PN" "2"
					( Origin gPackager )
				)
				( objectStatus "R2T17.2" )
			)
			( pin "@baseboard_fab2_lib.baseboard_fab2(sch_1):page93_i30:a0"
				( attribute "PN" "13"
					( Origin gPackager )
				)
				( objectStatus "U2T4.13" )
			)
			( pin "@baseboard_fab2_lib.baseboard_fab2(sch_1):page93_i30:a1"
				( attribute "PN" "12"
					( Origin gPackager )
				)
				( objectStatus "U2T4.12" )
			)
			( pin "@baseboard_fab2_lib.baseboard_fab2(sch_1):page93_i30:a2"
				( attribute "PN" "10"
					( Origin gPackager )
				)
				( objectStatus "U2T4.10" )
			)
			( pin "@baseboard_fab2_lib.baseboard_fab2(sch_1):page93_i30:a3"
				( attribute "PN" "9"
					( Origin gPackager )
				)
				( objectStatus "U2T4.9" )
			)
			( pin "@baseboard_fab2_lib.baseboard_fab2(sch_1):page93_i30:b0"
				( attribute "PN" "2"
					( Origin gPackager )
				)
				( objectStatus "U2T4.2" )
			)
			( pin "@baseboard_fab2_lib.baseboard_fab2(sch_1):page93_i30:b1"
				( attribute "PN" "3"
					( Origin gPackager )
				)
				( objectStatus "U2T4.3" )
			)
			( pin "@baseboard_fab2_lib.baseboard_fab2(sch_1):page93_i30:b2"
				( attribute "PN" "5"
					( Origin gPackager )
				)
				( objectStatus "U2T4.5" )
			)
			( pin "@baseboard_fab2_lib.baseboard_fab2(sch_1):page93_i30:b3"
				( attribute "PN" "6"
					( Origin gPackager )
				)
				( objectStatus "U2T4.6" )
			)
			( pin "@baseboard_fab2_lib.baseboard_fab2(sch_1):page93_i30:dir"
				( attribute "PN" "1"
					( Origin gPackager )
				)
				( objectStatus "U2T4.1" )
			)
			( pin "@baseboard_fab2_lib.baseboard_fab2(sch_1):page93_i30:gnd(0)"
				( attribute "PN" "7"
					( Origin gPackager )
				)
				( objectStatus "U2T4.7" )
			)
			( pin "@baseboard_fab2_lib.baseboard_fab2(sch_1):page93_i30:gnd(1)"
				( attribute "PN" "8"
					( Origin gPackager )
				)
				( objectStatus "U2T4.8" )
			)
			( pin "@baseboard_fab2_lib.baseboard_fab2(sch_1):page93_i30:gnd(2)"
				( attribute "PN" "11"
					( Origin gPackager )
				)
				( objectStatus "U2T4.11" )
			)
			( pin "@baseboard_fab2_lib.baseboard_fab2(sch_1):page93_i30:vcc"
				( attribute "PN" "14"
					( Origin gPackager )
				)
				( objectStatus "U2T4.14" )
			)
			( pin "@baseboard_fab2_lib.baseboard_fab2(sch_1):page93_i30:vref"
				( attribute "PN" "4"
					( Origin gPackager )
				)
				( objectStatus "U2T4.4" )
			)
			( pin "@baseboard_fab2_lib.baseboard_fab2(sch_1):page93_i39:a"
				( attribute "PN" "1"
					( Origin gPackager )
				)
				( objectStatus "R2T38.1" )
			)
			( pin "@baseboard_fab2_lib.baseboard_fab2(sch_1):page93_i39:b"
				( attribute "PN" "2"
					( Origin gPackager )
				)
				( objectStatus "R2T38.2" )
			)
			( pin "@baseboard_fab2_lib.baseboard_fab2(sch_1):page93_i40:a"
				( attribute "PN" "1"
					( Origin gPackager )
				)
				( objectStatus "R2T33.1" )
			)
			( pin "@baseboard_fab2_lib.baseboard_fab2(sch_1):page93_i40:b"
				( attribute "PN" "2"
					( Origin gPackager )
				)
				( objectStatus "R2T33.2" )
			)
			( pin "@baseboard_fab2_lib.baseboard_fab2(sch_1):page93_i42:a"
				( attribute "PN" "1"
					( Origin gPackager )
				)
				( objectStatus "R2T30.1" )
			)
			( pin "@baseboard_fab2_lib.baseboard_fab2(sch_1):page93_i42:b"
				( attribute "PN" "2"
					( Origin gPackager )
				)
				( objectStatus "R2T30.2" )
			)
			( pin "@baseboard_fab2_lib.baseboard_fab2(sch_1):page93_i62:a"
				( attribute "PN" "1"
					( Origin gPackager )
				)
				( objectStatus "R7D24.1" )
			)
			( pin "@baseboard_fab2_lib.baseboard_fab2(sch_1):page93_i62:b"
				( attribute "PN" "2"
					( Origin gPackager )
				)
				( objectStatus "R7D24.2" )
			)
			( pin "@baseboard_fab2_lib.baseboard_fab2(sch_1):page93_i63:a"
				( attribute "PN" "1"
					( Origin gPackager )
				)
				( objectStatus "R2T19.1" )
			)
			( pin "@baseboard_fab2_lib.baseboard_fab2(sch_1):page93_i63:b"
				( attribute "PN" "2"
					( Origin gPackager )
				)
				( objectStatus "R2T19.2" )
			)
			( pin "@baseboard_fab2_lib.baseboard_fab2(sch_1):page93_i67:a"
				( attribute "PN" "1"
					( Origin gPackager )
				)
				( objectStatus "R2T16.1" )
			)
			( pin "@baseboard_fab2_lib.baseboard_fab2(sch_1):page93_i67:b"
				( attribute "PN" "2"
					( Origin gPackager )
				)
				( objectStatus "R2T16.2" )
			)
			( pin "@baseboard_fab2_lib.baseboard_fab2(sch_1):page93_i68:a"
				( attribute "PN" "1"
					( Origin gPackager )
				)
				( objectStatus "R2T31.1" )
			)
			( pin "@baseboard_fab2_lib.baseboard_fab2(sch_1):page93_i68:b"
				( attribute "PN" "2"
					( Origin gPackager )
				)
				( objectStatus "R2T31.2" )
			)
			( pin "@baseboard_fab2_lib.baseboard_fab2(sch_1):page93_i72:a"
				( attribute "PN" "1"
					( Origin gPackager )
				)
				( objectStatus "C2T33.1" )
			)
			( pin "@baseboard_fab2_lib.baseboard_fab2(sch_1):page93_i72:b"
				( attribute "PN" "2"
					( Origin gPackager )
				)
				( objectStatus "C2T33.2" )
			)
			( pin "@baseboard_fab2_lib.baseboard_fab2(sch_1):page93_i79:a"
				( attribute "PN" "1"
					( Origin gPackager )
				)
				( objectStatus "R4R3.1" )
			)
			( pin "@baseboard_fab2_lib.baseboard_fab2(sch_1):page93_i79:b"
				( attribute "PN" "2"
					( Origin gPackager )
				)
				( objectStatus "R4R3.2" )
			)
			( pin "@baseboard_fab2_lib.baseboard_fab2(sch_1):page93_i87:a"
				( attribute "PN" "1"
					( Origin gPackager )
				)
				( objectStatus "R2T26.1" )
			)
			( pin "@baseboard_fab2_lib.baseboard_fab2(sch_1):page93_i87:b"
				( attribute "PN" "2"
					( Origin gPackager )
				)
				( objectStatus "R2T26.2" )
			)
			( pin "@baseboard_fab2_lib.baseboard_fab2(sch_1):page93_i88:a"
				( attribute "PN" "1"
					( Origin gPackager )
				)
				( objectStatus "R2T57.1" )
			)
			( pin "@baseboard_fab2_lib.baseboard_fab2(sch_1):page93_i88:b"
				( attribute "PN" "2"
					( Origin gPackager )
				)
				( objectStatus "R2T57.2" )
			)
			( pin "@baseboard_fab2_lib.baseboard_fab2(sch_1):page93_i89:a"
				( attribute "PN" "1"
					( Origin gPackager )
				)
				( objectStatus "R2T61.1" )
			)
			( pin "@baseboard_fab2_lib.baseboard_fab2(sch_1):page93_i89:b"
				( attribute "PN" "2"
					( Origin gPackager )
				)
				( objectStatus "R2T61.2" )
			)
			( pin "@baseboard_fab2_lib.baseboard_fab2(sch_1):page93_i93:a"
				( attribute "PN" "1"
					( Origin gPackager )
				)
				( objectStatus "R2T62.1" )
			)
			( pin "@baseboard_fab2_lib.baseboard_fab2(sch_1):page93_i93:b"
				( attribute "PN" "2"
					( Origin gPackager )
				)
				( objectStatus "R2T62.2" )
			)
			( pin "@baseboard_fab2_lib.baseboard_fab2(sch_1):page93_i94:a"
				( attribute "PN" "1"
					( Origin gPackager )
				)
				( objectStatus "R2T58.1" )
			)
			( pin "@baseboard_fab2_lib.baseboard_fab2(sch_1):page93_i94:b"
				( attribute "PN" "2"
					( Origin gPackager )
				)
				( objectStatus "R2T58.2" )
			)
			( pin "@baseboard_fab2_lib.baseboard_fab2(sch_1):page93_i95:a"
				( attribute "PN" "1"
					( Origin gPackager )
				)
				( objectStatus "C2T32.1" )
			)
			( pin "@baseboard_fab2_lib.baseboard_fab2(sch_1):page93_i95:b"
				( attribute "PN" "2"
					( Origin gPackager )
				)
				( objectStatus "C2T32.2" )
			)
			( pin "@baseboard_fab2_lib.baseboard_fab2(sch_1):page152_i106:\1\"
				( attribute "PN" "1"
					( Origin gPackager )
				)
				( objectStatus "R1U43.1" )
			)
			( pin "@baseboard_fab2_lib.baseboard_fab2(sch_1):page152_i106:\2\"
				( attribute "PN" "2"
					( Origin gPackager )
				)
				( objectStatus "R1U43.2" )
			)
			( pin "@baseboard_fab2_lib.baseboard_fab2(sch_1):page93_i98:a"
				( attribute "PN" "1"
					( Origin gPackager )
				)
				( objectStatus "R2T39.1" )
			)
			( pin "@baseboard_fab2_lib.baseboard_fab2(sch_1):page93_i98:b"
				( attribute "PN" "2"
					( Origin gPackager )
				)
				( objectStatus "R2T39.2" )
			)
			( pin "@baseboard_fab2_lib.baseboard_fab2(sch_1):page93_i102:a"
				( attribute "PN" "1"
					( Origin gPackager )
				)
				( objectStatus "R2T68.1" )
			)
			( pin "@baseboard_fab2_lib.baseboard_fab2(sch_1):page93_i102:b"
				( attribute "PN" "2"
					( Origin gPackager )
				)
				( objectStatus "R2T68.2" )
			)
			( pin "@baseboard_fab2_lib.baseboard_fab2(sch_1):page93_i103:a"
				( attribute "PN" "1"
					( Origin gPackager )
				)
				( objectStatus "R2T60.1" )
			)
			( pin "@baseboard_fab2_lib.baseboard_fab2(sch_1):page93_i103:b"
				( attribute "PN" "2"
					( Origin gPackager )
				)
				( objectStatus "R2T60.2" )
			)
			( pin "@baseboard_fab2_lib.baseboard_fab2(sch_1):page93_i106:a"
				( attribute "PN" "1"
					( Origin gPackager )
				)
				( objectStatus "R7P28.1" )
			)
			( pin "@baseboard_fab2_lib.baseboard_fab2(sch_1):page93_i106:b"
				( attribute "PN" "2"
					( Origin gPackager )
				)
				( objectStatus "R7P28.2" )
			)
			( pin "@baseboard_fab2_lib.baseboard_fab2(sch_1):page93_i107:a"
				( attribute "PN" "1"
					( Origin gPackager )
				)
				( objectStatus "R2T59.1" )
			)
			( pin "@baseboard_fab2_lib.baseboard_fab2(sch_1):page93_i107:b"
				( attribute "PN" "2"
					( Origin gPackager )
				)
				( objectStatus "R2T59.2" )
			)
			( pin "@baseboard_fab2_lib.baseboard_fab2(sch_1):page93_i108:a"
				( attribute "PN" "1"
					( Origin gPackager )
				)
				( objectStatus "R2T69.1" )
			)
			( pin "@baseboard_fab2_lib.baseboard_fab2(sch_1):page93_i108:b"
				( attribute "PN" "2"
					( Origin gPackager )
				)
				( objectStatus "R2T69.2" )
			)
			( pin "@baseboard_fab2_lib.baseboard_fab2(sch_1):page93_i109:a"
				( attribute "PN" "1"
					( Origin gPackager )
				)
				( objectStatus "R2T71.1" )
			)
			( pin "@baseboard_fab2_lib.baseboard_fab2(sch_1):page93_i109:b"
				( attribute "PN" "2"
					( Origin gPackager )
				)
				( objectStatus "R2T71.2" )
			)
			( pin "@baseboard_fab2_lib.baseboard_fab2(sch_1):page93_i110:a"
				( attribute "PN" "1"
					( Origin gPackager )
				)
				( objectStatus "R7D43.1" )
			)
			( pin "@baseboard_fab2_lib.baseboard_fab2(sch_1):page93_i110:b"
				( attribute "PN" "2"
					( Origin gPackager )
				)
				( objectStatus "R7D43.2" )
			)
			( pin "@baseboard_fab2_lib.baseboard_fab2(sch_1):page93_i111:a"
				( attribute "PN" "1"
					( Origin gPackager )
				)
				( objectStatus "R2T65.1" )
			)
			( pin "@baseboard_fab2_lib.baseboard_fab2(sch_1):page93_i111:b"
				( attribute "PN" "2"
					( Origin gPackager )
				)
				( objectStatus "R2T65.2" )
			)
			( pin "@baseboard_fab2_lib.baseboard_fab2(sch_1):page93_i112:a"
				( attribute "PN" "1"
					( Origin gPackager )
				)
				( objectStatus "R2T66.1" )
			)
			( pin "@baseboard_fab2_lib.baseboard_fab2(sch_1):page93_i112:b"
				( attribute "PN" "2"
					( Origin gPackager )
				)
				( objectStatus "R2T66.2" )
			)
			( pin "@baseboard_fab2_lib.baseboard_fab2(sch_1):page93_i113:a"
				( attribute "PN" "1"
					( Origin gPackager )
				)
				( objectStatus "R2T67.1" )
			)
			( pin "@baseboard_fab2_lib.baseboard_fab2(sch_1):page93_i113:b"
				( attribute "PN" "2"
					( Origin gPackager )
				)
				( objectStatus "R2T67.2" )
			)
			( pin "@baseboard_fab2_lib.baseboard_fab2(sch_1):page93_i114:a"
				( attribute "PN" "1"
					( Origin gPackager )
				)
				( objectStatus "R7D41.1" )
			)
			( pin "@baseboard_fab2_lib.baseboard_fab2(sch_1):page93_i114:b"
				( attribute "PN" "2"
					( Origin gPackager )
				)
				( objectStatus "R7D41.2" )
			)
			( pin "@baseboard_fab2_lib.baseboard_fab2(sch_1):page93_i119:a"
				( attribute "PN" "1"
					( Origin gPackager )
				)
				( objectStatus "R8F38.1" )
			)
			( pin "@baseboard_fab2_lib.baseboard_fab2(sch_1):page93_i119:b"
				( attribute "PN" "2"
					( Origin gPackager )
				)
				( objectStatus "R8F38.2" )
			)
			( pin "@baseboard_fab2_lib.baseboard_fab2(sch_1):page93_i121:a"
				( attribute "PN" "1"
					( Origin gPackager )
				)
				( objectStatus "R2T64.1" )
			)
			( pin "@baseboard_fab2_lib.baseboard_fab2(sch_1):page93_i121:b"
				( attribute "PN" "2"
					( Origin gPackager )
				)
				( objectStatus "R2T64.2" )
			)
			( pin "@baseboard_fab2_lib.baseboard_fab2(sch_1):page93_i122:a"
				( attribute "PN" "1"
					( Origin gPackager )
				)
				( objectStatus "R1T36.1" )
			)
			( pin "@baseboard_fab2_lib.baseboard_fab2(sch_1):page93_i122:b"
				( attribute "PN" "2"
					( Origin gPackager )
				)
				( objectStatus "R1T36.2" )
			)
			( pin "@baseboard_fab2_lib.baseboard_fab2(sch_1):page93_i123:a"
				( attribute "PN" "1"
					( Origin gPackager )
				)
				( objectStatus "R1T37.1" )
			)
			( pin "@baseboard_fab2_lib.baseboard_fab2(sch_1):page93_i123:b"
				( attribute "PN" "2"
					( Origin gPackager )
				)
				( objectStatus "R1T37.2" )
			)
			( pin "@baseboard_fab2_lib.baseboard_fab2(sch_1):page93_i127:a"
				( attribute "PN" "1"
					( Origin gPackager )
				)
				( objectStatus "R2T50.1" )
			)
			( pin "@baseboard_fab2_lib.baseboard_fab2(sch_1):page93_i127:b"
				( attribute "PN" "2"
					( Origin gPackager )
				)
				( objectStatus "R2T50.2" )
			)
			( pin "@baseboard_fab2_lib.baseboard_fab2(sch_1):page93_i131:a"
				( attribute "PN" "1"
					( Origin gPackager )
				)
				( objectStatus "R8F37.1" )
			)
			( pin "@baseboard_fab2_lib.baseboard_fab2(sch_1):page93_i131:b"
				( attribute "PN" "2"
					( Origin gPackager )
				)
				( objectStatus "R8F37.2" )
			)
			( pin "@baseboard_fab2_lib.baseboard_fab2(sch_1):page93_i133:a"
				( attribute "PN" "1"
					( Origin gPackager )
				)
				( objectStatus "R2T63.1" )
			)
			( pin "@baseboard_fab2_lib.baseboard_fab2(sch_1):page93_i133:b"
				( attribute "PN" "2"
					( Origin gPackager )
				)
				( objectStatus "R2T63.2" )
			)
			( pin "@baseboard_fab2_lib.baseboard_fab2(sch_1):page93_i135:a"
				( attribute "PN" "1"
					( Origin gPackager )
				)
				( objectStatus "R1T35.1" )
			)
			( pin "@baseboard_fab2_lib.baseboard_fab2(sch_1):page93_i135:b"
				( attribute "PN" "2"
					( Origin gPackager )
				)
				( objectStatus "R1T35.2" )
			)
			( pin "@baseboard_fab2_lib.baseboard_fab2(sch_1):page93_i137:a"
				( attribute "PN" "1"
					( Origin gPackager )
				)
				( objectStatus "R1T38.1" )
			)
			( pin "@baseboard_fab2_lib.baseboard_fab2(sch_1):page93_i137:b"
				( attribute "PN" "2"
					( Origin gPackager )
				)
				( objectStatus "R1T38.2" )
			)
			( pin "@baseboard_fab2_lib.baseboard_fab2(sch_1):page93_i143:a"
				( attribute "PN" "1"
					( Origin gPackager )
				)
				( objectStatus "R2T72.1" )
			)
			( pin "@baseboard_fab2_lib.baseboard_fab2(sch_1):page93_i143:b"
				( attribute "PN" "2"
					( Origin gPackager )
				)
				( objectStatus "R2T72.2" )
			)
			( pin "@baseboard_fab2_lib.baseboard_fab2(sch_1):page93_i144:a"
				( attribute "PN" "1"
					( Origin gPackager )
				)
				( objectStatus "R2T73.1" )
			)
			( pin "@baseboard_fab2_lib.baseboard_fab2(sch_1):page93_i144:b"
				( attribute "PN" "2"
					( Origin gPackager )
				)
				( objectStatus "R2T73.2" )
			)
			( pin "@baseboard_fab2_lib.baseboard_fab2(sch_1):page94_i49:drain(0)"
				( attribute "PN" "6"
					( Origin gPackager )
				)
				( objectStatus "Q3U1.6" )
			)
			( pin "@baseboard_fab2_lib.baseboard_fab2(sch_1):page94_i49:gate(0)"
				( attribute "PN" "2"
					( Origin gPackager )
				)
				( objectStatus "Q3U1.2" )
			)
			( pin "@baseboard_fab2_lib.baseboard_fab2(sch_1):page94_i49:source(0)"
				( attribute "PN" "1"
					( Origin gPackager )
				)
				( objectStatus "Q3U1.1" )
			)
			( pin "@baseboard_fab2_lib.baseboard_fab2(sch_1):page94_i51:a"
				( attribute "PN" "1"
					( Origin gPackager )
				)
				( objectStatus "R7G7.1" )
			)
			( pin "@baseboard_fab2_lib.baseboard_fab2(sch_1):page94_i51:b"
				( attribute "PN" "2"
					( Origin gPackager )
				)
				( objectStatus "R7G7.2" )
			)
			( pin "@baseboard_fab2_lib.baseboard_fab2(sch_1):page94_i60:drain(0)"
				( attribute "PN" "6"
					( Origin gPackager )
				)
				( objectStatus "Q7E1.6" )
			)
			( pin "@baseboard_fab2_lib.baseboard_fab2(sch_1):page94_i60:gate(0)"
				( attribute "PN" "2"
					( Origin gPackager )
				)
				( objectStatus "Q7E1.2" )
			)
			( pin "@baseboard_fab2_lib.baseboard_fab2(sch_1):page94_i60:source(0)"
				( attribute "PN" "1"
					( Origin gPackager )
				)
				( objectStatus "Q7E1.1" )
			)
			( pin "@baseboard_fab2_lib.baseboard_fab2(sch_1):page94_i64:drain(0)"
				( attribute "PN" "3"
					( Origin gPackager )
				)
				( objectStatus "Q7E1.3" )
			)
			( pin "@baseboard_fab2_lib.baseboard_fab2(sch_1):page94_i64:gate(0)"
				( attribute "PN" "5"
					( Origin gPackager )
				)
				( objectStatus "Q7E1.5" )
			)
			( pin "@baseboard_fab2_lib.baseboard_fab2(sch_1):page94_i64:source(0)"
				( attribute "PN" "4"
					( Origin gPackager )
				)
				( objectStatus "Q7E1.4" )
			)
			( pin "@baseboard_fab2_lib.baseboard_fab2(sch_1):page94_i66:a"
				( attribute "PN" "1"
					( Origin gPackager )
				)
				( objectStatus "R3R4.1" )
			)
			( pin "@baseboard_fab2_lib.baseboard_fab2(sch_1):page94_i66:b"
				( attribute "PN" "2"
					( Origin gPackager )
				)
				( objectStatus "R3R4.2" )
			)
			( pin "@baseboard_fab2_lib.baseboard_fab2(sch_1):page94_i69:drain(0)"
				( attribute "PN" "6"
					( Origin gPackager )
				)
				( objectStatus "Q7E2.6" )
			)
			( pin "@baseboard_fab2_lib.baseboard_fab2(sch_1):page94_i69:gate(0)"
				( attribute "PN" "2"
					( Origin gPackager )
				)
				( objectStatus "Q7E2.2" )
			)
			( pin "@baseboard_fab2_lib.baseboard_fab2(sch_1):page94_i69:source(0)"
				( attribute "PN" "1"
					( Origin gPackager )
				)
				( objectStatus "Q7E2.1" )
			)
			( pin "@baseboard_fab2_lib.baseboard_fab2(sch_1):page94_i75:drain(0)"
				( attribute "PN" "3"
					( Origin gPackager )
				)
				( objectStatus "Q7E2.3" )
			)
			( pin "@baseboard_fab2_lib.baseboard_fab2(sch_1):page94_i75:gate(0)"
				( attribute "PN" "5"
					( Origin gPackager )
				)
				( objectStatus "Q7E2.5" )
			)
			( pin "@baseboard_fab2_lib.baseboard_fab2(sch_1):page94_i75:source(0)"
				( attribute "PN" "4"
					( Origin gPackager )
				)
				( objectStatus "Q7E2.4" )
			)
			( pin "@baseboard_fab2_lib.baseboard_fab2(sch_1):page94_i77:drain(0)"
				( attribute "PN" "3"
					( Origin gPackager )
				)
				( objectStatus "Q4B1.3" )
			)
			( pin "@baseboard_fab2_lib.baseboard_fab2(sch_1):page94_i77:gate(0)"
				( attribute "PN" "5"
					( Origin gPackager )
				)
				( objectStatus "Q4B1.5" )
			)
			( pin "@baseboard_fab2_lib.baseboard_fab2(sch_1):page94_i77:source(0)"
				( attribute "PN" "4"
					( Origin gPackager )
				)
				( objectStatus "Q4B1.4" )
			)
			( pin "@baseboard_fab2_lib.baseboard_fab2(sch_1):page94_i79:a"
				( attribute "PN" "1"
					( Origin gPackager )
				)
				( objectStatus "R3R10.1" )
			)
			( pin "@baseboard_fab2_lib.baseboard_fab2(sch_1):page94_i79:b"
				( attribute "PN" "2"
					( Origin gPackager )
				)
				( objectStatus "R3R10.2" )
			)
			( pin "@baseboard_fab2_lib.baseboard_fab2(sch_1):page94_i82:a"
				( attribute "PN" "1"
					( Origin gPackager )
				)
				( objectStatus "R6M4.1" )
			)
			( pin "@baseboard_fab2_lib.baseboard_fab2(sch_1):page94_i82:b"
				( attribute "PN" "2"
					( Origin gPackager )
				)
				( objectStatus "R6M4.2" )
			)
			( pin "@baseboard_fab2_lib.baseboard_fab2(sch_1):page94_i84:drain(0)"
				( attribute "PN" "6"
					( Origin gPackager )
				)
				( objectStatus "Q4B1.6" )
			)
			( pin "@baseboard_fab2_lib.baseboard_fab2(sch_1):page94_i84:gate(0)"
				( attribute "PN" "2"
					( Origin gPackager )
				)
				( objectStatus "Q4B1.2" )
			)
			( pin "@baseboard_fab2_lib.baseboard_fab2(sch_1):page94_i84:source(0)"
				( attribute "PN" "1"
					( Origin gPackager )
				)
				( objectStatus "Q4B1.1" )
			)
			( pin "@baseboard_fab2_lib.baseboard_fab2(sch_1):page94_i89:drain(0)"
				( attribute "PN" "3"
					( Origin gPackager )
				)
				( objectStatus "Q3U1.3" )
			)
			( pin "@baseboard_fab2_lib.baseboard_fab2(sch_1):page94_i89:gate(0)"
				( attribute "PN" "5"
					( Origin gPackager )
				)
				( objectStatus "Q3U1.5" )
			)
			( pin "@baseboard_fab2_lib.baseboard_fab2(sch_1):page94_i89:source(0)"
				( attribute "PN" "4"
					( Origin gPackager )
				)
				( objectStatus "Q3U1.4" )
			)
			( pin "@baseboard_fab2_lib.baseboard_fab2(sch_1):page94_i91:a"
				( attribute "PN" "1"
					( Origin gPackager )
				)
				( objectStatus "R4U1.1" )
			)
			( pin "@baseboard_fab2_lib.baseboard_fab2(sch_1):page94_i91:b"
				( attribute "PN" "2"
					( Origin gPackager )
				)
				( objectStatus "R4U1.2" )
			)
			( pin "@baseboard_fab2_lib.baseboard_fab2(sch_1):page94_i94:a"
				( attribute "PN" "1"
					( Origin gPackager )
				)
				( objectStatus "R4U3.1" )
			)
			( pin "@baseboard_fab2_lib.baseboard_fab2(sch_1):page94_i94:b"
				( attribute "PN" "2"
					( Origin gPackager )
				)
				( objectStatus "R4U3.2" )
			)
			( pin "@baseboard_fab2_lib.baseboard_fab2(sch_1):page94_i98:drain(0)"
				( attribute "PN" "6"
					( Origin gPackager )
				)
				( objectStatus "Q4U1.6" )
			)
			( pin "@baseboard_fab2_lib.baseboard_fab2(sch_1):page94_i98:gate(0)"
				( attribute "PN" "2"
					( Origin gPackager )
				)
				( objectStatus "Q4U1.2" )
			)
			( pin "@baseboard_fab2_lib.baseboard_fab2(sch_1):page94_i98:source(0)"
				( attribute "PN" "1"
					( Origin gPackager )
				)
				( objectStatus "Q4U1.1" )
			)
			( pin "@baseboard_fab2_lib.baseboard_fab2(sch_1):page94_i100:a"
				( attribute "PN" "1"
					( Origin gPackager )
				)
				( objectStatus "R4U2.1" )
			)
			( pin "@baseboard_fab2_lib.baseboard_fab2(sch_1):page94_i100:b"
				( attribute "PN" "2"
					( Origin gPackager )
				)
				( objectStatus "R4U2.2" )
			)
			( pin "@baseboard_fab2_lib.baseboard_fab2(sch_1):page94_i102:drain(0)"
				( attribute "PN" "3"
					( Origin gPackager )
				)
				( objectStatus "Q4U1.3" )
			)
			( pin "@baseboard_fab2_lib.baseboard_fab2(sch_1):page94_i102:gate(0)"
				( attribute "PN" "5"
					( Origin gPackager )
				)
				( objectStatus "Q4U1.5" )
			)
			( pin "@baseboard_fab2_lib.baseboard_fab2(sch_1):page94_i102:source(0)"
				( attribute "PN" "4"
					( Origin gPackager )
				)
				( objectStatus "Q4U1.4" )
			)
			( pin "@baseboard_fab2_lib.baseboard_fab2(sch_1):page94_i104:a"
				( attribute "PN" "1"
					( Origin gPackager )
				)
				( objectStatus "R4U4.1" )
			)
			( pin "@baseboard_fab2_lib.baseboard_fab2(sch_1):page94_i104:b"
				( attribute "PN" "2"
					( Origin gPackager )
				)
				( objectStatus "R4U4.2" )
			)
			( pin "@baseboard_fab2_lib.baseboard_fab2(sch_1):page95_i28:drain(0)"
				( attribute "PN" "6"
					( Origin gPackager )
				)
				( objectStatus "Q2U1.6" )
			)
			( pin "@baseboard_fab2_lib.baseboard_fab2(sch_1):page95_i28:gate(0)"
				( attribute "PN" "2"
					( Origin gPackager )
				)
				( objectStatus "Q2U1.2" )
			)
			( pin "@baseboard_fab2_lib.baseboard_fab2(sch_1):page95_i28:source(0)"
				( attribute "PN" "1"
					( Origin gPackager )
				)
				( objectStatus "Q2U1.1" )
			)
			( pin "@baseboard_fab2_lib.baseboard_fab2(sch_1):page95_i32:drain(0)"
				( attribute "PN" "6"
					( Origin gPackager )
				)
				( objectStatus "Q4B2.6" )
			)
			( pin "@baseboard_fab2_lib.baseboard_fab2(sch_1):page95_i32:gate(0)"
				( attribute "PN" "2"
					( Origin gPackager )
				)
				( objectStatus "Q4B2.2" )
			)
			( pin "@baseboard_fab2_lib.baseboard_fab2(sch_1):page95_i32:source(0)"
				( attribute "PN" "1"
					( Origin gPackager )
				)
				( objectStatus "Q4B2.1" )
			)
			( pin "@baseboard_fab2_lib.baseboard_fab2(sch_1):page95_i33:drain(0)"
				( attribute "PN" "3"
					( Origin gPackager )
				)
				( objectStatus "Q4B2.3" )
			)
			( pin "@baseboard_fab2_lib.baseboard_fab2(sch_1):page95_i33:gate(0)"
				( attribute "PN" "5"
					( Origin gPackager )
				)
				( objectStatus "Q4B2.5" )
			)
			( pin "@baseboard_fab2_lib.baseboard_fab2(sch_1):page95_i33:source(0)"
				( attribute "PN" "4"
					( Origin gPackager )
				)
				( objectStatus "Q4B2.4" )
			)
			( pin "@baseboard_fab2_lib.baseboard_fab2(sch_1):page95_i51:drain(0)"
				( attribute "PN" "3"
					( Origin gPackager )
				)
				( objectStatus "Q7E3.3" )
			)
			( pin "@baseboard_fab2_lib.baseboard_fab2(sch_1):page95_i51:gate(0)"
				( attribute "PN" "5"
					( Origin gPackager )
				)
				( objectStatus "Q7E3.5" )
			)
			( pin "@baseboard_fab2_lib.baseboard_fab2(sch_1):page95_i51:source(0)"
				( attribute "PN" "4"
					( Origin gPackager )
				)
				( objectStatus "Q7E3.4" )
			)
			( pin "@baseboard_fab2_lib.baseboard_fab2(sch_1):page95_i52:drain(0)"
				( attribute "PN" "6"
					( Origin gPackager )
				)
				( objectStatus "Q7E3.6" )
			)
			( pin "@baseboard_fab2_lib.baseboard_fab2(sch_1):page95_i52:gate(0)"
				( attribute "PN" "2"
					( Origin gPackager )
				)
				( objectStatus "Q7E3.2" )
			)
			( pin "@baseboard_fab2_lib.baseboard_fab2(sch_1):page95_i52:source(0)"
				( attribute "PN" "1"
					( Origin gPackager )
				)
				( objectStatus "Q7E3.1" )
			)
			( pin "@baseboard_fab2_lib.baseboard_fab2(sch_1):page95_i59:drain(0)"
				( attribute "PN" "3"
					( Origin gPackager )
				)
				( objectStatus "Q7E5.3" )
			)
			( pin "@baseboard_fab2_lib.baseboard_fab2(sch_1):page95_i59:gate(0)"
				( attribute "PN" "5"
					( Origin gPackager )
				)
				( objectStatus "Q7E5.5" )
			)
			( pin "@baseboard_fab2_lib.baseboard_fab2(sch_1):page95_i59:source(0)"
				( attribute "PN" "4"
					( Origin gPackager )
				)
				( objectStatus "Q7E5.4" )
			)
			( pin "@baseboard_fab2_lib.baseboard_fab2(sch_1):page95_i62:a"
				( attribute "PN" "1"
					( Origin gPackager )
				)
				( objectStatus "R7E10.1" )
			)
			( pin "@baseboard_fab2_lib.baseboard_fab2(sch_1):page95_i62:b"
				( attribute "PN" "2"
					( Origin gPackager )
				)
				( objectStatus "R7E10.2" )
			)
			( pin "@baseboard_fab2_lib.baseboard_fab2(sch_1):page95_i69:drain(0)"
				( attribute "PN" "3"
					( Origin gPackager )
				)
				( objectStatus "Q7E6.3" )
			)
			( pin "@baseboard_fab2_lib.baseboard_fab2(sch_1):page95_i69:gate(0)"
				( attribute "PN" "5"
					( Origin gPackager )
				)
				( objectStatus "Q7E6.5" )
			)
			( pin "@baseboard_fab2_lib.baseboard_fab2(sch_1):page95_i69:source(0)"
				( attribute "PN" "4"
					( Origin gPackager )
				)
				( objectStatus "Q7E6.4" )
			)
			( pin "@baseboard_fab2_lib.baseboard_fab2(sch_1):page95_i72:a"
				( attribute "PN" "1"
					( Origin gPackager )
				)
				( objectStatus "R7E11.1" )
			)
			( pin "@baseboard_fab2_lib.baseboard_fab2(sch_1):page95_i72:b"
				( attribute "PN" "2"
					( Origin gPackager )
				)
				( objectStatus "R7E11.2" )
			)
			( pin "@baseboard_fab2_lib.baseboard_fab2(sch_1):page95_i92:a"
				( attribute "PN" "1"
					( Origin gPackager )
				)
				( objectStatus "C7E3.1" )
			)
			( pin "@baseboard_fab2_lib.baseboard_fab2(sch_1):page95_i92:b"
				( attribute "PN" "2"
					( Origin gPackager )
				)
				( objectStatus "C7E3.2" )
			)
			( pin "@baseboard_fab2_lib.baseboard_fab2(sch_1):page134_i15:drn"
				( attribute "PN" "3"
					( Origin gPackager )
				)
				( objectStatus "Q8D2.3" )
			)
			( pin "@baseboard_fab2_lib.baseboard_fab2(sch_1):page134_i15:gate"
				( attribute "PN" "1"
					( Origin gPackager )
				)
				( objectStatus "Q8D2.1" )
			)
			( pin "@baseboard_fab2_lib.baseboard_fab2(sch_1):page134_i15:src"
				( attribute "PN" "2"
					( Origin gPackager )
				)
				( objectStatus "Q8D2.2" )
			)
			( pin "@baseboard_fab2_lib.baseboard_fab2(sch_1):page95_i106:a"
				( attribute "PN" "1"
					( Origin gPackager )
				)
				( objectStatus "R7E7.1" )
			)
			( pin "@baseboard_fab2_lib.baseboard_fab2(sch_1):page95_i106:b"
				( attribute "PN" "2"
					( Origin gPackager )
				)
				( objectStatus "R7E7.2" )
			)
			( pin "@baseboard_fab2_lib.baseboard_fab2(sch_1):page95_i108:a"
				( attribute "PN" "1"
					( Origin gPackager )
				)
				( objectStatus "R7E9.1" )
			)
			( pin "@baseboard_fab2_lib.baseboard_fab2(sch_1):page95_i108:b"
				( attribute "PN" "2"
					( Origin gPackager )
				)
				( objectStatus "R7E9.2" )
			)
			( pin "@baseboard_fab2_lib.baseboard_fab2(sch_1):page95_i111:drain(0)"
				( attribute "PN" "6"
					( Origin gPackager )
				)
				( objectStatus "Q7E5.6" )
			)
			( pin "@baseboard_fab2_lib.baseboard_fab2(sch_1):page95_i111:gate(0)"
				( attribute "PN" "2"
					( Origin gPackager )
				)
				( objectStatus "Q7E5.2" )
			)
			( pin "@baseboard_fab2_lib.baseboard_fab2(sch_1):page95_i111:source(0)"
				( attribute "PN" "1"
					( Origin gPackager )
				)
				( objectStatus "Q7E5.1" )
			)
			( pin "@baseboard_fab2_lib.baseboard_fab2(sch_1):page95_i112:drain(0)"
				( attribute "PN" "6"
					( Origin gPackager )
				)
				( objectStatus "Q7E6.6" )
			)
			( pin "@baseboard_fab2_lib.baseboard_fab2(sch_1):page95_i112:gate(0)"
				( attribute "PN" "2"
					( Origin gPackager )
				)
				( objectStatus "Q7E6.2" )
			)
			( pin "@baseboard_fab2_lib.baseboard_fab2(sch_1):page95_i112:source(0)"
				( attribute "PN" "1"
					( Origin gPackager )
				)
				( objectStatus "Q7E6.1" )
			)
			( pin "@baseboard_fab2_lib.baseboard_fab2(sch_1):page95_i113:drain(0)"
				( attribute "PN" "3"
					( Origin gPackager )
				)
				( objectStatus "Q2U1.3" )
			)
			( pin "@baseboard_fab2_lib.baseboard_fab2(sch_1):page95_i113:gate(0)"
				( attribute "PN" "5"
					( Origin gPackager )
				)
				( objectStatus "Q2U1.5" )
			)
			( pin "@baseboard_fab2_lib.baseboard_fab2(sch_1):page95_i113:source(0)"
				( attribute "PN" "4"
					( Origin gPackager )
				)
				( objectStatus "Q2U1.4" )
			)
			( pin "@baseboard_fab2_lib.baseboard_fab2(sch_1):page95_i115:a"
				( attribute "PN" "1"
					( Origin gPackager )
				)
				( objectStatus "C7E4.1" )
			)
			( pin "@baseboard_fab2_lib.baseboard_fab2(sch_1):page95_i115:b"
				( attribute "PN" "2"
					( Origin gPackager )
				)
				( objectStatus "C7E4.2" )
			)
			( pin "@baseboard_fab2_lib.baseboard_fab2(sch_1):page95_i117:a(0)"
				( attribute "PN" "1"
					( Origin gPackager )
				)
				( objectStatus "U7E2.1" )
			)
			( pin "@baseboard_fab2_lib.baseboard_fab2(sch_1):page95_i117:b(0)"
				( attribute "PN" "2"
					( Origin gPackager )
				)
				( objectStatus "U7E2.2" )
			)
			( pin "@baseboard_fab2_lib.baseboard_fab2(sch_1):page95_i117:y(0)"
				( attribute "PN" "4"
					( Origin gPackager )
				)
				( objectStatus "U7E2.4" )
			)
			( pin "@baseboard_fab2_lib.baseboard_fab2(sch_1):page95_i118:a(0)"
				( attribute "PN" "1"
					( Origin gPackager )
				)
				( objectStatus "U7E3.1" )
			)
			( pin "@baseboard_fab2_lib.baseboard_fab2(sch_1):page95_i118:b(0)"
				( attribute "PN" "2"
					( Origin gPackager )
				)
				( objectStatus "U7E3.2" )
			)
			( pin "@baseboard_fab2_lib.baseboard_fab2(sch_1):page95_i118:y(0)"
				( attribute "PN" "4"
					( Origin gPackager )
				)
				( objectStatus "U7E3.4" )
			)
			( pin "@baseboard_fab2_lib.baseboard_fab2(sch_1):page149_i90:a"
				( attribute "PN" "1"
					( Origin gPackager )
				)
				( objectStatus "R25W93.1" )
			)
			( pin "@baseboard_fab2_lib.baseboard_fab2(sch_1):page149_i90:b"
				( attribute "PN" "2"
					( Origin gPackager )
				)
				( objectStatus "R25W93.2" )
			)
			( pin "@baseboard_fab2_lib.baseboard_fab2(sch_1):page96_i2:a"
				( attribute "PN" "1"
					( Origin gPackager )
				)
				( objectStatus "R6D12.1" )
			)
			( pin "@baseboard_fab2_lib.baseboard_fab2(sch_1):page96_i2:b"
				( attribute "PN" "2"
					( Origin gPackager )
				)
				( objectStatus "R6D12.2" )
			)
			( pin "@baseboard_fab2_lib.baseboard_fab2(sch_1):page96_i3:a"
				( attribute "PN" "1"
					( Origin gPackager )
				)
				( objectStatus "R6D8.1" )
			)
			( pin "@baseboard_fab2_lib.baseboard_fab2(sch_1):page96_i3:b"
				( attribute "PN" "2"
					( Origin gPackager )
				)
				( objectStatus "R6D8.2" )
			)
			( pin "@baseboard_fab2_lib.baseboard_fab2(sch_1):page96_i5:a"
				( attribute "PN" "1"
					( Origin gPackager )
				)
				( objectStatus "R3P29.1" )
			)
			( pin "@baseboard_fab2_lib.baseboard_fab2(sch_1):page96_i5:b"
				( attribute "PN" "2"
					( Origin gPackager )
				)
				( objectStatus "R3P29.2" )
			)
			( pin "@baseboard_fab2_lib.baseboard_fab2(sch_1):page96_i7:a"
				( attribute "PN" "1"
					( Origin gPackager )
				)
				( objectStatus "R3P38.1" )
			)
			( pin "@baseboard_fab2_lib.baseboard_fab2(sch_1):page96_i7:b"
				( attribute "PN" "2"
					( Origin gPackager )
				)
				( objectStatus "R3P38.2" )
			)
			( pin "@baseboard_fab2_lib.baseboard_fab2(sch_1):page96_i25:a"
				( attribute "PN" "1"
					( Origin gPackager )
				)
				( objectStatus "R3D20.1" )
			)
			( pin "@baseboard_fab2_lib.baseboard_fab2(sch_1):page96_i25:b"
				( attribute "PN" "2"
					( Origin gPackager )
				)
				( objectStatus "R3D20.2" )
			)
			( pin "@baseboard_fab2_lib.baseboard_fab2(sch_1):page96_i26:a"
				( attribute "PN" "1"
					( Origin gPackager )
				)
				( objectStatus "R3D15.1" )
			)
			( pin "@baseboard_fab2_lib.baseboard_fab2(sch_1):page96_i26:b"
				( attribute "PN" "2"
					( Origin gPackager )
				)
				( objectStatus "R3D15.2" )
			)
			( pin "@baseboard_fab2_lib.baseboard_fab2(sch_1):page96_i28:a"
				( attribute "PN" "1"
					( Origin gPackager )
				)
				( objectStatus "R7M9.1" )
			)
			( pin "@baseboard_fab2_lib.baseboard_fab2(sch_1):page96_i28:b"
				( attribute "PN" "2"
					( Origin gPackager )
				)
				( objectStatus "R7M9.2" )
			)
			( pin "@baseboard_fab2_lib.baseboard_fab2(sch_1):page96_i30:a"
				( attribute "PN" "1"
					( Origin gPackager )
				)
				( objectStatus "R3D21.1" )
			)
			( pin "@baseboard_fab2_lib.baseboard_fab2(sch_1):page96_i30:b"
				( attribute "PN" "2"
					( Origin gPackager )
				)
				( objectStatus "R3D21.2" )
			)
			( pin "@baseboard_fab2_lib.baseboard_fab2(sch_1):page96_i36:a"
				( attribute "PN" "1"
					( Origin gPackager )
				)
				( objectStatus "R3P36.1" )
			)
			( pin "@baseboard_fab2_lib.baseboard_fab2(sch_1):page96_i36:b"
				( attribute "PN" "2"
					( Origin gPackager )
				)
				( objectStatus "R3P36.2" )
			)
			( pin "@baseboard_fab2_lib.baseboard_fab2(sch_1):page96_i42:a0"
				( attribute "PN" "13"
					( Origin gPackager )
				)
				( objectStatus "U3P1.13" )
			)
			( pin "@baseboard_fab2_lib.baseboard_fab2(sch_1):page96_i42:a1"
				( attribute "PN" "12"
					( Origin gPackager )
				)
				( objectStatus "U3P1.12" )
			)
			( pin "@baseboard_fab2_lib.baseboard_fab2(sch_1):page96_i42:a2"
				( attribute "PN" "10"
					( Origin gPackager )
				)
				( objectStatus "U3P1.10" )
			)
			( pin "@baseboard_fab2_lib.baseboard_fab2(sch_1):page96_i42:a3"
				( attribute "PN" "9"
					( Origin gPackager )
				)
				( objectStatus "U3P1.9" )
			)
			( pin "@baseboard_fab2_lib.baseboard_fab2(sch_1):page96_i42:b0"
				( attribute "PN" "2"
					( Origin gPackager )
				)
				( objectStatus "U3P1.2" )
			)
			( pin "@baseboard_fab2_lib.baseboard_fab2(sch_1):page96_i42:b1"
				( attribute "PN" "3"
					( Origin gPackager )
				)
				( objectStatus "U3P1.3" )
			)
			( pin "@baseboard_fab2_lib.baseboard_fab2(sch_1):page96_i42:b2"
				( attribute "PN" "5"
					( Origin gPackager )
				)
				( objectStatus "U3P1.5" )
			)
			( pin "@baseboard_fab2_lib.baseboard_fab2(sch_1):page96_i42:b3"
				( attribute "PN" "6"
					( Origin gPackager )
				)
				( objectStatus "U3P1.6" )
			)
			( pin "@baseboard_fab2_lib.baseboard_fab2(sch_1):page96_i42:dir"
				( attribute "PN" "1"
					( Origin gPackager )
				)
				( objectStatus "U3P1.1" )
			)
			( pin "@baseboard_fab2_lib.baseboard_fab2(sch_1):page96_i42:gnd(0)"
				( attribute "PN" "7"
					( Origin gPackager )
				)
				( objectStatus "U3P1.7" )
			)
			( pin "@baseboard_fab2_lib.baseboard_fab2(sch_1):page96_i42:gnd(1)"
				( attribute "PN" "8"
					( Origin gPackager )
				)
				( objectStatus "U3P1.8" )
			)
			( pin "@baseboard_fab2_lib.baseboard_fab2(sch_1):page96_i42:gnd(2)"
				( attribute "PN" "11"
					( Origin gPackager )
				)
				( objectStatus "U3P1.11" )
			)
			( pin "@baseboard_fab2_lib.baseboard_fab2(sch_1):page96_i42:vcc"
				( attribute "PN" "14"
					( Origin gPackager )
				)
				( objectStatus "U3P1.14" )
			)
			( pin "@baseboard_fab2_lib.baseboard_fab2(sch_1):page96_i42:vref"
				( attribute "PN" "4"
					( Origin gPackager )
				)
				( objectStatus "U3P1.4" )
			)
			( pin "@baseboard_fab2_lib.baseboard_fab2(sch_1):page96_i46:a0"
				( attribute "PN" "13"
					( Origin gPackager )
				)
				( objectStatus "U4C2.13" )
			)
			( pin "@baseboard_fab2_lib.baseboard_fab2(sch_1):page96_i46:a1"
				( attribute "PN" "12"
					( Origin gPackager )
				)
				( objectStatus "U4C2.12" )
			)
			( pin "@baseboard_fab2_lib.baseboard_fab2(sch_1):page96_i46:a2"
				( attribute "PN" "10"
					( Origin gPackager )
				)
				( objectStatus "U4C2.10" )
			)
			( pin "@baseboard_fab2_lib.baseboard_fab2(sch_1):page96_i46:a3"
				( attribute "PN" "9"
					( Origin gPackager )
				)
				( objectStatus "U4C2.9" )
			)
			( pin "@baseboard_fab2_lib.baseboard_fab2(sch_1):page96_i46:b0"
				( attribute "PN" "2"
					( Origin gPackager )
				)
				( objectStatus "U4C2.2" )
			)
			( pin "@baseboard_fab2_lib.baseboard_fab2(sch_1):page96_i46:b1"
				( attribute "PN" "3"
					( Origin gPackager )
				)
				( objectStatus "U4C2.3" )
			)
			( pin "@baseboard_fab2_lib.baseboard_fab2(sch_1):page96_i46:b2"
				( attribute "PN" "5"
					( Origin gPackager )
				)
				( objectStatus "U4C2.5" )
			)
			( pin "@baseboard_fab2_lib.baseboard_fab2(sch_1):page96_i46:b3"
				( attribute "PN" "6"
					( Origin gPackager )
				)
				( objectStatus "U4C2.6" )
			)
			( pin "@baseboard_fab2_lib.baseboard_fab2(sch_1):page96_i46:dir"
				( attribute "PN" "1"
					( Origin gPackager )
				)
				( objectStatus "U4C2.1" )
			)
			( pin "@baseboard_fab2_lib.baseboard_fab2(sch_1):page96_i46:gnd(0)"
				( attribute "PN" "7"
					( Origin gPackager )
				)
				( objectStatus "U4C2.7" )
			)
			( pin "@baseboard_fab2_lib.baseboard_fab2(sch_1):page96_i46:gnd(1)"
				( attribute "PN" "8"
					( Origin gPackager )
				)
				( objectStatus "U4C2.8" )
			)
			( pin "@baseboard_fab2_lib.baseboard_fab2(sch_1):page96_i46:gnd(2)"
				( attribute "PN" "11"
					( Origin gPackager )
				)
				( objectStatus "U4C2.11" )
			)
			( pin "@baseboard_fab2_lib.baseboard_fab2(sch_1):page96_i46:vcc"
				( attribute "PN" "14"
					( Origin gPackager )
				)
				( objectStatus "U4C2.14" )
			)
			( pin "@baseboard_fab2_lib.baseboard_fab2(sch_1):page96_i46:vref"
				( attribute "PN" "4"
					( Origin gPackager )
				)
				( objectStatus "U4C2.4" )
			)
			( pin "@baseboard_fab2_lib.baseboard_fab2(sch_1):page96_i55:a"
				( attribute "PN" "1"
					( Origin gPackager )
				)
				( objectStatus "R4C8.1" )
			)
			( pin "@baseboard_fab2_lib.baseboard_fab2(sch_1):page96_i55:b"
				( attribute "PN" "2"
					( Origin gPackager )
				)
				( objectStatus "R4C8.2" )
			)
			( pin "@baseboard_fab2_lib.baseboard_fab2(sch_1):page96_i69:a"
				( attribute "PN" "1"
					( Origin gPackager )
				)
				( objectStatus "R4C9.1" )
			)
			( pin "@baseboard_fab2_lib.baseboard_fab2(sch_1):page96_i69:b"
				( attribute "PN" "2"
					( Origin gPackager )
				)
				( objectStatus "R4C9.2" )
			)
			( pin "@baseboard_fab2_lib.baseboard_fab2(sch_1):page96_i71:a"
				( attribute "PN" "1"
					( Origin gPackager )
				)
				( objectStatus "R3P32.1" )
			)
			( pin "@baseboard_fab2_lib.baseboard_fab2(sch_1):page96_i71:b"
				( attribute "PN" "2"
					( Origin gPackager )
				)
				( objectStatus "R3P32.2" )
			)
			( pin "@baseboard_fab2_lib.baseboard_fab2(sch_1):page96_i73:a"
				( attribute "PN" "1"
					( Origin gPackager )
				)
				( objectStatus "C3P42.1" )
			)
			( pin "@baseboard_fab2_lib.baseboard_fab2(sch_1):page96_i73:b"
				( attribute "PN" "2"
					( Origin gPackager )
				)
				( objectStatus "C3P42.2" )
			)
			( pin "@baseboard_fab2_lib.baseboard_fab2(sch_1):page96_i75:a"
				( attribute "PN" "1"
					( Origin gPackager )
				)
				( objectStatus "C4C3.1" )
			)
			( pin "@baseboard_fab2_lib.baseboard_fab2(sch_1):page96_i75:b"
				( attribute "PN" "2"
					( Origin gPackager )
				)
				( objectStatus "C4C3.2" )
			)
			( pin "@baseboard_fab2_lib.baseboard_fab2(sch_1):page97_i33:a"
				( attribute "PN" "1"
					( Origin gPackager )
				)
				( objectStatus "R3D18.1" )
			)
			( pin "@baseboard_fab2_lib.baseboard_fab2(sch_1):page97_i33:b"
				( attribute "PN" "2"
					( Origin gPackager )
				)
				( objectStatus "R3D18.2" )
			)
			( pin "@baseboard_fab2_lib.baseboard_fab2(sch_1):page97_i42:a"
				( attribute "PN" "1"
					( Origin gPackager )
				)
				( objectStatus "R4R4.1" )
			)
			( pin "@baseboard_fab2_lib.baseboard_fab2(sch_1):page97_i42:b"
				( attribute "PN" "2"
					( Origin gPackager )
				)
				( objectStatus "R4R4.2" )
			)
			( pin "@baseboard_fab2_lib.baseboard_fab2(sch_1):page97_i44:a"
				( attribute "PN" "1"
					( Origin gPackager )
				)
				( objectStatus "R7P20.1" )
			)
			( pin "@baseboard_fab2_lib.baseboard_fab2(sch_1):page97_i44:b"
				( attribute "PN" "2"
					( Origin gPackager )
				)
				( objectStatus "R7P20.2" )
			)
			( pin "@baseboard_fab2_lib.baseboard_fab2(sch_1):page97_i72:a"
				( attribute "PN" "1"
					( Origin gPackager )
				)
				( objectStatus "R4P21.1" )
			)
			( pin "@baseboard_fab2_lib.baseboard_fab2(sch_1):page97_i72:b"
				( attribute "PN" "2"
					( Origin gPackager )
				)
				( objectStatus "R4P21.2" )
			)
			( pin "@baseboard_fab2_lib.baseboard_fab2(sch_1):page97_i76:a"
				( attribute "PN" "1"
					( Origin gPackager )
				)
				( objectStatus "R4C10.1" )
			)
			( pin "@baseboard_fab2_lib.baseboard_fab2(sch_1):page97_i76:b"
				( attribute "PN" "2"
					( Origin gPackager )
				)
				( objectStatus "R4C10.2" )
			)
			( pin "@baseboard_fab2_lib.baseboard_fab2(sch_1):page97_i80:a"
				( attribute "PN" "1"
					( Origin gPackager )
				)
				( objectStatus "R4P5.1" )
			)
			( pin "@baseboard_fab2_lib.baseboard_fab2(sch_1):page97_i80:b"
				( attribute "PN" "2"
					( Origin gPackager )
				)
				( objectStatus "R4P5.2" )
			)
			( pin "@baseboard_fab2_lib.baseboard_fab2(sch_1):page97_i81:a"
				( attribute "PN" "1"
					( Origin gPackager )
				)
				( objectStatus "R7P13.1" )
			)
			( pin "@baseboard_fab2_lib.baseboard_fab2(sch_1):page97_i81:b"
				( attribute "PN" "2"
					( Origin gPackager )
				)
				( objectStatus "R7P13.2" )
			)
			( pin "@baseboard_fab2_lib.baseboard_fab2(sch_1):page98_i4:a"
				( attribute "PN" "1"
					( Origin gPackager )
				)
				( objectStatus "R4F5.1" )
			)
			( pin "@baseboard_fab2_lib.baseboard_fab2(sch_1):page98_i4:b"
				( attribute "PN" "2"
					( Origin gPackager )
				)
				( objectStatus "R4F5.2" )
			)
			( pin "@baseboard_fab2_lib.baseboard_fab2(sch_1):page98_i5:a"
				( attribute "PN" "1"
					( Origin gPackager )
				)
				( objectStatus "R4F3.1" )
			)
			( pin "@baseboard_fab2_lib.baseboard_fab2(sch_1):page98_i5:b"
				( attribute "PN" "2"
					( Origin gPackager )
				)
				( objectStatus "R4F3.2" )
			)
			( pin "@baseboard_fab2_lib.baseboard_fab2(sch_1):page98_i7:a"
				( attribute "PN" "1"
					( Origin gPackager )
				)
				( objectStatus "C4F9.1" )
			)
			( pin "@baseboard_fab2_lib.baseboard_fab2(sch_1):page98_i7:b"
				( attribute "PN" "2"
					( Origin gPackager )
				)
				( objectStatus "C4F9.2" )
			)
			( pin "@baseboard_fab2_lib.baseboard_fab2(sch_1):page98_i9:a"
				( attribute "PN" "1"
					( Origin gPackager )
				)
				( objectStatus "R6M1.1" )
			)
			( pin "@baseboard_fab2_lib.baseboard_fab2(sch_1):page98_i9:b"
				( attribute "PN" "2"
					( Origin gPackager )
				)
				( objectStatus "R6M1.2" )
			)
			( pin "@baseboard_fab2_lib.baseboard_fab2(sch_1):page98_i12:a"
				( attribute "PN" "1"
					( Origin gPackager )
				)
				( objectStatus "R6L16.1" )
			)
			( pin "@baseboard_fab2_lib.baseboard_fab2(sch_1):page98_i12:b"
				( attribute "PN" "2"
					( Origin gPackager )
				)
				( objectStatus "R6L16.2" )
			)
			( pin "@baseboard_fab2_lib.baseboard_fab2(sch_1):page98_i14:a"
				( attribute "PN" "1"
					( Origin gPackager )
				)
				( objectStatus "R6M2.1" )
			)
			( pin "@baseboard_fab2_lib.baseboard_fab2(sch_1):page98_i14:b"
				( attribute "PN" "2"
					( Origin gPackager )
				)
				( objectStatus "R6M2.2" )
			)
			( pin "@baseboard_fab2_lib.baseboard_fab2(sch_1):page98_i33:a"
				( attribute "PN" "1"
					( Origin gPackager )
				)
				( objectStatus "C6M2.1" )
			)
			( pin "@baseboard_fab2_lib.baseboard_fab2(sch_1):page98_i33:b"
				( attribute "PN" "2"
					( Origin gPackager )
				)
				( objectStatus "C6M2.2" )
			)
			( pin "@baseboard_fab2_lib.baseboard_fab2(sch_1):page98_i36:a"
				( attribute "PN" "1"
					( Origin gPackager )
				)
				( objectStatus "R4F4.1" )
			)
			( pin "@baseboard_fab2_lib.baseboard_fab2(sch_1):page98_i36:b"
				( attribute "PN" "2"
					( Origin gPackager )
				)
				( objectStatus "R4F4.2" )
			)
			( pin "@baseboard_fab2_lib.baseboard_fab2(sch_1):page98_i38:a"
				( attribute "PN" "1"
					( Origin gPackager )
				)
				( objectStatus "R4G2.1" )
			)
			( pin "@baseboard_fab2_lib.baseboard_fab2(sch_1):page98_i38:b"
				( attribute "PN" "2"
					( Origin gPackager )
				)
				( objectStatus "R4G2.2" )
			)
			( pin "@baseboard_fab2_lib.baseboard_fab2(sch_1):page98_i40:a"
				( attribute "PN" "1"
					( Origin gPackager )
				)
				( objectStatus "R4G3.1" )
			)
			( pin "@baseboard_fab2_lib.baseboard_fab2(sch_1):page98_i40:b"
				( attribute "PN" "2"
					( Origin gPackager )
				)
				( objectStatus "R4G3.2" )
			)
			( pin "@baseboard_fab2_lib.baseboard_fab2(sch_1):page98_i42:a"
				( attribute "PN" "1"
					( Origin gPackager )
				)
				( objectStatus "R4G1.1" )
			)
			( pin "@baseboard_fab2_lib.baseboard_fab2(sch_1):page98_i42:b"
				( attribute "PN" "2"
					( Origin gPackager )
				)
				( objectStatus "R4G1.2" )
			)
			( pin "@baseboard_fab2_lib.baseboard_fab2(sch_1):page98_i43:a"
				( attribute "PN" "1"
					( Origin gPackager )
				)
				( objectStatus "C4G1.1" )
			)
			( pin "@baseboard_fab2_lib.baseboard_fab2(sch_1):page98_i43:b"
				( attribute "PN" "2"
					( Origin gPackager )
				)
				( objectStatus "C4G1.2" )
			)
			( pin "@baseboard_fab2_lib.baseboard_fab2(sch_1):page98_i46:a"
				( attribute "PN" "1"
					( Origin gPackager )
				)
				( objectStatus "R4G21.1" )
			)
			( pin "@baseboard_fab2_lib.baseboard_fab2(sch_1):page98_i46:b"
				( attribute "PN" "2"
					( Origin gPackager )
				)
				( objectStatus "R4G21.2" )
			)
			( pin "@baseboard_fab2_lib.baseboard_fab2(sch_1):page98_i48:a"
				( attribute "PN" "1"
					( Origin gPackager )
				)
				( objectStatus "R4G22.1" )
			)
			( pin "@baseboard_fab2_lib.baseboard_fab2(sch_1):page98_i48:b"
				( attribute "PN" "2"
					( Origin gPackager )
				)
				( objectStatus "R4G22.2" )
			)
			( pin "@baseboard_fab2_lib.baseboard_fab2(sch_1):page98_i50:a"
				( attribute "PN" "1"
					( Origin gPackager )
				)
				( objectStatus "R4G20.1" )
			)
			( pin "@baseboard_fab2_lib.baseboard_fab2(sch_1):page98_i50:b"
				( attribute "PN" "2"
					( Origin gPackager )
				)
				( objectStatus "R4G20.2" )
			)
			( pin "@baseboard_fab2_lib.baseboard_fab2(sch_1):page98_i51:a"
				( attribute "PN" "1"
					( Origin gPackager )
				)
				( objectStatus "C4G17.1" )
			)
			( pin "@baseboard_fab2_lib.baseboard_fab2(sch_1):page98_i51:b"
				( attribute "PN" "2"
					( Origin gPackager )
				)
				( objectStatus "C4G17.2" )
			)
			( pin "@baseboard_fab2_lib.baseboard_fab2(sch_1):page98_i54:a"
				( attribute "PN" "1"
					( Origin gPackager )
				)
				( objectStatus "R6L13.1" )
			)
			( pin "@baseboard_fab2_lib.baseboard_fab2(sch_1):page98_i54:b"
				( attribute "PN" "2"
					( Origin gPackager )
				)
				( objectStatus "R6L13.2" )
			)
			( pin "@baseboard_fab2_lib.baseboard_fab2(sch_1):page98_i56:a"
				( attribute "PN" "1"
					( Origin gPackager )
				)
				( objectStatus "R6L12.1" )
			)
			( pin "@baseboard_fab2_lib.baseboard_fab2(sch_1):page98_i56:b"
				( attribute "PN" "2"
					( Origin gPackager )
				)
				( objectStatus "R6L12.2" )
			)
			( pin "@baseboard_fab2_lib.baseboard_fab2(sch_1):page98_i58:a"
				( attribute "PN" "1"
					( Origin gPackager )
				)
				( objectStatus "R6L14.1" )
			)
			( pin "@baseboard_fab2_lib.baseboard_fab2(sch_1):page98_i58:b"
				( attribute "PN" "2"
					( Origin gPackager )
				)
				( objectStatus "R6L14.2" )
			)
			( pin "@baseboard_fab2_lib.baseboard_fab2(sch_1):page98_i59:a"
				( attribute "PN" "1"
					( Origin gPackager )
				)
				( objectStatus "C6L7.1" )
			)
			( pin "@baseboard_fab2_lib.baseboard_fab2(sch_1):page98_i59:b"
				( attribute "PN" "2"
					( Origin gPackager )
				)
				( objectStatus "C6L7.2" )
			)
			( pin "@baseboard_fab2_lib.baseboard_fab2(sch_1):page98_i62:a"
				( attribute "PN" "1"
					( Origin gPackager )
				)
				( objectStatus "R6L2.1" )
			)
			( pin "@baseboard_fab2_lib.baseboard_fab2(sch_1):page98_i62:b"
				( attribute "PN" "2"
					( Origin gPackager )
				)
				( objectStatus "R6L2.2" )
			)
			( pin "@baseboard_fab2_lib.baseboard_fab2(sch_1):page98_i64:a"
				( attribute "PN" "1"
					( Origin gPackager )
				)
				( objectStatus "R6L1.1" )
			)
			( pin "@baseboard_fab2_lib.baseboard_fab2(sch_1):page98_i64:b"
				( attribute "PN" "2"
					( Origin gPackager )
				)
				( objectStatus "R6L1.2" )
			)
			( pin "@baseboard_fab2_lib.baseboard_fab2(sch_1):page98_i66:a"
				( attribute "PN" "1"
					( Origin gPackager )
				)
				( objectStatus "R6L3.1" )
			)
			( pin "@baseboard_fab2_lib.baseboard_fab2(sch_1):page98_i66:b"
				( attribute "PN" "2"
					( Origin gPackager )
				)
				( objectStatus "R6L3.2" )
			)
			( pin "@baseboard_fab2_lib.baseboard_fab2(sch_1):page98_i67:a"
				( attribute "PN" "1"
					( Origin gPackager )
				)
				( objectStatus "C6L2.1" )
			)
			( pin "@baseboard_fab2_lib.baseboard_fab2(sch_1):page98_i67:b"
				( attribute "PN" "2"
					( Origin gPackager )
				)
				( objectStatus "C6L2.2" )
			)
			( pin "@baseboard_fab2_lib.baseboard_fab2(sch_1):page99_i2:a"
				( attribute "PN" "1"
					( Origin gPackager )
				)
				( objectStatus "C6F2.1" )
			)
			( pin "@baseboard_fab2_lib.baseboard_fab2(sch_1):page99_i2:b"
				( attribute "PN" "2"
					( Origin gPackager )
				)
				( objectStatus "C6F2.2" )
			)
			( pin "@baseboard_fab2_lib.baseboard_fab2(sch_1):page99_i7:a"
				( attribute "PN" "1"
					( Origin gPackager )
				)
				( objectStatus "C6F3.1" )
			)
			( pin "@baseboard_fab2_lib.baseboard_fab2(sch_1):page99_i7:b"
				( attribute "PN" "2"
					( Origin gPackager )
				)
				( objectStatus "C6F3.2" )
			)
			( pin "@baseboard_fab2_lib.baseboard_fab2(sch_1):page99_i9:a"
				( attribute "PN" "1"
					( Origin gPackager )
				)
				( objectStatus "R4T9.1" )
			)
			( pin "@baseboard_fab2_lib.baseboard_fab2(sch_1):page99_i9:b"
				( attribute "PN" "2"
					( Origin gPackager )
				)
				( objectStatus "R4T9.2" )
			)
			( pin "@baseboard_fab2_lib.baseboard_fab2(sch_1):page99_i10:a"
				( attribute "PN" "1"
					( Origin gPackager )
				)
				( objectStatus "R4T10.1" )
			)
			( pin "@baseboard_fab2_lib.baseboard_fab2(sch_1):page99_i10:b"
				( attribute "PN" "2"
					( Origin gPackager )
				)
				( objectStatus "R4T10.2" )
			)
			( pin "@baseboard_fab2_lib.baseboard_fab2(sch_1):page99_i11:a"
				( attribute "PN" "1"
					( Origin gPackager )
				)
				( objectStatus "R4T8.1" )
			)
			( pin "@baseboard_fab2_lib.baseboard_fab2(sch_1):page99_i11:b"
				( attribute "PN" "2"
					( Origin gPackager )
				)
				( objectStatus "R4T8.2" )
			)
			( pin "@baseboard_fab2_lib.baseboard_fab2(sch_1):page99_i13:a"
				( attribute "PN" "1"
					( Origin gPackager )
				)
				( objectStatus "R4T7.1" )
			)
			( pin "@baseboard_fab2_lib.baseboard_fab2(sch_1):page99_i13:b"
				( attribute "PN" "2"
					( Origin gPackager )
				)
				( objectStatus "R4T7.2" )
			)
			( pin "@baseboard_fab2_lib.baseboard_fab2(sch_1):page99_i15:en"
				( attribute "PN" "5"
					( Origin gPackager )
				)
				( objectStatus "U6F1.5" )
			)
			( pin "@baseboard_fab2_lib.baseboard_fab2(sch_1):page99_i15:scla"
				( attribute "PN" "2"
					( Origin gPackager )
				)
				( objectStatus "U6F1.2" )
			)
			( pin "@baseboard_fab2_lib.baseboard_fab2(sch_1):page99_i15:sclb"
				( attribute "PN" "7"
					( Origin gPackager )
				)
				( objectStatus "U6F1.7" )
			)
			( pin "@baseboard_fab2_lib.baseboard_fab2(sch_1):page99_i15:sdaa"
				( attribute "PN" "3"
					( Origin gPackager )
				)
				( objectStatus "U6F1.3" )
			)
			( pin "@baseboard_fab2_lib.baseboard_fab2(sch_1):page99_i15:sdab"
				( attribute "PN" "6"
					( Origin gPackager )
				)
				( objectStatus "U6F1.6" )
			)
			( pin "@baseboard_fab2_lib.baseboard_fab2(sch_1):page99_i15:vcca"
				( attribute "PN" "1"
					( Origin gPackager )
				)
				( objectStatus "U6F1.1" )
			)
			( pin "@baseboard_fab2_lib.baseboard_fab2(sch_1):page99_i15:vccb"
				( attribute "PN" "8"
					( Origin gPackager )
				)
				( objectStatus "U6F1.8" )
			)
			( pin "@baseboard_fab2_lib.baseboard_fab2(sch_1):page99_i17:a"
				( attribute "PN" "1"
					( Origin gPackager )
				)
				( objectStatus "R4T6.1" )
			)
			( pin "@baseboard_fab2_lib.baseboard_fab2(sch_1):page99_i17:b"
				( attribute "PN" "2"
					( Origin gPackager )
				)
				( objectStatus "R4T6.2" )
			)
			( pin "@baseboard_fab2_lib.baseboard_fab2(sch_1):page99_i19:a"
				( attribute "PN" "1"
					( Origin gPackager )
				)
				( objectStatus "R4T5.1" )
			)
			( pin "@baseboard_fab2_lib.baseboard_fab2(sch_1):page99_i19:b"
				( attribute "PN" "2"
					( Origin gPackager )
				)
				( objectStatus "R4T5.2" )
			)
			( pin "@baseboard_fab2_lib.baseboard_fab2(sch_1):page99_i20:a"
				( attribute "PN" "1"
					( Origin gPackager )
				)
				( objectStatus "R4T4.1" )
			)
			( pin "@baseboard_fab2_lib.baseboard_fab2(sch_1):page99_i20:b"
				( attribute "PN" "2"
					( Origin gPackager )
				)
				( objectStatus "R4T4.2" )
			)
			( pin "@baseboard_fab2_lib.baseboard_fab2(sch_1):page99_i23:a"
				( attribute "PN" "1"
					( Origin gPackager )
				)
				( objectStatus "C7E1.1" )
			)
			( pin "@baseboard_fab2_lib.baseboard_fab2(sch_1):page99_i23:b"
				( attribute "PN" "2"
					( Origin gPackager )
				)
				( objectStatus "C7E1.2" )
			)
			( pin "@baseboard_fab2_lib.baseboard_fab2(sch_1):page99_i27:a"
				( attribute "PN" "1"
					( Origin gPackager )
				)
				( objectStatus "C4G22.1" )
			)
			( pin "@baseboard_fab2_lib.baseboard_fab2(sch_1):page99_i27:b"
				( attribute "PN" "2"
					( Origin gPackager )
				)
				( objectStatus "C4G22.2" )
			)
			( pin "@baseboard_fab2_lib.baseboard_fab2(sch_1):page99_i32:a"
				( attribute "PN" "1"
					( Origin gPackager )
				)
				( objectStatus "C7E2.1" )
			)
			( pin "@baseboard_fab2_lib.baseboard_fab2(sch_1):page99_i32:b"
				( attribute "PN" "2"
					( Origin gPackager )
				)
				( objectStatus "C7E2.2" )
			)
			( pin "@baseboard_fab2_lib.baseboard_fab2(sch_1):page99_i34:a"
				( attribute "PN" "1"
					( Origin gPackager )
				)
				( objectStatus "R3R9.1" )
			)
			( pin "@baseboard_fab2_lib.baseboard_fab2(sch_1):page99_i34:b"
				( attribute "PN" "2"
					( Origin gPackager )
				)
				( objectStatus "R3R9.2" )
			)
			( pin "@baseboard_fab2_lib.baseboard_fab2(sch_1):page99_i35:a"
				( attribute "PN" "1"
					( Origin gPackager )
				)
				( objectStatus "R3R8.1" )
			)
			( pin "@baseboard_fab2_lib.baseboard_fab2(sch_1):page99_i35:b"
				( attribute "PN" "2"
					( Origin gPackager )
				)
				( objectStatus "R3R8.2" )
			)
			( pin "@baseboard_fab2_lib.baseboard_fab2(sch_1):page99_i41:a"
				( attribute "PN" "1"
					( Origin gPackager )
				)
				( objectStatus "C4G25.1" )
			)
			( pin "@baseboard_fab2_lib.baseboard_fab2(sch_1):page99_i41:b"
				( attribute "PN" "2"
					( Origin gPackager )
				)
				( objectStatus "C4G25.2" )
			)
			( pin "@baseboard_fab2_lib.baseboard_fab2(sch_1):page99_i42:a"
				( attribute "PN" "1"
					( Origin gPackager )
				)
				( objectStatus "R6U13.1" )
			)
			( pin "@baseboard_fab2_lib.baseboard_fab2(sch_1):page99_i42:b"
				( attribute "PN" "2"
					( Origin gPackager )
				)
				( objectStatus "R6U13.2" )
			)
			( pin "@baseboard_fab2_lib.baseboard_fab2(sch_1):page225_i307:a"
				( attribute "PN" "1"
					( Origin gPackager )
				)
				( objectStatus "C8U11.1" )
			)
			( pin "@baseboard_fab2_lib.baseboard_fab2(sch_1):page225_i307:b"
				( attribute "PN" "2"
					( Origin gPackager )
				)
				( objectStatus "C8U11.2" )
			)
			( pin "@baseboard_fab2_lib.baseboard_fab2(sch_1):page99_i47:a"
				( attribute "PN" "1"
					( Origin gPackager )
				)
				( objectStatus "C3B4.1" )
			)
			( pin "@baseboard_fab2_lib.baseboard_fab2(sch_1):page99_i47:b"
				( attribute "PN" "2"
					( Origin gPackager )
				)
				( objectStatus "C3B4.2" )
			)
			( pin "@baseboard_fab2_lib.baseboard_fab2(sch_1):page99_i53:a"
				( attribute "PN" "1"
					( Origin gPackager )
				)
				( objectStatus "C3B5.1" )
			)
			( pin "@baseboard_fab2_lib.baseboard_fab2(sch_1):page99_i53:b"
				( attribute "PN" "2"
					( Origin gPackager )
				)
				( objectStatus "C3B5.2" )
			)
			( pin "@baseboard_fab2_lib.baseboard_fab2(sch_1):page99_i55:a"
				( attribute "PN" "1"
					( Origin gPackager )
				)
				( objectStatus "R7M5.1" )
			)
			( pin "@baseboard_fab2_lib.baseboard_fab2(sch_1):page99_i55:b"
				( attribute "PN" "2"
					( Origin gPackager )
				)
				( objectStatus "R7M5.2" )
			)
			( pin "@baseboard_fab2_lib.baseboard_fab2(sch_1):page99_i56:a"
				( attribute "PN" "1"
					( Origin gPackager )
				)
				( objectStatus "R7M4.1" )
			)
			( pin "@baseboard_fab2_lib.baseboard_fab2(sch_1):page99_i56:b"
				( attribute "PN" "2"
					( Origin gPackager )
				)
				( objectStatus "R7M4.2" )
			)
			( pin "@baseboard_fab2_lib.baseboard_fab2(sch_1):page99_i61:en"
				( attribute "PN" "5"
					( Origin gPackager )
				)
				( objectStatus "U7E1.5" )
			)
			( pin "@baseboard_fab2_lib.baseboard_fab2(sch_1):page99_i61:scla"
				( attribute "PN" "2"
					( Origin gPackager )
				)
				( objectStatus "U7E1.2" )
			)
			( pin "@baseboard_fab2_lib.baseboard_fab2(sch_1):page99_i61:sclb"
				( attribute "PN" "7"
					( Origin gPackager )
				)
				( objectStatus "U7E1.7" )
			)
			( pin "@baseboard_fab2_lib.baseboard_fab2(sch_1):page99_i61:sdaa"
				( attribute "PN" "3"
					( Origin gPackager )
				)
				( objectStatus "U7E1.3" )
			)
			( pin "@baseboard_fab2_lib.baseboard_fab2(sch_1):page99_i61:sdab"
				( attribute "PN" "6"
					( Origin gPackager )
				)
				( objectStatus "U7E1.6" )
			)
			( pin "@baseboard_fab2_lib.baseboard_fab2(sch_1):page99_i61:vcca"
				( attribute "PN" "1"
					( Origin gPackager )
				)
				( objectStatus "U7E1.1" )
			)
			( pin "@baseboard_fab2_lib.baseboard_fab2(sch_1):page99_i61:vccb"
				( attribute "PN" "8"
					( Origin gPackager )
				)
				( objectStatus "U7E1.8" )
			)
			( pin "@baseboard_fab2_lib.baseboard_fab2(sch_1):page99_i63:en"
				( attribute "PN" "5"
					( Origin gPackager )
				)
				( objectStatus "U4G1.5" )
			)
			( pin "@baseboard_fab2_lib.baseboard_fab2(sch_1):page99_i63:scla"
				( attribute "PN" "2"
					( Origin gPackager )
				)
				( objectStatus "U4G1.2" )
			)
			( pin "@baseboard_fab2_lib.baseboard_fab2(sch_1):page99_i63:sclb"
				( attribute "PN" "7"
					( Origin gPackager )
				)
				( objectStatus "U4G1.7" )
			)
			( pin "@baseboard_fab2_lib.baseboard_fab2(sch_1):page99_i63:sdaa"
				( attribute "PN" "3"
					( Origin gPackager )
				)
				( objectStatus "U4G1.3" )
			)
			( pin "@baseboard_fab2_lib.baseboard_fab2(sch_1):page99_i63:sdab"
				( attribute "PN" "6"
					( Origin gPackager )
				)
				( objectStatus "U4G1.6" )
			)
			( pin "@baseboard_fab2_lib.baseboard_fab2(sch_1):page99_i63:vcca"
				( attribute "PN" "1"
					( Origin gPackager )
				)
				( objectStatus "U4G1.1" )
			)
			( pin "@baseboard_fab2_lib.baseboard_fab2(sch_1):page99_i63:vccb"
				( attribute "PN" "8"
					( Origin gPackager )
				)
				( objectStatus "U4G1.8" )
			)
			( pin "@baseboard_fab2_lib.baseboard_fab2(sch_1):page99_i65:a"
				( attribute "PN" "1"
					( Origin gPackager )
				)
				( objectStatus "R3R13.1" )
			)
			( pin "@baseboard_fab2_lib.baseboard_fab2(sch_1):page99_i65:b"
				( attribute "PN" "2"
					( Origin gPackager )
				)
				( objectStatus "R3R13.2" )
			)
			( pin "@baseboard_fab2_lib.baseboard_fab2(sch_1):page99_i67:a"
				( attribute "PN" "1"
					( Origin gPackager )
				)
				( objectStatus "R3P60.1" )
			)
			( pin "@baseboard_fab2_lib.baseboard_fab2(sch_1):page99_i67:b"
				( attribute "PN" "2"
					( Origin gPackager )
				)
				( objectStatus "R3P60.2" )
			)
			( pin "@baseboard_fab2_lib.baseboard_fab2(sch_1):page99_i70:a"
				( attribute "PN" "1"
					( Origin gPackager )
				)
				( objectStatus "R6T1.1" )
			)
			( pin "@baseboard_fab2_lib.baseboard_fab2(sch_1):page99_i70:b"
				( attribute "PN" "2"
					( Origin gPackager )
				)
				( objectStatus "R6T1.2" )
			)
			( pin "@baseboard_fab2_lib.baseboard_fab2(sch_1):page99_i72:a"
				( attribute "PN" "1"
					( Origin gPackager )
				)
				( objectStatus "R6T2.1" )
			)
			( pin "@baseboard_fab2_lib.baseboard_fab2(sch_1):page99_i72:b"
				( attribute "PN" "2"
					( Origin gPackager )
				)
				( objectStatus "R6T2.2" )
			)
			( pin "@baseboard_fab2_lib.baseboard_fab2(sch_1):page99_i75:en"
				( attribute "PN" "5"
					( Origin gPackager )
				)
				( objectStatus "U3B1.5" )
			)
			( pin "@baseboard_fab2_lib.baseboard_fab2(sch_1):page99_i75:scla"
				( attribute "PN" "2"
					( Origin gPackager )
				)
				( objectStatus "U3B1.2" )
			)
			( pin "@baseboard_fab2_lib.baseboard_fab2(sch_1):page99_i75:sclb"
				( attribute "PN" "7"
					( Origin gPackager )
				)
				( objectStatus "U3B1.7" )
			)
			( pin "@baseboard_fab2_lib.baseboard_fab2(sch_1):page99_i75:sdaa"
				( attribute "PN" "3"
					( Origin gPackager )
				)
				( objectStatus "U3B1.3" )
			)
			( pin "@baseboard_fab2_lib.baseboard_fab2(sch_1):page99_i75:sdab"
				( attribute "PN" "6"
					( Origin gPackager )
				)
				( objectStatus "U3B1.6" )
			)
			( pin "@baseboard_fab2_lib.baseboard_fab2(sch_1):page99_i75:vcca"
				( attribute "PN" "1"
					( Origin gPackager )
				)
				( objectStatus "U3B1.1" )
			)
			( pin "@baseboard_fab2_lib.baseboard_fab2(sch_1):page99_i75:vccb"
				( attribute "PN" "8"
					( Origin gPackager )
				)
				( objectStatus "U3B1.8" )
			)
			( pin "@baseboard_fab2_lib.baseboard_fab2(sch_1):page99_i77:a"
				( attribute "PN" "1"
					( Origin gPackager )
				)
				( objectStatus "R7M7.1" )
			)
			( pin "@baseboard_fab2_lib.baseboard_fab2(sch_1):page99_i77:b"
				( attribute "PN" "2"
					( Origin gPackager )
				)
				( objectStatus "R7M7.2" )
			)
			( pin "@baseboard_fab2_lib.baseboard_fab2(sch_1):page99_i79:a"
				( attribute "PN" "1"
					( Origin gPackager )
				)
				( objectStatus "R7M2.1" )
			)
			( pin "@baseboard_fab2_lib.baseboard_fab2(sch_1):page99_i79:b"
				( attribute "PN" "2"
					( Origin gPackager )
				)
				( objectStatus "R7M2.2" )
			)
			( pin "@baseboard_fab2_lib.baseboard_fab2(sch_1):page99_i83:a"
				( attribute "PN" "1"
					( Origin gPackager )
				)
				( objectStatus "R4T3.1" )
			)
			( pin "@baseboard_fab2_lib.baseboard_fab2(sch_1):page99_i83:b"
				( attribute "PN" "2"
					( Origin gPackager )
				)
				( objectStatus "R4T3.2" )
			)
			( pin "@baseboard_fab2_lib.baseboard_fab2(sch_1):page99_i88:a"
				( attribute "PN" "1"
					( Origin gPackager )
				)
				( objectStatus "R3R7.1" )
			)
			( pin "@baseboard_fab2_lib.baseboard_fab2(sch_1):page99_i88:b"
				( attribute "PN" "2"
					( Origin gPackager )
				)
				( objectStatus "R3R7.2" )
			)
			( pin "@baseboard_fab2_lib.baseboard_fab2(sch_1):page99_i92:a"
				( attribute "PN" "1"
					( Origin gPackager )
				)
				( objectStatus "R6T3.1" )
			)
			( pin "@baseboard_fab2_lib.baseboard_fab2(sch_1):page99_i92:b"
				( attribute "PN" "2"
					( Origin gPackager )
				)
				( objectStatus "R6T3.2" )
			)
			( pin "@baseboard_fab2_lib.baseboard_fab2(sch_1):page99_i98:a"
				( attribute "PN" "1"
					( Origin gPackager )
				)
				( objectStatus "R7M3.1" )
			)
			( pin "@baseboard_fab2_lib.baseboard_fab2(sch_1):page99_i98:b"
				( attribute "PN" "2"
					( Origin gPackager )
				)
				( objectStatus "R7M3.2" )
			)
			( pin "@baseboard_fab2_lib.baseboard_fab2(sch_1):page99_i101:a"
				( attribute "PN" "1"
					( Origin gPackager )
				)
				( objectStatus "R3R12.1" )
			)
			( pin "@baseboard_fab2_lib.baseboard_fab2(sch_1):page99_i101:b"
				( attribute "PN" "2"
					( Origin gPackager )
				)
				( objectStatus "R3R12.2" )
			)
			( pin "@baseboard_fab2_lib.baseboard_fab2(sch_1):page99_i103:a"
				( attribute "PN" "1"
					( Origin gPackager )
				)
				( objectStatus "R3R5.1" )
			)
			( pin "@baseboard_fab2_lib.baseboard_fab2(sch_1):page99_i103:b"
				( attribute "PN" "2"
					( Origin gPackager )
				)
				( objectStatus "R3R5.2" )
			)
			( pin "@baseboard_fab2_lib.baseboard_fab2(sch_1):page99_i104:a"
				( attribute "PN" "1"
					( Origin gPackager )
				)
				( objectStatus "R6U18.1" )
			)
			( pin "@baseboard_fab2_lib.baseboard_fab2(sch_1):page99_i104:b"
				( attribute "PN" "2"
					( Origin gPackager )
				)
				( objectStatus "R6U18.2" )
			)
			( pin "@baseboard_fab2_lib.baseboard_fab2(sch_1):page99_i106:a"
				( attribute "PN" "1"
					( Origin gPackager )
				)
				( objectStatus "R6U17.1" )
			)
			( pin "@baseboard_fab2_lib.baseboard_fab2(sch_1):page99_i106:b"
				( attribute "PN" "2"
					( Origin gPackager )
				)
				( objectStatus "R6U17.2" )
			)
			( pin "@baseboard_fab2_lib.baseboard_fab2(sch_1):page99_i107:a"
				( attribute "PN" "1"
					( Origin gPackager )
				)
				( objectStatus "R7M6.1" )
			)
			( pin "@baseboard_fab2_lib.baseboard_fab2(sch_1):page99_i107:b"
				( attribute "PN" "2"
					( Origin gPackager )
				)
				( objectStatus "R7M6.2" )
			)
			( pin "@baseboard_fab2_lib.baseboard_fab2(sch_1):page99_i109:a"
				( attribute "PN" "1"
					( Origin gPackager )
				)
				( objectStatus "R7M1.1" )
			)
			( pin "@baseboard_fab2_lib.baseboard_fab2(sch_1):page99_i109:b"
				( attribute "PN" "2"
					( Origin gPackager )
				)
				( objectStatus "R7M1.2" )
			)
			( pin "@baseboard_fab2_lib.baseboard_fab2(sch_1):page99_i110:a"
				( attribute "PN" "1"
					( Origin gPackager )
				)
				( objectStatus "R3R14.1" )
			)
			( pin "@baseboard_fab2_lib.baseboard_fab2(sch_1):page99_i110:b"
				( attribute "PN" "2"
					( Origin gPackager )
				)
				( objectStatus "R3R14.2" )
			)
			( pin "@baseboard_fab2_lib.baseboard_fab2(sch_1):page99_i111:a"
				( attribute "PN" "1"
					( Origin gPackager )
				)
				( objectStatus "R6T4.1" )
			)
			( pin "@baseboard_fab2_lib.baseboard_fab2(sch_1):page99_i111:b"
				( attribute "PN" "2"
					( Origin gPackager )
				)
				( objectStatus "R6T4.2" )
			)
			( pin "@baseboard_fab2_lib.baseboard_fab2(sch_1):page99_i112:a"
				( attribute "PN" "1"
					( Origin gPackager )
				)
				( objectStatus "R7M8.1" )
			)
			( pin "@baseboard_fab2_lib.baseboard_fab2(sch_1):page99_i112:b"
				( attribute "PN" "2"
					( Origin gPackager )
				)
				( objectStatus "R7M8.2" )
			)
			( pin "@baseboard_fab2_lib.baseboard_fab2(sch_1):page100_i2:a"
				( attribute "PN" "1"
					( Origin gPackager )
				)
				( objectStatus "R1F6.1" )
			)
			( pin "@baseboard_fab2_lib.baseboard_fab2(sch_1):page100_i2:b"
				( attribute "PN" "2"
					( Origin gPackager )
				)
				( objectStatus "R1F6.2" )
			)
			( pin "@baseboard_fab2_lib.baseboard_fab2(sch_1):page100_i4:a"
				( attribute "PN" "1"
					( Origin gPackager )
				)
				( objectStatus "R9L11.1" )
			)
			( pin "@baseboard_fab2_lib.baseboard_fab2(sch_1):page100_i4:b"
				( attribute "PN" "2"
					( Origin gPackager )
				)
				( objectStatus "R9L11.2" )
			)
			( pin "@baseboard_fab2_lib.baseboard_fab2(sch_1):page100_i6:a"
				( attribute "PN" "1"
					( Origin gPackager )
				)
				( objectStatus "R1F5.1" )
			)
			( pin "@baseboard_fab2_lib.baseboard_fab2(sch_1):page100_i6:b"
				( attribute "PN" "2"
					( Origin gPackager )
				)
				( objectStatus "R1F5.2" )
			)
			( pin "@baseboard_fab2_lib.baseboard_fab2(sch_1):page100_i7:a"
				( attribute "PN" "1"
					( Origin gPackager )
				)
				( objectStatus "R1F4.1" )
			)
			( pin "@baseboard_fab2_lib.baseboard_fab2(sch_1):page100_i7:b"
				( attribute "PN" "2"
					( Origin gPackager )
				)
				( objectStatus "R1F4.2" )
			)
			( pin "@baseboard_fab2_lib.baseboard_fab2(sch_1):page100_i8:a"
				( attribute "PN" "1"
					( Origin gPackager )
				)
				( objectStatus "C1F19.1" )
			)
			( pin "@baseboard_fab2_lib.baseboard_fab2(sch_1):page100_i8:b"
				( attribute "PN" "2"
					( Origin gPackager )
				)
				( objectStatus "C1F19.2" )
			)
			( pin "@baseboard_fab2_lib.baseboard_fab2(sch_1):page100_i11:a"
				( attribute "PN" "1"
					( Origin gPackager )
				)
				( objectStatus "R9M1.1" )
			)
			( pin "@baseboard_fab2_lib.baseboard_fab2(sch_1):page100_i11:b"
				( attribute "PN" "2"
					( Origin gPackager )
				)
				( objectStatus "R9M1.2" )
			)
			( pin "@baseboard_fab2_lib.baseboard_fab2(sch_1):page100_i13:a"
				( attribute "PN" "1"
					( Origin gPackager )
				)
				( objectStatus "R9M2.1" )
			)
			( pin "@baseboard_fab2_lib.baseboard_fab2(sch_1):page100_i13:b"
				( attribute "PN" "2"
					( Origin gPackager )
				)
				( objectStatus "R9M2.2" )
			)
			( pin "@baseboard_fab2_lib.baseboard_fab2(sch_1):page100_i15:a"
				( attribute "PN" "1"
					( Origin gPackager )
				)
				( objectStatus "C9M2.1" )
			)
			( pin "@baseboard_fab2_lib.baseboard_fab2(sch_1):page100_i15:b"
				( attribute "PN" "2"
					( Origin gPackager )
				)
				( objectStatus "C9M2.2" )
			)
			( pin "@baseboard_fab2_lib.baseboard_fab2(sch_1):page100_i19:a"
				( attribute "PN" "1"
					( Origin gPackager )
				)
				( objectStatus "R1G2.1" )
			)
			( pin "@baseboard_fab2_lib.baseboard_fab2(sch_1):page100_i19:b"
				( attribute "PN" "2"
					( Origin gPackager )
				)
				( objectStatus "R1G2.2" )
			)
			( pin "@baseboard_fab2_lib.baseboard_fab2(sch_1):page100_i20:a"
				( attribute "PN" "1"
					( Origin gPackager )
				)
				( objectStatus "R1G3.1" )
			)
			( pin "@baseboard_fab2_lib.baseboard_fab2(sch_1):page100_i20:b"
				( attribute "PN" "2"
					( Origin gPackager )
				)
				( objectStatus "R1G3.2" )
			)
			( pin "@baseboard_fab2_lib.baseboard_fab2(sch_1):page100_i22:a"
				( attribute "PN" "1"
					( Origin gPackager )
				)
				( objectStatus "R9L7.1" )
			)
			( pin "@baseboard_fab2_lib.baseboard_fab2(sch_1):page100_i22:b"
				( attribute "PN" "2"
					( Origin gPackager )
				)
				( objectStatus "R9L7.2" )
			)
			( pin "@baseboard_fab2_lib.baseboard_fab2(sch_1):page100_i24:a"
				( attribute "PN" "1"
					( Origin gPackager )
				)
				( objectStatus "R9L6.1" )
			)
			( pin "@baseboard_fab2_lib.baseboard_fab2(sch_1):page100_i24:b"
				( attribute "PN" "2"
					( Origin gPackager )
				)
				( objectStatus "R9L6.2" )
			)
			( pin "@baseboard_fab2_lib.baseboard_fab2(sch_1):page100_i25:a"
				( attribute "PN" "1"
					( Origin gPackager )
				)
				( objectStatus "R1G1.1" )
			)
			( pin "@baseboard_fab2_lib.baseboard_fab2(sch_1):page100_i25:b"
				( attribute "PN" "2"
					( Origin gPackager )
				)
				( objectStatus "R1G1.2" )
			)
			( pin "@baseboard_fab2_lib.baseboard_fab2(sch_1):page100_i26:a"
				( attribute "PN" "1"
					( Origin gPackager )
				)
				( objectStatus "C1G8.1" )
			)
			( pin "@baseboard_fab2_lib.baseboard_fab2(sch_1):page100_i26:b"
				( attribute "PN" "2"
					( Origin gPackager )
				)
				( objectStatus "C1G8.2" )
			)
			( pin "@baseboard_fab2_lib.baseboard_fab2(sch_1):page100_i29:a"
				( attribute "PN" "1"
					( Origin gPackager )
				)
				( objectStatus "R9L8.1" )
			)
			( pin "@baseboard_fab2_lib.baseboard_fab2(sch_1):page100_i29:b"
				( attribute "PN" "2"
					( Origin gPackager )
				)
				( objectStatus "R9L8.2" )
			)
			( pin "@baseboard_fab2_lib.baseboard_fab2(sch_1):page100_i30:a"
				( attribute "PN" "1"
					( Origin gPackager )
				)
				( objectStatus "C9L8.1" )
			)
			( pin "@baseboard_fab2_lib.baseboard_fab2(sch_1):page100_i30:b"
				( attribute "PN" "2"
					( Origin gPackager )
				)
				( objectStatus "C9L8.2" )
			)
			( pin "@baseboard_fab2_lib.baseboard_fab2(sch_1):page100_i35:a"
				( attribute "PN" "1"
					( Origin gPackager )
				)
				( objectStatus "R1G15.1" )
			)
			( pin "@baseboard_fab2_lib.baseboard_fab2(sch_1):page100_i35:b"
				( attribute "PN" "2"
					( Origin gPackager )
				)
				( objectStatus "R1G15.2" )
			)
			( pin "@baseboard_fab2_lib.baseboard_fab2(sch_1):page100_i36:a"
				( attribute "PN" "1"
					( Origin gPackager )
				)
				( objectStatus "R1G17.1" )
			)
			( pin "@baseboard_fab2_lib.baseboard_fab2(sch_1):page100_i36:b"
				( attribute "PN" "2"
					( Origin gPackager )
				)
				( objectStatus "R1G17.2" )
			)
			( pin "@baseboard_fab2_lib.baseboard_fab2(sch_1):page100_i38:a"
				( attribute "PN" "1"
					( Origin gPackager )
				)
				( objectStatus "R9L2.1" )
			)
			( pin "@baseboard_fab2_lib.baseboard_fab2(sch_1):page100_i38:b"
				( attribute "PN" "2"
					( Origin gPackager )
				)
				( objectStatus "R9L2.2" )
			)
			( pin "@baseboard_fab2_lib.baseboard_fab2(sch_1):page100_i40:a"
				( attribute "PN" "1"
					( Origin gPackager )
				)
				( objectStatus "R9L1.1" )
			)
			( pin "@baseboard_fab2_lib.baseboard_fab2(sch_1):page100_i40:b"
				( attribute "PN" "2"
					( Origin gPackager )
				)
				( objectStatus "R9L1.2" )
			)
			( pin "@baseboard_fab2_lib.baseboard_fab2(sch_1):page100_i41:a"
				( attribute "PN" "1"
					( Origin gPackager )
				)
				( objectStatus "R1G14.1" )
			)
			( pin "@baseboard_fab2_lib.baseboard_fab2(sch_1):page100_i41:b"
				( attribute "PN" "2"
					( Origin gPackager )
				)
				( objectStatus "R1G14.2" )
			)
			( pin "@baseboard_fab2_lib.baseboard_fab2(sch_1):page100_i42:a"
				( attribute "PN" "1"
					( Origin gPackager )
				)
				( objectStatus "C1G18.1" )
			)
			( pin "@baseboard_fab2_lib.baseboard_fab2(sch_1):page100_i42:b"
				( attribute "PN" "2"
					( Origin gPackager )
				)
				( objectStatus "C1G18.2" )
			)
			( pin "@baseboard_fab2_lib.baseboard_fab2(sch_1):page100_i45:a"
				( attribute "PN" "1"
					( Origin gPackager )
				)
				( objectStatus "R9L3.1" )
			)
			( pin "@baseboard_fab2_lib.baseboard_fab2(sch_1):page100_i45:b"
				( attribute "PN" "2"
					( Origin gPackager )
				)
				( objectStatus "R9L3.2" )
			)
			( pin "@baseboard_fab2_lib.baseboard_fab2(sch_1):page100_i46:a"
				( attribute "PN" "1"
					( Origin gPackager )
				)
				( objectStatus "C9L3.1" )
			)
			( pin "@baseboard_fab2_lib.baseboard_fab2(sch_1):page100_i46:b"
				( attribute "PN" "2"
					( Origin gPackager )
				)
				( objectStatus "C9L3.2" )
			)
			( pin "@baseboard_fab2_lib.baseboard_fab2(sch_1):page101_i20:a"
				( attribute "PN" "1"
					( Origin gPackager )
				)
				( objectStatus "R8F29.1" )
			)
			( pin "@baseboard_fab2_lib.baseboard_fab2(sch_1):page101_i20:b"
				( attribute "PN" "2"
					( Origin gPackager )
				)
				( objectStatus "R8F29.2" )
			)
			( pin "@baseboard_fab2_lib.baseboard_fab2(sch_1):page101_i28:a"
				( attribute "PN" "1"
					( Origin gPackager )
				)
				( objectStatus "R8F25.1" )
			)
			( pin "@baseboard_fab2_lib.baseboard_fab2(sch_1):page101_i28:b"
				( attribute "PN" "2"
					( Origin gPackager )
				)
				( objectStatus "R8F25.2" )
			)
			( pin "@baseboard_fab2_lib.baseboard_fab2(sch_1):page101_i34:\25mhz_0\"
				( attribute "PN" "16"
					( Origin gPackager )
				)
				( objectStatus "EU8F2.16" )
			)
			( pin "@baseboard_fab2_lib.baseboard_fab2(sch_1):page101_i34:\25mhz_1\"
				( attribute "PN" "17"
					( Origin gPackager )
				)
				( objectStatus "EU8F2.17" )
			)
			( pin "@baseboard_fab2_lib.baseboard_fab2(sch_1):page101_i34:\32khz\"
				( attribute "PN" "13"
					( Origin gPackager )
				)
				( objectStatus "EU8F2.13" )
			)
			( pin "@baseboard_fab2_lib.baseboard_fab2(sch_1):page101_i34:\33mhz_smbadr\"
				( attribute "PN" "22"
					( Origin gPackager )
				)
				( objectStatus "EU8F2.22" )
			)
			( pin "@baseboard_fab2_lib.baseboard_fab2(sch_1):page101_i34:cpuclkc0"
				( attribute "PN" "8"
					( Origin gPackager )
				)
				( objectStatus "EU8F2.8" )
			)
			( pin "@baseboard_fab2_lib.baseboard_fab2(sch_1):page101_i34:cpuclkt0"
				( attribute "PN" "7"
					( Origin gPackager )
				)
				( objectStatus "EU8F2.7" )
			)
			( pin "@baseboard_fab2_lib.baseboard_fab2(sch_1):page101_i34:dot96ssc"
				( attribute "PN" "4"
					( Origin gPackager )
				)
				( objectStatus "EU8F2.4" )
			)
			( pin "@baseboard_fab2_lib.baseboard_fab2(sch_1):page101_i34:dot96sst"
				( attribute "PN" "3"
					( Origin gPackager )
				)
				( objectStatus "EU8F2.3" )
			)
			( pin "@baseboard_fab2_lib.baseboard_fab2(sch_1):page101_i34:gnd(0)"
				( attribute "PN" "1"
					( Origin gPackager )
				)
				( objectStatus "EU8F2.1" )
			)
			( pin "@baseboard_fab2_lib.baseboard_fab2(sch_1):page101_i34:gnd(1)"
				( attribute "PN" "41"
					( Origin gPackager )
				)
				( objectStatus "EU8F2.41" )
			)
			( pin "@baseboard_fab2_lib.baseboard_fab2(sch_1):page101_i34:gnd32k"
				( attribute "PN" "14"
					( Origin gPackager )
				)
				( objectStatus "EU8F2.14" )
			)
			( pin "@baseboard_fab2_lib.baseboard_fab2(sch_1):page101_i34:gnd33"
				( attribute "PN" "21"
					( Origin gPackager )
				)
				( objectStatus "EU8F2.21" )
			)
			( pin "@baseboard_fab2_lib.baseboard_fab2(sch_1):page101_i34:gnd_rgmii"
				( attribute "PN" "35"
					( Origin gPackager )
				)
				( objectStatus "EU8F2.35" )
			)
			( pin "@baseboard_fab2_lib.baseboard_fab2(sch_1):page101_i34:gndcpu"
				( attribute "PN" "10"
					( Origin gPackager )
				)
				( objectStatus "EU8F2.10" )
			)
			( pin "@baseboard_fab2_lib.baseboard_fab2(sch_1):page101_i34:gndref"
				( attribute "PN" "18"
					( Origin gPackager )
				)
				( objectStatus "EU8F2.18" )
			)
			( pin "@baseboard_fab2_lib.baseboard_fab2(sch_1):page101_i34:gndrmii(0)"
				( attribute "PN" "27"
					( Origin gPackager )
				)
				( objectStatus "EU8F2.27" )
			)
			( pin "@baseboard_fab2_lib.baseboard_fab2(sch_1):page101_i34:gndrmii(1)"
				( attribute "PN" "30"
					( Origin gPackager )
				)
				( objectStatus "EU8F2.30" )
			)
			( pin "@baseboard_fab2_lib.baseboard_fab2(sch_1):page101_i34:iref"
				( attribute "PN" "11"
					( Origin gPackager )
				)
				( objectStatus "EU8F2.11" )
			)
			( pin "@baseboard_fab2_lib.baseboard_fab2(sch_1):page101_i34:oe_96"
				( attribute "PN" "5"
					( Origin gPackager )
				)
				( objectStatus "EU8F2.5" )
			)
			( pin "@baseboard_fab2_lib.baseboard_fab2(sch_1):page101_i34:oe_cpu"
				( attribute "PN" "6"
					( Origin gPackager )
				)
				( objectStatus "EU8F2.6" )
			)
			( pin "@baseboard_fab2_lib.baseboard_fab2(sch_1):page101_i34:rgmii(0)"
				( attribute "PN" "37"
					( Origin gPackager )
				)
				( objectStatus "EU8F2.37" )
			)
			( pin "@baseboard_fab2_lib.baseboard_fab2(sch_1):page101_i34:rgmii(1)"
				( attribute "PN" "36"
					( Origin gPackager )
				)
				( objectStatus "EU8F2.36" )
			)
			( pin "@baseboard_fab2_lib.baseboard_fab2(sch_1):page101_i34:rmii(0)"
				( attribute "PN" "33"
					( Origin gPackager )
				)
				( objectStatus "EU8F2.33" )
			)
			( pin "@baseboard_fab2_lib.baseboard_fab2(sch_1):page101_i34:rmii(1)"
				( attribute "PN" "32"
					( Origin gPackager )
				)
				( objectStatus "EU8F2.32" )
			)
			( pin "@baseboard_fab2_lib.baseboard_fab2(sch_1):page101_i34:rmii(2)"
				( attribute "PN" "29"
					( Origin gPackager )
				)
				( objectStatus "EU8F2.29" )
			)
			( pin "@baseboard_fab2_lib.baseboard_fab2(sch_1):page101_i34:rmii(3)"
				( attribute "PN" "28"
					( Origin gPackager )
				)
				( objectStatus "EU8F2.28" )
			)
			( pin "@baseboard_fab2_lib.baseboard_fab2(sch_1):page101_i34:rmii(4)"
				( attribute "PN" "25"
					( Origin gPackager )
				)
				( objectStatus "EU8F2.25" )
			)
			( pin "@baseboard_fab2_lib.baseboard_fab2(sch_1):page101_i34:rmii(5)"
				( attribute "PN" "24"
					( Origin gPackager )
				)
				( objectStatus "EU8F2.24" )
			)
			( pin "@baseboard_fab2_lib.baseboard_fab2(sch_1):page101_i34:smbclk"
				( attribute "PN" "38"
					( Origin gPackager )
				)
				( objectStatus "EU8F2.38" )
			)
			( pin "@baseboard_fab2_lib.baseboard_fab2(sch_1):page101_i34:smbdat"
				( attribute "PN" "39"
					( Origin gPackager )
				)
				( objectStatus "EU8F2.39" )
			)
			( pin "@baseboard_fab2_lib.baseboard_fab2(sch_1):page101_i34:vdd32k"
				( attribute "PN" "12"
					( Origin gPackager )
				)
				( objectStatus "EU8F2.12" )
			)
			( pin "@baseboard_fab2_lib.baseboard_fab2(sch_1):page101_i34:vdd33"
				( attribute "PN" "23"
					( Origin gPackager )
				)
				( objectStatus "EU8F2.23" )
			)
			( pin "@baseboard_fab2_lib.baseboard_fab2(sch_1):page101_i34:vdd96"
				( attribute "PN" "2"
					( Origin gPackager )
				)
				( objectStatus "EU8F2.2" )
			)
			( pin "@baseboard_fab2_lib.baseboard_fab2(sch_1):page101_i34:vdd_rgmii"
				( attribute "PN" "34"
					( Origin gPackager )
				)
				( objectStatus "EU8F2.34" )
			)
			( pin "@baseboard_fab2_lib.baseboard_fab2(sch_1):page101_i34:vddcpu"
				( attribute "PN" "9"
					( Origin gPackager )
				)
				( objectStatus "EU8F2.9" )
			)
			( pin "@baseboard_fab2_lib.baseboard_fab2(sch_1):page101_i34:vddref"
				( attribute "PN" "15"
					( Origin gPackager )
				)
				( objectStatus "EU8F2.15" )
			)
			( pin "@baseboard_fab2_lib.baseboard_fab2(sch_1):page101_i34:vddrmii(0)"
				( attribute "PN" "26"
					( Origin gPackager )
				)
				( objectStatus "EU8F2.26" )
			)
			( pin "@baseboard_fab2_lib.baseboard_fab2(sch_1):page101_i34:vddrmii(1)"
				( attribute "PN" "31"
					( Origin gPackager )
				)
				( objectStatus "EU8F2.31" )
			)
			( pin "@baseboard_fab2_lib.baseboard_fab2(sch_1):page101_i34:vttpwr_gd_pd_n"
				( attribute "PN" "40"
					( Origin gPackager )
				)
				( objectStatus "EU8F2.40" )
			)
			( pin "@baseboard_fab2_lib.baseboard_fab2(sch_1):page101_i34:x1_25"
				( attribute "PN" "19"
					( Origin gPackager )
				)
				( objectStatus "EU8F2.19" )
			)
			( pin "@baseboard_fab2_lib.baseboard_fab2(sch_1):page101_i34:x2_25"
				( attribute "PN" "20"
					( Origin gPackager )
				)
				( objectStatus "EU8F2.20" )
			)
			( pin "@baseboard_fab2_lib.baseboard_fab2(sch_1):page101_i48:a"
				( attribute "PN" "1"
					( Origin gPackager )
				)
				( objectStatus "R2T25.1" )
			)
			( pin "@baseboard_fab2_lib.baseboard_fab2(sch_1):page101_i48:b"
				( attribute "PN" "2"
					( Origin gPackager )
				)
				( objectStatus "R2T25.2" )
			)
			( pin "@baseboard_fab2_lib.baseboard_fab2(sch_1):page101_i52:a"
				( attribute "PN" "1"
					( Origin gPackager )
				)
				( objectStatus "Y8F1.1" )
			)
			( pin "@baseboard_fab2_lib.baseboard_fab2(sch_1):page101_i52:b"
				( attribute "PN" "3"
					( Origin gPackager )
				)
				( objectStatus "Y8F1.3" )
			)
			( pin "@baseboard_fab2_lib.baseboard_fab2(sch_1):page227_i153:f"
				( attribute "PN" "2"
					( Origin gPackager )
				)
				( objectStatus "L1A1.2" )
			)
			( pin "@baseboard_fab2_lib.baseboard_fab2(sch_1):page227_i153:s"
				( attribute "PN" "1"
					( Origin gPackager )
				)
				( objectStatus "L1A1.1" )
			)
			( pin "@baseboard_fab2_lib.baseboard_fab2(sch_1):page101_i89:a"
				( attribute "PN" "1"
					( Origin gPackager )
				)
				( objectStatus "C2T31.1" )
			)
			( pin "@baseboard_fab2_lib.baseboard_fab2(sch_1):page101_i89:b"
				( attribute "PN" "2"
					( Origin gPackager )
				)
				( objectStatus "C2T31.2" )
			)
			( pin "@baseboard_fab2_lib.baseboard_fab2(sch_1):page101_i90:a"
				( attribute "PN" "1"
					( Origin gPackager )
				)
				( objectStatus "C2T27.1" )
			)
			( pin "@baseboard_fab2_lib.baseboard_fab2(sch_1):page101_i90:b"
				( attribute "PN" "2"
					( Origin gPackager )
				)
				( objectStatus "C2T27.2" )
			)
			( pin "@baseboard_fab2_lib.baseboard_fab2(sch_1):page101_i94:a"
				( attribute "PN" "1"
					( Origin gPackager )
				)
				( objectStatus "R2T23.1" )
			)
			( pin "@baseboard_fab2_lib.baseboard_fab2(sch_1):page101_i94:b"
				( attribute "PN" "2"
					( Origin gPackager )
				)
				( objectStatus "R2T23.2" )
			)
			( pin "@baseboard_fab2_lib.baseboard_fab2(sch_1):page101_i95:a"
				( attribute "PN" "1"
					( Origin gPackager )
				)
				( objectStatus "R2T52.1" )
			)
			( pin "@baseboard_fab2_lib.baseboard_fab2(sch_1):page101_i95:b"
				( attribute "PN" "2"
					( Origin gPackager )
				)
				( objectStatus "R2T52.2" )
			)
			( pin "@baseboard_fab2_lib.baseboard_fab2(sch_1):page101_i97:a"
				( attribute "PN" "1"
					( Origin gPackager )
				)
				( objectStatus "C2T38.1" )
			)
			( pin "@baseboard_fab2_lib.baseboard_fab2(sch_1):page101_i97:b"
				( attribute "PN" "2"
					( Origin gPackager )
				)
				( objectStatus "C2T38.2" )
			)
			( pin "@baseboard_fab2_lib.baseboard_fab2(sch_1):page101_i99:a"
				( attribute "PN" "1"
					( Origin gPackager )
				)
				( objectStatus "C2T37.1" )
			)
			( pin "@baseboard_fab2_lib.baseboard_fab2(sch_1):page101_i99:b"
				( attribute "PN" "2"
					( Origin gPackager )
				)
				( objectStatus "C2T37.2" )
			)
			( pin "@baseboard_fab2_lib.baseboard_fab2(sch_1):page101_i104:a"
				( attribute "PN" "1"
					( Origin gPackager )
				)
				( objectStatus "C2T18.1" )
			)
			( pin "@baseboard_fab2_lib.baseboard_fab2(sch_1):page101_i104:b"
				( attribute "PN" "2"
					( Origin gPackager )
				)
				( objectStatus "C2T18.2" )
			)
			( pin "@baseboard_fab2_lib.baseboard_fab2(sch_1):page101_i105:a"
				( attribute "PN" "1"
					( Origin gPackager )
				)
				( objectStatus "R2T21.1" )
			)
			( pin "@baseboard_fab2_lib.baseboard_fab2(sch_1):page101_i105:b"
				( attribute "PN" "2"
					( Origin gPackager )
				)
				( objectStatus "R2T21.2" )
			)
			( pin "@baseboard_fab2_lib.baseboard_fab2(sch_1):page101_i106:a"
				( attribute "PN" "1"
					( Origin gPackager )
				)
				( objectStatus "C2T19.1" )
			)
			( pin "@baseboard_fab2_lib.baseboard_fab2(sch_1):page101_i106:b"
				( attribute "PN" "2"
					( Origin gPackager )
				)
				( objectStatus "C2T19.2" )
			)
			( pin "@baseboard_fab2_lib.baseboard_fab2(sch_1):page101_i109:a"
				( attribute "PN" "1"
					( Origin gPackager )
				)
				( objectStatus "C2T34.1" )
			)
			( pin "@baseboard_fab2_lib.baseboard_fab2(sch_1):page101_i109:b"
				( attribute "PN" "2"
					( Origin gPackager )
				)
				( objectStatus "C2T34.2" )
			)
			( pin "@baseboard_fab2_lib.baseboard_fab2(sch_1):page101_i110:a"
				( attribute "PN" "1"
					( Origin gPackager )
				)
				( objectStatus "C2T30.1" )
			)
			( pin "@baseboard_fab2_lib.baseboard_fab2(sch_1):page101_i110:b"
				( attribute "PN" "2"
					( Origin gPackager )
				)
				( objectStatus "C2T30.2" )
			)
			( pin "@baseboard_fab2_lib.baseboard_fab2(sch_1):page101_i111:a"
				( attribute "PN" "1"
					( Origin gPackager )
				)
				( objectStatus "C2T25.1" )
			)
			( pin "@baseboard_fab2_lib.baseboard_fab2(sch_1):page101_i111:b"
				( attribute "PN" "2"
					( Origin gPackager )
				)
				( objectStatus "C2T25.2" )
			)
			( pin "@baseboard_fab2_lib.baseboard_fab2(sch_1):page101_i112:a"
				( attribute "PN" "1"
					( Origin gPackager )
				)
				( objectStatus "C2T17.1" )
			)
			( pin "@baseboard_fab2_lib.baseboard_fab2(sch_1):page101_i112:b"
				( attribute "PN" "2"
					( Origin gPackager )
				)
				( objectStatus "C2T17.2" )
			)
			( pin "@baseboard_fab2_lib.baseboard_fab2(sch_1):page101_i113:a"
				( attribute "PN" "1"
					( Origin gPackager )
				)
				( objectStatus "C2T22.1" )
			)
			( pin "@baseboard_fab2_lib.baseboard_fab2(sch_1):page101_i113:b"
				( attribute "PN" "2"
					( Origin gPackager )
				)
				( objectStatus "C2T22.2" )
			)
			( pin "@baseboard_fab2_lib.baseboard_fab2(sch_1):page101_i114:a"
				( attribute "PN" "1"
					( Origin gPackager )
				)
				( objectStatus "FB2T2.1" )
			)
			( pin "@baseboard_fab2_lib.baseboard_fab2(sch_1):page101_i114:b"
				( attribute "PN" "2"
					( Origin gPackager )
				)
				( objectStatus "FB2T2.2" )
			)
			( pin "@baseboard_fab2_lib.baseboard_fab2(sch_1):page101_i116:a"
				( attribute "PN" "1"
					( Origin gPackager )
				)
				( objectStatus "C2T28.1" )
			)
			( pin "@baseboard_fab2_lib.baseboard_fab2(sch_1):page101_i116:b"
				( attribute "PN" "2"
					( Origin gPackager )
				)
				( objectStatus "C2T28.2" )
			)
			( pin "@baseboard_fab2_lib.baseboard_fab2(sch_1):page101_i124:a"
				( attribute "PN" "1"
					( Origin gPackager )
				)
				( objectStatus "R2T42.1" )
			)
			( pin "@baseboard_fab2_lib.baseboard_fab2(sch_1):page101_i124:b"
				( attribute "PN" "2"
					( Origin gPackager )
				)
				( objectStatus "R2T42.2" )
			)
			( pin "@baseboard_fab2_lib.baseboard_fab2(sch_1):page101_i125:a"
				( attribute "PN" "1"
					( Origin gPackager )
				)
				( objectStatus "R2T46.1" )
			)
			( pin "@baseboard_fab2_lib.baseboard_fab2(sch_1):page101_i125:b"
				( attribute "PN" "2"
					( Origin gPackager )
				)
				( objectStatus "R2T46.2" )
			)
			( pin "@baseboard_fab2_lib.baseboard_fab2(sch_1):page101_i143:a"
				( attribute "PN" "1"
					( Origin gPackager )
				)
				( objectStatus "R8G24.1" )
			)
			( pin "@baseboard_fab2_lib.baseboard_fab2(sch_1):page101_i143:b"
				( attribute "PN" "2"
					( Origin gPackager )
				)
				( objectStatus "R8G24.2" )
			)
			( pin "@baseboard_fab2_lib.baseboard_fab2(sch_1):page101_i130:a"
				( attribute "PN" "1"
					( Origin gPackager )
				)
				( objectStatus "R2T47.1" )
			)
			( pin "@baseboard_fab2_lib.baseboard_fab2(sch_1):page101_i130:b"
				( attribute "PN" "2"
					( Origin gPackager )
				)
				( objectStatus "R2T47.2" )
			)
			( pin "@baseboard_fab2_lib.baseboard_fab2(sch_1):page102_i1:\100m_133m_n\"
				( attribute "PN" "4"
					( Origin gPackager )
				)
				( objectStatus "EU4D2.4" )
			)
			( pin "@baseboard_fab2_lib.baseboard_fab2(sch_1):page102_i1:clk_inn"
				( attribute "PN" "10"
					( Origin gPackager )
				)
				( objectStatus "EU4D2.10" )
			)
			( pin "@baseboard_fab2_lib.baseboard_fab2(sch_1):page102_i1:clk_inp"
				( attribute "PN" "9"
					( Origin gPackager )
				)
				( objectStatus "EU4D2.9" )
			)
			( pin "@baseboard_fab2_lib.baseboard_fab2(sch_1):page102_i1:dif_0n"
				( attribute "PN" "18"
					( Origin gPackager )
				)
				( objectStatus "EU4D2.18" )
			)
			( pin "@baseboard_fab2_lib.baseboard_fab2(sch_1):page102_i1:dif_0p"
				( attribute "PN" "17"
					( Origin gPackager )
				)
				( objectStatus "EU4D2.17" )
			)
			( pin "@baseboard_fab2_lib.baseboard_fab2(sch_1):page102_i1:dif_1n"
				( attribute "PN" "22"
					( Origin gPackager )
				)
				( objectStatus "EU4D2.22" )
			)
			( pin "@baseboard_fab2_lib.baseboard_fab2(sch_1):page102_i1:dif_1p"
				( attribute "PN" "21"
					( Origin gPackager )
				)
				( objectStatus "EU4D2.21" )
			)
			( pin "@baseboard_fab2_lib.baseboard_fab2(sch_1):page102_i1:dif_2n"
				( attribute "PN" "27"
					( Origin gPackager )
				)
				( objectStatus "EU4D2.27" )
			)
			( pin "@baseboard_fab2_lib.baseboard_fab2(sch_1):page102_i1:dif_2p"
				( attribute "PN" "26"
					( Origin gPackager )
				)
				( objectStatus "EU4D2.26" )
			)
			( pin "@baseboard_fab2_lib.baseboard_fab2(sch_1):page102_i1:dif_3n"
				( attribute "PN" "31"
					( Origin gPackager )
				)
				( objectStatus "EU4D2.31" )
			)
			( pin "@baseboard_fab2_lib.baseboard_fab2(sch_1):page102_i1:dif_3p"
				( attribute "PN" "30"
					( Origin gPackager )
				)
				( objectStatus "EU4D2.30" )
			)
			( pin "@baseboard_fab2_lib.baseboard_fab2(sch_1):page102_i1:dif_4n"
				( attribute "PN" "35"
					( Origin gPackager )
				)
				( objectStatus "EU4D2.35" )
			)
			( pin "@baseboard_fab2_lib.baseboard_fab2(sch_1):page102_i1:dif_4p"
				( attribute "PN" "34"
					( Origin gPackager )
				)
				( objectStatus "EU4D2.34" )
			)
			( pin "@baseboard_fab2_lib.baseboard_fab2(sch_1):page102_i1:dif_5n"
				( attribute "PN" "39"
					( Origin gPackager )
				)
				( objectStatus "EU4D2.39" )
			)
			( pin "@baseboard_fab2_lib.baseboard_fab2(sch_1):page102_i1:dif_5p"
				( attribute "PN" "38"
					( Origin gPackager )
				)
				( objectStatus "EU4D2.38" )
			)
			( pin "@baseboard_fab2_lib.baseboard_fab2(sch_1):page102_i1:dif_6n"
				( attribute "PN" "43"
					( Origin gPackager )
				)
				( objectStatus "EU4D2.43" )
			)
			( pin "@baseboard_fab2_lib.baseboard_fab2(sch_1):page102_i1:dif_6p"
				( attribute "PN" "42"
					( Origin gPackager )
				)
				( objectStatus "EU4D2.42" )
			)
			( pin "@baseboard_fab2_lib.baseboard_fab2(sch_1):page102_i1:dif_7n"
				( attribute "PN" "47"
					( Origin gPackager )
				)
				( objectStatus "EU4D2.47" )
			)
			( pin "@baseboard_fab2_lib.baseboard_fab2(sch_1):page102_i1:dif_7p"
				( attribute "PN" "46"
					( Origin gPackager )
				)
				( objectStatus "EU4D2.46" )
			)
			( pin "@baseboard_fab2_lib.baseboard_fab2(sch_1):page102_i1:dif_8n"
				( attribute "PN" "51"
					( Origin gPackager )
				)
				( objectStatus "EU4D2.51" )
			)
			( pin "@baseboard_fab2_lib.baseboard_fab2(sch_1):page102_i1:dif_8p"
				( attribute "PN" "50"
					( Origin gPackager )
				)
				( objectStatus "EU4D2.50" )
			)
			( pin "@baseboard_fab2_lib.baseboard_fab2(sch_1):page102_i1:dif_9n"
				( attribute "PN" "55"
					( Origin gPackager )
				)
				( objectStatus "EU4D2.55" )
			)
			( pin "@baseboard_fab2_lib.baseboard_fab2(sch_1):page102_i1:dif_9p"
				( attribute "PN" "54"
					( Origin gPackager )
				)
				( objectStatus "EU4D2.54" )
			)
			( pin "@baseboard_fab2_lib.baseboard_fab2(sch_1):page102_i1:dif_10n"
				( attribute "PN" "60"
					( Origin gPackager )
				)
				( objectStatus "EU4D2.60" )
			)
			( pin "@baseboard_fab2_lib.baseboard_fab2(sch_1):page102_i1:dif_10p"
				( attribute "PN" "59"
					( Origin gPackager )
				)
				( objectStatus "EU4D2.59" )
			)
			( pin "@baseboard_fab2_lib.baseboard_fab2(sch_1):page102_i1:dif_11n"
				( attribute "PN" "64"
					( Origin gPackager )
				)
				( objectStatus "EU4D2.64" )
			)
			( pin "@baseboard_fab2_lib.baseboard_fab2(sch_1):page102_i1:dif_11p"
				( attribute "PN" "63"
					( Origin gPackager )
				)
				( objectStatus "EU4D2.63" )
			)
			( pin "@baseboard_fab2_lib.baseboard_fab2(sch_1):page102_i1:gnd(0)"
				( attribute "PN" "7"
					( Origin gPackager )
				)
				( objectStatus "EU4D2.7" )
			)
			( pin "@baseboard_fab2_lib.baseboard_fab2(sch_1):page102_i1:gnd(1)"
				( attribute "PN" "23"
					( Origin gPackager )
				)
				( objectStatus "EU4D2.23" )
			)
			( pin "@baseboard_fab2_lib.baseboard_fab2(sch_1):page102_i1:gnd(2)"
				( attribute "PN" "33"
					( Origin gPackager )
				)
				( objectStatus "EU4D2.33" )
			)
			( pin "@baseboard_fab2_lib.baseboard_fab2(sch_1):page102_i1:gnd(3)"
				( attribute "PN" "41"
					( Origin gPackager )
				)
				( objectStatus "EU4D2.41" )
			)
			( pin "@baseboard_fab2_lib.baseboard_fab2(sch_1):page102_i1:gnd(4)"
				( attribute "PN" "48"
					( Origin gPackager )
				)
				( objectStatus "EU4D2.48" )
			)
			( pin "@baseboard_fab2_lib.baseboard_fab2(sch_1):page102_i1:gnd(5)"
				( attribute "PN" "58"
					( Origin gPackager )
				)
				( objectStatus "EU4D2.58" )
			)
			( pin "@baseboard_fab2_lib.baseboard_fab2(sch_1):page102_i1:gnda"
				( attribute "PN" "2"
					( Origin gPackager )
				)
				( objectStatus "EU4D2.2" )
			)
			( pin "@baseboard_fab2_lib.baseboard_fab2(sch_1):page102_i1:hbw_bypass_lobw_n"
				( attribute "PN" "5"
					( Origin gPackager )
				)
				( objectStatus "EU4D2.5" )
			)
			( pin "@baseboard_fab2_lib.baseboard_fab2(sch_1):page102_i1:nc(0)"
				( attribute "PN" "3"
					( Origin gPackager )
				)
				( objectStatus "EU4D2.3" )
			)
			( pin "@baseboard_fab2_lib.baseboard_fab2(sch_1):page102_i1:nc(1)"
				( attribute "PN" "16"
					( Origin gPackager )
				)
				( objectStatus "EU4D2.16" )
			)
			( pin "@baseboard_fab2_lib.baseboard_fab2(sch_1):page102_i1:nc(2)"
				( attribute "PN" "15"
					( Origin gPackager )
				)
				( objectStatus "EU4D2.15" )
			)
			( pin "@baseboard_fab2_lib.baseboard_fab2(sch_1):page102_i1:oe_0_n"
				( attribute "PN" "19"
					( Origin gPackager )
				)
				( objectStatus "EU4D2.19" )
			)
			( pin "@baseboard_fab2_lib.baseboard_fab2(sch_1):page102_i1:oe_1_n"
				( attribute "PN" "20"
					( Origin gPackager )
				)
				( objectStatus "EU4D2.20" )
			)
			( pin "@baseboard_fab2_lib.baseboard_fab2(sch_1):page102_i1:oe_2_n"
				( attribute "PN" "28"
					( Origin gPackager )
				)
				( objectStatus "EU4D2.28" )
			)
			( pin "@baseboard_fab2_lib.baseboard_fab2(sch_1):page102_i1:oe_3_n"
				( attribute "PN" "29"
					( Origin gPackager )
				)
				( objectStatus "EU4D2.29" )
			)
			( pin "@baseboard_fab2_lib.baseboard_fab2(sch_1):page102_i1:oe_4_n"
				( attribute "PN" "36"
					( Origin gPackager )
				)
				( objectStatus "EU4D2.36" )
			)
			( pin "@baseboard_fab2_lib.baseboard_fab2(sch_1):page102_i1:oe_5_n"
				( attribute "PN" "37"
					( Origin gPackager )
				)
				( objectStatus "EU4D2.37" )
			)
			( pin "@baseboard_fab2_lib.baseboard_fab2(sch_1):page102_i1:oe_6_n"
				( attribute "PN" "44"
					( Origin gPackager )
				)
				( objectStatus "EU4D2.44" )
			)
			( pin "@baseboard_fab2_lib.baseboard_fab2(sch_1):page102_i1:oe_7_n"
				( attribute "PN" "45"
					( Origin gPackager )
				)
				( objectStatus "EU4D2.45" )
			)
			( pin "@baseboard_fab2_lib.baseboard_fab2(sch_1):page102_i1:oe_8_n"
				( attribute "PN" "52"
					( Origin gPackager )
				)
				( objectStatus "EU4D2.52" )
			)
			( pin "@baseboard_fab2_lib.baseboard_fab2(sch_1):page102_i1:oe_9_n"
				( attribute "PN" "53"
					( Origin gPackager )
				)
				( objectStatus "EU4D2.53" )
			)
			( pin "@baseboard_fab2_lib.baseboard_fab2(sch_1):page102_i1:oe_10_n"
				( attribute "PN" "61"
					( Origin gPackager )
				)
				( objectStatus "EU4D2.61" )
			)
			( pin "@baseboard_fab2_lib.baseboard_fab2(sch_1):page102_i1:oe_11_n"
				( attribute "PN" "62"
					( Origin gPackager )
				)
				( objectStatus "EU4D2.62" )
			)
			( pin "@baseboard_fab2_lib.baseboard_fab2(sch_1):page102_i1:pwrgd_pwrdn_n"
				( attribute "PN" "6"
					( Origin gPackager )
				)
				( objectStatus "EU4D2.6" )
			)
			( pin "@baseboard_fab2_lib.baseboard_fab2(sch_1):page102_i1:sa_0"
				( attribute "PN" "11"
					( Origin gPackager )
				)
				( objectStatus "EU4D2.11" )
			)
			( pin "@baseboard_fab2_lib.baseboard_fab2(sch_1):page102_i1:sa_1"
				( attribute "PN" "14"
					( Origin gPackager )
				)
				( objectStatus "EU4D2.14" )
			)
			( pin "@baseboard_fab2_lib.baseboard_fab2(sch_1):page102_i1:scl"
				( attribute "PN" "13"
					( Origin gPackager )
				)
				( objectStatus "EU4D2.13" )
			)
			( pin "@baseboard_fab2_lib.baseboard_fab2(sch_1):page102_i1:sda"
				( attribute "PN" "12"
					( Origin gPackager )
				)
				( objectStatus "EU4D2.12" )
			)
			( pin "@baseboard_fab2_lib.baseboard_fab2(sch_1):page102_i1:thpad"
				( attribute "PN" "65"
					( Origin gPackager )
				)
				( objectStatus "EU4D2.65" )
			)
			( pin "@baseboard_fab2_lib.baseboard_fab2(sch_1):page102_i1:vdd(0)"
				( attribute "PN" "24"
					( Origin gPackager )
				)
				( objectStatus "EU4D2.24" )
			)
			( pin "@baseboard_fab2_lib.baseboard_fab2(sch_1):page102_i1:vdd(1)"
				( attribute "PN" "40"
					( Origin gPackager )
				)
				( objectStatus "EU4D2.40" )
			)
			( pin "@baseboard_fab2_lib.baseboard_fab2(sch_1):page102_i1:vdd(2)"
				( attribute "PN" "57"
					( Origin gPackager )
				)
				( objectStatus "EU4D2.57" )
			)
			( pin "@baseboard_fab2_lib.baseboard_fab2(sch_1):page102_i1:vdda"
				( attribute "PN" "1"
					( Origin gPackager )
				)
				( objectStatus "EU4D2.1" )
			)
			( pin "@baseboard_fab2_lib.baseboard_fab2(sch_1):page102_i1:vddio(0)"
				( attribute "PN" "25"
					( Origin gPackager )
				)
				( objectStatus "EU4D2.25" )
			)
			( pin "@baseboard_fab2_lib.baseboard_fab2(sch_1):page102_i1:vddio(1)"
				( attribute "PN" "32"
					( Origin gPackager )
				)
				( objectStatus "EU4D2.32" )
			)
			( pin "@baseboard_fab2_lib.baseboard_fab2(sch_1):page102_i1:vddio(2)"
				( attribute "PN" "49"
					( Origin gPackager )
				)
				( objectStatus "EU4D2.49" )
			)
			( pin "@baseboard_fab2_lib.baseboard_fab2(sch_1):page102_i1:vddio(3)"
				( attribute "PN" "56"
					( Origin gPackager )
				)
				( objectStatus "EU4D2.56" )
			)
			( pin "@baseboard_fab2_lib.baseboard_fab2(sch_1):page102_i1:vddr"
				( attribute "PN" "8"
					( Origin gPackager )
				)
				( objectStatus "EU4D2.8" )
			)
			( pin "@baseboard_fab2_lib.baseboard_fab2(sch_1):page102_i8:a"
				( attribute "PN" "1"
					( Origin gPackager )
				)
				( objectStatus "FB6P1.1" )
			)
			( pin "@baseboard_fab2_lib.baseboard_fab2(sch_1):page102_i8:b"
				( attribute "PN" "2"
					( Origin gPackager )
				)
				( objectStatus "FB6P1.2" )
			)
			( pin "@baseboard_fab2_lib.baseboard_fab2(sch_1):page102_i10:a"
				( attribute "PN" "1"
					( Origin gPackager )
				)
				( objectStatus "C3D22.1" )
			)
			( pin "@baseboard_fab2_lib.baseboard_fab2(sch_1):page102_i10:b"
				( attribute "PN" "2"
					( Origin gPackager )
				)
				( objectStatus "C3D22.2" )
			)
			( pin "@baseboard_fab2_lib.baseboard_fab2(sch_1):page102_i11:a"
				( attribute "PN" "1"
					( Origin gPackager )
				)
				( objectStatus "C6P4.1" )
			)
			( pin "@baseboard_fab2_lib.baseboard_fab2(sch_1):page102_i11:b"
				( attribute "PN" "2"
					( Origin gPackager )
				)
				( objectStatus "C6P4.2" )
			)
			( pin "@baseboard_fab2_lib.baseboard_fab2(sch_1):page102_i12:a"
				( attribute "PN" "1"
					( Origin gPackager )
				)
				( objectStatus "C6P6.1" )
			)
			( pin "@baseboard_fab2_lib.baseboard_fab2(sch_1):page102_i12:b"
				( attribute "PN" "2"
					( Origin gPackager )
				)
				( objectStatus "C6P6.2" )
			)
			( pin "@baseboard_fab2_lib.baseboard_fab2(sch_1):page102_i13:a"
				( attribute "PN" "1"
					( Origin gPackager )
				)
				( objectStatus "C6P10.1" )
			)
			( pin "@baseboard_fab2_lib.baseboard_fab2(sch_1):page102_i13:b"
				( attribute "PN" "2"
					( Origin gPackager )
				)
				( objectStatus "C6P10.2" )
			)
			( pin "@baseboard_fab2_lib.baseboard_fab2(sch_1):page102_i14:a"
				( attribute "PN" "1"
					( Origin gPackager )
				)
				( objectStatus "C6P5.1" )
			)
			( pin "@baseboard_fab2_lib.baseboard_fab2(sch_1):page102_i14:b"
				( attribute "PN" "2"
					( Origin gPackager )
				)
				( objectStatus "C6P5.2" )
			)
			( pin "@baseboard_fab2_lib.baseboard_fab2(sch_1):page102_i15:a"
				( attribute "PN" "1"
					( Origin gPackager )
				)
				( objectStatus "C6P12.1" )
			)
			( pin "@baseboard_fab2_lib.baseboard_fab2(sch_1):page102_i15:b"
				( attribute "PN" "2"
					( Origin gPackager )
				)
				( objectStatus "C6P12.2" )
			)
			( pin "@baseboard_fab2_lib.baseboard_fab2(sch_1):page102_i16:a"
				( attribute "PN" "1"
					( Origin gPackager )
				)
				( objectStatus "C6P11.1" )
			)
			( pin "@baseboard_fab2_lib.baseboard_fab2(sch_1):page102_i16:b"
				( attribute "PN" "2"
					( Origin gPackager )
				)
				( objectStatus "C6P11.2" )
			)
			( pin "@baseboard_fab2_lib.baseboard_fab2(sch_1):page102_i18:a"
				( attribute "PN" "1"
					( Origin gPackager )
				)
				( objectStatus "C4D24.1" )
			)
			( pin "@baseboard_fab2_lib.baseboard_fab2(sch_1):page102_i18:b"
				( attribute "PN" "2"
					( Origin gPackager )
				)
				( objectStatus "C4D24.2" )
			)
			( pin "@baseboard_fab2_lib.baseboard_fab2(sch_1):page102_i19:a"
				( attribute "PN" "1"
					( Origin gPackager )
				)
				( objectStatus "C4D23.1" )
			)
			( pin "@baseboard_fab2_lib.baseboard_fab2(sch_1):page102_i19:b"
				( attribute "PN" "2"
					( Origin gPackager )
				)
				( objectStatus "C4D23.2" )
			)
			( pin "@baseboard_fab2_lib.baseboard_fab2(sch_1):page102_i21:a"
				( attribute "PN" "1"
					( Origin gPackager )
				)
				( objectStatus "R3D14.1" )
			)
			( pin "@baseboard_fab2_lib.baseboard_fab2(sch_1):page102_i21:b"
				( attribute "PN" "2"
					( Origin gPackager )
				)
				( objectStatus "R3D14.2" )
			)
			( pin "@baseboard_fab2_lib.baseboard_fab2(sch_1):page102_i26:a"
				( attribute "PN" "1"
					( Origin gPackager )
				)
				( objectStatus "R6P25.1" )
			)
			( pin "@baseboard_fab2_lib.baseboard_fab2(sch_1):page102_i26:b"
				( attribute "PN" "2"
					( Origin gPackager )
				)
				( objectStatus "R6P25.2" )
			)
			( pin "@baseboard_fab2_lib.baseboard_fab2(sch_1):page102_i28:a"
				( attribute "PN" "1"
					( Origin gPackager )
				)
				( objectStatus "C4D22.1" )
			)
			( pin "@baseboard_fab2_lib.baseboard_fab2(sch_1):page102_i28:b"
				( attribute "PN" "2"
					( Origin gPackager )
				)
				( objectStatus "C4D22.2" )
			)
			( pin "@baseboard_fab2_lib.baseboard_fab2(sch_1):page102_i30:a"
				( attribute "PN" "1"
					( Origin gPackager )
				)
				( objectStatus "C4D27.1" )
			)
			( pin "@baseboard_fab2_lib.baseboard_fab2(sch_1):page102_i30:b"
				( attribute "PN" "2"
					( Origin gPackager )
				)
				( objectStatus "C4D27.2" )
			)
			( pin "@baseboard_fab2_lib.baseboard_fab2(sch_1):page102_i37:a"
				( attribute "PN" "1"
					( Origin gPackager )
				)
				( objectStatus "R4D38.1" )
			)
			( pin "@baseboard_fab2_lib.baseboard_fab2(sch_1):page102_i37:b"
				( attribute "PN" "2"
					( Origin gPackager )
				)
				( objectStatus "R4D38.2" )
			)
			( pin "@baseboard_fab2_lib.baseboard_fab2(sch_1):page102_i38:a"
				( attribute "PN" "1"
					( Origin gPackager )
				)
				( objectStatus "R4D35.1" )
			)
			( pin "@baseboard_fab2_lib.baseboard_fab2(sch_1):page102_i38:b"
				( attribute "PN" "2"
					( Origin gPackager )
				)
				( objectStatus "R4D35.2" )
			)
			( pin "@baseboard_fab2_lib.baseboard_fab2(sch_1):page102_i45:a"
				( attribute "PN" "1"
					( Origin gPackager )
				)
				( objectStatus "R4D40.1" )
			)
			( pin "@baseboard_fab2_lib.baseboard_fab2(sch_1):page102_i45:b"
				( attribute "PN" "2"
					( Origin gPackager )
				)
				( objectStatus "R4D40.2" )
			)
			( pin "@baseboard_fab2_lib.baseboard_fab2(sch_1):page102_i46:a"
				( attribute "PN" "1"
					( Origin gPackager )
				)
				( objectStatus "R6P23.1" )
			)
			( pin "@baseboard_fab2_lib.baseboard_fab2(sch_1):page102_i46:b"
				( attribute "PN" "2"
					( Origin gPackager )
				)
				( objectStatus "R6P23.2" )
			)
			( pin "@baseboard_fab2_lib.baseboard_fab2(sch_1):page102_i47:a"
				( attribute "PN" "1"
					( Origin gPackager )
				)
				( objectStatus "R6P22.1" )
			)
			( pin "@baseboard_fab2_lib.baseboard_fab2(sch_1):page102_i47:b"
				( attribute "PN" "2"
					( Origin gPackager )
				)
				( objectStatus "R6P22.2" )
			)
			( pin "@baseboard_fab2_lib.baseboard_fab2(sch_1):page102_i53:a"
				( attribute "PN" "1"
					( Origin gPackager )
				)
				( objectStatus "R4D41.1" )
			)
			( pin "@baseboard_fab2_lib.baseboard_fab2(sch_1):page102_i53:b"
				( attribute "PN" "2"
					( Origin gPackager )
				)
				( objectStatus "R4D41.2" )
			)
			( pin "@baseboard_fab2_lib.baseboard_fab2(sch_1):page102_i79:a"
				( attribute "PN" "1"
					( Origin gPackager )
				)
				( objectStatus "C6P9.1" )
			)
			( pin "@baseboard_fab2_lib.baseboard_fab2(sch_1):page102_i79:b"
				( attribute "PN" "2"
					( Origin gPackager )
				)
				( objectStatus "C6P9.2" )
			)
			( pin "@baseboard_fab2_lib.baseboard_fab2(sch_1):page102_i80:a"
				( attribute "PN" "1"
					( Origin gPackager )
				)
				( objectStatus "R6P21.1" )
			)
			( pin "@baseboard_fab2_lib.baseboard_fab2(sch_1):page102_i80:b"
				( attribute "PN" "2"
					( Origin gPackager )
				)
				( objectStatus "R6P21.2" )
			)
			( pin "@baseboard_fab2_lib.baseboard_fab2(sch_1):page102_i81:a"
				( attribute "PN" "1"
					( Origin gPackager )
				)
				( objectStatus "R6P20.1" )
			)
			( pin "@baseboard_fab2_lib.baseboard_fab2(sch_1):page102_i81:b"
				( attribute "PN" "2"
					( Origin gPackager )
				)
				( objectStatus "R6P20.2" )
			)
			( pin "@baseboard_fab2_lib.baseboard_fab2(sch_1):page102_i105:a"
				( attribute "PN" "1"
					( Origin gPackager )
				)
				( objectStatus "R4W3.1" )
			)
			( pin "@baseboard_fab2_lib.baseboard_fab2(sch_1):page102_i105:b"
				( attribute "PN" "2"
					( Origin gPackager )
				)
				( objectStatus "R4W3.2" )
			)
			( pin "@baseboard_fab2_lib.baseboard_fab2(sch_1):page102_i102:drain(0)"
				( attribute "PN" "6"
					( Origin gPackager )
				)
				( objectStatus "Q4W1.6" )
			)
			( pin "@baseboard_fab2_lib.baseboard_fab2(sch_1):page102_i102:gate(0)"
				( attribute "PN" "2"
					( Origin gPackager )
				)
				( objectStatus "Q4W1.2" )
			)
			( pin "@baseboard_fab2_lib.baseboard_fab2(sch_1):page102_i102:source(0)"
				( attribute "PN" "1"
					( Origin gPackager )
				)
				( objectStatus "Q4W1.1" )
			)
			( pin "@baseboard_fab2_lib.baseboard_fab2(sch_1):page102_i93:a"
				( attribute "PN" "1"
					( Origin gPackager )
				)
				( objectStatus "R4D69.1" )
			)
			( pin "@baseboard_fab2_lib.baseboard_fab2(sch_1):page102_i93:b"
				( attribute "PN" "2"
					( Origin gPackager )
				)
				( objectStatus "R4D69.2" )
			)
			( pin "@baseboard_fab2_lib.baseboard_fab2(sch_1):page102_i94:a"
				( attribute "PN" "1"
					( Origin gPackager )
				)
				( objectStatus "R4D70.1" )
			)
			( pin "@baseboard_fab2_lib.baseboard_fab2(sch_1):page102_i94:b"
				( attribute "PN" "2"
					( Origin gPackager )
				)
				( objectStatus "R4D70.2" )
			)
			( pin "@baseboard_fab2_lib.baseboard_fab2(sch_1):page103_i1:a"
				( attribute "PN" "1"
					( Origin gPackager )
				)
				( objectStatus "R4D25.1" )
			)
			( pin "@baseboard_fab2_lib.baseboard_fab2(sch_1):page103_i1:b"
				( attribute "PN" "2"
					( Origin gPackager )
				)
				( objectStatus "R4D25.2" )
			)
			( pin "@baseboard_fab2_lib.baseboard_fab2(sch_1):page103_i9:a"
				( attribute "PN" "1"
					( Origin gPackager )
				)
				( objectStatus "R4D23.1" )
			)
			( pin "@baseboard_fab2_lib.baseboard_fab2(sch_1):page103_i9:b"
				( attribute "PN" "2"
					( Origin gPackager )
				)
				( objectStatus "R4D23.2" )
			)
			( pin "@baseboard_fab2_lib.baseboard_fab2(sch_1):page103_i14:a"
				( attribute "PN" "1"
					( Origin gPackager )
				)
				( objectStatus "R4D28.1" )
			)
			( pin "@baseboard_fab2_lib.baseboard_fab2(sch_1):page103_i14:b"
				( attribute "PN" "2"
					( Origin gPackager )
				)
				( objectStatus "R4D28.2" )
			)
			( pin "@baseboard_fab2_lib.baseboard_fab2(sch_1):page103_i19:a"
				( attribute "PN" "1"
					( Origin gPackager )
				)
				( objectStatus "R4D19.1" )
			)
			( pin "@baseboard_fab2_lib.baseboard_fab2(sch_1):page103_i19:b"
				( attribute "PN" "2"
					( Origin gPackager )
				)
				( objectStatus "R4D19.2" )
			)
			( pin "@baseboard_fab2_lib.baseboard_fab2(sch_1):page103_i24:a"
				( attribute "PN" "1"
					( Origin gPackager )
				)
				( objectStatus "R4D21.1" )
			)
			( pin "@baseboard_fab2_lib.baseboard_fab2(sch_1):page103_i24:b"
				( attribute "PN" "2"
					( Origin gPackager )
				)
				( objectStatus "R4D21.2" )
			)
			( pin "@baseboard_fab2_lib.baseboard_fab2(sch_1):page103_i29:a"
				( attribute "PN" "1"
					( Origin gPackager )
				)
				( objectStatus "R4D13.1" )
			)
			( pin "@baseboard_fab2_lib.baseboard_fab2(sch_1):page103_i29:b"
				( attribute "PN" "2"
					( Origin gPackager )
				)
				( objectStatus "R4D13.2" )
			)
			( pin "@baseboard_fab2_lib.baseboard_fab2(sch_1):page103_i34:a"
				( attribute "PN" "1"
					( Origin gPackager )
				)
				( objectStatus "R4D16.1" )
			)
			( pin "@baseboard_fab2_lib.baseboard_fab2(sch_1):page103_i34:b"
				( attribute "PN" "2"
					( Origin gPackager )
				)
				( objectStatus "R4D16.2" )
			)
			( pin "@baseboard_fab2_lib.baseboard_fab2(sch_1):page103_i39:a"
				( attribute "PN" "1"
					( Origin gPackager )
				)
				( objectStatus "R4D9.1" )
			)
			( pin "@baseboard_fab2_lib.baseboard_fab2(sch_1):page103_i39:b"
				( attribute "PN" "2"
					( Origin gPackager )
				)
				( objectStatus "R4D9.2" )
			)
			( pin "@baseboard_fab2_lib.baseboard_fab2(sch_1):page103_i44:a"
				( attribute "PN" "1"
					( Origin gPackager )
				)
				( objectStatus "R4D11.1" )
			)
			( pin "@baseboard_fab2_lib.baseboard_fab2(sch_1):page103_i44:b"
				( attribute "PN" "2"
					( Origin gPackager )
				)
				( objectStatus "R4D11.2" )
			)
			( pin "@baseboard_fab2_lib.baseboard_fab2(sch_1):page103_i49:a"
				( attribute "PN" "1"
					( Origin gPackager )
				)
				( objectStatus "R4D2.1" )
			)
			( pin "@baseboard_fab2_lib.baseboard_fab2(sch_1):page103_i49:b"
				( attribute "PN" "2"
					( Origin gPackager )
				)
				( objectStatus "R4D2.2" )
			)
			( pin "@baseboard_fab2_lib.baseboard_fab2(sch_1):page103_i54:a"
				( attribute "PN" "1"
					( Origin gPackager )
				)
				( objectStatus "R4D1.1" )
			)
			( pin "@baseboard_fab2_lib.baseboard_fab2(sch_1):page103_i54:b"
				( attribute "PN" "2"
					( Origin gPackager )
				)
				( objectStatus "R4D1.2" )
			)
			( pin "@baseboard_fab2_lib.baseboard_fab2(sch_1):page103_i59:a"
				( attribute "PN" "1"
					( Origin gPackager )
				)
				( objectStatus "R4D4.1" )
			)
			( pin "@baseboard_fab2_lib.baseboard_fab2(sch_1):page103_i59:b"
				( attribute "PN" "2"
					( Origin gPackager )
				)
				( objectStatus "R4D4.2" )
			)
			( pin "@baseboard_fab2_lib.baseboard_fab2(sch_1):page103_i64:a"
				( attribute "PN" "1"
					( Origin gPackager )
				)
				( objectStatus "R4D3.1" )
			)
			( pin "@baseboard_fab2_lib.baseboard_fab2(sch_1):page103_i64:b"
				( attribute "PN" "2"
					( Origin gPackager )
				)
				( objectStatus "R4D3.2" )
			)
			( pin "@baseboard_fab2_lib.baseboard_fab2(sch_1):page103_i69:a"
				( attribute "PN" "1"
					( Origin gPackager )
				)
				( objectStatus "R4D29.1" )
			)
			( pin "@baseboard_fab2_lib.baseboard_fab2(sch_1):page103_i69:b"
				( attribute "PN" "2"
					( Origin gPackager )
				)
				( objectStatus "R4D29.2" )
			)
			( pin "@baseboard_fab2_lib.baseboard_fab2(sch_1):page103_i74:a"
				( attribute "PN" "1"
					( Origin gPackager )
				)
				( objectStatus "R4D6.1" )
			)
			( pin "@baseboard_fab2_lib.baseboard_fab2(sch_1):page103_i74:b"
				( attribute "PN" "2"
					( Origin gPackager )
				)
				( objectStatus "R4D6.2" )
			)
			( pin "@baseboard_fab2_lib.baseboard_fab2(sch_1):page103_i79:a"
				( attribute "PN" "1"
					( Origin gPackager )
				)
				( objectStatus "R4D5.1" )
			)
			( pin "@baseboard_fab2_lib.baseboard_fab2(sch_1):page103_i79:b"
				( attribute "PN" "2"
					( Origin gPackager )
				)
				( objectStatus "R4D5.2" )
			)
			( pin "@baseboard_fab2_lib.baseboard_fab2(sch_1):page103_i84:a"
				( attribute "PN" "1"
					( Origin gPackager )
				)
				( objectStatus "R4D8.1" )
			)
			( pin "@baseboard_fab2_lib.baseboard_fab2(sch_1):page103_i84:b"
				( attribute "PN" "2"
					( Origin gPackager )
				)
				( objectStatus "R4D8.2" )
			)
			( pin "@baseboard_fab2_lib.baseboard_fab2(sch_1):page103_i89:a"
				( attribute "PN" "1"
					( Origin gPackager )
				)
				( objectStatus "R4D7.1" )
			)
			( pin "@baseboard_fab2_lib.baseboard_fab2(sch_1):page103_i89:b"
				( attribute "PN" "2"
					( Origin gPackager )
				)
				( objectStatus "R4D7.2" )
			)
			( pin "@baseboard_fab2_lib.baseboard_fab2(sch_1):page103_i94:a"
				( attribute "PN" "1"
					( Origin gPackager )
				)
				( objectStatus "R4D12.1" )
			)
			( pin "@baseboard_fab2_lib.baseboard_fab2(sch_1):page103_i94:b"
				( attribute "PN" "2"
					( Origin gPackager )
				)
				( objectStatus "R4D12.2" )
			)
			( pin "@baseboard_fab2_lib.baseboard_fab2(sch_1):page103_i99:a"
				( attribute "PN" "1"
					( Origin gPackager )
				)
				( objectStatus "R4D10.1" )
			)
			( pin "@baseboard_fab2_lib.baseboard_fab2(sch_1):page103_i99:b"
				( attribute "PN" "2"
					( Origin gPackager )
				)
				( objectStatus "R4D10.2" )
			)
			( pin "@baseboard_fab2_lib.baseboard_fab2(sch_1):page103_i104:a"
				( attribute "PN" "1"
					( Origin gPackager )
				)
				( objectStatus "R4D17.1" )
			)
			( pin "@baseboard_fab2_lib.baseboard_fab2(sch_1):page103_i104:b"
				( attribute "PN" "2"
					( Origin gPackager )
				)
				( objectStatus "R4D17.2" )
			)
			( pin "@baseboard_fab2_lib.baseboard_fab2(sch_1):page103_i109:a"
				( attribute "PN" "1"
					( Origin gPackager )
				)
				( objectStatus "R4D14.1" )
			)
			( pin "@baseboard_fab2_lib.baseboard_fab2(sch_1):page103_i109:b"
				( attribute "PN" "2"
					( Origin gPackager )
				)
				( objectStatus "R4D14.2" )
			)
			( pin "@baseboard_fab2_lib.baseboard_fab2(sch_1):page103_i114:a"
				( attribute "PN" "1"
					( Origin gPackager )
				)
				( objectStatus "R4D22.1" )
			)
			( pin "@baseboard_fab2_lib.baseboard_fab2(sch_1):page103_i114:b"
				( attribute "PN" "2"
					( Origin gPackager )
				)
				( objectStatus "R4D22.2" )
			)
			( pin "@baseboard_fab2_lib.baseboard_fab2(sch_1):page103_i119:a"
				( attribute "PN" "1"
					( Origin gPackager )
				)
				( objectStatus "R4D20.1" )
			)
			( pin "@baseboard_fab2_lib.baseboard_fab2(sch_1):page103_i119:b"
				( attribute "PN" "2"
					( Origin gPackager )
				)
				( objectStatus "R4D20.2" )
			)
			( pin "@baseboard_fab2_lib.baseboard_fab2(sch_1):page103_i121:a"
				( attribute "PN" "1"
					( Origin gPackager )
				)
				( objectStatus "R7P9.1" )
			)
			( pin "@baseboard_fab2_lib.baseboard_fab2(sch_1):page103_i121:b"
				( attribute "PN" "2"
					( Origin gPackager )
				)
				( objectStatus "R7P9.2" )
			)
			( pin "@baseboard_fab2_lib.baseboard_fab2(sch_1):page103_i123:a"
				( attribute "PN" "1"
					( Origin gPackager )
				)
				( objectStatus "R7P12.1" )
			)
			( pin "@baseboard_fab2_lib.baseboard_fab2(sch_1):page103_i123:b"
				( attribute "PN" "2"
					( Origin gPackager )
				)
				( objectStatus "R7P12.2" )
			)
			( pin "@baseboard_fab2_lib.baseboard_fab2(sch_1):page103_i125:a"
				( attribute "PN" "1"
					( Origin gPackager )
				)
				( objectStatus "R7P6.1" )
			)
			( pin "@baseboard_fab2_lib.baseboard_fab2(sch_1):page103_i125:b"
				( attribute "PN" "2"
					( Origin gPackager )
				)
				( objectStatus "R7P6.2" )
			)
			( pin "@baseboard_fab2_lib.baseboard_fab2(sch_1):page103_i127:a"
				( attribute "PN" "1"
					( Origin gPackager )
				)
				( objectStatus "R7P7.1" )
			)
			( pin "@baseboard_fab2_lib.baseboard_fab2(sch_1):page103_i127:b"
				( attribute "PN" "2"
					( Origin gPackager )
				)
				( objectStatus "R7P7.2" )
			)
			( pin "@baseboard_fab2_lib.baseboard_fab2(sch_1):page103_i129:a"
				( attribute "PN" "1"
					( Origin gPackager )
				)
				( objectStatus "R7P3.1" )
			)
			( pin "@baseboard_fab2_lib.baseboard_fab2(sch_1):page103_i129:b"
				( attribute "PN" "2"
					( Origin gPackager )
				)
				( objectStatus "R7P3.2" )
			)
			( pin "@baseboard_fab2_lib.baseboard_fab2(sch_1):page103_i131:a"
				( attribute "PN" "1"
					( Origin gPackager )
				)
				( objectStatus "R7P4.1" )
			)
			( pin "@baseboard_fab2_lib.baseboard_fab2(sch_1):page103_i131:b"
				( attribute "PN" "2"
					( Origin gPackager )
				)
				( objectStatus "R7P4.2" )
			)
			( pin "@baseboard_fab2_lib.baseboard_fab2(sch_1):page103_i133:a"
				( attribute "PN" "1"
					( Origin gPackager )
				)
				( objectStatus "R7P1.1" )
			)
			( pin "@baseboard_fab2_lib.baseboard_fab2(sch_1):page103_i133:b"
				( attribute "PN" "2"
					( Origin gPackager )
				)
				( objectStatus "R7P1.2" )
			)
			( pin "@baseboard_fab2_lib.baseboard_fab2(sch_1):page103_i135:a"
				( attribute "PN" "1"
					( Origin gPackager )
				)
				( objectStatus "R7P2.1" )
			)
			( pin "@baseboard_fab2_lib.baseboard_fab2(sch_1):page103_i135:b"
				( attribute "PN" "2"
					( Origin gPackager )
				)
				( objectStatus "R7P2.2" )
			)
			( pin "@baseboard_fab2_lib.baseboard_fab2(sch_1):page103_i137:a"
				( attribute "PN" "1"
					( Origin gPackager )
				)
				( objectStatus "R6P7.1" )
			)
			( pin "@baseboard_fab2_lib.baseboard_fab2(sch_1):page103_i137:b"
				( attribute "PN" "2"
					( Origin gPackager )
				)
				( objectStatus "R6P7.2" )
			)
			( pin "@baseboard_fab2_lib.baseboard_fab2(sch_1):page103_i139:a"
				( attribute "PN" "1"
					( Origin gPackager )
				)
				( objectStatus "R6P8.1" )
			)
			( pin "@baseboard_fab2_lib.baseboard_fab2(sch_1):page103_i139:b"
				( attribute "PN" "2"
					( Origin gPackager )
				)
				( objectStatus "R6P8.2" )
			)
			( pin "@baseboard_fab2_lib.baseboard_fab2(sch_1):page103_i141:a"
				( attribute "PN" "1"
					( Origin gPackager )
				)
				( objectStatus "R6P5.1" )
			)
			( pin "@baseboard_fab2_lib.baseboard_fab2(sch_1):page103_i141:b"
				( attribute "PN" "2"
					( Origin gPackager )
				)
				( objectStatus "R6P5.2" )
			)
			( pin "@baseboard_fab2_lib.baseboard_fab2(sch_1):page103_i143:a"
				( attribute "PN" "1"
					( Origin gPackager )
				)
				( objectStatus "R6P6.1" )
			)
			( pin "@baseboard_fab2_lib.baseboard_fab2(sch_1):page103_i143:b"
				( attribute "PN" "2"
					( Origin gPackager )
				)
				( objectStatus "R6P6.2" )
			)
			( pin "@baseboard_fab2_lib.baseboard_fab2(sch_1):page103_i145:a"
				( attribute "PN" "1"
					( Origin gPackager )
				)
				( objectStatus "R6P3.1" )
			)
			( pin "@baseboard_fab2_lib.baseboard_fab2(sch_1):page103_i145:b"
				( attribute "PN" "2"
					( Origin gPackager )
				)
				( objectStatus "R6P3.2" )
			)
			( pin "@baseboard_fab2_lib.baseboard_fab2(sch_1):page103_i147:a"
				( attribute "PN" "1"
					( Origin gPackager )
				)
				( objectStatus "R6P4.1" )
			)
			( pin "@baseboard_fab2_lib.baseboard_fab2(sch_1):page103_i147:b"
				( attribute "PN" "2"
					( Origin gPackager )
				)
				( objectStatus "R6P4.2" )
			)
			( pin "@baseboard_fab2_lib.baseboard_fab2(sch_1):page103_i149:a"
				( attribute "PN" "1"
					( Origin gPackager )
				)
				( objectStatus "R6P1.1" )
			)
			( pin "@baseboard_fab2_lib.baseboard_fab2(sch_1):page103_i149:b"
				( attribute "PN" "2"
					( Origin gPackager )
				)
				( objectStatus "R6P1.2" )
			)
			( pin "@baseboard_fab2_lib.baseboard_fab2(sch_1):page103_i151:a"
				( attribute "PN" "1"
					( Origin gPackager )
				)
				( objectStatus "R6P2.1" )
			)
			( pin "@baseboard_fab2_lib.baseboard_fab2(sch_1):page103_i151:b"
				( attribute "PN" "2"
					( Origin gPackager )
				)
				( objectStatus "R6P2.2" )
			)
			( pin "@baseboard_fab2_lib.baseboard_fab2(sch_1):page103_i153:a"
				( attribute "PN" "1"
					( Origin gPackager )
				)
				( objectStatus "R6P11.1" )
			)
			( pin "@baseboard_fab2_lib.baseboard_fab2(sch_1):page103_i153:b"
				( attribute "PN" "2"
					( Origin gPackager )
				)
				( objectStatus "R6P11.2" )
			)
			( pin "@baseboard_fab2_lib.baseboard_fab2(sch_1):page103_i155:a"
				( attribute "PN" "1"
					( Origin gPackager )
				)
				( objectStatus "R6P9.1" )
			)
			( pin "@baseboard_fab2_lib.baseboard_fab2(sch_1):page103_i155:b"
				( attribute "PN" "2"
					( Origin gPackager )
				)
				( objectStatus "R6P9.2" )
			)
			( pin "@baseboard_fab2_lib.baseboard_fab2(sch_1):page103_i157:a"
				( attribute "PN" "1"
					( Origin gPackager )
				)
				( objectStatus "R6P13.1" )
			)
			( pin "@baseboard_fab2_lib.baseboard_fab2(sch_1):page103_i157:b"
				( attribute "PN" "2"
					( Origin gPackager )
				)
				( objectStatus "R6P13.2" )
			)
			( pin "@baseboard_fab2_lib.baseboard_fab2(sch_1):page103_i159:a"
				( attribute "PN" "1"
					( Origin gPackager )
				)
				( objectStatus "R6P12.1" )
			)
			( pin "@baseboard_fab2_lib.baseboard_fab2(sch_1):page103_i159:b"
				( attribute "PN" "2"
					( Origin gPackager )
				)
				( objectStatus "R6P12.2" )
			)
			( pin "@baseboard_fab2_lib.baseboard_fab2(sch_1):page103_i161:a"
				( attribute "PN" "1"
					( Origin gPackager )
				)
				( objectStatus "R4D24.1" )
			)
			( pin "@baseboard_fab2_lib.baseboard_fab2(sch_1):page103_i161:b"
				( attribute "PN" "2"
					( Origin gPackager )
				)
				( objectStatus "R4D24.2" )
			)
			( pin "@baseboard_fab2_lib.baseboard_fab2(sch_1):page103_i163:a"
				( attribute "PN" "1"
					( Origin gPackager )
				)
				( objectStatus "R4D18.1" )
			)
			( pin "@baseboard_fab2_lib.baseboard_fab2(sch_1):page103_i163:b"
				( attribute "PN" "2"
					( Origin gPackager )
				)
				( objectStatus "R4D18.2" )
			)
			( pin "@baseboard_fab2_lib.baseboard_fab2(sch_1):page103_i165:a"
				( attribute "PN" "1"
					( Origin gPackager )
				)
				( objectStatus "R6P17.1" )
			)
			( pin "@baseboard_fab2_lib.baseboard_fab2(sch_1):page103_i165:b"
				( attribute "PN" "2"
					( Origin gPackager )
				)
				( objectStatus "R6P17.2" )
			)
			( pin "@baseboard_fab2_lib.baseboard_fab2(sch_1):page103_i167:a"
				( attribute "PN" "1"
					( Origin gPackager )
				)
				( objectStatus "R6P15.1" )
			)
			( pin "@baseboard_fab2_lib.baseboard_fab2(sch_1):page103_i167:b"
				( attribute "PN" "2"
					( Origin gPackager )
				)
				( objectStatus "R6P15.2" )
			)
			( pin "@baseboard_fab2_lib.baseboard_fab2(sch_1):page104_i25:a"
				( attribute "PN" "1"
					( Origin gPackager )
				)
				( objectStatus "C6F1.1" )
			)
			( pin "@baseboard_fab2_lib.baseboard_fab2(sch_1):page104_i25:b"
				( attribute "PN" "2"
					( Origin gPackager )
				)
				( objectStatus "C6F1.2" )
			)
			( pin "@baseboard_fab2_lib.baseboard_fab2(sch_1):page104_i34:a"
				( attribute "PN" "1"
					( Origin gPackager )
				)
				( objectStatus "C3F2.1" )
			)
			( pin "@baseboard_fab2_lib.baseboard_fab2(sch_1):page104_i34:b"
				( attribute "PN" "2"
					( Origin gPackager )
				)
				( objectStatus "C3F2.2" )
			)
			( pin "@baseboard_fab2_lib.baseboard_fab2(sch_1):page104_i37:a"
				( attribute "PN" "1"
					( Origin gPackager )
				)
				( objectStatus "R6F8.1" )
			)
			( pin "@baseboard_fab2_lib.baseboard_fab2(sch_1):page104_i37:b"
				( attribute "PN" "2"
					( Origin gPackager )
				)
				( objectStatus "R6F8.2" )
			)
			( pin "@baseboard_fab2_lib.baseboard_fab2(sch_1):page104_i41:a"
				( attribute "PN" "1"
					( Origin gPackager )
				)
				( objectStatus "R6F6.1" )
			)
			( pin "@baseboard_fab2_lib.baseboard_fab2(sch_1):page104_i41:b"
				( attribute "PN" "2"
					( Origin gPackager )
				)
				( objectStatus "R6F6.2" )
			)
			( pin "@baseboard_fab2_lib.baseboard_fab2(sch_1):page104_i51:a"
				( attribute "PN" "1"
					( Origin gPackager )
				)
				( objectStatus "R3F1.1" )
			)
			( pin "@baseboard_fab2_lib.baseboard_fab2(sch_1):page104_i51:b"
				( attribute "PN" "2"
					( Origin gPackager )
				)
				( objectStatus "R3F1.2" )
			)
			( pin "@baseboard_fab2_lib.baseboard_fab2(sch_1):page104_i53:a"
				( attribute "PN" "1"
					( Origin gPackager )
				)
				( objectStatus "R3F3.1" )
			)
			( pin "@baseboard_fab2_lib.baseboard_fab2(sch_1):page104_i53:b"
				( attribute "PN" "2"
					( Origin gPackager )
				)
				( objectStatus "R3F3.2" )
			)
			( pin "@baseboard_fab2_lib.baseboard_fab2(sch_1):page104_i67:a"
				( attribute "PN" "1"
					( Origin gPackager )
				)
				( objectStatus "R6F7.1" )
			)
			( pin "@baseboard_fab2_lib.baseboard_fab2(sch_1):page104_i67:b"
				( attribute "PN" "2"
					( Origin gPackager )
				)
				( objectStatus "R6F7.2" )
			)
			( pin "@baseboard_fab2_lib.baseboard_fab2(sch_1):page104_i68:a"
				( attribute "PN" "1"
					( Origin gPackager )
				)
				( objectStatus "R6F9.1" )
			)
			( pin "@baseboard_fab2_lib.baseboard_fab2(sch_1):page104_i68:b"
				( attribute "PN" "2"
					( Origin gPackager )
				)
				( objectStatus "R6F9.2" )
			)
			( pin "@baseboard_fab2_lib.baseboard_fab2(sch_1):page104_i69:a"
				( attribute "PN" "1"
					( Origin gPackager )
				)
				( objectStatus "R3F2.1" )
			)
			( pin "@baseboard_fab2_lib.baseboard_fab2(sch_1):page104_i69:b"
				( attribute "PN" "2"
					( Origin gPackager )
				)
				( objectStatus "R3F2.2" )
			)
			( pin "@baseboard_fab2_lib.baseboard_fab2(sch_1):page104_i70:a"
				( attribute "PN" "1"
					( Origin gPackager )
				)
				( objectStatus "R3F4.1" )
			)
			( pin "@baseboard_fab2_lib.baseboard_fab2(sch_1):page104_i70:b"
				( attribute "PN" "2"
					( Origin gPackager )
				)
				( objectStatus "R3F4.2" )
			)
			( pin "@baseboard_fab2_lib.baseboard_fab2(sch_1):page104_i71:enable_disable"
				( attribute "PN" "1"
					( Origin gPackager )
				)
				( objectStatus "Y6F1.1" )
			)
			( pin "@baseboard_fab2_lib.baseboard_fab2(sch_1):page104_i71:gnd"
				( attribute "PN" "3"
					( Origin gPackager )
				)
				( objectStatus "Y6F1.3" )
			)
			( pin "@baseboard_fab2_lib.baseboard_fab2(sch_1):page104_i71:nc_gnd"
				( attribute "PN" "2"
					( Origin gPackager )
				)
				( objectStatus "Y6F1.2" )
			)
			( pin "@baseboard_fab2_lib.baseboard_fab2(sch_1):page104_i71:\out\"
				( attribute "PN" "4"
					( Origin gPackager )
				)
				( objectStatus "Y6F1.4" )
			)
			( pin "@baseboard_fab2_lib.baseboard_fab2(sch_1):page104_i71:out_n"
				( attribute "PN" "5"
					( Origin gPackager )
				)
				( objectStatus "Y6F1.5" )
			)
			( pin "@baseboard_fab2_lib.baseboard_fab2(sch_1):page104_i71:vcc"
				( attribute "PN" "6"
					( Origin gPackager )
				)
				( objectStatus "Y6F1.6" )
			)
			( pin "@baseboard_fab2_lib.baseboard_fab2(sch_1):page104_i72:enable_disable"
				( attribute "PN" "1"
					( Origin gPackager )
				)
				( objectStatus "Y3F1.1" )
			)
			( pin "@baseboard_fab2_lib.baseboard_fab2(sch_1):page104_i72:gnd"
				( attribute "PN" "3"
					( Origin gPackager )
				)
				( objectStatus "Y3F1.3" )
			)
			( pin "@baseboard_fab2_lib.baseboard_fab2(sch_1):page104_i72:nc_gnd"
				( attribute "PN" "2"
					( Origin gPackager )
				)
				( objectStatus "Y3F1.2" )
			)
			( pin "@baseboard_fab2_lib.baseboard_fab2(sch_1):page104_i72:\out\"
				( attribute "PN" "4"
					( Origin gPackager )
				)
				( objectStatus "Y3F1.4" )
			)
			( pin "@baseboard_fab2_lib.baseboard_fab2(sch_1):page104_i72:out_n"
				( attribute "PN" "5"
					( Origin gPackager )
				)
				( objectStatus "Y3F1.5" )
			)
			( pin "@baseboard_fab2_lib.baseboard_fab2(sch_1):page104_i72:vcc"
				( attribute "PN" "6"
					( Origin gPackager )
				)
				( objectStatus "Y3F1.6" )
			)
			( pin "@baseboard_fab2_lib.baseboard_fab2(sch_1):page104_i78:a"
				( attribute "PN" "1"
					( Origin gPackager )
				)
				( objectStatus "R6F10.1" )
			)
			( pin "@baseboard_fab2_lib.baseboard_fab2(sch_1):page104_i78:b"
				( attribute "PN" "2"
					( Origin gPackager )
				)
				( objectStatus "R6F10.2" )
			)
			( pin "@baseboard_fab2_lib.baseboard_fab2(sch_1):page104_i79:a"
				( attribute "PN" "1"
					( Origin gPackager )
				)
				( objectStatus "R6F11.1" )
			)
			( pin "@baseboard_fab2_lib.baseboard_fab2(sch_1):page104_i79:b"
				( attribute "PN" "2"
					( Origin gPackager )
				)
				( objectStatus "R6F11.2" )
			)
			( pin "@baseboard_fab2_lib.baseboard_fab2(sch_1):page104_i84:a"
				( attribute "PN" "1"
					( Origin gPackager )
				)
				( objectStatus "R3F5.1" )
			)
			( pin "@baseboard_fab2_lib.baseboard_fab2(sch_1):page104_i84:b"
				( attribute "PN" "2"
					( Origin gPackager )
				)
				( objectStatus "R3F5.2" )
			)
			( pin "@baseboard_fab2_lib.baseboard_fab2(sch_1):page104_i88:a"
				( attribute "PN" "1"
					( Origin gPackager )
				)
				( objectStatus "R3F6.1" )
			)
			( pin "@baseboard_fab2_lib.baseboard_fab2(sch_1):page104_i88:b"
				( attribute "PN" "2"
					( Origin gPackager )
				)
				( objectStatus "R3F6.2" )
			)
			( pin "@baseboard_fab2_lib.baseboard_fab2(sch_1):page104_i93:a"
				( attribute "PN" "1"
					( Origin gPackager )
				)
				( objectStatus "R8D43.1" )
			)
			( pin "@baseboard_fab2_lib.baseboard_fab2(sch_1):page104_i93:b"
				( attribute "PN" "2"
					( Origin gPackager )
				)
				( objectStatus "R8D43.2" )
			)
			( pin "@baseboard_fab2_lib.baseboard_fab2(sch_1):page104_i94:a"
				( attribute "PN" "1"
					( Origin gPackager )
				)
				( objectStatus "R7D40.1" )
			)
			( pin "@baseboard_fab2_lib.baseboard_fab2(sch_1):page104_i94:b"
				( attribute "PN" "2"
					( Origin gPackager )
				)
				( objectStatus "R7D40.2" )
			)
			( pin "@baseboard_fab2_lib.baseboard_fab2(sch_1):page104_i96:a"
				( attribute "PN" "1"
					( Origin gPackager )
				)
				( objectStatus "R7D36.1" )
			)
			( pin "@baseboard_fab2_lib.baseboard_fab2(sch_1):page104_i96:b"
				( attribute "PN" "2"
					( Origin gPackager )
				)
				( objectStatus "R7D36.2" )
			)
			( pin "@baseboard_fab2_lib.baseboard_fab2(sch_1):page104_i97:a"
				( attribute "PN" "1"
					( Origin gPackager )
				)
				( objectStatus "R7D38.1" )
			)
			( pin "@baseboard_fab2_lib.baseboard_fab2(sch_1):page104_i97:b"
				( attribute "PN" "2"
					( Origin gPackager )
				)
				( objectStatus "R7D38.2" )
			)
			( pin "@baseboard_fab2_lib.baseboard_fab2(sch_1):page105_i1:a"
				( attribute "PN" "1"
					( Origin gPackager )
				)
				( objectStatus "C7G24.1" )
			)
			( pin "@baseboard_fab2_lib.baseboard_fab2(sch_1):page105_i1:b"
				( attribute "PN" "2"
					( Origin gPackager )
				)
				( objectStatus "C7G24.2" )
			)
			( pin "@baseboard_fab2_lib.baseboard_fab2(sch_1):page105_i6:a"
				( attribute "PN" "1"
					( Origin gPackager )
				)
				( objectStatus "C7G6.1" )
			)
			( pin "@baseboard_fab2_lib.baseboard_fab2(sch_1):page105_i6:b"
				( attribute "PN" "2"
					( Origin gPackager )
				)
				( objectStatus "C7G6.2" )
			)
			( pin "@baseboard_fab2_lib.baseboard_fab2(sch_1):page105_i7:a"
				( attribute "PN" "1"
					( Origin gPackager )
				)
				( objectStatus "C7G7.1" )
			)
			( pin "@baseboard_fab2_lib.baseboard_fab2(sch_1):page105_i7:b"
				( attribute "PN" "2"
					( Origin gPackager )
				)
				( objectStatus "C7G7.2" )
			)
			( pin "@baseboard_fab2_lib.baseboard_fab2(sch_1):page105_i8:a"
				( attribute "PN" "1"
					( Origin gPackager )
				)
				( objectStatus "C7G10.1" )
			)
			( pin "@baseboard_fab2_lib.baseboard_fab2(sch_1):page105_i8:b"
				( attribute "PN" "2"
					( Origin gPackager )
				)
				( objectStatus "C7G10.2" )
			)
			( pin "@baseboard_fab2_lib.baseboard_fab2(sch_1):page105_i12:a"
				( attribute "PN" "1"
					( Origin gPackager )
				)
				( objectStatus "C7G12.1" )
			)
			( pin "@baseboard_fab2_lib.baseboard_fab2(sch_1):page105_i12:b"
				( attribute "PN" "2"
					( Origin gPackager )
				)
				( objectStatus "C7G12.2" )
			)
			( pin "@baseboard_fab2_lib.baseboard_fab2(sch_1):page105_i13:a"
				( attribute "PN" "1"
					( Origin gPackager )
				)
				( objectStatus "C7G13.1" )
			)
			( pin "@baseboard_fab2_lib.baseboard_fab2(sch_1):page105_i13:b"
				( attribute "PN" "2"
					( Origin gPackager )
				)
				( objectStatus "C7G13.2" )
			)
			( pin "@baseboard_fab2_lib.baseboard_fab2(sch_1):page105_i20:a"
				( attribute "PN" "1"
					( Origin gPackager )
				)
				( objectStatus "C7G5.1" )
			)
			( pin "@baseboard_fab2_lib.baseboard_fab2(sch_1):page105_i20:b"
				( attribute "PN" "2"
					( Origin gPackager )
				)
				( objectStatus "C7G5.2" )
			)
			( pin "@baseboard_fab2_lib.baseboard_fab2(sch_1):page105_i21:a"
				( attribute "PN" "1"
					( Origin gPackager )
				)
				( objectStatus "C7G9.1" )
			)
			( pin "@baseboard_fab2_lib.baseboard_fab2(sch_1):page105_i21:b"
				( attribute "PN" "2"
					( Origin gPackager )
				)
				( objectStatus "C7G9.2" )
			)
			( pin "@baseboard_fab2_lib.baseboard_fab2(sch_1):page105_i22:a"
				( attribute "PN" "1"
					( Origin gPackager )
				)
				( objectStatus "C7G8.1" )
			)
			( pin "@baseboard_fab2_lib.baseboard_fab2(sch_1):page105_i22:b"
				( attribute "PN" "2"
					( Origin gPackager )
				)
				( objectStatus "C7G8.2" )
			)
			( pin "@baseboard_fab2_lib.baseboard_fab2(sch_1):page105_i27:a"
				( attribute "PN" "1"
					( Origin gPackager )
				)
				( objectStatus "C7G11.1" )
			)
			( pin "@baseboard_fab2_lib.baseboard_fab2(sch_1):page105_i27:b"
				( attribute "PN" "2"
					( Origin gPackager )
				)
				( objectStatus "C7G11.2" )
			)
			( pin "@baseboard_fab2_lib.baseboard_fab2(sch_1):page105_i28:a"
				( attribute "PN" "1"
					( Origin gPackager )
				)
				( objectStatus "C7G14.1" )
			)
			( pin "@baseboard_fab2_lib.baseboard_fab2(sch_1):page105_i28:b"
				( attribute "PN" "2"
					( Origin gPackager )
				)
				( objectStatus "C7G14.2" )
			)
			( pin "@baseboard_fab2_lib.baseboard_fab2(sch_1):page105_i31:a"
				( attribute "PN" "1"
					( Origin gPackager )
				)
				( objectStatus "C7G16.1" )
			)
			( pin "@baseboard_fab2_lib.baseboard_fab2(sch_1):page105_i31:b"
				( attribute "PN" "2"
					( Origin gPackager )
				)
				( objectStatus "C7G16.2" )
			)
			( pin "@baseboard_fab2_lib.baseboard_fab2(sch_1):page105_i32:a"
				( attribute "PN" "1"
					( Origin gPackager )
				)
				( objectStatus "C7G18.1" )
			)
			( pin "@baseboard_fab2_lib.baseboard_fab2(sch_1):page105_i32:b"
				( attribute "PN" "2"
					( Origin gPackager )
				)
				( objectStatus "C7G18.2" )
			)
			( pin "@baseboard_fab2_lib.baseboard_fab2(sch_1):page105_i37:a"
				( attribute "PN" "1"
					( Origin gPackager )
				)
				( objectStatus "C7G22.1" )
			)
			( pin "@baseboard_fab2_lib.baseboard_fab2(sch_1):page105_i37:b"
				( attribute "PN" "2"
					( Origin gPackager )
				)
				( objectStatus "C7G22.2" )
			)
			( pin "@baseboard_fab2_lib.baseboard_fab2(sch_1):page105_i44:a"
				( attribute "PN" "1"
					( Origin gPackager )
				)
				( objectStatus "C7G17.1" )
			)
			( pin "@baseboard_fab2_lib.baseboard_fab2(sch_1):page105_i44:b"
				( attribute "PN" "2"
					( Origin gPackager )
				)
				( objectStatus "C7G17.2" )
			)
			( pin "@baseboard_fab2_lib.baseboard_fab2(sch_1):page105_i45:a"
				( attribute "PN" "1"
					( Origin gPackager )
				)
				( objectStatus "C7G15.1" )
			)
			( pin "@baseboard_fab2_lib.baseboard_fab2(sch_1):page105_i45:b"
				( attribute "PN" "2"
					( Origin gPackager )
				)
				( objectStatus "C7G15.2" )
			)
			( pin "@baseboard_fab2_lib.baseboard_fab2(sch_1):page105_i51:a"
				( attribute "PN" "1"
					( Origin gPackager )
				)
				( objectStatus "C7G21.1" )
			)
			( pin "@baseboard_fab2_lib.baseboard_fab2(sch_1):page105_i51:b"
				( attribute "PN" "2"
					( Origin gPackager )
				)
				( objectStatus "C7G21.2" )
			)
			( pin "@baseboard_fab2_lib.baseboard_fab2(sch_1):page105_i52:a"
				( attribute "PN" "1"
					( Origin gPackager )
				)
				( objectStatus "C7G23.1" )
			)
			( pin "@baseboard_fab2_lib.baseboard_fab2(sch_1):page105_i52:b"
				( attribute "PN" "2"
					( Origin gPackager )
				)
				( objectStatus "C7G23.2" )
			)
			( pin "@baseboard_fab2_lib.baseboard_fab2(sch_1):page105_i55:a"
				( attribute "PN" "1"
					( Origin gPackager )
				)
				( objectStatus "C7G26.1" )
			)
			( pin "@baseboard_fab2_lib.baseboard_fab2(sch_1):page105_i55:b"
				( attribute "PN" "2"
					( Origin gPackager )
				)
				( objectStatus "C7G26.2" )
			)
			( pin "@baseboard_fab2_lib.baseboard_fab2(sch_1):page105_i56:a"
				( attribute "PN" "1"
					( Origin gPackager )
				)
				( objectStatus "C8G4.1" )
			)
			( pin "@baseboard_fab2_lib.baseboard_fab2(sch_1):page105_i56:b"
				( attribute "PN" "2"
					( Origin gPackager )
				)
				( objectStatus "C8G4.2" )
			)
			( pin "@baseboard_fab2_lib.baseboard_fab2(sch_1):page105_i58:a"
				( attribute "PN" "1"
					( Origin gPackager )
				)
				( objectStatus "C8G2.1" )
			)
			( pin "@baseboard_fab2_lib.baseboard_fab2(sch_1):page105_i58:b"
				( attribute "PN" "2"
					( Origin gPackager )
				)
				( objectStatus "C8G2.2" )
			)
			( pin "@baseboard_fab2_lib.baseboard_fab2(sch_1):page105_i61:a"
				( attribute "PN" "1"
					( Origin gPackager )
				)
				( objectStatus "C8G6.1" )
			)
			( pin "@baseboard_fab2_lib.baseboard_fab2(sch_1):page105_i61:b"
				( attribute "PN" "2"
					( Origin gPackager )
				)
				( objectStatus "C8G6.2" )
			)
			( pin "@baseboard_fab2_lib.baseboard_fab2(sch_1):page105_i62:a"
				( attribute "PN" "1"
					( Origin gPackager )
				)
				( objectStatus "C8G7.1" )
			)
			( pin "@baseboard_fab2_lib.baseboard_fab2(sch_1):page105_i62:b"
				( attribute "PN" "2"
					( Origin gPackager )
				)
				( objectStatus "C8G7.2" )
			)
			( pin "@baseboard_fab2_lib.baseboard_fab2(sch_1):page105_i69:a"
				( attribute "PN" "1"
					( Origin gPackager )
				)
				( objectStatus "C7G25.1" )
			)
			( pin "@baseboard_fab2_lib.baseboard_fab2(sch_1):page105_i69:b"
				( attribute "PN" "2"
					( Origin gPackager )
				)
				( objectStatus "C7G25.2" )
			)
			( pin "@baseboard_fab2_lib.baseboard_fab2(sch_1):page105_i70:a"
				( attribute "PN" "1"
					( Origin gPackager )
				)
				( objectStatus "C8G1.1" )
			)
			( pin "@baseboard_fab2_lib.baseboard_fab2(sch_1):page105_i70:b"
				( attribute "PN" "2"
					( Origin gPackager )
				)
				( objectStatus "C8G1.2" )
			)
			( pin "@baseboard_fab2_lib.baseboard_fab2(sch_1):page105_i71:a"
				( attribute "PN" "1"
					( Origin gPackager )
				)
				( objectStatus "C8G3.1" )
			)
			( pin "@baseboard_fab2_lib.baseboard_fab2(sch_1):page105_i71:b"
				( attribute "PN" "2"
					( Origin gPackager )
				)
				( objectStatus "C8G3.2" )
			)
			( pin "@baseboard_fab2_lib.baseboard_fab2(sch_1):page105_i75:a"
				( attribute "PN" "1"
					( Origin gPackager )
				)
				( objectStatus "C8G5.1" )
			)
			( pin "@baseboard_fab2_lib.baseboard_fab2(sch_1):page105_i75:b"
				( attribute "PN" "2"
					( Origin gPackager )
				)
				( objectStatus "C8G5.2" )
			)
			( pin "@baseboard_fab2_lib.baseboard_fab2(sch_1):page105_i76:a"
				( attribute "PN" "1"
					( Origin gPackager )
				)
				( objectStatus "C8G8.1" )
			)
			( pin "@baseboard_fab2_lib.baseboard_fab2(sch_1):page105_i76:b"
				( attribute "PN" "2"
					( Origin gPackager )
				)
				( objectStatus "C8G8.2" )
			)
			( pin "@baseboard_fab2_lib.baseboard_fab2(sch_1):page105_i93:a"
				( attribute "PN" "1"
					( Origin gPackager )
				)
				( objectStatus "C8G9.1" )
			)
			( pin "@baseboard_fab2_lib.baseboard_fab2(sch_1):page105_i93:b"
				( attribute "PN" "2"
					( Origin gPackager )
				)
				( objectStatus "C8G9.2" )
			)
			( pin "@baseboard_fab2_lib.baseboard_fab2(sch_1):page105_i96:a"
				( attribute "PN" "1"
					( Origin gPackager )
				)
				( objectStatus "C8G10.1" )
			)
			( pin "@baseboard_fab2_lib.baseboard_fab2(sch_1):page105_i96:b"
				( attribute "PN" "2"
					( Origin gPackager )
				)
				( objectStatus "C8G10.2" )
			)
			( pin "@baseboard_fab2_lib.baseboard_fab2(sch_1):page105_i153:a"
				( attribute "PN" "1"
					( Origin gPackager )
				)
				( objectStatus "C6B18.1" )
			)
			( pin "@baseboard_fab2_lib.baseboard_fab2(sch_1):page105_i153:b"
				( attribute "PN" "2"
					( Origin gPackager )
				)
				( objectStatus "C6B18.2" )
			)
			( pin "@baseboard_fab2_lib.baseboard_fab2(sch_1):page105_i160:a"
				( attribute "PN" "1"
					( Origin gPackager )
				)
				( objectStatus "C6B19.1" )
			)
			( pin "@baseboard_fab2_lib.baseboard_fab2(sch_1):page105_i160:b"
				( attribute "PN" "2"
					( Origin gPackager )
				)
				( objectStatus "C6B19.2" )
			)
			( pin "@baseboard_fab2_lib.baseboard_fab2(sch_1):page105_i163:a"
				( attribute "PN" "1"
					( Origin gPackager )
				)
				( objectStatus "C6B15.1" )
			)
			( pin "@baseboard_fab2_lib.baseboard_fab2(sch_1):page105_i163:b"
				( attribute "PN" "2"
					( Origin gPackager )
				)
				( objectStatus "C6B15.2" )
			)
			( pin "@baseboard_fab2_lib.baseboard_fab2(sch_1):page105_i166:a"
				( attribute "PN" "1"
					( Origin gPackager )
				)
				( objectStatus "C6B11.1" )
			)
			( pin "@baseboard_fab2_lib.baseboard_fab2(sch_1):page105_i166:b"
				( attribute "PN" "2"
					( Origin gPackager )
				)
				( objectStatus "C6B11.2" )
			)
			( pin "@baseboard_fab2_lib.baseboard_fab2(sch_1):page105_i169:a"
				( attribute "PN" "1"
					( Origin gPackager )
				)
				( objectStatus "C6B6.1" )
			)
			( pin "@baseboard_fab2_lib.baseboard_fab2(sch_1):page105_i169:b"
				( attribute "PN" "2"
					( Origin gPackager )
				)
				( objectStatus "C6B6.2" )
			)
			( pin "@baseboard_fab2_lib.baseboard_fab2(sch_1):page105_i173:a"
				( attribute "PN" "1"
					( Origin gPackager )
				)
				( objectStatus "C6B20.1" )
			)
			( pin "@baseboard_fab2_lib.baseboard_fab2(sch_1):page105_i173:b"
				( attribute "PN" "2"
					( Origin gPackager )
				)
				( objectStatus "C6B20.2" )
			)
			( pin "@baseboard_fab2_lib.baseboard_fab2(sch_1):page105_i175:a"
				( attribute "PN" "1"
					( Origin gPackager )
				)
				( objectStatus "C6B17.1" )
			)
			( pin "@baseboard_fab2_lib.baseboard_fab2(sch_1):page105_i175:b"
				( attribute "PN" "2"
					( Origin gPackager )
				)
				( objectStatus "C6B17.2" )
			)
			( pin "@baseboard_fab2_lib.baseboard_fab2(sch_1):page105_i180:a"
				( attribute "PN" "1"
					( Origin gPackager )
				)
				( objectStatus "C6B16.1" )
			)
			( pin "@baseboard_fab2_lib.baseboard_fab2(sch_1):page105_i180:b"
				( attribute "PN" "2"
					( Origin gPackager )
				)
				( objectStatus "C6B16.2" )
			)
			( pin "@baseboard_fab2_lib.baseboard_fab2(sch_1):page105_i181:a"
				( attribute "PN" "1"
					( Origin gPackager )
				)
				( objectStatus "C6B14.1" )
			)
			( pin "@baseboard_fab2_lib.baseboard_fab2(sch_1):page105_i181:b"
				( attribute "PN" "2"
					( Origin gPackager )
				)
				( objectStatus "C6B14.2" )
			)
			( pin "@baseboard_fab2_lib.baseboard_fab2(sch_1):page105_i185:a"
				( attribute "PN" "1"
					( Origin gPackager )
				)
				( objectStatus "C6B9.1" )
			)
			( pin "@baseboard_fab2_lib.baseboard_fab2(sch_1):page105_i185:b"
				( attribute "PN" "2"
					( Origin gPackager )
				)
				( objectStatus "C6B9.2" )
			)
			( pin "@baseboard_fab2_lib.baseboard_fab2(sch_1):page105_i187:a"
				( attribute "PN" "1"
					( Origin gPackager )
				)
				( objectStatus "C6B12.1" )
			)
			( pin "@baseboard_fab2_lib.baseboard_fab2(sch_1):page105_i187:b"
				( attribute "PN" "2"
					( Origin gPackager )
				)
				( objectStatus "C6B12.2" )
			)
			( pin "@baseboard_fab2_lib.baseboard_fab2(sch_1):page105_i189:a"
				( attribute "PN" "1"
					( Origin gPackager )
				)
				( objectStatus "C6B13.1" )
			)
			( pin "@baseboard_fab2_lib.baseboard_fab2(sch_1):page105_i189:b"
				( attribute "PN" "2"
					( Origin gPackager )
				)
				( objectStatus "C6B13.2" )
			)
			( pin "@baseboard_fab2_lib.baseboard_fab2(sch_1):page105_i193:a"
				( attribute "PN" "1"
					( Origin gPackager )
				)
				( objectStatus "C6B10.1" )
			)
			( pin "@baseboard_fab2_lib.baseboard_fab2(sch_1):page105_i193:b"
				( attribute "PN" "2"
					( Origin gPackager )
				)
				( objectStatus "C6B10.2" )
			)
			( pin "@baseboard_fab2_lib.baseboard_fab2(sch_1):page105_i196:a"
				( attribute "PN" "1"
					( Origin gPackager )
				)
				( objectStatus "C6B4.1" )
			)
			( pin "@baseboard_fab2_lib.baseboard_fab2(sch_1):page105_i196:b"
				( attribute "PN" "2"
					( Origin gPackager )
				)
				( objectStatus "C6B4.2" )
			)
			( pin "@baseboard_fab2_lib.baseboard_fab2(sch_1):page105_i198:a"
				( attribute "PN" "1"
					( Origin gPackager )
				)
				( objectStatus "C6B8.1" )
			)
			( pin "@baseboard_fab2_lib.baseboard_fab2(sch_1):page105_i198:b"
				( attribute "PN" "2"
					( Origin gPackager )
				)
				( objectStatus "C6B8.2" )
			)
			( pin "@baseboard_fab2_lib.baseboard_fab2(sch_1):page105_i201:a"
				( attribute "PN" "1"
					( Origin gPackager )
				)
				( objectStatus "C6B5.1" )
			)
			( pin "@baseboard_fab2_lib.baseboard_fab2(sch_1):page105_i201:b"
				( attribute "PN" "2"
					( Origin gPackager )
				)
				( objectStatus "C6B5.2" )
			)
			( pin "@baseboard_fab2_lib.baseboard_fab2(sch_1):page105_i205:a"
				( attribute "PN" "1"
					( Origin gPackager )
				)
				( objectStatus "C3M25.1" )
			)
			( pin "@baseboard_fab2_lib.baseboard_fab2(sch_1):page105_i205:b"
				( attribute "PN" "2"
					( Origin gPackager )
				)
				( objectStatus "C3M25.2" )
			)
			( pin "@baseboard_fab2_lib.baseboard_fab2(sch_1):page105_i206:a"
				( attribute "PN" "1"
					( Origin gPackager )
				)
				( objectStatus "C3M34.1" )
			)
			( pin "@baseboard_fab2_lib.baseboard_fab2(sch_1):page105_i206:b"
				( attribute "PN" "2"
					( Origin gPackager )
				)
				( objectStatus "C3M34.2" )
			)
			( pin "@baseboard_fab2_lib.baseboard_fab2(sch_1):page105_i212:a"
				( attribute "PN" "1"
					( Origin gPackager )
				)
				( objectStatus "C3M28.1" )
			)
			( pin "@baseboard_fab2_lib.baseboard_fab2(sch_1):page105_i212:b"
				( attribute "PN" "2"
					( Origin gPackager )
				)
				( objectStatus "C3M28.2" )
			)
			( pin "@baseboard_fab2_lib.baseboard_fab2(sch_1):page105_i217:a"
				( attribute "PN" "1"
					( Origin gPackager )
				)
				( objectStatus "C3M33.1" )
			)
			( pin "@baseboard_fab2_lib.baseboard_fab2(sch_1):page105_i217:b"
				( attribute "PN" "2"
					( Origin gPackager )
				)
				( objectStatus "C3M33.2" )
			)
			( pin "@baseboard_fab2_lib.baseboard_fab2(sch_1):page105_i218:a"
				( attribute "PN" "1"
					( Origin gPackager )
				)
				( objectStatus "C3M36.1" )
			)
			( pin "@baseboard_fab2_lib.baseboard_fab2(sch_1):page105_i218:b"
				( attribute "PN" "2"
					( Origin gPackager )
				)
				( objectStatus "C3M36.2" )
			)
			( pin "@baseboard_fab2_lib.baseboard_fab2(sch_1):page105_i223:a"
				( attribute "PN" "1"
					( Origin gPackager )
				)
				( objectStatus "C3M32.1" )
			)
			( pin "@baseboard_fab2_lib.baseboard_fab2(sch_1):page105_i223:b"
				( attribute "PN" "2"
					( Origin gPackager )
				)
				( objectStatus "C3M32.2" )
			)
			( pin "@baseboard_fab2_lib.baseboard_fab2(sch_1):page105_i225:a"
				( attribute "PN" "1"
					( Origin gPackager )
				)
				( objectStatus "C3M35.1" )
			)
			( pin "@baseboard_fab2_lib.baseboard_fab2(sch_1):page105_i225:b"
				( attribute "PN" "2"
					( Origin gPackager )
				)
				( objectStatus "C3M35.2" )
			)
			( pin "@baseboard_fab2_lib.baseboard_fab2(sch_1):page105_i229:a"
				( attribute "PN" "1"
					( Origin gPackager )
				)
				( objectStatus "C3M26.1" )
			)
			( pin "@baseboard_fab2_lib.baseboard_fab2(sch_1):page105_i229:b"
				( attribute "PN" "2"
					( Origin gPackager )
				)
				( objectStatus "C3M26.2" )
			)
			( pin "@baseboard_fab2_lib.baseboard_fab2(sch_1):page105_i232:a"
				( attribute "PN" "1"
					( Origin gPackager )
				)
				( objectStatus "C3M3.1" )
			)
			( pin "@baseboard_fab2_lib.baseboard_fab2(sch_1):page105_i232:b"
				( attribute "PN" "2"
					( Origin gPackager )
				)
				( objectStatus "C3M3.2" )
			)
			( pin "@baseboard_fab2_lib.baseboard_fab2(sch_1):page105_i234:a"
				( attribute "PN" "1"
					( Origin gPackager )
				)
				( objectStatus "C3M11.1" )
			)
			( pin "@baseboard_fab2_lib.baseboard_fab2(sch_1):page105_i234:b"
				( attribute "PN" "2"
					( Origin gPackager )
				)
				( objectStatus "C3M11.2" )
			)
			( pin "@baseboard_fab2_lib.baseboard_fab2(sch_1):page105_i239:a"
				( attribute "PN" "1"
					( Origin gPackager )
				)
				( objectStatus "C3M13.1" )
			)
			( pin "@baseboard_fab2_lib.baseboard_fab2(sch_1):page105_i239:b"
				( attribute "PN" "2"
					( Origin gPackager )
				)
				( objectStatus "C3M13.2" )
			)
			( pin "@baseboard_fab2_lib.baseboard_fab2(sch_1):page105_i244:a"
				( attribute "PN" "1"
					( Origin gPackager )
				)
				( objectStatus "C3M4.1" )
			)
			( pin "@baseboard_fab2_lib.baseboard_fab2(sch_1):page105_i244:b"
				( attribute "PN" "2"
					( Origin gPackager )
				)
				( objectStatus "C3M4.2" )
			)
			( pin "@baseboard_fab2_lib.baseboard_fab2(sch_1):page105_i246:a"
				( attribute "PN" "1"
					( Origin gPackager )
				)
				( objectStatus "C3M12.1" )
			)
			( pin "@baseboard_fab2_lib.baseboard_fab2(sch_1):page105_i246:b"
				( attribute "PN" "2"
					( Origin gPackager )
				)
				( objectStatus "C3M12.2" )
			)
			( pin "@baseboard_fab2_lib.baseboard_fab2(sch_1):page105_i247:a"
				( attribute "PN" "1"
					( Origin gPackager )
				)
				( objectStatus "C3M2.1" )
			)
			( pin "@baseboard_fab2_lib.baseboard_fab2(sch_1):page105_i247:b"
				( attribute "PN" "2"
					( Origin gPackager )
				)
				( objectStatus "C3M2.2" )
			)
			( pin "@baseboard_fab2_lib.baseboard_fab2(sch_1):page105_i253:a"
				( attribute "PN" "1"
					( Origin gPackager )
				)
				( objectStatus "C3M14.1" )
			)
			( pin "@baseboard_fab2_lib.baseboard_fab2(sch_1):page105_i253:b"
				( attribute "PN" "2"
					( Origin gPackager )
				)
				( objectStatus "C3M14.2" )
			)
			( pin "@baseboard_fab2_lib.baseboard_fab2(sch_1):page105_i255:a"
				( attribute "PN" "1"
					( Origin gPackager )
				)
				( objectStatus "C3M1.1" )
			)
			( pin "@baseboard_fab2_lib.baseboard_fab2(sch_1):page105_i255:b"
				( attribute "PN" "2"
					( Origin gPackager )
				)
				( objectStatus "C3M1.2" )
			)
			( pin "@baseboard_fab2_lib.baseboard_fab2(sch_1):page106_i10:a"
				( attribute "PN" "1"
					( Origin gPackager )
				)
				( objectStatus "C1R2.1" )
			)
			( pin "@baseboard_fab2_lib.baseboard_fab2(sch_1):page106_i10:b"
				( attribute "PN" "2"
					( Origin gPackager )
				)
				( objectStatus "C1R2.2" )
			)
			( pin "@baseboard_fab2_lib.baseboard_fab2(sch_1):page106_i26:a"
				( attribute "PN" "1"
					( Origin gPackager )
				)
				( objectStatus "C1R4.1" )
			)
			( pin "@baseboard_fab2_lib.baseboard_fab2(sch_1):page106_i26:b"
				( attribute "PN" "2"
					( Origin gPackager )
				)
				( objectStatus "C1R4.2" )
			)
			( pin "@baseboard_fab2_lib.baseboard_fab2(sch_1):page106_i29:a"
				( attribute "PN" "1"
					( Origin gPackager )
				)
				( objectStatus "C1R1.1" )
			)
			( pin "@baseboard_fab2_lib.baseboard_fab2(sch_1):page106_i29:b"
				( attribute "PN" "2"
					( Origin gPackager )
				)
				( objectStatus "C1R1.2" )
			)
			( pin "@baseboard_fab2_lib.baseboard_fab2(sch_1):page106_i37:a"
				( attribute "PN" "1"
					( Origin gPackager )
				)
				( objectStatus "C1R3.1" )
			)
			( pin "@baseboard_fab2_lib.baseboard_fab2(sch_1):page106_i37:b"
				( attribute "PN" "2"
					( Origin gPackager )
				)
				( objectStatus "C1R3.2" )
			)
			( pin "@baseboard_fab2_lib.baseboard_fab2(sch_1):page106_i40:a"
				( attribute "PN" "1"
					( Origin gPackager )
				)
				( objectStatus "C1R6.1" )
			)
			( pin "@baseboard_fab2_lib.baseboard_fab2(sch_1):page106_i40:b"
				( attribute "PN" "2"
					( Origin gPackager )
				)
				( objectStatus "C1R6.2" )
			)
			( pin "@baseboard_fab2_lib.baseboard_fab2(sch_1):page106_i55:a"
				( attribute "PN" "1"
					( Origin gPackager )
				)
				( objectStatus "C1R8.1" )
			)
			( pin "@baseboard_fab2_lib.baseboard_fab2(sch_1):page106_i55:b"
				( attribute "PN" "2"
					( Origin gPackager )
				)
				( objectStatus "C1R8.2" )
			)
			( pin "@baseboard_fab2_lib.baseboard_fab2(sch_1):page106_i59:a"
				( attribute "PN" "1"
					( Origin gPackager )
				)
				( objectStatus "C1R5.1" )
			)
			( pin "@baseboard_fab2_lib.baseboard_fab2(sch_1):page106_i59:b"
				( attribute "PN" "2"
					( Origin gPackager )
				)
				( objectStatus "C1R5.2" )
			)
			( pin "@baseboard_fab2_lib.baseboard_fab2(sch_1):page106_i70:a"
				( attribute "PN" "1"
					( Origin gPackager )
				)
				( objectStatus "C1R7.1" )
			)
			( pin "@baseboard_fab2_lib.baseboard_fab2(sch_1):page106_i70:b"
				( attribute "PN" "2"
					( Origin gPackager )
				)
				( objectStatus "C1R7.2" )
			)
			( pin "@baseboard_fab2_lib.baseboard_fab2(sch_1):page106_i76:a"
				( attribute "PN" "1"
					( Origin gPackager )
				)
				( objectStatus "C2M14.1" )
			)
			( pin "@baseboard_fab2_lib.baseboard_fab2(sch_1):page106_i76:b"
				( attribute "PN" "2"
					( Origin gPackager )
				)
				( objectStatus "C2M14.2" )
			)
			( pin "@baseboard_fab2_lib.baseboard_fab2(sch_1):page106_i78:a"
				( attribute "PN" "1"
					( Origin gPackager )
				)
				( objectStatus "C1M18.1" )
			)
			( pin "@baseboard_fab2_lib.baseboard_fab2(sch_1):page106_i78:b"
				( attribute "PN" "2"
					( Origin gPackager )
				)
				( objectStatus "C1M18.2" )
			)
			( pin "@baseboard_fab2_lib.baseboard_fab2(sch_1):page106_i82:a"
				( attribute "PN" "1"
					( Origin gPackager )
				)
				( objectStatus "C1M16.1" )
			)
			( pin "@baseboard_fab2_lib.baseboard_fab2(sch_1):page106_i82:b"
				( attribute "PN" "2"
					( Origin gPackager )
				)
				( objectStatus "C1M16.2" )
			)
			( pin "@baseboard_fab2_lib.baseboard_fab2(sch_1):page106_i85:a"
				( attribute "PN" "1"
					( Origin gPackager )
				)
				( objectStatus "C1M14.1" )
			)
			( pin "@baseboard_fab2_lib.baseboard_fab2(sch_1):page106_i85:b"
				( attribute "PN" "2"
					( Origin gPackager )
				)
				( objectStatus "C1M14.2" )
			)
			( pin "@baseboard_fab2_lib.baseboard_fab2(sch_1):page106_i86:a"
				( attribute "PN" "1"
					( Origin gPackager )
				)
				( objectStatus "C2M15.1" )
			)
			( pin "@baseboard_fab2_lib.baseboard_fab2(sch_1):page106_i86:b"
				( attribute "PN" "2"
					( Origin gPackager )
				)
				( objectStatus "C2M15.2" )
			)
			( pin "@baseboard_fab2_lib.baseboard_fab2(sch_1):page106_i90:a"
				( attribute "PN" "1"
					( Origin gPackager )
				)
				( objectStatus "C1M19.1" )
			)
			( pin "@baseboard_fab2_lib.baseboard_fab2(sch_1):page106_i90:b"
				( attribute "PN" "2"
					( Origin gPackager )
				)
				( objectStatus "C1M19.2" )
			)
			( pin "@baseboard_fab2_lib.baseboard_fab2(sch_1):page106_i92:a"
				( attribute "PN" "1"
					( Origin gPackager )
				)
				( objectStatus "C1M17.1" )
			)
			( pin "@baseboard_fab2_lib.baseboard_fab2(sch_1):page106_i92:b"
				( attribute "PN" "2"
					( Origin gPackager )
				)
				( objectStatus "C1M17.2" )
			)
			( pin "@baseboard_fab2_lib.baseboard_fab2(sch_1):page106_i95:a"
				( attribute "PN" "1"
					( Origin gPackager )
				)
				( objectStatus "C1M15.1" )
			)
			( pin "@baseboard_fab2_lib.baseboard_fab2(sch_1):page106_i95:b"
				( attribute "PN" "2"
					( Origin gPackager )
				)
				( objectStatus "C1M15.2" )
			)
			( pin "@baseboard_fab2_lib.baseboard_fab2(sch_1):page106_i100:a"
				( attribute "PN" "1"
					( Origin gPackager )
				)
				( objectStatus "C1M12.1" )
			)
			( pin "@baseboard_fab2_lib.baseboard_fab2(sch_1):page106_i100:b"
				( attribute "PN" "2"
					( Origin gPackager )
				)
				( objectStatus "C1M12.2" )
			)
			( pin "@baseboard_fab2_lib.baseboard_fab2(sch_1):page106_i102:a"
				( attribute "PN" "1"
					( Origin gPackager )
				)
				( objectStatus "C1M10.1" )
			)
			( pin "@baseboard_fab2_lib.baseboard_fab2(sch_1):page106_i102:b"
				( attribute "PN" "2"
					( Origin gPackager )
				)
				( objectStatus "C1M10.2" )
			)
			( pin "@baseboard_fab2_lib.baseboard_fab2(sch_1):page106_i105:a"
				( attribute "PN" "1"
					( Origin gPackager )
				)
				( objectStatus "C1M8.1" )
			)
			( pin "@baseboard_fab2_lib.baseboard_fab2(sch_1):page106_i105:b"
				( attribute "PN" "2"
					( Origin gPackager )
				)
				( objectStatus "C1M8.2" )
			)
			( pin "@baseboard_fab2_lib.baseboard_fab2(sch_1):page106_i109:a"
				( attribute "PN" "1"
					( Origin gPackager )
				)
				( objectStatus "C1M6.1" )
			)
			( pin "@baseboard_fab2_lib.baseboard_fab2(sch_1):page106_i109:b"
				( attribute "PN" "2"
					( Origin gPackager )
				)
				( objectStatus "C1M6.2" )
			)
			( pin "@baseboard_fab2_lib.baseboard_fab2(sch_1):page106_i111:a"
				( attribute "PN" "1"
					( Origin gPackager )
				)
				( objectStatus "C1M13.1" )
			)
			( pin "@baseboard_fab2_lib.baseboard_fab2(sch_1):page106_i111:b"
				( attribute "PN" "2"
					( Origin gPackager )
				)
				( objectStatus "C1M13.2" )
			)
			( pin "@baseboard_fab2_lib.baseboard_fab2(sch_1):page106_i114:a"
				( attribute "PN" "1"
					( Origin gPackager )
				)
				( objectStatus "C1M9.1" )
			)
			( pin "@baseboard_fab2_lib.baseboard_fab2(sch_1):page106_i114:b"
				( attribute "PN" "2"
					( Origin gPackager )
				)
				( objectStatus "C1M9.2" )
			)
			( pin "@baseboard_fab2_lib.baseboard_fab2(sch_1):page106_i117:a"
				( attribute "PN" "1"
					( Origin gPackager )
				)
				( objectStatus "C1M11.1" )
			)
			( pin "@baseboard_fab2_lib.baseboard_fab2(sch_1):page106_i117:b"
				( attribute "PN" "2"
					( Origin gPackager )
				)
				( objectStatus "C1M11.2" )
			)
			( pin "@baseboard_fab2_lib.baseboard_fab2(sch_1):page106_i122:a"
				( attribute "PN" "1"
					( Origin gPackager )
				)
				( objectStatus "C1M7.1" )
			)
			( pin "@baseboard_fab2_lib.baseboard_fab2(sch_1):page106_i122:b"
				( attribute "PN" "2"
					( Origin gPackager )
				)
				( objectStatus "C1M7.2" )
			)
			( pin "@baseboard_fab2_lib.baseboard_fab2(sch_1):page106_i123:a"
				( attribute "PN" "1"
					( Origin gPackager )
				)
				( objectStatus "C2R7.1" )
			)
			( pin "@baseboard_fab2_lib.baseboard_fab2(sch_1):page106_i123:b"
				( attribute "PN" "2"
					( Origin gPackager )
				)
				( objectStatus "C2R7.2" )
			)
			( pin "@baseboard_fab2_lib.baseboard_fab2(sch_1):page106_i128:a"
				( attribute "PN" "1"
					( Origin gPackager )
				)
				( objectStatus "C1R10.1" )
			)
			( pin "@baseboard_fab2_lib.baseboard_fab2(sch_1):page106_i128:b"
				( attribute "PN" "2"
					( Origin gPackager )
				)
				( objectStatus "C1R10.2" )
			)
			( pin "@baseboard_fab2_lib.baseboard_fab2(sch_1):page106_i130:a"
				( attribute "PN" "1"
					( Origin gPackager )
				)
				( objectStatus "C2R14.1" )
			)
			( pin "@baseboard_fab2_lib.baseboard_fab2(sch_1):page106_i130:b"
				( attribute "PN" "2"
					( Origin gPackager )
				)
				( objectStatus "C2R14.2" )
			)
			( pin "@baseboard_fab2_lib.baseboard_fab2(sch_1):page106_i134:a"
				( attribute "PN" "1"
					( Origin gPackager )
				)
				( objectStatus "C1R9.1" )
			)
			( pin "@baseboard_fab2_lib.baseboard_fab2(sch_1):page106_i134:b"
				( attribute "PN" "2"
					( Origin gPackager )
				)
				( objectStatus "C1R9.2" )
			)
			( pin "@baseboard_fab2_lib.baseboard_fab2(sch_1):page106_i137:a"
				( attribute "PN" "1"
					( Origin gPackager )
				)
				( objectStatus "C2R13.1" )
			)
			( pin "@baseboard_fab2_lib.baseboard_fab2(sch_1):page106_i137:b"
				( attribute "PN" "2"
					( Origin gPackager )
				)
				( objectStatus "C2R13.2" )
			)
			( pin "@baseboard_fab2_lib.baseboard_fab2(sch_1):page106_i141:a"
				( attribute "PN" "1"
					( Origin gPackager )
				)
				( objectStatus "C2R8.1" )
			)
			( pin "@baseboard_fab2_lib.baseboard_fab2(sch_1):page106_i141:b"
				( attribute "PN" "2"
					( Origin gPackager )
				)
				( objectStatus "C2R8.2" )
			)
			( pin "@baseboard_fab2_lib.baseboard_fab2(sch_1):page106_i142:a"
				( attribute "PN" "1"
					( Origin gPackager )
				)
				( objectStatus "C2R10.1" )
			)
			( pin "@baseboard_fab2_lib.baseboard_fab2(sch_1):page106_i142:b"
				( attribute "PN" "2"
					( Origin gPackager )
				)
				( objectStatus "C2R10.2" )
			)
			( pin "@baseboard_fab2_lib.baseboard_fab2(sch_1):page106_i147:a"
				( attribute "PN" "1"
					( Origin gPackager )
				)
				( objectStatus "C2R9.1" )
			)
			( pin "@baseboard_fab2_lib.baseboard_fab2(sch_1):page106_i147:b"
				( attribute "PN" "2"
					( Origin gPackager )
				)
				( objectStatus "C2R9.2" )
			)
			( pin "@baseboard_fab2_lib.baseboard_fab2(sch_1):page107_i207:a"
				( attribute "PN" "1"
					( Origin gPackager )
				)
				( objectStatus "C3P13.1" )
			)
			( pin "@baseboard_fab2_lib.baseboard_fab2(sch_1):page107_i207:b"
				( attribute "PN" "2"
					( Origin gPackager )
				)
				( objectStatus "C3P13.2" )
			)
			( pin "@baseboard_fab2_lib.baseboard_fab2(sch_1):page107_i208:a"
				( attribute "PN" "1"
					( Origin gPackager )
				)
				( objectStatus "C3P17.1" )
			)
			( pin "@baseboard_fab2_lib.baseboard_fab2(sch_1):page107_i208:b"
				( attribute "PN" "2"
					( Origin gPackager )
				)
				( objectStatus "C3P17.2" )
			)
			( pin "@baseboard_fab2_lib.baseboard_fab2(sch_1):page107_i212:a"
				( attribute "PN" "1"
					( Origin gPackager )
				)
				( objectStatus "C3P11.1" )
			)
			( pin "@baseboard_fab2_lib.baseboard_fab2(sch_1):page107_i212:b"
				( attribute "PN" "2"
					( Origin gPackager )
				)
				( objectStatus "C3P11.2" )
			)
			( pin "@baseboard_fab2_lib.baseboard_fab2(sch_1):page107_i215:a"
				( attribute "PN" "1"
					( Origin gPackager )
				)
				( objectStatus "C3P20.1" )
			)
			( pin "@baseboard_fab2_lib.baseboard_fab2(sch_1):page107_i215:b"
				( attribute "PN" "2"
					( Origin gPackager )
				)
				( objectStatus "C3P20.2" )
			)
			( pin "@baseboard_fab2_lib.baseboard_fab2(sch_1):page107_i216:a"
				( attribute "PN" "1"
					( Origin gPackager )
				)
				( objectStatus "C3P25.1" )
			)
			( pin "@baseboard_fab2_lib.baseboard_fab2(sch_1):page107_i216:b"
				( attribute "PN" "2"
					( Origin gPackager )
				)
				( objectStatus "C3P25.2" )
			)
			( pin "@baseboard_fab2_lib.baseboard_fab2(sch_1):page107_i219:a"
				( attribute "PN" "1"
					( Origin gPackager )
				)
				( objectStatus "C3P18.1" )
			)
			( pin "@baseboard_fab2_lib.baseboard_fab2(sch_1):page107_i219:b"
				( attribute "PN" "2"
					( Origin gPackager )
				)
				( objectStatus "C3P18.2" )
			)
			( pin "@baseboard_fab2_lib.baseboard_fab2(sch_1):page107_i223:a"
				( attribute "PN" "1"
					( Origin gPackager )
				)
				( objectStatus "C3P27.1" )
			)
			( pin "@baseboard_fab2_lib.baseboard_fab2(sch_1):page107_i223:b"
				( attribute "PN" "2"
					( Origin gPackager )
				)
				( objectStatus "C3P27.2" )
			)
			( pin "@baseboard_fab2_lib.baseboard_fab2(sch_1):page107_i226:a"
				( attribute "PN" "1"
					( Origin gPackager )
				)
				( objectStatus "C3P15.1" )
			)
			( pin "@baseboard_fab2_lib.baseboard_fab2(sch_1):page107_i226:b"
				( attribute "PN" "2"
					( Origin gPackager )
				)
				( objectStatus "C3P15.2" )
			)
			( pin "@baseboard_fab2_lib.baseboard_fab2(sch_1):page107_i229:a"
				( attribute "PN" "1"
					( Origin gPackager )
				)
				( objectStatus "C3P23.1" )
			)
			( pin "@baseboard_fab2_lib.baseboard_fab2(sch_1):page107_i229:b"
				( attribute "PN" "2"
					( Origin gPackager )
				)
				( objectStatus "C3P23.2" )
			)
			( pin "@baseboard_fab2_lib.baseboard_fab2(sch_1):page107_i232:a"
				( attribute "PN" "1"
					( Origin gPackager )
				)
				( objectStatus "C3P28.1" )
			)
			( pin "@baseboard_fab2_lib.baseboard_fab2(sch_1):page107_i232:b"
				( attribute "PN" "2"
					( Origin gPackager )
				)
				( objectStatus "C3P28.2" )
			)
			( pin "@baseboard_fab2_lib.baseboard_fab2(sch_1):page107_i234:a"
				( attribute "PN" "1"
					( Origin gPackager )
				)
				( objectStatus "C3P32.1" )
			)
			( pin "@baseboard_fab2_lib.baseboard_fab2(sch_1):page107_i234:b"
				( attribute "PN" "2"
					( Origin gPackager )
				)
				( objectStatus "C3P32.2" )
			)
			( pin "@baseboard_fab2_lib.baseboard_fab2(sch_1):page107_i235:a"
				( attribute "PN" "1"
					( Origin gPackager )
				)
				( objectStatus "C3P37.1" )
			)
			( pin "@baseboard_fab2_lib.baseboard_fab2(sch_1):page107_i235:b"
				( attribute "PN" "2"
					( Origin gPackager )
				)
				( objectStatus "C3P37.2" )
			)
			( pin "@baseboard_fab2_lib.baseboard_fab2(sch_1):page107_i240:a"
				( attribute "PN" "1"
					( Origin gPackager )
				)
				( objectStatus "C3P35.1" )
			)
			( pin "@baseboard_fab2_lib.baseboard_fab2(sch_1):page107_i240:b"
				( attribute "PN" "2"
					( Origin gPackager )
				)
				( objectStatus "C3P35.2" )
			)
			( pin "@baseboard_fab2_lib.baseboard_fab2(sch_1):page107_i241:a"
				( attribute "PN" "1"
					( Origin gPackager )
				)
				( objectStatus "C3P40.1" )
			)
			( pin "@baseboard_fab2_lib.baseboard_fab2(sch_1):page107_i241:b"
				( attribute "PN" "2"
					( Origin gPackager )
				)
				( objectStatus "C3P40.2" )
			)
			( pin "@baseboard_fab2_lib.baseboard_fab2(sch_1):page107_i245:a"
				( attribute "PN" "1"
					( Origin gPackager )
				)
				( objectStatus "C3P30.1" )
			)
			( pin "@baseboard_fab2_lib.baseboard_fab2(sch_1):page107_i245:b"
				( attribute "PN" "2"
					( Origin gPackager )
				)
				( objectStatus "C3P30.2" )
			)
			( pin "@baseboard_fab2_lib.baseboard_fab2(sch_1):page107_i248:a"
				( attribute "PN" "1"
					( Origin gPackager )
				)
				( objectStatus "C3P39.1" )
			)
			( pin "@baseboard_fab2_lib.baseboard_fab2(sch_1):page107_i248:b"
				( attribute "PN" "2"
					( Origin gPackager )
				)
				( objectStatus "C3P39.2" )
			)
			( pin "@baseboard_fab2_lib.baseboard_fab2(sch_1):page107_i257:a"
				( attribute "PN" "1"
					( Origin gPackager )
				)
				( objectStatus "C2U4.1" )
			)
			( pin "@baseboard_fab2_lib.baseboard_fab2(sch_1):page107_i257:b"
				( attribute "PN" "2"
					( Origin gPackager )
				)
				( objectStatus "C2U4.2" )
			)
			( pin "@baseboard_fab2_lib.baseboard_fab2(sch_1):page107_i260:a"
				( attribute "PN" "1"
					( Origin gPackager )
				)
				( objectStatus "C2U6.1" )
			)
			( pin "@baseboard_fab2_lib.baseboard_fab2(sch_1):page107_i260:b"
				( attribute "PN" "2"
					( Origin gPackager )
				)
				( objectStatus "C2U6.2" )
			)
			( pin "@baseboard_fab2_lib.baseboard_fab2(sch_1):page107_i264:a"
				( attribute "PN" "1"
					( Origin gPackager )
				)
				( objectStatus "C2U8.1" )
			)
			( pin "@baseboard_fab2_lib.baseboard_fab2(sch_1):page107_i264:b"
				( attribute "PN" "2"
					( Origin gPackager )
				)
				( objectStatus "C2U8.2" )
			)
			( pin "@baseboard_fab2_lib.baseboard_fab2(sch_1):page107_i265:a"
				( attribute "PN" "1"
					( Origin gPackager )
				)
				( objectStatus "C2U12.1" )
			)
			( pin "@baseboard_fab2_lib.baseboard_fab2(sch_1):page107_i265:b"
				( attribute "PN" "2"
					( Origin gPackager )
				)
				( objectStatus "C2U12.2" )
			)
			( pin "@baseboard_fab2_lib.baseboard_fab2(sch_1):page107_i267:a"
				( attribute "PN" "1"
					( Origin gPackager )
				)
				( objectStatus "C2U10.1" )
			)
			( pin "@baseboard_fab2_lib.baseboard_fab2(sch_1):page107_i267:b"
				( attribute "PN" "2"
					( Origin gPackager )
				)
				( objectStatus "C2U10.2" )
			)
			( pin "@baseboard_fab2_lib.baseboard_fab2(sch_1):page107_i272:a"
				( attribute "PN" "1"
					( Origin gPackager )
				)
				( objectStatus "C2U3.1" )
			)
			( pin "@baseboard_fab2_lib.baseboard_fab2(sch_1):page107_i272:b"
				( attribute "PN" "2"
					( Origin gPackager )
				)
				( objectStatus "C2U3.2" )
			)
			( pin "@baseboard_fab2_lib.baseboard_fab2(sch_1):page107_i274:a"
				( attribute "PN" "1"
					( Origin gPackager )
				)
				( objectStatus "C2U5.1" )
			)
			( pin "@baseboard_fab2_lib.baseboard_fab2(sch_1):page107_i274:b"
				( attribute "PN" "2"
					( Origin gPackager )
				)
				( objectStatus "C2U5.2" )
			)
			( pin "@baseboard_fab2_lib.baseboard_fab2(sch_1):page107_i277:a"
				( attribute "PN" "1"
					( Origin gPackager )
				)
				( objectStatus "C2U7.1" )
			)
			( pin "@baseboard_fab2_lib.baseboard_fab2(sch_1):page107_i277:b"
				( attribute "PN" "2"
					( Origin gPackager )
				)
				( objectStatus "C2U7.2" )
			)
			( pin "@baseboard_fab2_lib.baseboard_fab2(sch_1):page107_i278:a"
				( attribute "PN" "1"
					( Origin gPackager )
				)
				( objectStatus "C2U11.1" )
			)
			( pin "@baseboard_fab2_lib.baseboard_fab2(sch_1):page107_i278:b"
				( attribute "PN" "2"
					( Origin gPackager )
				)
				( objectStatus "C2U11.2" )
			)
			( pin "@baseboard_fab2_lib.baseboard_fab2(sch_1):page107_i279:a"
				( attribute "PN" "1"
					( Origin gPackager )
				)
				( objectStatus "C2U9.1" )
			)
			( pin "@baseboard_fab2_lib.baseboard_fab2(sch_1):page107_i279:b"
				( attribute "PN" "2"
					( Origin gPackager )
				)
				( objectStatus "C2U9.2" )
			)
			( pin "@baseboard_fab2_lib.baseboard_fab2(sch_1):page107_i286:a"
				( attribute "PN" "1"
					( Origin gPackager )
				)
				( objectStatus "C2U16.1" )
			)
			( pin "@baseboard_fab2_lib.baseboard_fab2(sch_1):page107_i286:b"
				( attribute "PN" "2"
					( Origin gPackager )
				)
				( objectStatus "C2U16.2" )
			)
			( pin "@baseboard_fab2_lib.baseboard_fab2(sch_1):page107_i287:a"
				( attribute "PN" "1"
					( Origin gPackager )
				)
				( objectStatus "C2U14.1" )
			)
			( pin "@baseboard_fab2_lib.baseboard_fab2(sch_1):page107_i287:b"
				( attribute "PN" "2"
					( Origin gPackager )
				)
				( objectStatus "C2U14.2" )
			)
			( pin "@baseboard_fab2_lib.baseboard_fab2(sch_1):page107_i294:a"
				( attribute "PN" "1"
					( Origin gPackager )
				)
				( objectStatus "C2U18.1" )
			)
			( pin "@baseboard_fab2_lib.baseboard_fab2(sch_1):page107_i294:b"
				( attribute "PN" "2"
					( Origin gPackager )
				)
				( objectStatus "C2U18.2" )
			)
			( pin "@baseboard_fab2_lib.baseboard_fab2(sch_1):page107_i296:a"
				( attribute "PN" "1"
					( Origin gPackager )
				)
				( objectStatus "C2U15.1" )
			)
			( pin "@baseboard_fab2_lib.baseboard_fab2(sch_1):page107_i296:b"
				( attribute "PN" "2"
					( Origin gPackager )
				)
				( objectStatus "C2U15.2" )
			)
			( pin "@baseboard_fab2_lib.baseboard_fab2(sch_1):page107_i297:a"
				( attribute "PN" "1"
					( Origin gPackager )
				)
				( objectStatus "C2U13.1" )
			)
			( pin "@baseboard_fab2_lib.baseboard_fab2(sch_1):page107_i297:b"
				( attribute "PN" "2"
					( Origin gPackager )
				)
				( objectStatus "C2U13.2" )
			)
			( pin "@baseboard_fab2_lib.baseboard_fab2(sch_1):page107_i300:a"
				( attribute "PN" "1"
					( Origin gPackager )
				)
				( objectStatus "C2U17.1" )
			)
			( pin "@baseboard_fab2_lib.baseboard_fab2(sch_1):page107_i300:b"
				( attribute "PN" "2"
					( Origin gPackager )
				)
				( objectStatus "C2U17.2" )
			)
			( pin "@baseboard_fab2_lib.baseboard_fab2(sch_1):page107_i489:a"
				( attribute "PN" "1"
					( Origin gPackager )
				)
				( objectStatus "C3P34.1" )
			)
			( pin "@baseboard_fab2_lib.baseboard_fab2(sch_1):page107_i489:b"
				( attribute "PN" "2"
					( Origin gPackager )
				)
				( objectStatus "C3P34.2" )
			)
			( pin "@baseboard_fab2_lib.baseboard_fab2(sch_1):page107_i497:a"
				( attribute "PN" "1"
					( Origin gPackager )
				)
				( objectStatus "R2U27.1" )
			)
			( pin "@baseboard_fab2_lib.baseboard_fab2(sch_1):page107_i497:b"
				( attribute "PN" "2"
					( Origin gPackager )
				)
				( objectStatus "R2U27.2" )
			)
			( pin "@baseboard_fab2_lib.baseboard_fab2(sch_1):page107_i488:a"
				( attribute "PN" "1"
					( Origin gPackager )
				)
				( objectStatus "C3P31.1" )
			)
			( pin "@baseboard_fab2_lib.baseboard_fab2(sch_1):page107_i488:b"
				( attribute "PN" "2"
					( Origin gPackager )
				)
				( objectStatus "C3P31.2" )
			)
			( pin "@baseboard_fab2_lib.baseboard_fab2(sch_1):page107_i487:a"
				( attribute "PN" "1"
					( Origin gPackager )
				)
				( objectStatus "C3P26.1" )
			)
			( pin "@baseboard_fab2_lib.baseboard_fab2(sch_1):page107_i487:b"
				( attribute "PN" "2"
					( Origin gPackager )
				)
				( objectStatus "C3P26.2" )
			)
			( pin "@baseboard_fab2_lib.baseboard_fab2(sch_1):page107_i486:a"
				( attribute "PN" "1"
					( Origin gPackager )
				)
				( objectStatus "C3P38.1" )
			)
			( pin "@baseboard_fab2_lib.baseboard_fab2(sch_1):page107_i486:b"
				( attribute "PN" "2"
					( Origin gPackager )
				)
				( objectStatus "C3P38.2" )
			)
			( pin "@baseboard_fab2_lib.baseboard_fab2(sch_1):page107_i496:a"
				( attribute "PN" "1"
					( Origin gPackager )
				)
				( objectStatus "R2U25.1" )
			)
			( pin "@baseboard_fab2_lib.baseboard_fab2(sch_1):page107_i496:b"
				( attribute "PN" "2"
					( Origin gPackager )
				)
				( objectStatus "R2U25.2" )
			)
			( pin "@baseboard_fab2_lib.baseboard_fab2(sch_1):page107_i495:a"
				( attribute "PN" "1"
					( Origin gPackager )
				)
				( objectStatus "R2U23.1" )
			)
			( pin "@baseboard_fab2_lib.baseboard_fab2(sch_1):page107_i495:b"
				( attribute "PN" "2"
					( Origin gPackager )
				)
				( objectStatus "R2U23.2" )
			)
			( pin "@baseboard_fab2_lib.baseboard_fab2(sch_1):page107_i494:a"
				( attribute "PN" "1"
					( Origin gPackager )
				)
				( objectStatus "R2U29.1" )
			)
			( pin "@baseboard_fab2_lib.baseboard_fab2(sch_1):page107_i494:b"
				( attribute "PN" "2"
					( Origin gPackager )
				)
				( objectStatus "R2U29.2" )
			)
			( pin "@baseboard_fab2_lib.baseboard_fab2(sch_1):page107_i485:a"
				( attribute "PN" "1"
					( Origin gPackager )
				)
				( objectStatus "C3P19.1" )
			)
			( pin "@baseboard_fab2_lib.baseboard_fab2(sch_1):page107_i485:b"
				( attribute "PN" "2"
					( Origin gPackager )
				)
				( objectStatus "C3P19.2" )
			)
			( pin "@baseboard_fab2_lib.baseboard_fab2(sch_1):page107_i484:a"
				( attribute "PN" "1"
					( Origin gPackager )
				)
				( objectStatus "C3P22.1" )
			)
			( pin "@baseboard_fab2_lib.baseboard_fab2(sch_1):page107_i484:b"
				( attribute "PN" "2"
					( Origin gPackager )
				)
				( objectStatus "C3P22.2" )
			)
			( pin "@baseboard_fab2_lib.baseboard_fab2(sch_1):page107_i483:a"
				( attribute "PN" "1"
					( Origin gPackager )
				)
				( objectStatus "C3P14.1" )
			)
			( pin "@baseboard_fab2_lib.baseboard_fab2(sch_1):page107_i483:b"
				( attribute "PN" "2"
					( Origin gPackager )
				)
				( objectStatus "C3P14.2" )
			)
			( pin "@baseboard_fab2_lib.baseboard_fab2(sch_1):page107_i493:a"
				( attribute "PN" "1"
					( Origin gPackager )
				)
				( objectStatus "R2U19.1" )
			)
			( pin "@baseboard_fab2_lib.baseboard_fab2(sch_1):page107_i493:b"
				( attribute "PN" "2"
					( Origin gPackager )
				)
				( objectStatus "R2U19.2" )
			)
			( pin "@baseboard_fab2_lib.baseboard_fab2(sch_1):page107_i492:a"
				( attribute "PN" "1"
					( Origin gPackager )
				)
				( objectStatus "R2U17.1" )
			)
			( pin "@baseboard_fab2_lib.baseboard_fab2(sch_1):page107_i492:b"
				( attribute "PN" "2"
					( Origin gPackager )
				)
				( objectStatus "R2U17.2" )
			)
			( pin "@baseboard_fab2_lib.baseboard_fab2(sch_1):page107_i482:a"
				( attribute "PN" "1"
					( Origin gPackager )
				)
				( objectStatus "C3P10.1" )
			)
			( pin "@baseboard_fab2_lib.baseboard_fab2(sch_1):page107_i482:b"
				( attribute "PN" "2"
					( Origin gPackager )
				)
				( objectStatus "C3P10.2" )
			)
			( pin "@baseboard_fab2_lib.baseboard_fab2(sch_1):page107_i491:a"
				( attribute "PN" "1"
					( Origin gPackager )
				)
				( objectStatus "R2U21.1" )
			)
			( pin "@baseboard_fab2_lib.baseboard_fab2(sch_1):page107_i491:b"
				( attribute "PN" "2"
					( Origin gPackager )
				)
				( objectStatus "R2U21.2" )
			)
			( pin "@baseboard_fab2_lib.baseboard_fab2(sch_1):page107_i490:a"
				( attribute "PN" "1"
					( Origin gPackager )
				)
				( objectStatus "R2U15.1" )
			)
			( pin "@baseboard_fab2_lib.baseboard_fab2(sch_1):page107_i490:b"
				( attribute "PN" "2"
					( Origin gPackager )
				)
				( objectStatus "R2U15.2" )
			)
			( pin "@baseboard_fab2_lib.baseboard_fab2(sch_1):page211_i96:a"
				( attribute "PN" "1"
					( Origin gPackager )
				)
				( objectStatus "RF13.1" )
			)
			( pin "@baseboard_fab2_lib.baseboard_fab2(sch_1):page211_i96:b"
				( attribute "PN" "2"
					( Origin gPackager )
				)
				( objectStatus "RF13.2" )
			)
			( pin "@baseboard_fab2_lib.baseboard_fab2(sch_1):page221_i2:a"
				( attribute "PN" "1"
					( Origin gPackager )
				)
				( objectStatus "C4G23.1" )
			)
			( pin "@baseboard_fab2_lib.baseboard_fab2(sch_1):page221_i2:b"
				( attribute "PN" "2"
					( Origin gPackager )
				)
				( objectStatus "C4G23.2" )
			)
			( pin "@baseboard_fab2_lib.baseboard_fab2(sch_1):page108_i1:a"
				( attribute "PN" "1"
					( Origin gPackager )
				)
				( objectStatus "C2U20.1" )
			)
			( pin "@baseboard_fab2_lib.baseboard_fab2(sch_1):page108_i1:b"
				( attribute "PN" "2"
					( Origin gPackager )
				)
				( objectStatus "C2U20.2" )
			)
			( pin "@baseboard_fab2_lib.baseboard_fab2(sch_1):page108_i2:a"
				( attribute "PN" "1"
					( Origin gPackager )
				)
				( objectStatus "C2U24.1" )
			)
			( pin "@baseboard_fab2_lib.baseboard_fab2(sch_1):page108_i2:b"
				( attribute "PN" "2"
					( Origin gPackager )
				)
				( objectStatus "C2U24.2" )
			)
			( pin "@baseboard_fab2_lib.baseboard_fab2(sch_1):page108_i5:a"
				( attribute "PN" "1"
					( Origin gPackager )
				)
				( objectStatus "C2U21.1" )
			)
			( pin "@baseboard_fab2_lib.baseboard_fab2(sch_1):page108_i5:b"
				( attribute "PN" "2"
					( Origin gPackager )
				)
				( objectStatus "C2U21.2" )
			)
			( pin "@baseboard_fab2_lib.baseboard_fab2(sch_1):page108_i7:a"
				( attribute "PN" "1"
					( Origin gPackager )
				)
				( objectStatus "C2U25.1" )
			)
			( pin "@baseboard_fab2_lib.baseboard_fab2(sch_1):page108_i7:b"
				( attribute "PN" "2"
					( Origin gPackager )
				)
				( objectStatus "C2U25.2" )
			)
			( pin "@baseboard_fab2_lib.baseboard_fab2(sch_1):page108_i173:a"
				( attribute "PN" "1"
					( Origin gPackager )
				)
				( objectStatus "R2U37.1" )
			)
			( pin "@baseboard_fab2_lib.baseboard_fab2(sch_1):page108_i173:b"
				( attribute "PN" "2"
					( Origin gPackager )
				)
				( objectStatus "R2U37.2" )
			)
			( pin "@baseboard_fab2_lib.baseboard_fab2(sch_1):page108_i258:io1"
				( attribute "PN" "1"
					( Origin gPackager )
				)
				( objectStatus "J8G1.1" )
			)
			( pin "@baseboard_fab2_lib.baseboard_fab2(sch_1):page108_i258:io2"
				( attribute "PN" "2"
					( Origin gPackager )
				)
				( objectStatus "J8G1.2" )
			)
			( pin "@baseboard_fab2_lib.baseboard_fab2(sch_1):page108_i258:io3"
				( attribute "PN" "3"
					( Origin gPackager )
				)
				( objectStatus "J8G1.3" )
			)
			( pin "@baseboard_fab2_lib.baseboard_fab2(sch_1):page108_i258:io4"
				( attribute "PN" "4"
					( Origin gPackager )
				)
				( objectStatus "J8G1.4" )
			)
			( pin "@baseboard_fab2_lib.baseboard_fab2(sch_1):page108_i258:io5"
				( attribute "PN" "5"
					( Origin gPackager )
				)
				( objectStatus "J8G1.5" )
			)
			( pin "@baseboard_fab2_lib.baseboard_fab2(sch_1):page108_i258:io6"
				( attribute "PN" "6"
					( Origin gPackager )
				)
				( objectStatus "J8G1.6" )
			)
			( pin "@baseboard_fab2_lib.baseboard_fab2(sch_1):page108_i258:io7"
				( attribute "PN" "7"
					( Origin gPackager )
				)
				( objectStatus "J8G1.7" )
			)
			( pin "@baseboard_fab2_lib.baseboard_fab2(sch_1):page108_i258:io8"
				( attribute "PN" "8"
					( Origin gPackager )
				)
				( objectStatus "J8G1.8" )
			)
			( pin "@baseboard_fab2_lib.baseboard_fab2(sch_1):page108_i258:io9"
				( attribute "PN" "9"
					( Origin gPackager )
				)
				( objectStatus "J8G1.9" )
			)
			( pin "@baseboard_fab2_lib.baseboard_fab2(sch_1):page108_i258:io10"
				( attribute "PN" "10"
					( Origin gPackager )
				)
				( objectStatus "J8G1.10" )
			)
			( pin "@baseboard_fab2_lib.baseboard_fab2(sch_1):page108_i258:io11"
				( attribute "PN" "11"
					( Origin gPackager )
				)
				( objectStatus "J8G1.11" )
			)
			( pin "@baseboard_fab2_lib.baseboard_fab2(sch_1):page108_i258:io12"
				( attribute "PN" "12"
					( Origin gPackager )
				)
				( objectStatus "J8G1.12" )
			)
			( pin "@baseboard_fab2_lib.baseboard_fab2(sch_1):page108_i258:io13"
				( attribute "PN" "13"
					( Origin gPackager )
				)
				( objectStatus "J8G1.13" )
			)
			( pin "@baseboard_fab2_lib.baseboard_fab2(sch_1):page108_i258:io14"
				( attribute "PN" "14"
					( Origin gPackager )
				)
				( objectStatus "J8G1.14" )
			)
			( pin "@baseboard_fab2_lib.baseboard_fab2(sch_1):page108_i258:io15"
				( attribute "PN" "15"
					( Origin gPackager )
				)
				( objectStatus "J8G1.15" )
			)
			( pin "@baseboard_fab2_lib.baseboard_fab2(sch_1):page108_i258:io16"
				( attribute "PN" "16"
					( Origin gPackager )
				)
				( objectStatus "J8G1.16" )
			)
			( pin "@baseboard_fab2_lib.baseboard_fab2(sch_1):page108_i258:io17"
				( attribute "PN" "17"
					( Origin gPackager )
				)
				( objectStatus "J8G1.17" )
			)
			( pin "@baseboard_fab2_lib.baseboard_fab2(sch_1):page108_i258:io18"
				( attribute "PN" "18"
					( Origin gPackager )
				)
				( objectStatus "J8G1.18" )
			)
			( pin "@baseboard_fab2_lib.baseboard_fab2(sch_1):page108_i258:io19"
				( attribute "PN" "19"
					( Origin gPackager )
				)
				( objectStatus "J8G1.19" )
			)
			( pin "@baseboard_fab2_lib.baseboard_fab2(sch_1):page108_i258:io20"
				( attribute "PN" "20"
					( Origin gPackager )
				)
				( objectStatus "J8G1.20" )
			)
			( pin "@baseboard_fab2_lib.baseboard_fab2(sch_1):page108_i258:io21"
				( attribute "PN" "21"
					( Origin gPackager )
				)
				( objectStatus "J8G1.21" )
			)
			( pin "@baseboard_fab2_lib.baseboard_fab2(sch_1):page108_i258:io22"
				( attribute "PN" "22"
					( Origin gPackager )
				)
				( objectStatus "J8G1.22" )
			)
			( pin "@baseboard_fab2_lib.baseboard_fab2(sch_1):page108_i258:io23"
				( attribute "PN" "23"
					( Origin gPackager )
				)
				( objectStatus "J8G1.23" )
			)
			( pin "@baseboard_fab2_lib.baseboard_fab2(sch_1):page108_i258:io24"
				( attribute "PN" "24"
					( Origin gPackager )
				)
				( objectStatus "J8G1.24" )
			)
			( pin "@baseboard_fab2_lib.baseboard_fab2(sch_1):page108_i258:io25"
				( attribute "PN" "25"
					( Origin gPackager )
				)
				( objectStatus "J8G1.25" )
			)
			( pin "@baseboard_fab2_lib.baseboard_fab2(sch_1):page108_i258:io26"
				( attribute "PN" "26"
					( Origin gPackager )
				)
				( objectStatus "J8G1.26" )
			)
			( pin "@baseboard_fab2_lib.baseboard_fab2(sch_1):page108_i258:io27"
				( attribute "PN" "27"
					( Origin gPackager )
				)
				( objectStatus "J8G1.27" )
			)
			( pin "@baseboard_fab2_lib.baseboard_fab2(sch_1):page108_i258:io28"
				( attribute "PN" "28"
					( Origin gPackager )
				)
				( objectStatus "J8G1.28" )
			)
			( pin "@baseboard_fab2_lib.baseboard_fab2(sch_1):page108_i258:io29"
				( attribute "PN" "29"
					( Origin gPackager )
				)
				( objectStatus "J8G1.29" )
			)
			( pin "@baseboard_fab2_lib.baseboard_fab2(sch_1):page108_i258:io30"
				( attribute "PN" "30"
					( Origin gPackager )
				)
				( objectStatus "J8G1.30" )
			)
			( pin "@baseboard_fab2_lib.baseboard_fab2(sch_1):page108_i258:io31"
				( attribute "PN" "31"
					( Origin gPackager )
				)
				( objectStatus "J8G1.31" )
			)
			( pin "@baseboard_fab2_lib.baseboard_fab2(sch_1):page108_i258:io32"
				( attribute "PN" "32"
					( Origin gPackager )
				)
				( objectStatus "J8G1.32" )
			)
			( pin "@baseboard_fab2_lib.baseboard_fab2(sch_1):page108_i258:io33"
				( attribute "PN" "33"
					( Origin gPackager )
				)
				( objectStatus "J8G1.33" )
			)
			( pin "@baseboard_fab2_lib.baseboard_fab2(sch_1):page108_i258:io34"
				( attribute "PN" "34"
					( Origin gPackager )
				)
				( objectStatus "J8G1.34" )
			)
			( pin "@baseboard_fab2_lib.baseboard_fab2(sch_1):page108_i258:io35"
				( attribute "PN" "35"
					( Origin gPackager )
				)
				( objectStatus "J8G1.35" )
			)
			( pin "@baseboard_fab2_lib.baseboard_fab2(sch_1):page108_i258:io36"
				( attribute "PN" "36"
					( Origin gPackager )
				)
				( objectStatus "J8G1.36" )
			)
			( pin "@baseboard_fab2_lib.baseboard_fab2(sch_1):page108_i258:io37"
				( attribute "PN" "37"
					( Origin gPackager )
				)
				( objectStatus "J8G1.37" )
			)
			( pin "@baseboard_fab2_lib.baseboard_fab2(sch_1):page108_i258:io38"
				( attribute "PN" "38"
					( Origin gPackager )
				)
				( objectStatus "J8G1.38" )
			)
			( pin "@baseboard_fab2_lib.baseboard_fab2(sch_1):page108_i258:io39"
				( attribute "PN" "39"
					( Origin gPackager )
				)
				( objectStatus "J8G1.39" )
			)
			( pin "@baseboard_fab2_lib.baseboard_fab2(sch_1):page108_i258:io40"
				( attribute "PN" "40"
					( Origin gPackager )
				)
				( objectStatus "J8G1.40" )
			)
			( pin "@baseboard_fab2_lib.baseboard_fab2(sch_1):page108_i258:io41"
				( attribute "PN" "41"
					( Origin gPackager )
				)
				( objectStatus "J8G1.41" )
			)
			( pin "@baseboard_fab2_lib.baseboard_fab2(sch_1):page108_i258:io42"
				( attribute "PN" "42"
					( Origin gPackager )
				)
				( objectStatus "J8G1.42" )
			)
			( pin "@baseboard_fab2_lib.baseboard_fab2(sch_1):page108_i258:io43"
				( attribute "PN" "43"
					( Origin gPackager )
				)
				( objectStatus "J8G1.43" )
			)
			( pin "@baseboard_fab2_lib.baseboard_fab2(sch_1):page108_i258:io44"
				( attribute "PN" "44"
					( Origin gPackager )
				)
				( objectStatus "J8G1.44" )
			)
			( pin "@baseboard_fab2_lib.baseboard_fab2(sch_1):page108_i258:io45"
				( attribute "PN" "45"
					( Origin gPackager )
				)
				( objectStatus "J8G1.45" )
			)
			( pin "@baseboard_fab2_lib.baseboard_fab2(sch_1):page108_i258:io46"
				( attribute "PN" "46"
					( Origin gPackager )
				)
				( objectStatus "J8G1.46" )
			)
			( pin "@baseboard_fab2_lib.baseboard_fab2(sch_1):page108_i258:io47"
				( attribute "PN" "47"
					( Origin gPackager )
				)
				( objectStatus "J8G1.47" )
			)
			( pin "@baseboard_fab2_lib.baseboard_fab2(sch_1):page108_i258:io48"
				( attribute "PN" "48"
					( Origin gPackager )
				)
				( objectStatus "J8G1.48" )
			)
			( pin "@baseboard_fab2_lib.baseboard_fab2(sch_1):page108_i258:io49"
				( attribute "PN" "49"
					( Origin gPackager )
				)
				( objectStatus "J8G1.49" )
			)
			( pin "@baseboard_fab2_lib.baseboard_fab2(sch_1):page108_i258:io50"
				( attribute "PN" "50"
					( Origin gPackager )
				)
				( objectStatus "J8G1.50" )
			)
			( pin "@baseboard_fab2_lib.baseboard_fab2(sch_1):page108_i258:io51"
				( attribute "PN" "51"
					( Origin gPackager )
				)
				( objectStatus "J8G1.51" )
			)
			( pin "@baseboard_fab2_lib.baseboard_fab2(sch_1):page108_i258:io52"
				( attribute "PN" "52"
					( Origin gPackager )
				)
				( objectStatus "J8G1.52" )
			)
			( pin "@baseboard_fab2_lib.baseboard_fab2(sch_1):page108_i258:io53"
				( attribute "PN" "53"
					( Origin gPackager )
				)
				( objectStatus "J8G1.53" )
			)
			( pin "@baseboard_fab2_lib.baseboard_fab2(sch_1):page108_i258:io54"
				( attribute "PN" "54"
					( Origin gPackager )
				)
				( objectStatus "J8G1.54" )
			)
			( pin "@baseboard_fab2_lib.baseboard_fab2(sch_1):page108_i258:io55"
				( attribute "PN" "55"
					( Origin gPackager )
				)
				( objectStatus "J8G1.55" )
			)
			( pin "@baseboard_fab2_lib.baseboard_fab2(sch_1):page108_i258:io56"
				( attribute "PN" "56"
					( Origin gPackager )
				)
				( objectStatus "J8G1.56" )
			)
			( pin "@baseboard_fab2_lib.baseboard_fab2(sch_1):page108_i258:io57"
				( attribute "PN" "57"
					( Origin gPackager )
				)
				( objectStatus "J8G1.57" )
			)
			( pin "@baseboard_fab2_lib.baseboard_fab2(sch_1):page108_i258:io58"
				( attribute "PN" "58"
					( Origin gPackager )
				)
				( objectStatus "J8G1.58" )
			)
			( pin "@baseboard_fab2_lib.baseboard_fab2(sch_1):page108_i258:io59"
				( attribute "PN" "59"
					( Origin gPackager )
				)
				( objectStatus "J8G1.59" )
			)
			( pin "@baseboard_fab2_lib.baseboard_fab2(sch_1):page108_i258:io60"
				( attribute "PN" "60"
					( Origin gPackager )
				)
				( objectStatus "J8G1.60" )
			)
			( pin "@baseboard_fab2_lib.baseboard_fab2(sch_1):page108_i258:io61"
				( attribute "PN" "61"
					( Origin gPackager )
				)
				( objectStatus "J8G1.61" )
			)
			( pin "@baseboard_fab2_lib.baseboard_fab2(sch_1):page108_i258:io62"
				( attribute "PN" "62"
					( Origin gPackager )
				)
				( objectStatus "J8G1.62" )
			)
			( pin "@baseboard_fab2_lib.baseboard_fab2(sch_1):page108_i258:io63"
				( attribute "PN" "63"
					( Origin gPackager )
				)
				( objectStatus "J8G1.63" )
			)
			( pin "@baseboard_fab2_lib.baseboard_fab2(sch_1):page108_i258:io64"
				( attribute "PN" "64"
					( Origin gPackager )
				)
				( objectStatus "J8G1.64" )
			)
			( pin "@baseboard_fab2_lib.baseboard_fab2(sch_1):page108_i258:io65"
				( attribute "PN" "65"
					( Origin gPackager )
				)
				( objectStatus "J8G1.65" )
			)
			( pin "@baseboard_fab2_lib.baseboard_fab2(sch_1):page108_i258:io66"
				( attribute "PN" "66"
					( Origin gPackager )
				)
				( objectStatus "J8G1.66" )
			)
			( pin "@baseboard_fab2_lib.baseboard_fab2(sch_1):page108_i258:io67"
				( attribute "PN" "67"
					( Origin gPackager )
				)
				( objectStatus "J8G1.67" )
			)
			( pin "@baseboard_fab2_lib.baseboard_fab2(sch_1):page108_i258:io68"
				( attribute "PN" "68"
					( Origin gPackager )
				)
				( objectStatus "J8G1.68" )
			)
			( pin "@baseboard_fab2_lib.baseboard_fab2(sch_1):page108_i258:io69"
				( attribute "PN" "69"
					( Origin gPackager )
				)
				( objectStatus "J8G1.69" )
			)
			( pin "@baseboard_fab2_lib.baseboard_fab2(sch_1):page108_i258:io70"
				( attribute "PN" "70"
					( Origin gPackager )
				)
				( objectStatus "J8G1.70" )
			)
			( pin "@baseboard_fab2_lib.baseboard_fab2(sch_1):page108_i258:io71"
				( attribute "PN" "71"
					( Origin gPackager )
				)
				( objectStatus "J8G1.71" )
			)
			( pin "@baseboard_fab2_lib.baseboard_fab2(sch_1):page108_i258:io72"
				( attribute "PN" "72"
					( Origin gPackager )
				)
				( objectStatus "J8G1.72" )
			)
			( pin "@baseboard_fab2_lib.baseboard_fab2(sch_1):page108_i258:io73"
				( attribute "PN" "73"
					( Origin gPackager )
				)
				( objectStatus "J8G1.73" )
			)
			( pin "@baseboard_fab2_lib.baseboard_fab2(sch_1):page108_i258:io74"
				( attribute "PN" "74"
					( Origin gPackager )
				)
				( objectStatus "J8G1.74" )
			)
			( pin "@baseboard_fab2_lib.baseboard_fab2(sch_1):page108_i258:io75"
				( attribute "PN" "75"
					( Origin gPackager )
				)
				( objectStatus "J8G1.75" )
			)
			( pin "@baseboard_fab2_lib.baseboard_fab2(sch_1):page108_i258:io76"
				( attribute "PN" "76"
					( Origin gPackager )
				)
				( objectStatus "J8G1.76" )
			)
			( pin "@baseboard_fab2_lib.baseboard_fab2(sch_1):page108_i258:io77"
				( attribute "PN" "77"
					( Origin gPackager )
				)
				( objectStatus "J8G1.77" )
			)
			( pin "@baseboard_fab2_lib.baseboard_fab2(sch_1):page108_i258:io78"
				( attribute "PN" "78"
					( Origin gPackager )
				)
				( objectStatus "J8G1.78" )
			)
			( pin "@baseboard_fab2_lib.baseboard_fab2(sch_1):page108_i258:io79"
				( attribute "PN" "79"
					( Origin gPackager )
				)
				( objectStatus "J8G1.79" )
			)
			( pin "@baseboard_fab2_lib.baseboard_fab2(sch_1):page108_i258:io80"
				( attribute "PN" "80"
					( Origin gPackager )
				)
				( objectStatus "J8G1.80" )
			)
			( pin "@baseboard_fab2_lib.baseboard_fab2(sch_1):page108_i258:io81"
				( attribute "PN" "81"
					( Origin gPackager )
				)
				( objectStatus "J8G1.81" )
			)
			( pin "@baseboard_fab2_lib.baseboard_fab2(sch_1):page108_i258:io82"
				( attribute "PN" "82"
					( Origin gPackager )
				)
				( objectStatus "J8G1.82" )
			)
			( pin "@baseboard_fab2_lib.baseboard_fab2(sch_1):page108_i258:io83"
				( attribute "PN" "83"
					( Origin gPackager )
				)
				( objectStatus "J8G1.83" )
			)
			( pin "@baseboard_fab2_lib.baseboard_fab2(sch_1):page108_i258:io84"
				( attribute "PN" "84"
					( Origin gPackager )
				)
				( objectStatus "J8G1.84" )
			)
			( pin "@baseboard_fab2_lib.baseboard_fab2(sch_1):page108_i258:io85"
				( attribute "PN" "85"
					( Origin gPackager )
				)
				( objectStatus "J8G1.85" )
			)
			( pin "@baseboard_fab2_lib.baseboard_fab2(sch_1):page108_i258:io86"
				( attribute "PN" "86"
					( Origin gPackager )
				)
				( objectStatus "J8G1.86" )
			)
			( pin "@baseboard_fab2_lib.baseboard_fab2(sch_1):page108_i258:io87"
				( attribute "PN" "87"
					( Origin gPackager )
				)
				( objectStatus "J8G1.87" )
			)
			( pin "@baseboard_fab2_lib.baseboard_fab2(sch_1):page108_i258:io88"
				( attribute "PN" "88"
					( Origin gPackager )
				)
				( objectStatus "J8G1.88" )
			)
			( pin "@baseboard_fab2_lib.baseboard_fab2(sch_1):page108_i258:io89"
				( attribute "PN" "89"
					( Origin gPackager )
				)
				( objectStatus "J8G1.89" )
			)
			( pin "@baseboard_fab2_lib.baseboard_fab2(sch_1):page108_i258:io90"
				( attribute "PN" "90"
					( Origin gPackager )
				)
				( objectStatus "J8G1.90" )
			)
			( pin "@baseboard_fab2_lib.baseboard_fab2(sch_1):page108_i258:io91"
				( attribute "PN" "91"
					( Origin gPackager )
				)
				( objectStatus "J8G1.91" )
			)
			( pin "@baseboard_fab2_lib.baseboard_fab2(sch_1):page108_i258:io92"
				( attribute "PN" "92"
					( Origin gPackager )
				)
				( objectStatus "J8G1.92" )
			)
			( pin "@baseboard_fab2_lib.baseboard_fab2(sch_1):page108_i258:io93"
				( attribute "PN" "93"
					( Origin gPackager )
				)
				( objectStatus "J8G1.93" )
			)
			( pin "@baseboard_fab2_lib.baseboard_fab2(sch_1):page108_i258:io94"
				( attribute "PN" "94"
					( Origin gPackager )
				)
				( objectStatus "J8G1.94" )
			)
			( pin "@baseboard_fab2_lib.baseboard_fab2(sch_1):page108_i258:io95"
				( attribute "PN" "95"
					( Origin gPackager )
				)
				( objectStatus "J8G1.95" )
			)
			( pin "@baseboard_fab2_lib.baseboard_fab2(sch_1):page108_i258:io96"
				( attribute "PN" "96"
					( Origin gPackager )
				)
				( objectStatus "J8G1.96" )
			)
			( pin "@baseboard_fab2_lib.baseboard_fab2(sch_1):page108_i258:io97"
				( attribute "PN" "97"
					( Origin gPackager )
				)
				( objectStatus "J8G1.97" )
			)
			( pin "@baseboard_fab2_lib.baseboard_fab2(sch_1):page108_i258:io98"
				( attribute "PN" "98"
					( Origin gPackager )
				)
				( objectStatus "J8G1.98" )
			)
			( pin "@baseboard_fab2_lib.baseboard_fab2(sch_1):page108_i258:io99"
				( attribute "PN" "99"
					( Origin gPackager )
				)
				( objectStatus "J8G1.99" )
			)
			( pin "@baseboard_fab2_lib.baseboard_fab2(sch_1):page108_i258:io100"
				( attribute "PN" "100"
					( Origin gPackager )
				)
				( objectStatus "J8G1.100" )
			)
			( pin "@baseboard_fab2_lib.baseboard_fab2(sch_1):page108_i258:mh1"
				( attribute "PN" "MH1"
					( Origin gPackager )
				)
				( objectStatus "J8G1.MH1" )
			)
			( pin "@baseboard_fab2_lib.baseboard_fab2(sch_1):page108_i258:mh2"
				( attribute "PN" "MH2"
					( Origin gPackager )
				)
				( objectStatus "J8G1.MH2" )
			)
			( pin "@baseboard_fab2_lib.baseboard_fab2(sch_1):page108_i315:a"
				( attribute "PN" "1"
					( Origin gPackager )
				)
				( objectStatus "C2U23.1" )
			)
			( pin "@baseboard_fab2_lib.baseboard_fab2(sch_1):page108_i315:b"
				( attribute "PN" "2"
					( Origin gPackager )
				)
				( objectStatus "C2U23.2" )
			)
			( pin "@baseboard_fab2_lib.baseboard_fab2(sch_1):page108_i318:a"
				( attribute "PN" "1"
					( Origin gPackager )
				)
				( objectStatus "C2U22.1" )
			)
			( pin "@baseboard_fab2_lib.baseboard_fab2(sch_1):page108_i318:b"
				( attribute "PN" "2"
					( Origin gPackager )
				)
				( objectStatus "C2U22.2" )
			)
			( pin "@baseboard_fab2_lib.baseboard_fab2(sch_1):page108_i330:a"
				( attribute "PN" "1"
					( Origin gPackager )
				)
				( objectStatus "R2U31.1" )
			)
			( pin "@baseboard_fab2_lib.baseboard_fab2(sch_1):page108_i330:b"
				( attribute "PN" "2"
					( Origin gPackager )
				)
				( objectStatus "R2U31.2" )
			)
			( pin "@baseboard_fab2_lib.baseboard_fab2(sch_1):page108_i339:a"
				( attribute "PN" "1"
					( Origin gPackager )
				)
				( objectStatus "R2U32.1" )
			)
			( pin "@baseboard_fab2_lib.baseboard_fab2(sch_1):page108_i339:b"
				( attribute "PN" "2"
					( Origin gPackager )
				)
				( objectStatus "R2U32.2" )
			)
			( pin "@baseboard_fab2_lib.baseboard_fab2(sch_1):page108_i341:a"
				( attribute "PN" "1"
					( Origin gPackager )
				)
				( objectStatus "R7E22.1" )
			)
			( pin "@baseboard_fab2_lib.baseboard_fab2(sch_1):page108_i341:b"
				( attribute "PN" "2"
					( Origin gPackager )
				)
				( objectStatus "R7E22.2" )
			)
			( pin "@baseboard_fab2_lib.baseboard_fab2(sch_1):page108_i343:a"
				( attribute "PN" "1"
					( Origin gPackager )
				)
				( objectStatus "R7E21.1" )
			)
			( pin "@baseboard_fab2_lib.baseboard_fab2(sch_1):page108_i343:b"
				( attribute "PN" "2"
					( Origin gPackager )
				)
				( objectStatus "R7E21.2" )
			)
			( pin "@baseboard_fab2_lib.baseboard_fab2(sch_1):page111_i6:a"
				( attribute "PN" "1"
					( Origin gPackager )
				)
				( objectStatus "R1L13.1" )
			)
			( pin "@baseboard_fab2_lib.baseboard_fab2(sch_1):page111_i6:b"
				( attribute "PN" "2"
					( Origin gPackager )
				)
				( objectStatus "R1L13.2" )
			)
			( pin "@baseboard_fab2_lib.baseboard_fab2(sch_1):page111_i10:a"
				( attribute "PN" "1"
					( Origin gPackager )
				)
				( objectStatus "C9A2.1" )
			)
			( pin "@baseboard_fab2_lib.baseboard_fab2(sch_1):page111_i10:b"
				( attribute "PN" "2"
					( Origin gPackager )
				)
				( objectStatus "C9A2.2" )
			)
			( pin "@baseboard_fab2_lib.baseboard_fab2(sch_1):page111_i11:a"
				( attribute "PN" "1"
					( Origin gPackager )
				)
				( objectStatus "R9A14.1" )
			)
			( pin "@baseboard_fab2_lib.baseboard_fab2(sch_1):page111_i11:b"
				( attribute "PN" "2"
					( Origin gPackager )
				)
				( objectStatus "R9A14.2" )
			)
			( pin "@baseboard_fab2_lib.baseboard_fab2(sch_1):page111_i12:a"
				( attribute "PN" "1"
					( Origin gPackager )
				)
				( objectStatus "C9A5.1" )
			)
			( pin "@baseboard_fab2_lib.baseboard_fab2(sch_1):page111_i12:b"
				( attribute "PN" "2"
					( Origin gPackager )
				)
				( objectStatus "C9A5.2" )
			)
			( pin "@baseboard_fab2_lib.baseboard_fab2(sch_1):page111_i13:a"
				( attribute "PN" "1"
					( Origin gPackager )
				)
				( objectStatus "R1L23.1" )
			)
			( pin "@baseboard_fab2_lib.baseboard_fab2(sch_1):page111_i13:b"
				( attribute "PN" "2"
					( Origin gPackager )
				)
				( objectStatus "R1L23.2" )
			)
			( pin "@baseboard_fab2_lib.baseboard_fab2(sch_1):page111_i14:a"
				( attribute "PN" "1"
					( Origin gPackager )
				)
				( objectStatus "C1L8.1" )
			)
			( pin "@baseboard_fab2_lib.baseboard_fab2(sch_1):page111_i14:b"
				( attribute "PN" "2"
					( Origin gPackager )
				)
				( objectStatus "C1L8.2" )
			)
			( pin "@baseboard_fab2_lib.baseboard_fab2(sch_1):page111_i25:a"
				( attribute "PN" "1"
					( Origin gPackager )
				)
				( objectStatus "C9A6.1" )
			)
			( pin "@baseboard_fab2_lib.baseboard_fab2(sch_1):page111_i25:b"
				( attribute "PN" "2"
					( Origin gPackager )
				)
				( objectStatus "C9A6.2" )
			)
			( pin "@baseboard_fab2_lib.baseboard_fab2(sch_1):page111_i26:io1"
				( attribute "PN" "1"
					( Origin gPackager )
				)
				( objectStatus "J9A3.1" )
			)
			( pin "@baseboard_fab2_lib.baseboard_fab2(sch_1):page111_i26:io2"
				( attribute "PN" "2"
					( Origin gPackager )
				)
				( objectStatus "J9A3.2" )
			)
			( pin "@baseboard_fab2_lib.baseboard_fab2(sch_1):page111_i26:io3"
				( attribute "PN" "3"
					( Origin gPackager )
				)
				( objectStatus "J9A3.3" )
			)
			( pin "@baseboard_fab2_lib.baseboard_fab2(sch_1):page111_i26:io4"
				( attribute "PN" "4"
					( Origin gPackager )
				)
				( objectStatus "J9A3.4" )
			)
			( pin "@baseboard_fab2_lib.baseboard_fab2(sch_1):page111_i26:io5"
				( attribute "PN" "5"
					( Origin gPackager )
				)
				( objectStatus "J9A3.5" )
			)
			( pin "@baseboard_fab2_lib.baseboard_fab2(sch_1):page111_i26:io6"
				( attribute "PN" "6"
					( Origin gPackager )
				)
				( objectStatus "J9A3.6" )
			)
			( pin "@baseboard_fab2_lib.baseboard_fab2(sch_1):page111_i26:io7"
				( attribute "PN" "7"
					( Origin gPackager )
				)
				( objectStatus "J9A3.7" )
			)
			( pin "@baseboard_fab2_lib.baseboard_fab2(sch_1):page111_i26:io8"
				( attribute "PN" "8"
					( Origin gPackager )
				)
				( objectStatus "J9A3.8" )
			)
			( pin "@baseboard_fab2_lib.baseboard_fab2(sch_1):page111_i26:io9"
				( attribute "PN" "9"
					( Origin gPackager )
				)
				( objectStatus "J9A3.9" )
			)
			( pin "@baseboard_fab2_lib.baseboard_fab2(sch_1):page111_i26:io10"
				( attribute "PN" "10"
					( Origin gPackager )
				)
				( objectStatus "J9A3.10" )
			)
			( pin "@baseboard_fab2_lib.baseboard_fab2(sch_1):page111_i26:io11"
				( attribute "PN" "11"
					( Origin gPackager )
				)
				( objectStatus "J9A3.11" )
			)
			( pin "@baseboard_fab2_lib.baseboard_fab2(sch_1):page111_i26:io12"
				( attribute "PN" "12"
					( Origin gPackager )
				)
				( objectStatus "J9A3.12" )
			)
			( pin "@baseboard_fab2_lib.baseboard_fab2(sch_1):page111_i26:io13"
				( attribute "PN" "13"
					( Origin gPackager )
				)
				( objectStatus "J9A3.13" )
			)
			( pin "@baseboard_fab2_lib.baseboard_fab2(sch_1):page111_i26:io14"
				( attribute "PN" "14"
					( Origin gPackager )
				)
				( objectStatus "J9A3.14" )
			)
			( pin "@baseboard_fab2_lib.baseboard_fab2(sch_1):page111_i26:io15"
				( attribute "PN" "15"
					( Origin gPackager )
				)
				( objectStatus "J9A3.15" )
			)
			( pin "@baseboard_fab2_lib.baseboard_fab2(sch_1):page111_i26:io16"
				( attribute "PN" "16"
					( Origin gPackager )
				)
				( objectStatus "J9A3.16" )
			)
			( pin "@baseboard_fab2_lib.baseboard_fab2(sch_1):page111_i26:io17"
				( attribute "PN" "17"
					( Origin gPackager )
				)
				( objectStatus "J9A3.17" )
			)
			( pin "@baseboard_fab2_lib.baseboard_fab2(sch_1):page111_i26:io18"
				( attribute "PN" "18"
					( Origin gPackager )
				)
				( objectStatus "J9A3.18" )
			)
			( pin "@baseboard_fab2_lib.baseboard_fab2(sch_1):page111_i26:io19"
				( attribute "PN" "19"
					( Origin gPackager )
				)
				( objectStatus "J9A3.19" )
			)
			( pin "@baseboard_fab2_lib.baseboard_fab2(sch_1):page111_i26:io20"
				( attribute "PN" "20"
					( Origin gPackager )
				)
				( objectStatus "J9A3.20" )
			)
			( pin "@baseboard_fab2_lib.baseboard_fab2(sch_1):page111_i26:io21"
				( attribute "PN" "21"
					( Origin gPackager )
				)
				( objectStatus "J9A3.21" )
			)
			( pin "@baseboard_fab2_lib.baseboard_fab2(sch_1):page111_i26:io22"
				( attribute "PN" "22"
					( Origin gPackager )
				)
				( objectStatus "J9A3.22" )
			)
			( pin "@baseboard_fab2_lib.baseboard_fab2(sch_1):page111_i26:io23"
				( attribute "PN" "23"
					( Origin gPackager )
				)
				( objectStatus "J9A3.23" )
			)
			( pin "@baseboard_fab2_lib.baseboard_fab2(sch_1):page111_i26:io24"
				( attribute "PN" "24"
					( Origin gPackager )
				)
				( objectStatus "J9A3.24" )
			)
			( pin "@baseboard_fab2_lib.baseboard_fab2(sch_1):page111_i26:io25"
				( attribute "PN" "25"
					( Origin gPackager )
				)
				( objectStatus "J9A3.25" )
			)
			( pin "@baseboard_fab2_lib.baseboard_fab2(sch_1):page111_i26:io26"
				( attribute "PN" "26"
					( Origin gPackager )
				)
				( objectStatus "J9A3.26" )
			)
			( pin "@baseboard_fab2_lib.baseboard_fab2(sch_1):page111_i26:io27"
				( attribute "PN" "27"
					( Origin gPackager )
				)
				( objectStatus "J9A3.27" )
			)
			( pin "@baseboard_fab2_lib.baseboard_fab2(sch_1):page111_i26:io28"
				( attribute "PN" "28"
					( Origin gPackager )
				)
				( objectStatus "J9A3.28" )
			)
			( pin "@baseboard_fab2_lib.baseboard_fab2(sch_1):page111_i26:io29"
				( attribute "PN" "29"
					( Origin gPackager )
				)
				( objectStatus "J9A3.29" )
			)
			( pin "@baseboard_fab2_lib.baseboard_fab2(sch_1):page111_i26:io30"
				( attribute "PN" "30"
					( Origin gPackager )
				)
				( objectStatus "J9A3.30" )
			)
			( pin "@baseboard_fab2_lib.baseboard_fab2(sch_1):page111_i26:io31"
				( attribute "PN" "31"
					( Origin gPackager )
				)
				( objectStatus "J9A3.31" )
			)
			( pin "@baseboard_fab2_lib.baseboard_fab2(sch_1):page111_i26:io32"
				( attribute "PN" "32"
					( Origin gPackager )
				)
				( objectStatus "J9A3.32" )
			)
			( pin "@baseboard_fab2_lib.baseboard_fab2(sch_1):page111_i26:io33"
				( attribute "PN" "33"
					( Origin gPackager )
				)
				( objectStatus "J9A3.33" )
			)
			( pin "@baseboard_fab2_lib.baseboard_fab2(sch_1):page111_i26:io34"
				( attribute "PN" "34"
					( Origin gPackager )
				)
				( objectStatus "J9A3.34" )
			)
			( pin "@baseboard_fab2_lib.baseboard_fab2(sch_1):page111_i26:io35"
				( attribute "PN" "35"
					( Origin gPackager )
				)
				( objectStatus "J9A3.35" )
			)
			( pin "@baseboard_fab2_lib.baseboard_fab2(sch_1):page111_i26:io36"
				( attribute "PN" "36"
					( Origin gPackager )
				)
				( objectStatus "J9A3.36" )
			)
			( pin "@baseboard_fab2_lib.baseboard_fab2(sch_1):page111_i26:io37"
				( attribute "PN" "37"
					( Origin gPackager )
				)
				( objectStatus "J9A3.37" )
			)
			( pin "@baseboard_fab2_lib.baseboard_fab2(sch_1):page111_i26:io38"
				( attribute "PN" "38"
					( Origin gPackager )
				)
				( objectStatus "J9A3.38" )
			)
			( pin "@baseboard_fab2_lib.baseboard_fab2(sch_1):page111_i26:io39"
				( attribute "PN" "39"
					( Origin gPackager )
				)
				( objectStatus "J9A3.39" )
			)
			( pin "@baseboard_fab2_lib.baseboard_fab2(sch_1):page111_i26:io40"
				( attribute "PN" "40"
					( Origin gPackager )
				)
				( objectStatus "J9A3.40" )
			)
			( pin "@baseboard_fab2_lib.baseboard_fab2(sch_1):page111_i26:io41"
				( attribute "PN" "41"
					( Origin gPackager )
				)
				( objectStatus "J9A3.41" )
			)
			( pin "@baseboard_fab2_lib.baseboard_fab2(sch_1):page111_i26:io42"
				( attribute "PN" "42"
					( Origin gPackager )
				)
				( objectStatus "J9A3.42" )
			)
			( pin "@baseboard_fab2_lib.baseboard_fab2(sch_1):page111_i26:io43"
				( attribute "PN" "43"
					( Origin gPackager )
				)
				( objectStatus "J9A3.43" )
			)
			( pin "@baseboard_fab2_lib.baseboard_fab2(sch_1):page111_i26:io44"
				( attribute "PN" "44"
					( Origin gPackager )
				)
				( objectStatus "J9A3.44" )
			)
			( pin "@baseboard_fab2_lib.baseboard_fab2(sch_1):page111_i26:io45"
				( attribute "PN" "45"
					( Origin gPackager )
				)
				( objectStatus "J9A3.45" )
			)
			( pin "@baseboard_fab2_lib.baseboard_fab2(sch_1):page111_i26:io46"
				( attribute "PN" "46"
					( Origin gPackager )
				)
				( objectStatus "J9A3.46" )
			)
			( pin "@baseboard_fab2_lib.baseboard_fab2(sch_1):page111_i26:io47"
				( attribute "PN" "47"
					( Origin gPackager )
				)
				( objectStatus "J9A3.47" )
			)
			( pin "@baseboard_fab2_lib.baseboard_fab2(sch_1):page111_i26:io48"
				( attribute "PN" "48"
					( Origin gPackager )
				)
				( objectStatus "J9A3.48" )
			)
			( pin "@baseboard_fab2_lib.baseboard_fab2(sch_1):page111_i26:io49"
				( attribute "PN" "49"
					( Origin gPackager )
				)
				( objectStatus "J9A3.49" )
			)
			( pin "@baseboard_fab2_lib.baseboard_fab2(sch_1):page111_i26:io50"
				( attribute "PN" "50"
					( Origin gPackager )
				)
				( objectStatus "J9A3.50" )
			)
			( pin "@baseboard_fab2_lib.baseboard_fab2(sch_1):page111_i26:io51"
				( attribute "PN" "51"
					( Origin gPackager )
				)
				( objectStatus "J9A3.51" )
			)
			( pin "@baseboard_fab2_lib.baseboard_fab2(sch_1):page111_i26:io52"
				( attribute "PN" "52"
					( Origin gPackager )
				)
				( objectStatus "J9A3.52" )
			)
			( pin "@baseboard_fab2_lib.baseboard_fab2(sch_1):page111_i26:io53"
				( attribute "PN" "53"
					( Origin gPackager )
				)
				( objectStatus "J9A3.53" )
			)
			( pin "@baseboard_fab2_lib.baseboard_fab2(sch_1):page111_i26:io54"
				( attribute "PN" "54"
					( Origin gPackager )
				)
				( objectStatus "J9A3.54" )
			)
			( pin "@baseboard_fab2_lib.baseboard_fab2(sch_1):page111_i26:io55"
				( attribute "PN" "55"
					( Origin gPackager )
				)
				( objectStatus "J9A3.55" )
			)
			( pin "@baseboard_fab2_lib.baseboard_fab2(sch_1):page111_i26:io56"
				( attribute "PN" "56"
					( Origin gPackager )
				)
				( objectStatus "J9A3.56" )
			)
			( pin "@baseboard_fab2_lib.baseboard_fab2(sch_1):page111_i26:io57"
				( attribute "PN" "57"
					( Origin gPackager )
				)
				( objectStatus "J9A3.57" )
			)
			( pin "@baseboard_fab2_lib.baseboard_fab2(sch_1):page111_i26:io58"
				( attribute "PN" "58"
					( Origin gPackager )
				)
				( objectStatus "J9A3.58" )
			)
			( pin "@baseboard_fab2_lib.baseboard_fab2(sch_1):page111_i26:io59"
				( attribute "PN" "59"
					( Origin gPackager )
				)
				( objectStatus "J9A3.59" )
			)
			( pin "@baseboard_fab2_lib.baseboard_fab2(sch_1):page111_i26:io60"
				( attribute "PN" "60"
					( Origin gPackager )
				)
				( objectStatus "J9A3.60" )
			)
			( pin "@baseboard_fab2_lib.baseboard_fab2(sch_1):page111_i30:a"
				( attribute "PN" "1"
					( Origin gPackager )
				)
				( objectStatus "C1L5.1" )
			)
			( pin "@baseboard_fab2_lib.baseboard_fab2(sch_1):page111_i30:b"
				( attribute "PN" "2"
					( Origin gPackager )
				)
				( objectStatus "C1L5.2" )
			)
			( pin "@baseboard_fab2_lib.baseboard_fab2(sch_1):page111_i37:a"
				( attribute "PN" "1"
					( Origin gPackager )
				)
				( objectStatus "R2P2.1" )
			)
			( pin "@baseboard_fab2_lib.baseboard_fab2(sch_1):page111_i37:b"
				( attribute "PN" "2"
					( Origin gPackager )
				)
				( objectStatus "R2P2.2" )
			)
			( pin "@baseboard_fab2_lib.baseboard_fab2(sch_1):page111_i55:a"
				( attribute "PN" "1"
					( Origin gPackager )
				)
				( objectStatus "R9A4.1" )
			)
			( pin "@baseboard_fab2_lib.baseboard_fab2(sch_1):page111_i55:b"
				( attribute "PN" "2"
					( Origin gPackager )
				)
				( objectStatus "R9A4.2" )
			)
			( pin "@baseboard_fab2_lib.baseboard_fab2(sch_1):page111_i56:a"
				( attribute "PN" "1"
					( Origin gPackager )
				)
				( objectStatus "R1L17.1" )
			)
			( pin "@baseboard_fab2_lib.baseboard_fab2(sch_1):page111_i56:b"
				( attribute "PN" "2"
					( Origin gPackager )
				)
				( objectStatus "R1L17.2" )
			)
			( pin "@baseboard_fab2_lib.baseboard_fab2(sch_1):page111_i57:a"
				( attribute "PN" "1"
					( Origin gPackager )
				)
				( objectStatus "R9A17.1" )
			)
			( pin "@baseboard_fab2_lib.baseboard_fab2(sch_1):page111_i57:b"
				( attribute "PN" "2"
					( Origin gPackager )
				)
				( objectStatus "R9A17.2" )
			)
			( pin "@baseboard_fab2_lib.baseboard_fab2(sch_1):page111_i59:a"
				( attribute "PN" "1"
					( Origin gPackager )
				)
				( objectStatus "C9A4.1" )
			)
			( pin "@baseboard_fab2_lib.baseboard_fab2(sch_1):page111_i59:b"
				( attribute "PN" "2"
					( Origin gPackager )
				)
				( objectStatus "C9A4.2" )
			)
			( pin "@baseboard_fab2_lib.baseboard_fab2(sch_1):page111_i60:a"
				( attribute "PN" "1"
					( Origin gPackager )
				)
				( objectStatus "R9A15.1" )
			)
			( pin "@baseboard_fab2_lib.baseboard_fab2(sch_1):page111_i60:b"
				( attribute "PN" "2"
					( Origin gPackager )
				)
				( objectStatus "R9A15.2" )
			)
			( pin "@baseboard_fab2_lib.baseboard_fab2(sch_1):page111_i68:a"
				( attribute "PN" "1"
					( Origin gPackager )
				)
				( objectStatus "R1L29.1" )
			)
			( pin "@baseboard_fab2_lib.baseboard_fab2(sch_1):page111_i68:b"
				( attribute "PN" "2"
					( Origin gPackager )
				)
				( objectStatus "R1L29.2" )
			)
			( pin "@baseboard_fab2_lib.baseboard_fab2(sch_1):page111_i74:a"
				( attribute "PN" "1"
					( Origin gPackager )
				)
				( objectStatus "R9A3.1" )
			)
			( pin "@baseboard_fab2_lib.baseboard_fab2(sch_1):page111_i74:b"
				( attribute "PN" "2"
					( Origin gPackager )
				)
				( objectStatus "R9A3.2" )
			)
			( pin "@baseboard_fab2_lib.baseboard_fab2(sch_1):page111_i83:a"
				( attribute "PN" "1"
					( Origin gPackager )
				)
				( objectStatus "R9A2.1" )
			)
			( pin "@baseboard_fab2_lib.baseboard_fab2(sch_1):page111_i83:b"
				( attribute "PN" "2"
					( Origin gPackager )
				)
				( objectStatus "R9A2.2" )
			)
			( pin "@baseboard_fab2_lib.baseboard_fab2(sch_1):page111_i85:a"
				( attribute "PN" "2"
					( Origin gPackager )
				)
				( objectStatus "U1L4.2" )
			)
			( pin "@baseboard_fab2_lib.baseboard_fab2(sch_1):page111_i85:y"
				( attribute "PN" "4"
					( Origin gPackager )
				)
				( objectStatus "U1L4.4" )
			)
			( pin "@baseboard_fab2_lib.baseboard_fab2(sch_1):page111_i87:a"
				( attribute "PN" "1"
					( Origin gPackager )
				)
				( objectStatus "C1L11.1" )
			)
			( pin "@baseboard_fab2_lib.baseboard_fab2(sch_1):page111_i87:b"
				( attribute "PN" "2"
					( Origin gPackager )
				)
				( objectStatus "C1L11.2" )
			)
			( pin "@baseboard_fab2_lib.baseboard_fab2(sch_1):page111_i89:a"
				( attribute "PN" "1"
					( Origin gPackager )
				)
				( objectStatus "R8E2.1" )
			)
			( pin "@baseboard_fab2_lib.baseboard_fab2(sch_1):page111_i89:b"
				( attribute "PN" "2"
					( Origin gPackager )
				)
				( objectStatus "R8E2.2" )
			)
			( pin "@baseboard_fab2_lib.baseboard_fab2(sch_1):page111_i93:b(0)"
				( attribute "PN" "2"
					( Origin gPackager )
				)
				( objectStatus "Q9A1.2" )
			)
			( pin "@baseboard_fab2_lib.baseboard_fab2(sch_1):page111_i93:c(0)"
				( attribute "PN" "6"
					( Origin gPackager )
				)
				( objectStatus "Q9A1.6" )
			)
			( pin "@baseboard_fab2_lib.baseboard_fab2(sch_1):page111_i93:e(0)"
				( attribute "PN" "1"
					( Origin gPackager )
				)
				( objectStatus "Q9A1.1" )
			)
			( pin "@baseboard_fab2_lib.baseboard_fab2(sch_1):page111_i94:b(0)"
				( attribute "PN" "5"
					( Origin gPackager )
				)
				( objectStatus "Q9A1.5" )
			)
			( pin "@baseboard_fab2_lib.baseboard_fab2(sch_1):page111_i94:c(0)"
				( attribute "PN" "3"
					( Origin gPackager )
				)
				( objectStatus "Q9A1.3" )
			)
			( pin "@baseboard_fab2_lib.baseboard_fab2(sch_1):page111_i94:e(0)"
				( attribute "PN" "4"
					( Origin gPackager )
				)
				( objectStatus "Q9A1.4" )
			)
			( pin "@baseboard_fab2_lib.baseboard_fab2(sch_1):page111_i95:a"
				( attribute "PN" "1"
					( Origin gPackager )
				)
				( objectStatus "R9A1.1" )
			)
			( pin "@baseboard_fab2_lib.baseboard_fab2(sch_1):page111_i95:b"
				( attribute "PN" "2"
					( Origin gPackager )
				)
				( objectStatus "R9A1.2" )
			)
			( pin "@baseboard_fab2_lib.baseboard_fab2(sch_1):page112_i40:a"
				( attribute "PN" "4"
					( Origin gPackager )
				)
				( objectStatus "U1M7.4" )
			)
			( pin "@baseboard_fab2_lib.baseboard_fab2(sch_1):page112_i40:b0"
				( attribute "PN" "3"
					( Origin gPackager )
				)
				( objectStatus "U1M7.3" )
			)
			( pin "@baseboard_fab2_lib.baseboard_fab2(sch_1):page112_i40:b1"
				( attribute "PN" "1"
					( Origin gPackager )
				)
				( objectStatus "U1M7.1" )
			)
			( pin "@baseboard_fab2_lib.baseboard_fab2(sch_1):page112_i40:gnd"
				( attribute "PN" "2"
					( Origin gPackager )
				)
				( objectStatus "U1M7.2" )
			)
			( pin "@baseboard_fab2_lib.baseboard_fab2(sch_1):page112_i40:s"
				( attribute "PN" "6"
					( Origin gPackager )
				)
				( objectStatus "U1M7.6" )
			)
			( pin "@baseboard_fab2_lib.baseboard_fab2(sch_1):page112_i40:vcc"
				( attribute "PN" "5"
					( Origin gPackager )
				)
				( objectStatus "U1M7.5" )
			)
			( pin "@baseboard_fab2_lib.baseboard_fab2(sch_1):page112_i42:a"
				( attribute "PN" "1"
					( Origin gPackager )
				)
				( objectStatus "C1M36.1" )
			)
			( pin "@baseboard_fab2_lib.baseboard_fab2(sch_1):page112_i42:b"
				( attribute "PN" "2"
					( Origin gPackager )
				)
				( objectStatus "C1M36.2" )
			)
			( pin "@baseboard_fab2_lib.baseboard_fab2(sch_1):page112_i47:a"
				( attribute "PN" "1"
					( Origin gPackager )
				)
				( objectStatus "C1M37.1" )
			)
			( pin "@baseboard_fab2_lib.baseboard_fab2(sch_1):page112_i47:b"
				( attribute "PN" "2"
					( Origin gPackager )
				)
				( objectStatus "C1M37.2" )
			)
			( pin "@baseboard_fab2_lib.baseboard_fab2(sch_1):page112_i49:a"
				( attribute "PN" "1"
					( Origin gPackager )
				)
				( objectStatus "R6P46.1" )
			)
			( pin "@baseboard_fab2_lib.baseboard_fab2(sch_1):page112_i49:b"
				( attribute "PN" "2"
					( Origin gPackager )
				)
				( objectStatus "R6P46.2" )
			)
			( pin "@baseboard_fab2_lib.baseboard_fab2(sch_1):page112_i50:a"
				( attribute "PN" "1"
					( Origin gPackager )
				)
				( objectStatus "R7P30.1" )
			)
			( pin "@baseboard_fab2_lib.baseboard_fab2(sch_1):page112_i50:b"
				( attribute "PN" "2"
					( Origin gPackager )
				)
				( objectStatus "R7P30.2" )
			)
			( pin "@baseboard_fab2_lib.baseboard_fab2(sch_1):page112_i51:a"
				( attribute "PN" "1"
					( Origin gPackager )
				)
				( objectStatus "R1M3.1" )
			)
			( pin "@baseboard_fab2_lib.baseboard_fab2(sch_1):page112_i51:b"
				( attribute "PN" "2"
					( Origin gPackager )
				)
				( objectStatus "R1M3.2" )
			)
			( pin "@baseboard_fab2_lib.baseboard_fab2(sch_1):page112_i53:a"
				( attribute "PN" "1"
					( Origin gPackager )
				)
				( objectStatus "R4P15.1" )
			)
			( pin "@baseboard_fab2_lib.baseboard_fab2(sch_1):page112_i53:b"
				( attribute "PN" "2"
					( Origin gPackager )
				)
				( objectStatus "R4P15.2" )
			)
			( pin "@baseboard_fab2_lib.baseboard_fab2(sch_1):page112_i54:a"
				( attribute "PN" "1"
					( Origin gPackager )
				)
				( objectStatus "R1M4.1" )
			)
			( pin "@baseboard_fab2_lib.baseboard_fab2(sch_1):page112_i54:b"
				( attribute "PN" "2"
					( Origin gPackager )
				)
				( objectStatus "R1M4.2" )
			)
			( pin "@baseboard_fab2_lib.baseboard_fab2(sch_1):page112_i55:a"
				( attribute "PN" "1"
					( Origin gPackager )
				)
				( objectStatus "R6T7.1" )
			)
			( pin "@baseboard_fab2_lib.baseboard_fab2(sch_1):page112_i55:b"
				( attribute "PN" "2"
					( Origin gPackager )
				)
				( objectStatus "R6T7.2" )
			)
			( pin "@baseboard_fab2_lib.baseboard_fab2(sch_1):page112_i56:a"
				( attribute "PN" "1"
					( Origin gPackager )
				)
				( objectStatus "R6T6.1" )
			)
			( pin "@baseboard_fab2_lib.baseboard_fab2(sch_1):page112_i56:b"
				( attribute "PN" "2"
					( Origin gPackager )
				)
				( objectStatus "R6T6.2" )
			)
			( pin "@baseboard_fab2_lib.baseboard_fab2(sch_1):page112_i57:a"
				( attribute "PN" "1"
					( Origin gPackager )
				)
				( objectStatus "R4P12.1" )
			)
			( pin "@baseboard_fab2_lib.baseboard_fab2(sch_1):page112_i57:b"
				( attribute "PN" "2"
					( Origin gPackager )
				)
				( objectStatus "R4P12.2" )
			)
			( pin "@baseboard_fab2_lib.baseboard_fab2(sch_1):page112_i58:a"
				( attribute "PN" "1"
					( Origin gPackager )
				)
				( objectStatus "R4P23.1" )
			)
			( pin "@baseboard_fab2_lib.baseboard_fab2(sch_1):page112_i58:b"
				( attribute "PN" "2"
					( Origin gPackager )
				)
				( objectStatus "R4P23.2" )
			)
			( pin "@baseboard_fab2_lib.baseboard_fab2(sch_1):page112_i59:a"
				( attribute "PN" "1"
					( Origin gPackager )
				)
				( objectStatus "R4P24.1" )
			)
			( pin "@baseboard_fab2_lib.baseboard_fab2(sch_1):page112_i59:b"
				( attribute "PN" "2"
					( Origin gPackager )
				)
				( objectStatus "R4P24.2" )
			)
			( pin "@baseboard_fab2_lib.baseboard_fab2(sch_1):page112_i60:a"
				( attribute "PN" "1"
					( Origin gPackager )
				)
				( objectStatus "R1L15.1" )
			)
			( pin "@baseboard_fab2_lib.baseboard_fab2(sch_1):page112_i60:b"
				( attribute "PN" "2"
					( Origin gPackager )
				)
				( objectStatus "R1L15.2" )
			)
			( pin "@baseboard_fab2_lib.baseboard_fab2(sch_1):page112_i61:a"
				( attribute "PN" "1"
					( Origin gPackager )
				)
				( objectStatus "R7P29.1" )
			)
			( pin "@baseboard_fab2_lib.baseboard_fab2(sch_1):page112_i61:b"
				( attribute "PN" "2"
					( Origin gPackager )
				)
				( objectStatus "R7P29.2" )
			)
			( pin "@baseboard_fab2_lib.baseboard_fab2(sch_1):page112_i62:a"
				( attribute "PN" "1"
					( Origin gPackager )
				)
				( objectStatus "R6T5.1" )
			)
			( pin "@baseboard_fab2_lib.baseboard_fab2(sch_1):page112_i62:b"
				( attribute "PN" "2"
					( Origin gPackager )
				)
				( objectStatus "R6T5.2" )
			)
			( pin "@baseboard_fab2_lib.baseboard_fab2(sch_1):page112_i76:a"
				( attribute "PN" "1"
					( Origin gPackager )
				)
				( objectStatus "R1L39.1" )
			)
			( pin "@baseboard_fab2_lib.baseboard_fab2(sch_1):page112_i76:b"
				( attribute "PN" "2"
					( Origin gPackager )
				)
				( objectStatus "R1L39.2" )
			)
			( pin "@baseboard_fab2_lib.baseboard_fab2(sch_1):page112_i77:a"
				( attribute "PN" "1"
					( Origin gPackager )
				)
				( objectStatus "R1L41.1" )
			)
			( pin "@baseboard_fab2_lib.baseboard_fab2(sch_1):page112_i77:b"
				( attribute "PN" "2"
					( Origin gPackager )
				)
				( objectStatus "R1L41.2" )
			)
			( pin "@baseboard_fab2_lib.baseboard_fab2(sch_1):page112_i78:a"
				( attribute "PN" "1"
					( Origin gPackager )
				)
				( objectStatus "R9A11.1" )
			)
			( pin "@baseboard_fab2_lib.baseboard_fab2(sch_1):page112_i78:b"
				( attribute "PN" "2"
					( Origin gPackager )
				)
				( objectStatus "R9A11.2" )
			)
			( pin "@baseboard_fab2_lib.baseboard_fab2(sch_1):page112_i79:a"
				( attribute "PN" "1"
					( Origin gPackager )
				)
				( objectStatus "R8A13.1" )
			)
			( pin "@baseboard_fab2_lib.baseboard_fab2(sch_1):page112_i79:b"
				( attribute "PN" "2"
					( Origin gPackager )
				)
				( objectStatus "R8A13.2" )
			)
			( pin "@baseboard_fab2_lib.baseboard_fab2(sch_1):page112_i80:a"
				( attribute "PN" "1"
					( Origin gPackager )
				)
				( objectStatus "R8A14.1" )
			)
			( pin "@baseboard_fab2_lib.baseboard_fab2(sch_1):page112_i80:b"
				( attribute "PN" "2"
					( Origin gPackager )
				)
				( objectStatus "R8A14.2" )
			)
			( pin "@baseboard_fab2_lib.baseboard_fab2(sch_1):page112_i85:a"
				( attribute "PN" "1"
					( Origin gPackager )
				)
				( objectStatus "R3M10.1" )
			)
			( pin "@baseboard_fab2_lib.baseboard_fab2(sch_1):page112_i85:b"
				( attribute "PN" "2"
					( Origin gPackager )
				)
				( objectStatus "R3M10.2" )
			)
			( pin "@baseboard_fab2_lib.baseboard_fab2(sch_1):page112_i94:a"
				( attribute "PN" "1"
					( Origin gPackager )
				)
				( objectStatus "R8B2.1" )
			)
			( pin "@baseboard_fab2_lib.baseboard_fab2(sch_1):page112_i94:b"
				( attribute "PN" "2"
					( Origin gPackager )
				)
				( objectStatus "R8B2.2" )
			)
			( pin "@baseboard_fab2_lib.baseboard_fab2(sch_1):page112_i95:a"
				( attribute "PN" "1"
					( Origin gPackager )
				)
				( objectStatus "R8B1.1" )
			)
			( pin "@baseboard_fab2_lib.baseboard_fab2(sch_1):page112_i95:b"
				( attribute "PN" "2"
					( Origin gPackager )
				)
				( objectStatus "R8B1.2" )
			)
			( pin "@baseboard_fab2_lib.baseboard_fab2(sch_1):page112_i108:a(0)"
				( attribute "CDS_SEC" "4"
					( Origin gPackager )
				)
				( attribute "PN" "12"
					( Origin gPackager )
				)
				( attribute "SEC" "4"
					( Origin gPackager )
				)
				( objectStatus "U1L1.12" )
			)
			( pin "@baseboard_fab2_lib.baseboard_fab2(sch_1):page112_i108:a(1)"
				( attribute "CDS_SEC" "3"
					( Origin gPackager )
				)
				( attribute "PN" "9"
					( Origin gPackager )
				)
				( attribute "SEC" "3"
					( Origin gPackager )
				)
				( objectStatus "U1L1.9" )
			)
			( pin "@baseboard_fab2_lib.baseboard_fab2(sch_1):page112_i108:a(2)"
				( attribute "CDS_SEC" "2"
					( Origin gPackager )
				)
				( attribute "PN" "5"
					( Origin gPackager )
				)
				( attribute "SEC" "2"
					( Origin gPackager )
				)
				( objectStatus "U1L1.5" )
			)
			( pin "@baseboard_fab2_lib.baseboard_fab2(sch_1):page112_i108:a(3)"
				( attribute "CDS_SEC" "1"
					( Origin gPackager )
				)
				( attribute "PN" "2"
					( Origin gPackager )
				)
				( attribute "SEC" "1"
					( Origin gPackager )
				)
				( objectStatus "U1L1.2" )
			)
			( pin "@baseboard_fab2_lib.baseboard_fab2(sch_1):page112_i108:b(0)"
				( attribute "CDS_SEC" "4"
					( Origin gPackager )
				)
				( attribute "PN" "11"
					( Origin gPackager )
				)
				( attribute "SEC" "4"
					( Origin gPackager )
				)
				( objectStatus "U1L1.11" )
			)
			( pin "@baseboard_fab2_lib.baseboard_fab2(sch_1):page112_i108:b(1)"
				( attribute "CDS_SEC" "3"
					( Origin gPackager )
				)
				( attribute "PN" "8"
					( Origin gPackager )
				)
				( attribute "SEC" "3"
					( Origin gPackager )
				)
				( objectStatus "U1L1.8" )
			)
			( pin "@baseboard_fab2_lib.baseboard_fab2(sch_1):page112_i108:b(2)"
				( attribute "CDS_SEC" "2"
					( Origin gPackager )
				)
				( attribute "PN" "6"
					( Origin gPackager )
				)
				( attribute "SEC" "2"
					( Origin gPackager )
				)
				( objectStatus "U1L1.6" )
			)
			( pin "@baseboard_fab2_lib.baseboard_fab2(sch_1):page112_i108:b(3)"
				( attribute "CDS_SEC" "1"
					( Origin gPackager )
				)
				( attribute "PN" "3"
					( Origin gPackager )
				)
				( attribute "SEC" "1"
					( Origin gPackager )
				)
				( objectStatus "U1L1.3" )
			)
			( pin "@baseboard_fab2_lib.baseboard_fab2(sch_1):page112_i108:oe(0)"
				( attribute "CDS_SEC" "4"
					( Origin gPackager )
				)
				( attribute "PN" "13"
					( Origin gPackager )
				)
				( attribute "SEC" "4"
					( Origin gPackager )
				)
				( objectStatus "U1L1.13" )
			)
			( pin "@baseboard_fab2_lib.baseboard_fab2(sch_1):page112_i108:oe(1)"
				( attribute "CDS_SEC" "3"
					( Origin gPackager )
				)
				( attribute "PN" "10"
					( Origin gPackager )
				)
				( attribute "SEC" "3"
					( Origin gPackager )
				)
				( objectStatus "U1L1.10" )
			)
			( pin "@baseboard_fab2_lib.baseboard_fab2(sch_1):page112_i108:oe(2)"
				( attribute "CDS_SEC" "2"
					( Origin gPackager )
				)
				( attribute "PN" "4"
					( Origin gPackager )
				)
				( attribute "SEC" "2"
					( Origin gPackager )
				)
				( objectStatus "U1L1.4" )
			)
			( pin "@baseboard_fab2_lib.baseboard_fab2(sch_1):page112_i108:oe(3)"
				( attribute "CDS_SEC" "1"
					( Origin gPackager )
				)
				( attribute "PN" "1"
					( Origin gPackager )
				)
				( attribute "SEC" "1"
					( Origin gPackager )
				)
				( objectStatus "U1L1.1" )
			)
			( pin "@baseboard_fab2_lib.baseboard_fab2(sch_1):page112_i109:a(0)"
				( attribute "CDS_SEC" "4"
					( Origin gPackager )
				)
				( attribute "PN" "12"
					( Origin gPackager )
				)
				( attribute "SEC" "4"
					( Origin gPackager )
				)
				( objectStatus "U1L5.12" )
			)
			( pin "@baseboard_fab2_lib.baseboard_fab2(sch_1):page112_i109:a(1)"
				( attribute "CDS_SEC" "3"
					( Origin gPackager )
				)
				( attribute "PN" "9"
					( Origin gPackager )
				)
				( attribute "SEC" "3"
					( Origin gPackager )
				)
				( objectStatus "U1L5.9" )
			)
			( pin "@baseboard_fab2_lib.baseboard_fab2(sch_1):page112_i109:a(2)"
				( attribute "CDS_SEC" "2"
					( Origin gPackager )
				)
				( attribute "PN" "5"
					( Origin gPackager )
				)
				( attribute "SEC" "2"
					( Origin gPackager )
				)
				( objectStatus "U1L5.5" )
			)
			( pin "@baseboard_fab2_lib.baseboard_fab2(sch_1):page112_i109:a(3)"
				( attribute "CDS_SEC" "1"
					( Origin gPackager )
				)
				( attribute "PN" "2"
					( Origin gPackager )
				)
				( attribute "SEC" "1"
					( Origin gPackager )
				)
				( objectStatus "U1L5.2" )
			)
			( pin "@baseboard_fab2_lib.baseboard_fab2(sch_1):page112_i109:b(0)"
				( attribute "CDS_SEC" "4"
					( Origin gPackager )
				)
				( attribute "PN" "11"
					( Origin gPackager )
				)
				( attribute "SEC" "4"
					( Origin gPackager )
				)
				( objectStatus "U1L5.11" )
			)
			( pin "@baseboard_fab2_lib.baseboard_fab2(sch_1):page112_i109:b(1)"
				( attribute "CDS_SEC" "3"
					( Origin gPackager )
				)
				( attribute "PN" "8"
					( Origin gPackager )
				)
				( attribute "SEC" "3"
					( Origin gPackager )
				)
				( objectStatus "U1L5.8" )
			)
			( pin "@baseboard_fab2_lib.baseboard_fab2(sch_1):page112_i109:b(2)"
				( attribute "CDS_SEC" "2"
					( Origin gPackager )
				)
				( attribute "PN" "6"
					( Origin gPackager )
				)
				( attribute "SEC" "2"
					( Origin gPackager )
				)
				( objectStatus "U1L5.6" )
			)
			( pin "@baseboard_fab2_lib.baseboard_fab2(sch_1):page112_i109:b(3)"
				( attribute "CDS_SEC" "1"
					( Origin gPackager )
				)
				( attribute "PN" "3"
					( Origin gPackager )
				)
				( attribute "SEC" "1"
					( Origin gPackager )
				)
				( objectStatus "U1L5.3" )
			)
			( pin "@baseboard_fab2_lib.baseboard_fab2(sch_1):page112_i109:oe(0)"
				( attribute "CDS_SEC" "4"
					( Origin gPackager )
				)
				( attribute "PN" "13"
					( Origin gPackager )
				)
				( attribute "SEC" "4"
					( Origin gPackager )
				)
				( objectStatus "U1L5.13" )
			)
			( pin "@baseboard_fab2_lib.baseboard_fab2(sch_1):page112_i109:oe(1)"
				( attribute "CDS_SEC" "3"
					( Origin gPackager )
				)
				( attribute "PN" "10"
					( Origin gPackager )
				)
				( attribute "SEC" "3"
					( Origin gPackager )
				)
				( objectStatus "U1L5.10" )
			)
			( pin "@baseboard_fab2_lib.baseboard_fab2(sch_1):page112_i109:oe(2)"
				( attribute "CDS_SEC" "2"
					( Origin gPackager )
				)
				( attribute "PN" "4"
					( Origin gPackager )
				)
				( attribute "SEC" "2"
					( Origin gPackager )
				)
				( objectStatus "U1L5.4" )
			)
			( pin "@baseboard_fab2_lib.baseboard_fab2(sch_1):page112_i109:oe(3)"
				( attribute "CDS_SEC" "1"
					( Origin gPackager )
				)
				( attribute "PN" "1"
					( Origin gPackager )
				)
				( attribute "SEC" "1"
					( Origin gPackager )
				)
				( objectStatus "U1L5.1" )
			)
			( pin "@baseboard_fab2_lib.baseboard_fab2(sch_1):page112_i120:a"
				( attribute "PN" "1"
					( Origin gPackager )
				)
				( objectStatus "R6T9.1" )
			)
			( pin "@baseboard_fab2_lib.baseboard_fab2(sch_1):page112_i120:b"
				( attribute "PN" "2"
					( Origin gPackager )
				)
				( objectStatus "R6T9.2" )
			)
			( pin "@baseboard_fab2_lib.baseboard_fab2(sch_1):page112_i121:a"
				( attribute "PN" "1"
					( Origin gPackager )
				)
				( objectStatus "R6T8.1" )
			)
			( pin "@baseboard_fab2_lib.baseboard_fab2(sch_1):page112_i121:b"
				( attribute "PN" "2"
					( Origin gPackager )
				)
				( objectStatus "R6T8.2" )
			)
			( pin "@baseboard_fab2_lib.baseboard_fab2(sch_1):page112_i127:a"
				( attribute "PN" "2"
					( Origin gPackager )
				)
				( objectStatus "U1M4.2" )
			)
			( pin "@baseboard_fab2_lib.baseboard_fab2(sch_1):page112_i127:b"
				( attribute "PN" "4"
					( Origin gPackager )
				)
				( objectStatus "U1M4.4" )
			)
			( pin "@baseboard_fab2_lib.baseboard_fab2(sch_1):page112_i127:oe_n"
				( attribute "PN" "1"
					( Origin gPackager )
				)
				( objectStatus "U1M4.1" )
			)
			( pin "@baseboard_fab2_lib.baseboard_fab2(sch_1):page112_i131:a"
				( attribute "PN" "1"
					( Origin gPackager )
				)
				( objectStatus "C1M30.1" )
			)
			( pin "@baseboard_fab2_lib.baseboard_fab2(sch_1):page112_i131:b"
				( attribute "PN" "2"
					( Origin gPackager )
				)
				( objectStatus "C1M30.2" )
			)
			( pin "@baseboard_fab2_lib.baseboard_fab2(sch_1):page112_i136:a"
				( attribute "PN" "1"
					( Origin gPackager )
				)
				( objectStatus "C1L1.1" )
			)
			( pin "@baseboard_fab2_lib.baseboard_fab2(sch_1):page112_i136:b"
				( attribute "PN" "2"
					( Origin gPackager )
				)
				( objectStatus "C1L1.2" )
			)
			( pin "@baseboard_fab2_lib.baseboard_fab2(sch_1):page112_i140:a"
				( attribute "PN" "1"
					( Origin gPackager )
				)
				( objectStatus "C1L19.1" )
			)
			( pin "@baseboard_fab2_lib.baseboard_fab2(sch_1):page112_i140:b"
				( attribute "PN" "2"
					( Origin gPackager )
				)
				( objectStatus "C1L19.2" )
			)
			( pin "@baseboard_fab2_lib.baseboard_fab2(sch_1):page113_i107:a"
				( attribute "PN" "4"
					( Origin gPackager )
				)
				( objectStatus "U1M2.4" )
			)
			( pin "@baseboard_fab2_lib.baseboard_fab2(sch_1):page113_i107:b0"
				( attribute "PN" "3"
					( Origin gPackager )
				)
				( objectStatus "U1M2.3" )
			)
			( pin "@baseboard_fab2_lib.baseboard_fab2(sch_1):page113_i107:b1"
				( attribute "PN" "1"
					( Origin gPackager )
				)
				( objectStatus "U1M2.1" )
			)
			( pin "@baseboard_fab2_lib.baseboard_fab2(sch_1):page113_i107:gnd"
				( attribute "PN" "2"
					( Origin gPackager )
				)
				( objectStatus "U1M2.2" )
			)
			( pin "@baseboard_fab2_lib.baseboard_fab2(sch_1):page113_i107:s"
				( attribute "PN" "6"
					( Origin gPackager )
				)
				( objectStatus "U1M2.6" )
			)
			( pin "@baseboard_fab2_lib.baseboard_fab2(sch_1):page113_i107:vcc"
				( attribute "PN" "5"
					( Origin gPackager )
				)
				( objectStatus "U1M2.5" )
			)
			( pin "@baseboard_fab2_lib.baseboard_fab2(sch_1):page113_i116:a"
				( attribute "PN" "1"
					( Origin gPackager )
				)
				( objectStatus "C1M31.1" )
			)
			( pin "@baseboard_fab2_lib.baseboard_fab2(sch_1):page113_i116:b"
				( attribute "PN" "2"
					( Origin gPackager )
				)
				( objectStatus "C1M31.2" )
			)
			( pin "@baseboard_fab2_lib.baseboard_fab2(sch_1):page113_i117:a"
				( attribute "PN" "1"
					( Origin gPackager )
				)
				( objectStatus "C1M32.1" )
			)
			( pin "@baseboard_fab2_lib.baseboard_fab2(sch_1):page113_i117:b"
				( attribute "PN" "2"
					( Origin gPackager )
				)
				( objectStatus "C1M32.2" )
			)
			( pin "@baseboard_fab2_lib.baseboard_fab2(sch_1):page113_i119:a"
				( attribute "PN" "1"
					( Origin gPackager )
				)
				( objectStatus "C1M28.1" )
			)
			( pin "@baseboard_fab2_lib.baseboard_fab2(sch_1):page113_i119:b"
				( attribute "PN" "2"
					( Origin gPackager )
				)
				( objectStatus "C1M28.2" )
			)
			( pin "@baseboard_fab2_lib.baseboard_fab2(sch_1):page113_i127:a"
				( attribute "PN" "2"
					( Origin gPackager )
				)
				( objectStatus "U1M6.2" )
			)
			( pin "@baseboard_fab2_lib.baseboard_fab2(sch_1):page113_i127:b"
				( attribute "PN" "4"
					( Origin gPackager )
				)
				( objectStatus "U1M6.4" )
			)
			( pin "@baseboard_fab2_lib.baseboard_fab2(sch_1):page113_i127:oe_n"
				( attribute "PN" "1"
					( Origin gPackager )
				)
				( objectStatus "U1M6.1" )
			)
			( pin "@baseboard_fab2_lib.baseboard_fab2(sch_1):page113_i147:a"
				( attribute "PN" "1"
					( Origin gPackager )
				)
				( objectStatus "C1M29.1" )
			)
			( pin "@baseboard_fab2_lib.baseboard_fab2(sch_1):page113_i147:b"
				( attribute "PN" "2"
					( Origin gPackager )
				)
				( objectStatus "C1M29.2" )
			)
			( pin "@baseboard_fab2_lib.baseboard_fab2(sch_1):page113_i168:a"
				( attribute "PN" "1"
					( Origin gPackager )
				)
				( objectStatus "R9B14.1" )
			)
			( pin "@baseboard_fab2_lib.baseboard_fab2(sch_1):page113_i168:b"
				( attribute "PN" "2"
					( Origin gPackager )
				)
				( objectStatus "R9B14.2" )
			)
			( pin "@baseboard_fab2_lib.baseboard_fab2(sch_1):page113_i175:io1"
				( attribute "PN" "1"
					( Origin gPackager )
				)
				( objectStatus "J9B4.1" )
			)
			( pin "@baseboard_fab2_lib.baseboard_fab2(sch_1):page113_i175:io2"
				( attribute "PN" "2"
					( Origin gPackager )
				)
				( objectStatus "J9B4.2" )
			)
			( pin "@baseboard_fab2_lib.baseboard_fab2(sch_1):page113_i175:io3"
				( attribute "PN" "3"
					( Origin gPackager )
				)
				( objectStatus "J9B4.3" )
			)
			( pin "@baseboard_fab2_lib.baseboard_fab2(sch_1):page113_i175:io4"
				( attribute "PN" "4"
					( Origin gPackager )
				)
				( objectStatus "J9B4.4" )
			)
			( pin "@baseboard_fab2_lib.baseboard_fab2(sch_1):page113_i175:io5"
				( attribute "PN" "5"
					( Origin gPackager )
				)
				( objectStatus "J9B4.5" )
			)
			( pin "@baseboard_fab2_lib.baseboard_fab2(sch_1):page113_i175:io6"
				( attribute "PN" "6"
					( Origin gPackager )
				)
				( objectStatus "J9B4.6" )
			)
			( pin "@baseboard_fab2_lib.baseboard_fab2(sch_1):page113_i175:io7"
				( attribute "PN" "7"
					( Origin gPackager )
				)
				( objectStatus "J9B4.7" )
			)
			( pin "@baseboard_fab2_lib.baseboard_fab2(sch_1):page113_i175:io8"
				( attribute "PN" "8"
					( Origin gPackager )
				)
				( objectStatus "J9B4.8" )
			)
			( pin "@baseboard_fab2_lib.baseboard_fab2(sch_1):page113_i175:io9"
				( attribute "PN" "9"
					( Origin gPackager )
				)
				( objectStatus "J9B4.9" )
			)
			( pin "@baseboard_fab2_lib.baseboard_fab2(sch_1):page113_i175:io10"
				( attribute "PN" "10"
					( Origin gPackager )
				)
				( objectStatus "J9B4.10" )
			)
			( pin "@baseboard_fab2_lib.baseboard_fab2(sch_1):page113_i179:a"
				( attribute "PN" "1"
					( Origin gPackager )
				)
				( objectStatus "R9B9.1" )
			)
			( pin "@baseboard_fab2_lib.baseboard_fab2(sch_1):page113_i179:b"
				( attribute "PN" "2"
					( Origin gPackager )
				)
				( objectStatus "R9B9.2" )
			)
			( pin "@baseboard_fab2_lib.baseboard_fab2(sch_1):page113_i180:a"
				( attribute "PN" "1"
					( Origin gPackager )
				)
				( objectStatus "R9B10.1" )
			)
			( pin "@baseboard_fab2_lib.baseboard_fab2(sch_1):page113_i180:b"
				( attribute "PN" "2"
					( Origin gPackager )
				)
				( objectStatus "R9B10.2" )
			)
			( pin "@baseboard_fab2_lib.baseboard_fab2(sch_1):page113_i185:a"
				( attribute "PN" "2"
					( Origin gPackager )
				)
				( objectStatus "U9A5.2" )
			)
			( pin "@baseboard_fab2_lib.baseboard_fab2(sch_1):page113_i185:b"
				( attribute "PN" "4"
					( Origin gPackager )
				)
				( objectStatus "U9A5.4" )
			)
			( pin "@baseboard_fab2_lib.baseboard_fab2(sch_1):page113_i185:oe_n"
				( attribute "PN" "1"
					( Origin gPackager )
				)
				( objectStatus "U9A5.1" )
			)
			( pin "@baseboard_fab2_lib.baseboard_fab2(sch_1):page113_i190:a"
				( attribute "PN" "2"
					( Origin gPackager )
				)
				( objectStatus "U6M1.2" )
			)
			( pin "@baseboard_fab2_lib.baseboard_fab2(sch_1):page113_i190:b"
				( attribute "PN" "4"
					( Origin gPackager )
				)
				( objectStatus "U6M1.4" )
			)
			( pin "@baseboard_fab2_lib.baseboard_fab2(sch_1):page113_i190:oe_n"
				( attribute "PN" "1"
					( Origin gPackager )
				)
				( objectStatus "U6M1.1" )
			)
			( pin "@baseboard_fab2_lib.baseboard_fab2(sch_1):page113_i195:a"
				( attribute "PN" "1"
					( Origin gPackager )
				)
				( objectStatus "R1M22.1" )
			)
			( pin "@baseboard_fab2_lib.baseboard_fab2(sch_1):page113_i195:b"
				( attribute "PN" "2"
					( Origin gPackager )
				)
				( objectStatus "R1M22.2" )
			)
			( pin "@baseboard_fab2_lib.baseboard_fab2(sch_1):page113_i196:a"
				( attribute "PN" "2"
					( Origin gPackager )
				)
				( objectStatus "U1M5.2" )
			)
			( pin "@baseboard_fab2_lib.baseboard_fab2(sch_1):page113_i196:b"
				( attribute "PN" "4"
					( Origin gPackager )
				)
				( objectStatus "U1M5.4" )
			)
			( pin "@baseboard_fab2_lib.baseboard_fab2(sch_1):page113_i196:oe_n"
				( attribute "PN" "1"
					( Origin gPackager )
				)
				( objectStatus "U1M5.1" )
			)
			( pin "@baseboard_fab2_lib.baseboard_fab2(sch_1):page113_i199:a"
				( attribute "PN" "1"
					( Origin gPackager )
				)
				( objectStatus "R1M23.1" )
			)
			( pin "@baseboard_fab2_lib.baseboard_fab2(sch_1):page113_i199:b"
				( attribute "PN" "2"
					( Origin gPackager )
				)
				( objectStatus "R1M23.2" )
			)
			( pin "@baseboard_fab2_lib.baseboard_fab2(sch_1):page113_i202:a"
				( attribute "PN" "1"
					( Origin gPackager )
				)
				( objectStatus "R1M19.1" )
			)
			( pin "@baseboard_fab2_lib.baseboard_fab2(sch_1):page113_i202:b"
				( attribute "PN" "2"
					( Origin gPackager )
				)
				( objectStatus "R1M19.2" )
			)
			( pin "@baseboard_fab2_lib.baseboard_fab2(sch_1):page113_i203:a"
				( attribute "PN" "1"
					( Origin gPackager )
				)
				( objectStatus "R9B12.1" )
			)
			( pin "@baseboard_fab2_lib.baseboard_fab2(sch_1):page113_i203:b"
				( attribute "PN" "2"
					( Origin gPackager )
				)
				( objectStatus "R9B12.2" )
			)
			( pin "@baseboard_fab2_lib.baseboard_fab2(sch_1):page113_i204:a"
				( attribute "PN" "1"
					( Origin gPackager )
				)
				( objectStatus "R1M20.1" )
			)
			( pin "@baseboard_fab2_lib.baseboard_fab2(sch_1):page113_i204:b"
				( attribute "PN" "2"
					( Origin gPackager )
				)
				( objectStatus "R1M20.2" )
			)
			( pin "@baseboard_fab2_lib.baseboard_fab2(sch_1):page113_i205:a"
				( attribute "PN" "1"
					( Origin gPackager )
				)
				( objectStatus "R1M21.1" )
			)
			( pin "@baseboard_fab2_lib.baseboard_fab2(sch_1):page113_i205:b"
				( attribute "PN" "2"
					( Origin gPackager )
				)
				( objectStatus "R1M21.2" )
			)
			( pin "@baseboard_fab2_lib.baseboard_fab2(sch_1):page113_i206:a"
				( attribute "PN" "2"
					( Origin gPackager )
				)
				( objectStatus "U4R1.2" )
			)
			( pin "@baseboard_fab2_lib.baseboard_fab2(sch_1):page113_i206:b"
				( attribute "PN" "4"
					( Origin gPackager )
				)
				( objectStatus "U4R1.4" )
			)
			( pin "@baseboard_fab2_lib.baseboard_fab2(sch_1):page113_i206:oe_n"
				( attribute "PN" "1"
					( Origin gPackager )
				)
				( objectStatus "U4R1.1" )
			)
			( pin "@baseboard_fab2_lib.baseboard_fab2(sch_1):page113_i239:a"
				( attribute "PN" "1"
					( Origin gPackager )
				)
				( objectStatus "R9B11.1" )
			)
			( pin "@baseboard_fab2_lib.baseboard_fab2(sch_1):page113_i239:b"
				( attribute "PN" "2"
					( Origin gPackager )
				)
				( objectStatus "R9B11.2" )
			)
			( pin "@baseboard_fab2_lib.baseboard_fab2(sch_1):page113_i240:a"
				( attribute "PN" "1"
					( Origin gPackager )
				)
				( objectStatus "R9B13.1" )
			)
			( pin "@baseboard_fab2_lib.baseboard_fab2(sch_1):page113_i240:b"
				( attribute "PN" "2"
					( Origin gPackager )
				)
				( objectStatus "R9B13.2" )
			)
			( pin "@baseboard_fab2_lib.baseboard_fab2(sch_1):page113_i246:a"
				( attribute "PN" "1"
					( Origin gPackager )
				)
				( objectStatus "C4R2.1" )
			)
			( pin "@baseboard_fab2_lib.baseboard_fab2(sch_1):page113_i246:b"
				( attribute "PN" "2"
					( Origin gPackager )
				)
				( objectStatus "C4R2.2" )
			)
			( pin "@baseboard_fab2_lib.baseboard_fab2(sch_1):page113_i248:a"
				( attribute "PN" "1"
					( Origin gPackager )
				)
				( objectStatus "C1M33.1" )
			)
			( pin "@baseboard_fab2_lib.baseboard_fab2(sch_1):page113_i248:b"
				( attribute "PN" "2"
					( Origin gPackager )
				)
				( objectStatus "C1M33.2" )
			)
			( pin "@baseboard_fab2_lib.baseboard_fab2(sch_1):page113_i250:a"
				( attribute "PN" "1"
					( Origin gPackager )
				)
				( objectStatus "C6M6.1" )
			)
			( pin "@baseboard_fab2_lib.baseboard_fab2(sch_1):page113_i250:b"
				( attribute "PN" "2"
					( Origin gPackager )
				)
				( objectStatus "C6M6.2" )
			)
			( pin "@baseboard_fab2_lib.baseboard_fab2(sch_1):page113_i255:a"
				( attribute "PN" "4"
					( Origin gPackager )
				)
				( objectStatus "U2M1.4" )
			)
			( pin "@baseboard_fab2_lib.baseboard_fab2(sch_1):page113_i255:b0"
				( attribute "PN" "3"
					( Origin gPackager )
				)
				( objectStatus "U2M1.3" )
			)
			( pin "@baseboard_fab2_lib.baseboard_fab2(sch_1):page113_i255:b1"
				( attribute "PN" "1"
					( Origin gPackager )
				)
				( objectStatus "U2M1.1" )
			)
			( pin "@baseboard_fab2_lib.baseboard_fab2(sch_1):page113_i255:gnd"
				( attribute "PN" "2"
					( Origin gPackager )
				)
				( objectStatus "U2M1.2" )
			)
			( pin "@baseboard_fab2_lib.baseboard_fab2(sch_1):page113_i255:s"
				( attribute "PN" "6"
					( Origin gPackager )
				)
				( objectStatus "U2M1.6" )
			)
			( pin "@baseboard_fab2_lib.baseboard_fab2(sch_1):page113_i255:vcc"
				( attribute "PN" "5"
					( Origin gPackager )
				)
				( objectStatus "U2M1.5" )
			)
			( pin "@baseboard_fab2_lib.baseboard_fab2(sch_1):page113_i265:a"
				( attribute "PN" "1"
					( Origin gPackager )
				)
				( objectStatus "C1M34.1" )
			)
			( pin "@baseboard_fab2_lib.baseboard_fab2(sch_1):page113_i265:b"
				( attribute "PN" "2"
					( Origin gPackager )
				)
				( objectStatus "C1M34.2" )
			)
			( pin "@baseboard_fab2_lib.baseboard_fab2(sch_1):page113_i266:a"
				( attribute "PN" "1"
					( Origin gPackager )
				)
				( objectStatus "C1M35.1" )
			)
			( pin "@baseboard_fab2_lib.baseboard_fab2(sch_1):page113_i266:b"
				( attribute "PN" "2"
					( Origin gPackager )
				)
				( objectStatus "C1M35.2" )
			)
			( pin "@baseboard_fab2_lib.baseboard_fab2(sch_1):page113_i267:a"
				( attribute "PN" "1"
					( Origin gPackager )
				)
				( objectStatus "C1L20.1" )
			)
			( pin "@baseboard_fab2_lib.baseboard_fab2(sch_1):page113_i267:b"
				( attribute "PN" "2"
					( Origin gPackager )
				)
				( objectStatus "C1L20.2" )
			)
			( pin "@baseboard_fab2_lib.baseboard_fab2(sch_1):page114_i40:clkout_itpxdpn"
				( attribute "PN" "A39"
					( Origin gPackager )
				)
				( objectStatus "U7C1.A39" )
			)
			( pin "@baseboard_fab2_lib.baseboard_fab2(sch_1):page114_i40:clkout_itpxdpp"
				( attribute "PN" "C39"
					( Origin gPackager )
				)
				( objectStatus "U7C1.C39" )
			)
			( pin "@baseboard_fab2_lib.baseboard_fab2(sch_1):page114_i40:clkout_nssccap0n"
				( attribute "PN" "A32"
					( Origin gPackager )
				)
				( objectStatus "U7C1.A32" )
			)
			( pin "@baseboard_fab2_lib.baseboard_fab2(sch_1):page114_i40:clkout_nssccap0p"
				( attribute "PN" "C32"
					( Origin gPackager )
				)
				( objectStatus "U7C1.C32" )
			)
			( pin "@baseboard_fab2_lib.baseboard_fab2(sch_1):page114_i40:clkout_nssccap1n"
				( attribute "PN" "B38"
					( Origin gPackager )
				)
				( objectStatus "U7C1.B38" )
			)
			( pin "@baseboard_fab2_lib.baseboard_fab2(sch_1):page114_i40:clkout_nssccap1p"
				( attribute "PN" "D38"
					( Origin gPackager )
				)
				( objectStatus "U7C1.D38" )
			)
			( pin "@baseboard_fab2_lib.baseboard_fab2(sch_1):page114_i40:clkout_plat0n"
				( attribute "PN" "B29"
					( Origin gPackager )
				)
				( objectStatus "U7C1.B29" )
			)
			( pin "@baseboard_fab2_lib.baseboard_fab2(sch_1):page114_i40:clkout_plat0p"
				( attribute "PN" "D29"
					( Origin gPackager )
				)
				( objectStatus "U7C1.D29" )
			)
			( pin "@baseboard_fab2_lib.baseboard_fab2(sch_1):page114_i40:clkout_plat1n"
				( attribute "PN" "B40"
					( Origin gPackager )
				)
				( objectStatus "U7C1.B40" )
			)
			( pin "@baseboard_fab2_lib.baseboard_fab2(sch_1):page114_i40:clkout_plat1p"
				( attribute "PN" "D40"
					( Origin gPackager )
				)
				( objectStatus "U7C1.D40" )
			)
			( pin "@baseboard_fab2_lib.baseboard_fab2(sch_1):page114_i40:clkout_srcn(0)"
				( attribute "PN" "K38"
					( Origin gPackager )
				)
				( objectStatus "U7C1.K38" )
			)
			( pin "@baseboard_fab2_lib.baseboard_fab2(sch_1):page114_i40:clkout_srcn(1)"
				( attribute "PN" "K35"
					( Origin gPackager )
				)
				( objectStatus "U7C1.K35" )
			)
			( pin "@baseboard_fab2_lib.baseboard_fab2(sch_1):page114_i40:clkout_srcn(2)"
				( attribute "PN" "J33"
					( Origin gPackager )
				)
				( objectStatus "U7C1.J33" )
			)
			( pin "@baseboard_fab2_lib.baseboard_fab2(sch_1):page114_i40:clkout_srcn(3)"
				( attribute "PN" "K42"
					( Origin gPackager )
				)
				( objectStatus "U7C1.K42" )
			)
			( pin "@baseboard_fab2_lib.baseboard_fab2(sch_1):page114_i40:clkout_srcn(4)"
				( attribute "PN" "A28"
					( Origin gPackager )
				)
				( objectStatus "U7C1.A28" )
			)
			( pin "@baseboard_fab2_lib.baseboard_fab2(sch_1):page114_i40:clkout_srcn(5)"
				( attribute "PN" "J40"
					( Origin gPackager )
				)
				( objectStatus "U7C1.J40" )
			)
			( pin "@baseboard_fab2_lib.baseboard_fab2(sch_1):page114_i40:clkout_srcn(6)"
				( attribute "PN" "D33"
					( Origin gPackager )
				)
				( objectStatus "U7C1.D33" )
			)
			( pin "@baseboard_fab2_lib.baseboard_fab2(sch_1):page114_i40:clkout_srcn(7)"
				( attribute "PN" "H31"
					( Origin gPackager )
				)
				( objectStatus "U7C1.H31" )
			)
			( pin "@baseboard_fab2_lib.baseboard_fab2(sch_1):page114_i40:clkout_srcn(8)"
				( attribute "PN" "D31"
					( Origin gPackager )
				)
				( objectStatus "U7C1.D31" )
			)
			( pin "@baseboard_fab2_lib.baseboard_fab2(sch_1):page114_i40:clkout_srcn(9)"
				( attribute "PN" "J26"
					( Origin gPackager )
				)
				( objectStatus "U7C1.J26" )
			)
			( pin "@baseboard_fab2_lib.baseboard_fab2(sch_1):page114_i40:clkout_srcn(10)"
				( attribute "PN" "B23"
					( Origin gPackager )
				)
				( objectStatus "U7C1.B23" )
			)
			( pin "@baseboard_fab2_lib.baseboard_fab2(sch_1):page114_i40:clkout_srcn(11)"
				( attribute "PN" "B21"
					( Origin gPackager )
				)
				( objectStatus "U7C1.B21" )
			)
			( pin "@baseboard_fab2_lib.baseboard_fab2(sch_1):page114_i40:clkout_srcn(12)"
				( attribute "PN" "K24"
					( Origin gPackager )
				)
				( objectStatus "U7C1.K24" )
			)
			( pin "@baseboard_fab2_lib.baseboard_fab2(sch_1):page114_i40:clkout_srcn(13)"
				( attribute "PN" "C24"
					( Origin gPackager )
				)
				( objectStatus "U7C1.C24" )
			)
			( pin "@baseboard_fab2_lib.baseboard_fab2(sch_1):page114_i40:clkout_srcn(14)"
				( attribute "PN" "C20"
					( Origin gPackager )
				)
				( objectStatus "U7C1.C20" )
			)
			( pin "@baseboard_fab2_lib.baseboard_fab2(sch_1):page114_i40:clkout_srcn(15)"
				( attribute "PN" "K27"
					( Origin gPackager )
				)
				( objectStatus "U7C1.K27" )
			)
			( pin "@baseboard_fab2_lib.baseboard_fab2(sch_1):page114_i40:clkout_srcp(0)"
				( attribute "PN" "H38"
					( Origin gPackager )
				)
				( objectStatus "U7C1.H38" )
			)
			( pin "@baseboard_fab2_lib.baseboard_fab2(sch_1):page114_i40:clkout_srcp(1)"
				( attribute "PN" "H35"
					( Origin gPackager )
				)
				( objectStatus "U7C1.H35" )
			)
			( pin "@baseboard_fab2_lib.baseboard_fab2(sch_1):page114_i40:clkout_srcp(2)"
				( attribute "PN" "G33"
					( Origin gPackager )
				)
				( objectStatus "U7C1.G33" )
			)
			( pin "@baseboard_fab2_lib.baseboard_fab2(sch_1):page114_i40:clkout_srcp(3)"
				( attribute "PN" "H42"
					( Origin gPackager )
				)
				( objectStatus "U7C1.H42" )
			)
			( pin "@baseboard_fab2_lib.baseboard_fab2(sch_1):page114_i40:clkout_srcp(4)"
				( attribute "PN" "C28"
					( Origin gPackager )
				)
				( objectStatus "U7C1.C28" )
			)
			( pin "@baseboard_fab2_lib.baseboard_fab2(sch_1):page114_i40:clkout_srcp(5)"
				( attribute "PN" "G40"
					( Origin gPackager )
				)
				( objectStatus "U7C1.G40" )
			)
			( pin "@baseboard_fab2_lib.baseboard_fab2(sch_1):page114_i40:clkout_srcp(6)"
				( attribute "PN" "B33"
					( Origin gPackager )
				)
				( objectStatus "U7C1.B33" )
			)
			( pin "@baseboard_fab2_lib.baseboard_fab2(sch_1):page114_i40:clkout_srcp(7)"
				( attribute "PN" "K31"
					( Origin gPackager )
				)
				( objectStatus "U7C1.K31" )
			)
			( pin "@baseboard_fab2_lib.baseboard_fab2(sch_1):page114_i40:clkout_srcp(8)"
				( attribute "PN" "B31"
					( Origin gPackager )
				)
				( objectStatus "U7C1.B31" )
			)
			( pin "@baseboard_fab2_lib.baseboard_fab2(sch_1):page114_i40:clkout_srcp(9)"
				( attribute "PN" "G26"
					( Origin gPackager )
				)
				( objectStatus "U7C1.G26" )
			)
			( pin "@baseboard_fab2_lib.baseboard_fab2(sch_1):page114_i40:clkout_srcp(10)"
				( attribute "PN" "D23"
					( Origin gPackager )
				)
				( objectStatus "U7C1.D23" )
			)
			( pin "@baseboard_fab2_lib.baseboard_fab2(sch_1):page114_i40:clkout_srcp(11)"
				( attribute "PN" "D21"
					( Origin gPackager )
				)
				( objectStatus "U7C1.D21" )
			)
			( pin "@baseboard_fab2_lib.baseboard_fab2(sch_1):page114_i40:clkout_srcp(12)"
				( attribute "PN" "H24"
					( Origin gPackager )
				)
				( objectStatus "U7C1.H24" )
			)
			( pin "@baseboard_fab2_lib.baseboard_fab2(sch_1):page114_i40:clkout_srcp(13)"
				( attribute "PN" "A24"
					( Origin gPackager )
				)
				( objectStatus "U7C1.A24" )
			)
			( pin "@baseboard_fab2_lib.baseboard_fab2(sch_1):page114_i40:clkout_srcp(14)"
				( attribute "PN" "A20"
					( Origin gPackager )
				)
				( objectStatus "U7C1.A20" )
			)
			( pin "@baseboard_fab2_lib.baseboard_fab2(sch_1):page114_i40:clkout_srcp(15)"
				( attribute "PN" "H27"
					( Origin gPackager )
				)
				( objectStatus "U7C1.H27" )
			)
			( pin "@baseboard_fab2_lib.baseboard_fab2(sch_1):page114_i40:clockse_bmcclk"
				( attribute "PN" "BW50"
					( Origin gPackager )
				)
				( objectStatus "U7C1.BW50" )
			)
			( pin "@baseboard_fab2_lib.baseboard_fab2(sch_1):page114_i40:clockse_pmsyncclk1"
				( attribute "PN" "BY51"
					( Origin gPackager )
				)
				( objectStatus "U7C1.BY51" )
			)
			( pin "@baseboard_fab2_lib.baseboard_fab2(sch_1):page114_i40:clockse_pmsyncclk2"
				( attribute "PN" "BV51"
					( Origin gPackager )
				)
				( objectStatus "U7C1.BV51" )
			)
			( pin "@baseboard_fab2_lib.baseboard_fab2(sch_1):page114_i40:rsvd(64)"
				( attribute "PN" "C26"
					( Origin gPackager )
				)
				( objectStatus "U7C1.C26" )
			)
			( pin "@baseboard_fab2_lib.baseboard_fab2(sch_1):page114_i40:rsvd(65)"
				( attribute "PN" "A26"
					( Origin gPackager )
				)
				( objectStatus "U7C1.A26" )
			)
			( pin "@baseboard_fab2_lib.baseboard_fab2(sch_1):page114_i40:rtcx1"
				( attribute "PN" "K17"
					( Origin gPackager )
				)
				( objectStatus "U7C1.K17" )
			)
			( pin "@baseboard_fab2_lib.baseboard_fab2(sch_1):page114_i40:rtcx2"
				( attribute "PN" "H17"
					( Origin gPackager )
				)
				( objectStatus "U7C1.H17" )
			)
			( pin "@baseboard_fab2_lib.baseboard_fab2(sch_1):page114_i40:xclk_biasref"
				( attribute "PN" "G44"
					( Origin gPackager )
				)
				( objectStatus "U7C1.G44" )
			)
			( pin "@baseboard_fab2_lib.baseboard_fab2(sch_1):page114_i40:xtal_in"
				( attribute "PN" "B35"
					( Origin gPackager )
				)
				( objectStatus "U7C1.B35" )
			)
			( pin "@baseboard_fab2_lib.baseboard_fab2(sch_1):page114_i40:xtal_out"
				( attribute "PN" "D35"
					( Origin gPackager )
				)
				( objectStatus "U7C1.D35" )
			)
			( pin "@baseboard_fab2_lib.baseboard_fab2(sch_1):page212_i146:a"
				( attribute "PN" "1"
					( Origin gPackager )
				)
				( objectStatus "C3N38.1" )
			)
			( pin "@baseboard_fab2_lib.baseboard_fab2(sch_1):page212_i146:b"
				( attribute "PN" "2"
					( Origin gPackager )
				)
				( objectStatus "C3N38.2" )
			)
			( pin "@baseboard_fab2_lib.baseboard_fab2(sch_1):page114_i47:a"
				( attribute "PN" "1"
					( Origin gPackager )
				)
				( objectStatus "C7C5.1" )
			)
			( pin "@baseboard_fab2_lib.baseboard_fab2(sch_1):page114_i47:b"
				( attribute "PN" "2"
					( Origin gPackager )
				)
				( objectStatus "C7C5.2" )
			)
			( pin "@baseboard_fab2_lib.baseboard_fab2(sch_1):page114_i48:a"
				( attribute "PN" "1"
					( Origin gPackager )
				)
				( objectStatus "R7C1.1" )
			)
			( pin "@baseboard_fab2_lib.baseboard_fab2(sch_1):page114_i48:b"
				( attribute "PN" "2"
					( Origin gPackager )
				)
				( objectStatus "R7C1.2" )
			)
			( pin "@baseboard_fab2_lib.baseboard_fab2(sch_1):page114_i49:a"
				( attribute "PN" "1"
					( Origin gPackager )
				)
				( objectStatus "Y7C1.1" )
			)
			( pin "@baseboard_fab2_lib.baseboard_fab2(sch_1):page114_i49:b"
				( attribute "PN" "3"
					( Origin gPackager )
				)
				( objectStatus "Y7C1.3" )
			)
			( pin "@baseboard_fab2_lib.baseboard_fab2(sch_1):page114_i50:a"
				( attribute "PN" "1"
					( Origin gPackager )
				)
				( objectStatus "C7C4.1" )
			)
			( pin "@baseboard_fab2_lib.baseboard_fab2(sch_1):page114_i50:b"
				( attribute "PN" "2"
					( Origin gPackager )
				)
				( objectStatus "C7C4.2" )
			)
			( pin "@baseboard_fab2_lib.baseboard_fab2(sch_1):page114_i54:a"
				( attribute "PN" "1"
					( Origin gPackager )
				)
				( objectStatus "R7C6.1" )
			)
			( pin "@baseboard_fab2_lib.baseboard_fab2(sch_1):page114_i54:b"
				( attribute "PN" "2"
					( Origin gPackager )
				)
				( objectStatus "R7C6.2" )
			)
			( pin "@baseboard_fab2_lib.baseboard_fab2(sch_1):page114_i55:a"
				( attribute "PN" "1"
					( Origin gPackager )
				)
				( objectStatus "Y7C2.1" )
			)
			( pin "@baseboard_fab2_lib.baseboard_fab2(sch_1):page114_i55:b"
				( attribute "PN" "2"
					( Origin gPackager )
				)
				( objectStatus "Y7C2.2" )
			)
			( pin "@baseboard_fab2_lib.baseboard_fab2(sch_1):page212_i145:a"
				( attribute "PN" "1"
					( Origin gPackager )
				)
				( objectStatus "C3N26.1" )
			)
			( pin "@baseboard_fab2_lib.baseboard_fab2(sch_1):page212_i145:b"
				( attribute "PN" "2"
					( Origin gPackager )
				)
				( objectStatus "C3N26.2" )
			)
			( pin "@baseboard_fab2_lib.baseboard_fab2(sch_1):page114_i110:a"
				( attribute "PN" "1"
					( Origin gPackager )
				)
				( objectStatus "R8B20.1" )
			)
			( pin "@baseboard_fab2_lib.baseboard_fab2(sch_1):page114_i110:b"
				( attribute "PN" "2"
					( Origin gPackager )
				)
				( objectStatus "R8B20.2" )
			)
			( pin "@baseboard_fab2_lib.baseboard_fab2(sch_1):page114_i124:a"
				( attribute "PN" "1"
					( Origin gPackager )
				)
				( objectStatus "R8B21.1" )
			)
			( pin "@baseboard_fab2_lib.baseboard_fab2(sch_1):page114_i124:b"
				( attribute "PN" "2"
					( Origin gPackager )
				)
				( objectStatus "R8B21.2" )
			)
			( pin "@baseboard_fab2_lib.baseboard_fab2(sch_1):page114_i149:a"
				( attribute "PN" "1"
					( Origin gPackager )
				)
				( objectStatus "R3N1.1" )
			)
			( pin "@baseboard_fab2_lib.baseboard_fab2(sch_1):page114_i149:b"
				( attribute "PN" "2"
					( Origin gPackager )
				)
				( objectStatus "R3N1.2" )
			)
			( pin "@baseboard_fab2_lib.baseboard_fab2(sch_1):page115_i74:rsvd(55)"
				( attribute "PN" "BN68"
					( Origin gPackager )
				)
				( objectStatus "U7C1.BN68" )
			)
			( pin "@baseboard_fab2_lib.baseboard_fab2(sch_1):page115_i74:usb2_comp"
				( attribute "PN" "BN70"
					( Origin gPackager )
				)
				( objectStatus "U7C1.BN70" )
			)
			( pin "@baseboard_fab2_lib.baseboard_fab2(sch_1):page115_i74:usb2_vbus"
				( attribute "PN" "BR67"
					( Origin gPackager )
				)
				( objectStatus "U7C1.BR67" )
			)
			( pin "@baseboard_fab2_lib.baseboard_fab2(sch_1):page115_i74:usb2n_1"
				( attribute "PN" "BY60"
					( Origin gPackager )
				)
				( objectStatus "U7C1.BY60" )
			)
			( pin "@baseboard_fab2_lib.baseboard_fab2(sch_1):page115_i74:usb2n_2"
				( attribute "PN" "CA61"
					( Origin gPackager )
				)
				( objectStatus "U7C1.CA61" )
			)
			( pin "@baseboard_fab2_lib.baseboard_fab2(sch_1):page115_i74:usb2n_3"
				( attribute "PN" "CA59"
					( Origin gPackager )
				)
				( objectStatus "U7C1.CA59" )
			)
			( pin "@baseboard_fab2_lib.baseboard_fab2(sch_1):page115_i74:usb2n_4"
				( attribute "PN" "BY62"
					( Origin gPackager )
				)
				( objectStatus "U7C1.BY62" )
			)
			( pin "@baseboard_fab2_lib.baseboard_fab2(sch_1):page115_i74:usb2n_5"
				( attribute "PN" "BY58"
					( Origin gPackager )
				)
				( objectStatus "U7C1.BY58" )
			)
			( pin "@baseboard_fab2_lib.baseboard_fab2(sch_1):page115_i74:usb2n_6"
				( attribute "PN" "CA63"
					( Origin gPackager )
				)
				( objectStatus "U7C1.CA63" )
			)
			( pin "@baseboard_fab2_lib.baseboard_fab2(sch_1):page115_i74:usb2n_7"
				( attribute "PN" "CA57"
					( Origin gPackager )
				)
				( objectStatus "U7C1.CA57" )
			)
			( pin "@baseboard_fab2_lib.baseboard_fab2(sch_1):page115_i74:usb2n_8"
				( attribute "PN" "BY64"
					( Origin gPackager )
				)
				( objectStatus "U7C1.BY64" )
			)
			( pin "@baseboard_fab2_lib.baseboard_fab2(sch_1):page115_i74:usb2n_9"
				( attribute "PN" "BY55"
					( Origin gPackager )
				)
				( objectStatus "U7C1.BY55" )
			)
			( pin "@baseboard_fab2_lib.baseboard_fab2(sch_1):page115_i74:usb2n_10"
				( attribute "PN" "BW65"
					( Origin gPackager )
				)
				( objectStatus "U7C1.BW65" )
			)
			( pin "@baseboard_fab2_lib.baseboard_fab2(sch_1):page115_i74:usb2n_11"
				( attribute "PN" "CA54"
					( Origin gPackager )
				)
				( objectStatus "U7C1.CA54" )
			)
			( pin "@baseboard_fab2_lib.baseboard_fab2(sch_1):page115_i74:usb2n_12"
				( attribute "PN" "BW67"
					( Origin gPackager )
				)
				( objectStatus "U7C1.BW67" )
			)
			( pin "@baseboard_fab2_lib.baseboard_fab2(sch_1):page115_i74:usb2n_13"
				( attribute "PN" "BY53"
					( Origin gPackager )
				)
				( objectStatus "U7C1.BY53" )
			)
			( pin "@baseboard_fab2_lib.baseboard_fab2(sch_1):page115_i74:usb2n_14"
				( attribute "PN" "BW68"
					( Origin gPackager )
				)
				( objectStatus "U7C1.BW68" )
			)
			( pin "@baseboard_fab2_lib.baseboard_fab2(sch_1):page115_i74:usb2p_1"
				( attribute "PN" "BV60"
					( Origin gPackager )
				)
				( objectStatus "U7C1.BV60" )
			)
			( pin "@baseboard_fab2_lib.baseboard_fab2(sch_1):page115_i74:usb2p_2"
				( attribute "PN" "BW61"
					( Origin gPackager )
				)
				( objectStatus "U7C1.BW61" )
			)
			( pin "@baseboard_fab2_lib.baseboard_fab2(sch_1):page115_i74:usb2p_3"
				( attribute "PN" "BW59"
					( Origin gPackager )
				)
				( objectStatus "U7C1.BW59" )
			)
			( pin "@baseboard_fab2_lib.baseboard_fab2(sch_1):page115_i74:usb2p_4"
				( attribute "PN" "BV62"
					( Origin gPackager )
				)
				( objectStatus "U7C1.BV62" )
			)
			( pin "@baseboard_fab2_lib.baseboard_fab2(sch_1):page115_i74:usb2p_5"
				( attribute "PN" "BV58"
					( Origin gPackager )
				)
				( objectStatus "U7C1.BV58" )
			)
			( pin "@baseboard_fab2_lib.baseboard_fab2(sch_1):page115_i74:usb2p_6"
				( attribute "PN" "BW63"
					( Origin gPackager )
				)
				( objectStatus "U7C1.BW63" )
			)
			( pin "@baseboard_fab2_lib.baseboard_fab2(sch_1):page115_i74:usb2p_7"
				( attribute "PN" "BW57"
					( Origin gPackager )
				)
				( objectStatus "U7C1.BW57" )
			)
			( pin "@baseboard_fab2_lib.baseboard_fab2(sch_1):page115_i74:usb2p_8"
				( attribute "PN" "BV64"
					( Origin gPackager )
				)
				( objectStatus "U7C1.BV64" )
			)
			( pin "@baseboard_fab2_lib.baseboard_fab2(sch_1):page115_i74:usb2p_9"
				( attribute "PN" "BV55"
					( Origin gPackager )
				)
				( objectStatus "U7C1.BV55" )
			)
			( pin "@baseboard_fab2_lib.baseboard_fab2(sch_1):page115_i74:usb2p_10"
				( attribute "PN" "BU65"
					( Origin gPackager )
				)
				( objectStatus "U7C1.BU65" )
			)
			( pin "@baseboard_fab2_lib.baseboard_fab2(sch_1):page115_i74:usb2p_11"
				( attribute "PN" "BW54"
					( Origin gPackager )
				)
				( objectStatus "U7C1.BW54" )
			)
			( pin "@baseboard_fab2_lib.baseboard_fab2(sch_1):page115_i74:usb2p_12"
				( attribute "PN" "BV66"
					( Origin gPackager )
				)
				( objectStatus "U7C1.BV66" )
			)
			( pin "@baseboard_fab2_lib.baseboard_fab2(sch_1):page115_i74:usb2p_13"
				( attribute "PN" "BV53"
					( Origin gPackager )
				)
				( objectStatus "U7C1.BV53" )
			)
			( pin "@baseboard_fab2_lib.baseboard_fab2(sch_1):page115_i74:usb2p_14"
				( attribute "PN" "BU67"
					( Origin gPackager )
				)
				( objectStatus "U7C1.BU67" )
			)
			( pin "@baseboard_fab2_lib.baseboard_fab2(sch_1):page115_i74:usb3_1_rxn"
				( attribute "PN" "BK71"
					( Origin gPackager )
				)
				( objectStatus "U7C1.BK71" )
			)
			( pin "@baseboard_fab2_lib.baseboard_fab2(sch_1):page115_i74:usb3_1_rxp"
				( attribute "PN" "BK69"
					( Origin gPackager )
				)
				( objectStatus "U7C1.BK69" )
			)
			( pin "@baseboard_fab2_lib.baseboard_fab2(sch_1):page115_i74:usb3_1_txn"
				( attribute "PN" "BL52"
					( Origin gPackager )
				)
				( objectStatus "U7C1.BL52" )
			)
			( pin "@baseboard_fab2_lib.baseboard_fab2(sch_1):page115_i74:usb3_1_txp"
				( attribute "PN" "BK54"
					( Origin gPackager )
				)
				( objectStatus "U7C1.BK54" )
			)
			( pin "@baseboard_fab2_lib.baseboard_fab2(sch_1):page115_i74:usb3_2_rxn"
				( attribute "PN" "BJ72"
					( Origin gPackager )
				)
				( objectStatus "U7C1.BJ72" )
			)
			( pin "@baseboard_fab2_lib.baseboard_fab2(sch_1):page115_i74:usb3_2_rxp"
				( attribute "PN" "BJ70"
					( Origin gPackager )
				)
				( objectStatus "U7C1.BJ70" )
			)
			( pin "@baseboard_fab2_lib.baseboard_fab2(sch_1):page115_i74:usb3_2_txn"
				( attribute "PN" "BL56"
					( Origin gPackager )
				)
				( objectStatus "U7C1.BL56" )
			)
			( pin "@baseboard_fab2_lib.baseboard_fab2(sch_1):page115_i74:usb3_2_txp"
				( attribute "PN" "BJ56"
					( Origin gPackager )
				)
				( objectStatus "U7C1.BJ56" )
			)
			( pin "@baseboard_fab2_lib.baseboard_fab2(sch_1):page115_i74:usb3_3_rxn"
				( attribute "PN" "BH71"
					( Origin gPackager )
				)
				( objectStatus "U7C1.BH71" )
			)
			( pin "@baseboard_fab2_lib.baseboard_fab2(sch_1):page115_i74:usb3_3_rxp"
				( attribute "PN" "BH69"
					( Origin gPackager )
				)
				( objectStatus "U7C1.BH69" )
			)
			( pin "@baseboard_fab2_lib.baseboard_fab2(sch_1):page115_i74:usb3_3_txn"
				( attribute "PN" "BM54"
					( Origin gPackager )
				)
				( objectStatus "U7C1.BM54" )
			)
			( pin "@baseboard_fab2_lib.baseboard_fab2(sch_1):page115_i74:usb3_3_txp"
				( attribute "PN" "BN56"
					( Origin gPackager )
				)
				( objectStatus "U7C1.BN56" )
			)
			( pin "@baseboard_fab2_lib.baseboard_fab2(sch_1):page115_i74:usb3_4_rxn"
				( attribute "PN" "BF72"
					( Origin gPackager )
				)
				( objectStatus "U7C1.BF72" )
			)
			( pin "@baseboard_fab2_lib.baseboard_fab2(sch_1):page115_i74:usb3_4_rxp"
				( attribute "PN" "BF70"
					( Origin gPackager )
				)
				( objectStatus "U7C1.BF70" )
			)
			( pin "@baseboard_fab2_lib.baseboard_fab2(sch_1):page115_i74:usb3_4_txn"
				( attribute "PN" "BH58"
					( Origin gPackager )
				)
				( objectStatus "U7C1.BH58" )
			)
			( pin "@baseboard_fab2_lib.baseboard_fab2(sch_1):page115_i74:usb3_4_txp"
				( attribute "PN" "BG56"
					( Origin gPackager )
				)
				( objectStatus "U7C1.BG56" )
			)
			( pin "@baseboard_fab2_lib.baseboard_fab2(sch_1):page115_i74:usb3_5_rxn"
				( attribute "PN" "BE71"
					( Origin gPackager )
				)
				( objectStatus "U7C1.BE71" )
			)
			( pin "@baseboard_fab2_lib.baseboard_fab2(sch_1):page115_i74:usb3_5_rxp"
				( attribute "PN" "BE69"
					( Origin gPackager )
				)
				( objectStatus "U7C1.BE69" )
			)
			( pin "@baseboard_fab2_lib.baseboard_fab2(sch_1):page115_i74:usb3_5_txn"
				( attribute "PN" "BK58"
					( Origin gPackager )
				)
				( objectStatus "U7C1.BK58" )
			)
			( pin "@baseboard_fab2_lib.baseboard_fab2(sch_1):page115_i74:usb3_5_txp"
				( attribute "PN" "BJ59"
					( Origin gPackager )
				)
				( objectStatus "U7C1.BJ59" )
			)
			( pin "@baseboard_fab2_lib.baseboard_fab2(sch_1):page115_i74:usb3_6_rxn"
				( attribute "PN" "BD72"
					( Origin gPackager )
				)
				( objectStatus "U7C1.BD72" )
			)
			( pin "@baseboard_fab2_lib.baseboard_fab2(sch_1):page115_i74:usb3_6_rxp"
				( attribute "PN" "BD70"
					( Origin gPackager )
				)
				( objectStatus "U7C1.BD70" )
			)
			( pin "@baseboard_fab2_lib.baseboard_fab2(sch_1):page115_i74:usb3_6_txn"
				( attribute "PN" "BL59"
					( Origin gPackager )
				)
				( objectStatus "U7C1.BL59" )
			)
			( pin "@baseboard_fab2_lib.baseboard_fab2(sch_1):page115_i74:usb3_6_txp"
				( attribute "PN" "BM61"
					( Origin gPackager )
				)
				( objectStatus "U7C1.BM61" )
			)
			( pin "@baseboard_fab2_lib.baseboard_fab2(sch_1):page115_i90:a"
				( attribute "PN" "1"
					( Origin gPackager )
				)
				( objectStatus "R8B9.1" )
			)
			( pin "@baseboard_fab2_lib.baseboard_fab2(sch_1):page115_i90:b"
				( attribute "PN" "2"
					( Origin gPackager )
				)
				( objectStatus "R8B9.2" )
			)
			( pin "@baseboard_fab2_lib.baseboard_fab2(sch_1):page115_i114:a"
				( attribute "PN" "1"
					( Origin gPackager )
				)
				( objectStatus "R8B32.1" )
			)
			( pin "@baseboard_fab2_lib.baseboard_fab2(sch_1):page115_i114:b"
				( attribute "PN" "2"
					( Origin gPackager )
				)
				( objectStatus "R8B32.2" )
			)
			( pin "@baseboard_fab2_lib.baseboard_fab2(sch_1):page116_i108:a"
				( attribute "PN" "1"
					( Origin gPackager )
				)
				( objectStatus "R3M11.1" )
			)
			( pin "@baseboard_fab2_lib.baseboard_fab2(sch_1):page116_i108:b"
				( attribute "PN" "2"
					( Origin gPackager )
				)
				( objectStatus "R3M11.2" )
			)
			( pin "@baseboard_fab2_lib.baseboard_fab2(sch_1):page116_i181:a"
				( attribute "PN" "1"
					( Origin gPackager )
				)
				( objectStatus "R3M12.1" )
			)
			( pin "@baseboard_fab2_lib.baseboard_fab2(sch_1):page116_i181:b"
				( attribute "PN" "2"
					( Origin gPackager )
				)
				( objectStatus "R3M12.2" )
			)
			( pin "@baseboard_fab2_lib.baseboard_fab2(sch_1):page145_i159:a"
				( attribute "PN" "1"
					( Origin gPackager )
				)
				( objectStatus "C25W21.1" )
			)
			( pin "@baseboard_fab2_lib.baseboard_fab2(sch_1):page145_i159:b"
				( attribute "PN" "2"
					( Origin gPackager )
				)
				( objectStatus "C25W21.2" )
			)
			( pin "@baseboard_fab2_lib.baseboard_fab2(sch_1):page145_i158:a"
				( attribute "PN" "1"
					( Origin gPackager )
				)
				( objectStatus "C25W20.1" )
			)
			( pin "@baseboard_fab2_lib.baseboard_fab2(sch_1):page145_i158:b"
				( attribute "PN" "2"
					( Origin gPackager )
				)
				( objectStatus "C25W20.2" )
			)
			( pin "@baseboard_fab2_lib.baseboard_fab2(sch_1):page116_i220:extclkn"
				( attribute "PN" "D66"
					( Origin gPackager )
				)
				( objectStatus "U7C1.D66" )
			)
			( pin "@baseboard_fab2_lib.baseboard_fab2(sch_1):page116_i220:extclkp"
				( attribute "PN" "E67"
					( Origin gPackager )
				)
				( objectStatus "U7C1.E67" )
			)
			( pin "@baseboard_fab2_lib.baseboard_fab2(sch_1):page116_i220:pcie4_gbe_rxn"
				( attribute "PN" "AN70"
					( Origin gPackager )
				)
				( objectStatus "U7C1.AN70" )
			)
			( pin "@baseboard_fab2_lib.baseboard_fab2(sch_1):page116_i220:pcie4_gbe_rxp"
				( attribute "PN" "AN72"
					( Origin gPackager )
				)
				( objectStatus "U7C1.AN72" )
			)
			( pin "@baseboard_fab2_lib.baseboard_fab2(sch_1):page116_i220:pcie4_gbe_txn"
				( attribute "PN" "BG66"
					( Origin gPackager )
				)
				( objectStatus "U7C1.BG66" )
			)
			( pin "@baseboard_fab2_lib.baseboard_fab2(sch_1):page116_i220:pcie4_gbe_txp"
				( attribute "PN" "BJ66"
					( Origin gPackager )
				)
				( objectStatus "U7C1.BJ66" )
			)
			( pin "@baseboard_fab2_lib.baseboard_fab2(sch_1):page116_i220:pcie5_gbe_rxn"
				( attribute "PN" "AM69"
					( Origin gPackager )
				)
				( objectStatus "U7C1.AM69" )
			)
			( pin "@baseboard_fab2_lib.baseboard_fab2(sch_1):page116_i220:pcie5_gbe_rxp"
				( attribute "PN" "AM71"
					( Origin gPackager )
				)
				( objectStatus "U7C1.AM71" )
			)
			( pin "@baseboard_fab2_lib.baseboard_fab2(sch_1):page116_i220:pcie5_gbe_txn"
				( attribute "PN" "BH65"
					( Origin gPackager )
				)
				( objectStatus "U7C1.BH65" )
			)
			( pin "@baseboard_fab2_lib.baseboard_fab2(sch_1):page116_i220:pcie5_gbe_txp"
				( attribute "PN" "BJ63"
					( Origin gPackager )
				)
				( objectStatus "U7C1.BJ63" )
			)
			( pin "@baseboard_fab2_lib.baseboard_fab2(sch_1):page116_i220:pcie6_ssata0_rxn"
				( attribute "PN" "BB63"
					( Origin gPackager )
				)
				( objectStatus "U7C1.BB63" )
			)
			( pin "@baseboard_fab2_lib.baseboard_fab2(sch_1):page116_i220:pcie6_ssata0_rxp"
				( attribute "PN" "BD61"
					( Origin gPackager )
				)
				( objectStatus "U7C1.BD61" )
			)
			( pin "@baseboard_fab2_lib.baseboard_fab2(sch_1):page116_i220:pcie6_ssata0_txn"
				( attribute "PN" "AJ70"
					( Origin gPackager )
				)
				( objectStatus "U7C1.AJ70" )
			)
			( pin "@baseboard_fab2_lib.baseboard_fab2(sch_1):page116_i220:pcie6_ssata0_txp"
				( attribute "PN" "AJ72"
					( Origin gPackager )
				)
				( objectStatus "U7C1.AJ72" )
			)
			( pin "@baseboard_fab2_lib.baseboard_fab2(sch_1):page116_i220:pcie7_ssata1_rxn"
				( attribute "PN" "AY59"
					( Origin gPackager )
				)
				( objectStatus "U7C1.AY59" )
			)
			( pin "@baseboard_fab2_lib.baseboard_fab2(sch_1):page116_i220:pcie7_ssata1_rxp"
				( attribute "PN" "BA61"
					( Origin gPackager )
				)
				( objectStatus "U7C1.BA61" )
			)
			( pin "@baseboard_fab2_lib.baseboard_fab2(sch_1):page116_i220:pcie7_ssata1_txn"
				( attribute "PN" "AH69"
					( Origin gPackager )
				)
				( objectStatus "U7C1.AH69" )
			)
			( pin "@baseboard_fab2_lib.baseboard_fab2(sch_1):page116_i220:pcie7_ssata1_txp"
				( attribute "PN" "AH71"
					( Origin gPackager )
				)
				( objectStatus "U7C1.AH71" )
			)
			( pin "@baseboard_fab2_lib.baseboard_fab2(sch_1):page116_i220:pcie8_ssata2_gbe_rxn"
				( attribute "PN" "BA65"
					( Origin gPackager )
				)
				( objectStatus "U7C1.BA65" )
			)
			( pin "@baseboard_fab2_lib.baseboard_fab2(sch_1):page116_i220:pcie8_ssata2_gbe_rxp"
				( attribute "PN" "BD65"
					( Origin gPackager )
				)
				( objectStatus "U7C1.BD65" )
			)
			( pin "@baseboard_fab2_lib.baseboard_fab2(sch_1):page116_i220:pcie8_ssata2_gbe_txn"
				( attribute "PN" "AF70"
					( Origin gPackager )
				)
				( objectStatus "U7C1.AF70" )
			)
			( pin "@baseboard_fab2_lib.baseboard_fab2(sch_1):page116_i220:pcie8_ssata2_gbe_txp"
				( attribute "PN" "AF72"
					( Origin gPackager )
				)
				( objectStatus "U7C1.AF72" )
			)
			( pin "@baseboard_fab2_lib.baseboard_fab2(sch_1):page116_i220:pcie9_ssata3_rxn"
				( attribute "PN" "AW65"
					( Origin gPackager )
				)
				( objectStatus "U7C1.AW65" )
			)
			( pin "@baseboard_fab2_lib.baseboard_fab2(sch_1):page116_i220:pcie9_ssata3_rxp"
				( attribute "PN" "AY66"
					( Origin gPackager )
				)
				( objectStatus "U7C1.AY66" )
			)
			( pin "@baseboard_fab2_lib.baseboard_fab2(sch_1):page116_i220:pcie9_ssata3_txn"
				( attribute "PN" "AE69"
					( Origin gPackager )
				)
				( objectStatus "U7C1.AE69" )
			)
			( pin "@baseboard_fab2_lib.baseboard_fab2(sch_1):page116_i220:pcie9_ssata3_txp"
				( attribute "PN" "AE71"
					( Origin gPackager )
				)
				( objectStatus "U7C1.AE71" )
			)
			( pin "@baseboard_fab2_lib.baseboard_fab2(sch_1):page116_i220:pcie10_ssata4_rxn"
				( attribute "PN" "AV63"
					( Origin gPackager )
				)
				( objectStatus "U7C1.AV63" )
			)
			( pin "@baseboard_fab2_lib.baseboard_fab2(sch_1):page116_i220:pcie10_ssata4_rxp"
				( attribute "PN" "AU65"
					( Origin gPackager )
				)
				( objectStatus "U7C1.AU65" )
			)
			( pin "@baseboard_fab2_lib.baseboard_fab2(sch_1):page116_i220:pcie10_ssata4_txn"
				( attribute "PN" "AD70"
					( Origin gPackager )
				)
				( objectStatus "U7C1.AD70" )
			)
			( pin "@baseboard_fab2_lib.baseboard_fab2(sch_1):page116_i220:pcie10_ssata4_txp"
				( attribute "PN" "AD72"
					( Origin gPackager )
				)
				( objectStatus "U7C1.AD72" )
			)
			( pin "@baseboard_fab2_lib.baseboard_fab2(sch_1):page116_i220:pcie11_ssata5_gbe_rxn"
				( attribute "PN" "AT66"
					( Origin gPackager )
				)
				( objectStatus "U7C1.AT66" )
			)
			( pin "@baseboard_fab2_lib.baseboard_fab2(sch_1):page116_i220:pcie11_ssata5_gbe_rxp"
				( attribute "PN" "AV66"
					( Origin gPackager )
				)
				( objectStatus "U7C1.AV66" )
			)
			( pin "@baseboard_fab2_lib.baseboard_fab2(sch_1):page116_i220:pcie11_ssata5_gbe_txn"
				( attribute "PN" "AC69"
					( Origin gPackager )
				)
				( objectStatus "U7C1.AC69" )
			)
			( pin "@baseboard_fab2_lib.baseboard_fab2(sch_1):page116_i220:pcie11_ssata5_gbe_txp"
				( attribute "PN" "AC71"
					( Origin gPackager )
				)
				( objectStatus "U7C1.AC71" )
			)
			( pin "@baseboard_fab2_lib.baseboard_fab2(sch_1):page116_i220:pcie12_up0_sata0_rxn"
				( attribute "PN" "AR61"
					( Origin gPackager )
				)
				( objectStatus "U7C1.AR61" )
			)
			( pin "@baseboard_fab2_lib.baseboard_fab2(sch_1):page116_i220:pcie12_up0_sata0_rxp"
				( attribute "PN" "AT63"
					( Origin gPackager )
				)
				( objectStatus "U7C1.AT63" )
			)
			( pin "@baseboard_fab2_lib.baseboard_fab2(sch_1):page116_i220:pcie12_up0_sata0_txn"
				( attribute "PN" "W69"
					( Origin gPackager )
				)
				( objectStatus "U7C1.W69" )
			)
			( pin "@baseboard_fab2_lib.baseboard_fab2(sch_1):page116_i220:pcie12_up0_sata0_txp"
				( attribute "PN" "W71"
					( Origin gPackager )
				)
				( objectStatus "U7C1.W71" )
			)
			( pin "@baseboard_fab2_lib.baseboard_fab2(sch_1):page116_i220:pcie13_up1_sata1_rxn"
				( attribute "PN" "AL66"
					( Origin gPackager )
				)
				( objectStatus "U7C1.AL66" )
			)
			( pin "@baseboard_fab2_lib.baseboard_fab2(sch_1):page116_i220:pcie13_up1_sata1_rxp"
				( attribute "PN" "AN65"
					( Origin gPackager )
				)
				( objectStatus "U7C1.AN65" )
			)
			( pin "@baseboard_fab2_lib.baseboard_fab2(sch_1):page116_i220:pcie13_up1_sata1_txn"
				( attribute "PN" "V70"
					( Origin gPackager )
				)
				( objectStatus "U7C1.V70" )
			)
			( pin "@baseboard_fab2_lib.baseboard_fab2(sch_1):page116_i220:pcie13_up1_sata1_txp"
				( attribute "PN" "V72"
					( Origin gPackager )
				)
				( objectStatus "U7C1.V72" )
			)
			( pin "@baseboard_fab2_lib.baseboard_fab2(sch_1):page116_i220:pcie14_up2_sata2_rxn"
				( attribute "PN" "AK65"
					( Origin gPackager )
				)
				( objectStatus "U7C1.AK65" )
			)
			( pin "@baseboard_fab2_lib.baseboard_fab2(sch_1):page116_i220:pcie14_up2_sata2_rxp"
				( attribute "PN" "AJ63"
					( Origin gPackager )
				)
				( objectStatus "U7C1.AJ63" )
			)
			( pin "@baseboard_fab2_lib.baseboard_fab2(sch_1):page116_i220:pcie14_up2_sata2_txn"
				( attribute "PN" "T69"
					( Origin gPackager )
				)
				( objectStatus "U7C1.T69" )
			)
			( pin "@baseboard_fab2_lib.baseboard_fab2(sch_1):page116_i220:pcie14_up2_sata2_txp"
				( attribute "PN" "T71"
					( Origin gPackager )
				)
				( objectStatus "U7C1.T71" )
			)
			( pin "@baseboard_fab2_lib.baseboard_fab2(sch_1):page116_i220:pcie15_up3_sata3_rxn"
				( attribute "PN" "AP63"
					( Origin gPackager )
				)
				( objectStatus "U7C1.AP63" )
			)
			( pin "@baseboard_fab2_lib.baseboard_fab2(sch_1):page116_i220:pcie15_up3_sata3_rxp"
				( attribute "PN" "AL63"
					( Origin gPackager )
				)
				( objectStatus "U7C1.AL63" )
			)
			( pin "@baseboard_fab2_lib.baseboard_fab2(sch_1):page116_i220:pcie15_up3_sata3_txn"
				( attribute "PN" "R70"
					( Origin gPackager )
				)
				( objectStatus "U7C1.R70" )
			)
			( pin "@baseboard_fab2_lib.baseboard_fab2(sch_1):page116_i220:pcie15_up3_sata3_txp"
				( attribute "PN" "R72"
					( Origin gPackager )
				)
				( objectStatus "U7C1.R72" )
			)
			( pin "@baseboard_fab2_lib.baseboard_fab2(sch_1):page116_i220:pcie16_up4_sata4_rxn"
				( attribute "PN" "AF65"
					( Origin gPackager )
				)
				( objectStatus "U7C1.AF65" )
			)
			( pin "@baseboard_fab2_lib.baseboard_fab2(sch_1):page116_i220:pcie16_up4_sata4_rxp"
				( attribute "PN" "AH65"
					( Origin gPackager )
				)
				( objectStatus "U7C1.AH65" )
			)
			( pin "@baseboard_fab2_lib.baseboard_fab2(sch_1):page116_i220:pcie16_up4_sata4_txn"
				( attribute "PN" "P69"
					( Origin gPackager )
				)
				( objectStatus "U7C1.P69" )
			)
			( pin "@baseboard_fab2_lib.baseboard_fab2(sch_1):page116_i220:pcie16_up4_sata4_txp"
				( attribute "PN" "P71"
					( Origin gPackager )
				)
				( objectStatus "U7C1.P71" )
			)
			( pin "@baseboard_fab2_lib.baseboard_fab2(sch_1):page116_i220:pcie17_up5_sata5_rxn"
				( attribute "PN" "AH61"
					( Origin gPackager )
				)
				( objectStatus "U7C1.AH61" )
			)
			( pin "@baseboard_fab2_lib.baseboard_fab2(sch_1):page116_i220:pcie17_up5_sata5_rxp"
				( attribute "PN" "AG63"
					( Origin gPackager )
				)
				( objectStatus "U7C1.AG63" )
			)
			( pin "@baseboard_fab2_lib.baseboard_fab2(sch_1):page116_i220:pcie17_up5_sata5_txn"
				( attribute "PN" "N70"
					( Origin gPackager )
				)
				( objectStatus "U7C1.N70" )
			)
			( pin "@baseboard_fab2_lib.baseboard_fab2(sch_1):page116_i220:pcie17_up5_sata5_txp"
				( attribute "PN" "N72"
					( Origin gPackager )
				)
				( objectStatus "U7C1.N72" )
			)
			( pin "@baseboard_fab2_lib.baseboard_fab2(sch_1):page116_i220:pcie18_up6_sata6_rxn"
				( attribute "PN" "AP59"
					( Origin gPackager )
				)
				( objectStatus "U7C1.AP59" )
			)
			( pin "@baseboard_fab2_lib.baseboard_fab2(sch_1):page116_i220:pcie18_up6_sata6_rxp"
				( attribute "PN" "AN61"
					( Origin gPackager )
				)
				( objectStatus "U7C1.AN61" )
			)
			( pin "@baseboard_fab2_lib.baseboard_fab2(sch_1):page116_i220:pcie18_up6_sata6_txn"
				( attribute "PN" "M69"
					( Origin gPackager )
				)
				( objectStatus "U7C1.M69" )
			)
			( pin "@baseboard_fab2_lib.baseboard_fab2(sch_1):page116_i220:pcie18_up6_sata6_txp"
				( attribute "PN" "M71"
					( Origin gPackager )
				)
				( objectStatus "U7C1.M71" )
			)
			( pin "@baseboard_fab2_lib.baseboard_fab2(sch_1):page116_i220:pcie19_up7_sata7_rxn"
				( attribute "PN" "AA61"
					( Origin gPackager )
				)
				( objectStatus "U7C1.AA61" )
			)
			( pin "@baseboard_fab2_lib.baseboard_fab2(sch_1):page116_i220:pcie19_up7_sata7_rxp"
				( attribute "PN" "AD61"
					( Origin gPackager )
				)
				( objectStatus "U7C1.AD61" )
			)
			( pin "@baseboard_fab2_lib.baseboard_fab2(sch_1):page116_i220:pcie19_up7_sata7_txn"
				( attribute "PN" "L70"
					( Origin gPackager )
				)
				( objectStatus "U7C1.L70" )
			)
			( pin "@baseboard_fab2_lib.baseboard_fab2(sch_1):page116_i220:pcie19_up7_sata7_txp"
				( attribute "PN" "L72"
					( Origin gPackager )
				)
				( objectStatus "U7C1.L72" )
			)
			( pin "@baseboard_fab2_lib.baseboard_fab2(sch_1):page116_i220:pcie_rcompn"
				( attribute "PN" "BD58"
					( Origin gPackager )
				)
				( objectStatus "U7C1.BD58" )
			)
			( pin "@baseboard_fab2_lib.baseboard_fab2(sch_1):page116_i220:pcie_rcompp"
				( attribute "PN" "BB56"
					( Origin gPackager )
				)
				( objectStatus "U7C1.BB56" )
			)
			( pin "@baseboard_fab2_lib.baseboard_fab2(sch_1):page116_i220:pcieup_rcompn"
				( attribute "PN" "AF58"
					( Origin gPackager )
				)
				( objectStatus "U7C1.AF58" )
			)
			( pin "@baseboard_fab2_lib.baseboard_fab2(sch_1):page116_i220:pcieup_rcompp"
				( attribute "PN" "AH58"
					( Origin gPackager )
				)
				( objectStatus "U7C1.AH58" )
			)
			( pin "@baseboard_fab2_lib.baseboard_fab2(sch_1):page116_i220:rsvd(47)"
				( attribute "PN" "AP69"
					( Origin gPackager )
				)
				( objectStatus "U7C1.AP69" )
			)
			( pin "@baseboard_fab2_lib.baseboard_fab2(sch_1):page116_i220:rsvd(48)"
				( attribute "PN" "AP71"
					( Origin gPackager )
				)
				( objectStatus "U7C1.AP71" )
			)
			( pin "@baseboard_fab2_lib.baseboard_fab2(sch_1):page116_i220:rsvd(49)"
				( attribute "PN" "G67"
					( Origin gPackager )
				)
				( objectStatus "U7C1.G67" )
			)
			( pin "@baseboard_fab2_lib.baseboard_fab2(sch_1):page116_i220:rsvd(50)"
				( attribute "PN" "H69"
					( Origin gPackager )
				)
				( objectStatus "U7C1.H69" )
			)
			( pin "@baseboard_fab2_lib.baseboard_fab2(sch_1):page116_i220:rsvd(51)"
				( attribute "PN" "AA69"
					( Origin gPackager )
				)
				( objectStatus "U7C1.AA69" )
			)
			( pin "@baseboard_fab2_lib.baseboard_fab2(sch_1):page116_i220:rsvd(52)"
				( attribute "PN" "AA71"
					( Origin gPackager )
				)
				( objectStatus "U7C1.AA71" )
			)
			( pin "@baseboard_fab2_lib.baseboard_fab2(sch_1):page116_i220:usb3_7_pcie0_rxn"
				( attribute "PN" "BA71"
					( Origin gPackager )
				)
				( objectStatus "U7C1.BA71" )
			)
			( pin "@baseboard_fab2_lib.baseboard_fab2(sch_1):page116_i220:usb3_7_pcie0_rxp"
				( attribute "PN" "BA69"
					( Origin gPackager )
				)
				( objectStatus "U7C1.BA69" )
			)
			( pin "@baseboard_fab2_lib.baseboard_fab2(sch_1):page116_i220:usb3_7_pcie0_txn"
				( attribute "PN" "BR61"
					( Origin gPackager )
				)
				( objectStatus "U7C1.BR61" )
			)
			( pin "@baseboard_fab2_lib.baseboard_fab2(sch_1):page116_i220:usb3_7_pcie0_txp"
				( attribute "PN" "BN63"
					( Origin gPackager )
				)
				( objectStatus "U7C1.BN63" )
			)
			( pin "@baseboard_fab2_lib.baseboard_fab2(sch_1):page116_i220:usb3_8_pcie1_rxn"
				( attribute "PN" "AY72"
					( Origin gPackager )
				)
				( objectStatus "U7C1.AY72" )
			)
			( pin "@baseboard_fab2_lib.baseboard_fab2(sch_1):page116_i220:usb3_8_pcie1_rxp"
				( attribute "PN" "AY70"
					( Origin gPackager )
				)
				( objectStatus "U7C1.AY70" )
			)
			( pin "@baseboard_fab2_lib.baseboard_fab2(sch_1):page116_i220:usb3_8_pcie1_txn"
				( attribute "PN" "BM65"
					( Origin gPackager )
				)
				( objectStatus "U7C1.BM65" )
			)
			( pin "@baseboard_fab2_lib.baseboard_fab2(sch_1):page116_i220:usb3_8_pcie1_txp"
				( attribute "PN" "BR65"
					( Origin gPackager )
				)
				( objectStatus "U7C1.BR65" )
			)
			( pin "@baseboard_fab2_lib.baseboard_fab2(sch_1):page116_i220:usb3_9_pcie2_rxn"
				( attribute "PN" "AW71"
					( Origin gPackager )
				)
				( objectStatus "U7C1.AW71" )
			)
			( pin "@baseboard_fab2_lib.baseboard_fab2(sch_1):page116_i220:usb3_9_pcie2_rxp"
				( attribute "PN" "AW69"
					( Origin gPackager )
				)
				( objectStatus "U7C1.AW69" )
			)
			( pin "@baseboard_fab2_lib.baseboard_fab2(sch_1):page116_i220:usb3_9_pcie2_txn"
				( attribute "PN" "BK65"
					( Origin gPackager )
				)
				( objectStatus "U7C1.BK65" )
			)
			( pin "@baseboard_fab2_lib.baseboard_fab2(sch_1):page116_i220:usb3_9_pcie2_txp"
				( attribute "PN" "BL66"
					( Origin gPackager )
				)
				( objectStatus "U7C1.BL66" )
			)
			( pin "@baseboard_fab2_lib.baseboard_fab2(sch_1):page116_i220:usb3_10_pcie3_gbe_rxn"
				( attribute "PN" "AV72"
					( Origin gPackager )
				)
				( objectStatus "U7C1.AV72" )
			)
			( pin "@baseboard_fab2_lib.baseboard_fab2(sch_1):page116_i220:usb3_10_pcie3_gbe_rxp"
				( attribute "PN" "AV70"
					( Origin gPackager )
				)
				( objectStatus "U7C1.AV70" )
			)
			( pin "@baseboard_fab2_lib.baseboard_fab2(sch_1):page116_i220:usb3_10_pcie3_gbe_txn"
				( attribute "PN" "BH61"
					( Origin gPackager )
				)
				( objectStatus "U7C1.BH61" )
			)
			( pin "@baseboard_fab2_lib.baseboard_fab2(sch_1):page116_i220:usb3_10_pcie3_gbe_txp"
				( attribute "PN" "BK61"
					( Origin gPackager )
				)
				( objectStatus "U7C1.BK61" )
			)
			( pin "@baseboard_fab2_lib.baseboard_fab2(sch_1):page116_i229:a"
				( attribute "PN" "1"
					( Origin gPackager )
				)
				( objectStatus "R7B8.1" )
			)
			( pin "@baseboard_fab2_lib.baseboard_fab2(sch_1):page116_i229:b"
				( attribute "PN" "2"
					( Origin gPackager )
				)
				( objectStatus "R7B8.2" )
			)
			( pin "@baseboard_fab2_lib.baseboard_fab2(sch_1):page116_i230:a"
				( attribute "PN" "1"
					( Origin gPackager )
				)
				( objectStatus "R7B7.1" )
			)
			( pin "@baseboard_fab2_lib.baseboard_fab2(sch_1):page116_i230:b"
				( attribute "PN" "2"
					( Origin gPackager )
				)
				( objectStatus "R7B7.2" )
			)
			( pin "@baseboard_fab2_lib.baseboard_fab2(sch_1):page116_i234:a"
				( attribute "PN" "1"
					( Origin gPackager )
				)
				( objectStatus "R3M9.1" )
			)
			( pin "@baseboard_fab2_lib.baseboard_fab2(sch_1):page116_i234:b"
				( attribute "PN" "2"
					( Origin gPackager )
				)
				( objectStatus "R3M9.2" )
			)
			( pin "@baseboard_fab2_lib.baseboard_fab2(sch_1):page116_i235:a"
				( attribute "PN" "1"
					( Origin gPackager )
				)
				( objectStatus "R3M8.1" )
			)
			( pin "@baseboard_fab2_lib.baseboard_fab2(sch_1):page116_i235:b"
				( attribute "PN" "2"
					( Origin gPackager )
				)
				( objectStatus "R3M8.2" )
			)
			( pin "@baseboard_fab2_lib.baseboard_fab2(sch_1):page117_i9:dmi_rxn(0)"
				( attribute "PN" "D42"
					( Origin gPackager )
				)
				( objectStatus "U7C1.D42" )
			)
			( pin "@baseboard_fab2_lib.baseboard_fab2(sch_1):page117_i9:dmi_rxn(1)"
				( attribute "PN" "C43"
					( Origin gPackager )
				)
				( objectStatus "U7C1.C43" )
			)
			( pin "@baseboard_fab2_lib.baseboard_fab2(sch_1):page117_i9:dmi_rxn(2)"
				( attribute "PN" "D44"
					( Origin gPackager )
				)
				( objectStatus "U7C1.D44" )
			)
			( pin "@baseboard_fab2_lib.baseboard_fab2(sch_1):page117_i9:dmi_rxn(3)"
				( attribute "PN" "C45"
					( Origin gPackager )
				)
				( objectStatus "U7C1.C45" )
			)
			( pin "@baseboard_fab2_lib.baseboard_fab2(sch_1):page117_i9:dmi_rxp(0)"
				( attribute "PN" "B42"
					( Origin gPackager )
				)
				( objectStatus "U7C1.B42" )
			)
			( pin "@baseboard_fab2_lib.baseboard_fab2(sch_1):page117_i9:dmi_rxp(1)"
				( attribute "PN" "A43"
					( Origin gPackager )
				)
				( objectStatus "U7C1.A43" )
			)
			( pin "@baseboard_fab2_lib.baseboard_fab2(sch_1):page117_i9:dmi_rxp(2)"
				( attribute "PN" "B44"
					( Origin gPackager )
				)
				( objectStatus "U7C1.B44" )
			)
			( pin "@baseboard_fab2_lib.baseboard_fab2(sch_1):page117_i9:dmi_rxp(3)"
				( attribute "PN" "A45"
					( Origin gPackager )
				)
				( objectStatus "U7C1.A45" )
			)
			( pin "@baseboard_fab2_lib.baseboard_fab2(sch_1):page117_i9:dmi_txn(0)"
				( attribute "PN" "H46"
					( Origin gPackager )
				)
				( objectStatus "U7C1.H46" )
			)
			( pin "@baseboard_fab2_lib.baseboard_fab2(sch_1):page117_i9:dmi_txn(1)"
				( attribute "PN" "J48"
					( Origin gPackager )
				)
				( objectStatus "U7C1.J48" )
			)
			( pin "@baseboard_fab2_lib.baseboard_fab2(sch_1):page117_i9:dmi_txn(2)"
				( attribute "PN" "K50"
					( Origin gPackager )
				)
				( objectStatus "U7C1.K50" )
			)
			( pin "@baseboard_fab2_lib.baseboard_fab2(sch_1):page117_i9:dmi_txn(3)"
				( attribute "PN" "P52"
					( Origin gPackager )
				)
				( objectStatus "U7C1.P52" )
			)
			( pin "@baseboard_fab2_lib.baseboard_fab2(sch_1):page117_i9:dmi_txp(0)"
				( attribute "PN" "K46"
					( Origin gPackager )
				)
				( objectStatus "U7C1.K46" )
			)
			( pin "@baseboard_fab2_lib.baseboard_fab2(sch_1):page117_i9:dmi_txp(1)"
				( attribute "PN" "H50"
					( Origin gPackager )
				)
				( objectStatus "U7C1.H50" )
			)
			( pin "@baseboard_fab2_lib.baseboard_fab2(sch_1):page117_i9:dmi_txp(2)"
				( attribute "PN" "M52"
					( Origin gPackager )
				)
				( objectStatus "U7C1.M52" )
			)
			( pin "@baseboard_fab2_lib.baseboard_fab2(sch_1):page117_i9:dmi_txp(3)"
				( attribute "PN" "N54"
					( Origin gPackager )
				)
				( objectStatus "U7C1.N54" )
			)
			( pin "@baseboard_fab2_lib.baseboard_fab2(sch_1):page117_i9:pcieup_0_rxn"
				( attribute "PN" "C48"
					( Origin gPackager )
				)
				( objectStatus "U7C1.C48" )
			)
			( pin "@baseboard_fab2_lib.baseboard_fab2(sch_1):page117_i9:pcieup_0_rxp"
				( attribute "PN" "A48"
					( Origin gPackager )
				)
				( objectStatus "U7C1.A48" )
			)
			( pin "@baseboard_fab2_lib.baseboard_fab2(sch_1):page117_i9:pcieup_0_txn"
				( attribute "PN" "J52"
					( Origin gPackager )
				)
				( objectStatus "U7C1.J52" )
			)
			( pin "@baseboard_fab2_lib.baseboard_fab2(sch_1):page117_i9:pcieup_0_txp"
				( attribute "PN" "G52"
					( Origin gPackager )
				)
				( objectStatus "U7C1.G52" )
			)
			( pin "@baseboard_fab2_lib.baseboard_fab2(sch_1):page117_i9:pcieup_1_rxn"
				( attribute "PN" "D49"
					( Origin gPackager )
				)
				( objectStatus "U7C1.D49" )
			)
			( pin "@baseboard_fab2_lib.baseboard_fab2(sch_1):page117_i9:pcieup_1_rxp"
				( attribute "PN" "B49"
					( Origin gPackager )
				)
				( objectStatus "U7C1.B49" )
			)
			( pin "@baseboard_fab2_lib.baseboard_fab2(sch_1):page117_i9:pcieup_1_txn"
				( attribute "PN" "P56"
					( Origin gPackager )
				)
				( objectStatus "U7C1.P56" )
			)
			( pin "@baseboard_fab2_lib.baseboard_fab2(sch_1):page117_i9:pcieup_1_txp"
				( attribute "PN" "M56"
					( Origin gPackager )
				)
				( objectStatus "U7C1.M56" )
			)
			( pin "@baseboard_fab2_lib.baseboard_fab2(sch_1):page117_i9:pcieup_2_rxn"
				( attribute "PN" "C50"
					( Origin gPackager )
				)
				( objectStatus "U7C1.C50" )
			)
			( pin "@baseboard_fab2_lib.baseboard_fab2(sch_1):page117_i9:pcieup_2_rxp"
				( attribute "PN" "A50"
					( Origin gPackager )
				)
				( objectStatus "U7C1.A50" )
			)
			( pin "@baseboard_fab2_lib.baseboard_fab2(sch_1):page117_i9:pcieup_2_txn"
				( attribute "PN" "H54"
					( Origin gPackager )
				)
				( objectStatus "U7C1.H54" )
			)
			( pin "@baseboard_fab2_lib.baseboard_fab2(sch_1):page117_i9:pcieup_2_txp"
				( attribute "PN" "G56"
					( Origin gPackager )
				)
				( objectStatus "U7C1.G56" )
			)
			( pin "@baseboard_fab2_lib.baseboard_fab2(sch_1):page117_i9:pcieup_3_rxn"
				( attribute "PN" "D51"
					( Origin gPackager )
				)
				( objectStatus "U7C1.D51" )
			)
			( pin "@baseboard_fab2_lib.baseboard_fab2(sch_1):page117_i9:pcieup_3_rxp"
				( attribute "PN" "B51"
					( Origin gPackager )
				)
				( objectStatus "U7C1.B51" )
			)
			( pin "@baseboard_fab2_lib.baseboard_fab2(sch_1):page117_i9:pcieup_3_txn"
				( attribute "PN" "J56"
					( Origin gPackager )
				)
				( objectStatus "U7C1.J56" )
			)
			( pin "@baseboard_fab2_lib.baseboard_fab2(sch_1):page117_i9:pcieup_3_txp"
				( attribute "PN" "K58"
					( Origin gPackager )
				)
				( objectStatus "U7C1.K58" )
			)
			( pin "@baseboard_fab2_lib.baseboard_fab2(sch_1):page117_i9:pcieup_4_rxn"
				( attribute "PN" "C52"
					( Origin gPackager )
				)
				( objectStatus "U7C1.C52" )
			)
			( pin "@baseboard_fab2_lib.baseboard_fab2(sch_1):page117_i9:pcieup_4_rxp"
				( attribute "PN" "A52"
					( Origin gPackager )
				)
				( objectStatus "U7C1.A52" )
			)
			( pin "@baseboard_fab2_lib.baseboard_fab2(sch_1):page117_i9:pcieup_4_txn"
				( attribute "PN" "N58"
					( Origin gPackager )
				)
				( objectStatus "U7C1.N58" )
			)
			( pin "@baseboard_fab2_lib.baseboard_fab2(sch_1):page117_i9:pcieup_4_txp"
				( attribute "PN" "M59"
					( Origin gPackager )
				)
				( objectStatus "U7C1.M59" )
			)
			( pin "@baseboard_fab2_lib.baseboard_fab2(sch_1):page117_i9:pcieup_5_rxn"
				( attribute "PN" "D53"
					( Origin gPackager )
				)
				( objectStatus "U7C1.D53" )
			)
			( pin "@baseboard_fab2_lib.baseboard_fab2(sch_1):page117_i9:pcieup_5_rxp"
				( attribute "PN" "B53"
					( Origin gPackager )
				)
				( objectStatus "U7C1.B53" )
			)
			( pin "@baseboard_fab2_lib.baseboard_fab2(sch_1):page117_i9:pcieup_5_txn"
				( attribute "PN" "N61"
					( Origin gPackager )
				)
				( objectStatus "U7C1.N61" )
			)
			( pin "@baseboard_fab2_lib.baseboard_fab2(sch_1):page117_i9:pcieup_5_txp"
				( attribute "PN" "K61"
					( Origin gPackager )
				)
				( objectStatus "U7C1.K61" )
			)
			( pin "@baseboard_fab2_lib.baseboard_fab2(sch_1):page117_i9:pcieup_6_rxn"
				( attribute "PN" "C54"
					( Origin gPackager )
				)
				( objectStatus "U7C1.C54" )
			)
			( pin "@baseboard_fab2_lib.baseboard_fab2(sch_1):page117_i9:pcieup_6_rxp"
				( attribute "PN" "A54"
					( Origin gPackager )
				)
				( objectStatus "U7C1.A54" )
			)
			( pin "@baseboard_fab2_lib.baseboard_fab2(sch_1):page117_i9:pcieup_6_txn"
				( attribute "PN" "H61"
					( Origin gPackager )
				)
				( objectStatus "U7C1.H61" )
			)
			( pin "@baseboard_fab2_lib.baseboard_fab2(sch_1):page117_i9:pcieup_6_txp"
				( attribute "PN" "J63"
					( Origin gPackager )
				)
				( objectStatus "U7C1.J63" )
			)
			( pin "@baseboard_fab2_lib.baseboard_fab2(sch_1):page117_i9:pcieup_7_rxn"
				( attribute "PN" "D55"
					( Origin gPackager )
				)
				( objectStatus "U7C1.D55" )
			)
			( pin "@baseboard_fab2_lib.baseboard_fab2(sch_1):page117_i9:pcieup_7_rxp"
				( attribute "PN" "B55"
					( Origin gPackager )
				)
				( objectStatus "U7C1.B55" )
			)
			( pin "@baseboard_fab2_lib.baseboard_fab2(sch_1):page117_i9:pcieup_7_txn"
				( attribute "PN" "P59"
					( Origin gPackager )
				)
				( objectStatus "U7C1.P59" )
			)
			( pin "@baseboard_fab2_lib.baseboard_fab2(sch_1):page117_i9:pcieup_7_txp"
				( attribute "PN" "R61"
					( Origin gPackager )
				)
				( objectStatus "U7C1.R61" )
			)
			( pin "@baseboard_fab2_lib.baseboard_fab2(sch_1):page117_i9:pcieup_8_rxn"
				( attribute "PN" "C57"
					( Origin gPackager )
				)
				( objectStatus "U7C1.C57" )
			)
			( pin "@baseboard_fab2_lib.baseboard_fab2(sch_1):page117_i9:pcieup_8_rxp"
				( attribute "PN" "A57"
					( Origin gPackager )
				)
				( objectStatus "U7C1.A57" )
			)
			( pin "@baseboard_fab2_lib.baseboard_fab2(sch_1):page117_i9:pcieup_8_txn"
				( attribute "PN" "K65"
					( Origin gPackager )
				)
				( objectStatus "U7C1.K65" )
			)
			( pin "@baseboard_fab2_lib.baseboard_fab2(sch_1):page117_i9:pcieup_8_txp"
				( attribute "PN" "M63"
					( Origin gPackager )
				)
				( objectStatus "U7C1.M63" )
			)
			( pin "@baseboard_fab2_lib.baseboard_fab2(sch_1):page117_i9:pcieup_9_rxn"
				( attribute "PN" "D58"
					( Origin gPackager )
				)
				( objectStatus "U7C1.D58" )
			)
			( pin "@baseboard_fab2_lib.baseboard_fab2(sch_1):page117_i9:pcieup_9_rxp"
				( attribute "PN" "B58"
					( Origin gPackager )
				)
				( objectStatus "U7C1.B58" )
			)
			( pin "@baseboard_fab2_lib.baseboard_fab2(sch_1):page117_i9:pcieup_9_txn"
				( attribute "PN" "J66"
					( Origin gPackager )
				)
				( objectStatus "U7C1.J66" )
			)
			( pin "@baseboard_fab2_lib.baseboard_fab2(sch_1):page117_i9:pcieup_9_txp"
				( attribute "PN" "M66"
					( Origin gPackager )
				)
				( objectStatus "U7C1.M66" )
			)
			( pin "@baseboard_fab2_lib.baseboard_fab2(sch_1):page117_i9:pcieup_10_rxn"
				( attribute "PN" "C59"
					( Origin gPackager )
				)
				( objectStatus "U7C1.C59" )
			)
			( pin "@baseboard_fab2_lib.baseboard_fab2(sch_1):page117_i9:pcieup_10_rxp"
				( attribute "PN" "A59"
					( Origin gPackager )
				)
				( objectStatus "U7C1.A59" )
			)
			( pin "@baseboard_fab2_lib.baseboard_fab2(sch_1):page117_i9:pcieup_10_txn"
				( attribute "PN" "N65"
					( Origin gPackager )
				)
				( objectStatus "U7C1.N65" )
			)
			( pin "@baseboard_fab2_lib.baseboard_fab2(sch_1):page117_i9:pcieup_10_txp"
				( attribute "PN" "P66"
					( Origin gPackager )
				)
				( objectStatus "U7C1.P66" )
			)
			( pin "@baseboard_fab2_lib.baseboard_fab2(sch_1):page117_i9:pcieup_11_rxn"
				( attribute "PN" "D60"
					( Origin gPackager )
				)
				( objectStatus "U7C1.D60" )
			)
			( pin "@baseboard_fab2_lib.baseboard_fab2(sch_1):page117_i9:pcieup_11_rxp"
				( attribute "PN" "B60"
					( Origin gPackager )
				)
				( objectStatus "U7C1.B60" )
			)
			( pin "@baseboard_fab2_lib.baseboard_fab2(sch_1):page117_i9:pcieup_11_txn"
				( attribute "PN" "T59"
					( Origin gPackager )
				)
				( objectStatus "U7C1.T59" )
			)
			( pin "@baseboard_fab2_lib.baseboard_fab2(sch_1):page117_i9:pcieup_11_txp"
				( attribute "PN" "V59"
					( Origin gPackager )
				)
				( objectStatus "U7C1.V59" )
			)
			( pin "@baseboard_fab2_lib.baseboard_fab2(sch_1):page117_i9:pcieup_12_rxn"
				( attribute "PN" "C61"
					( Origin gPackager )
				)
				( objectStatus "U7C1.C61" )
			)
			( pin "@baseboard_fab2_lib.baseboard_fab2(sch_1):page117_i9:pcieup_12_rxp"
				( attribute "PN" "A61"
					( Origin gPackager )
				)
				( objectStatus "U7C1.A61" )
			)
			( pin "@baseboard_fab2_lib.baseboard_fab2(sch_1):page117_i9:pcieup_12_txn"
				( attribute "PN" "R65"
					( Origin gPackager )
				)
				( objectStatus "U7C1.R65" )
			)
			( pin "@baseboard_fab2_lib.baseboard_fab2(sch_1):page117_i9:pcieup_12_txp"
				( attribute "PN" "U65"
					( Origin gPackager )
				)
				( objectStatus "U7C1.U65" )
			)
			( pin "@baseboard_fab2_lib.baseboard_fab2(sch_1):page117_i9:pcieup_13_rxn"
				( attribute "PN" "D62"
					( Origin gPackager )
				)
				( objectStatus "U7C1.D62" )
			)
			( pin "@baseboard_fab2_lib.baseboard_fab2(sch_1):page117_i9:pcieup_13_rxp"
				( attribute "PN" "B62"
					( Origin gPackager )
				)
				( objectStatus "U7C1.B62" )
			)
			( pin "@baseboard_fab2_lib.baseboard_fab2(sch_1):page117_i9:pcieup_13_txn"
				( attribute "PN" "T63"
					( Origin gPackager )
				)
				( objectStatus "U7C1.T63" )
			)
			( pin "@baseboard_fab2_lib.baseboard_fab2(sch_1):page117_i9:pcieup_13_txp"
				( attribute "PN" "U61"
					( Origin gPackager )
				)
				( objectStatus "U7C1.U61" )
			)
			( pin "@baseboard_fab2_lib.baseboard_fab2(sch_1):page117_i9:pcieup_14_rxn"
				( attribute "PN" "C63"
					( Origin gPackager )
				)
				( objectStatus "U7C1.C63" )
			)
			( pin "@baseboard_fab2_lib.baseboard_fab2(sch_1):page117_i9:pcieup_14_rxp"
				( attribute "PN" "A63"
					( Origin gPackager )
				)
				( objectStatus "U7C1.A63" )
			)
			( pin "@baseboard_fab2_lib.baseboard_fab2(sch_1):page117_i9:pcieup_14_txn"
				( attribute "PN" "W65"
					( Origin gPackager )
				)
				( objectStatus "U7C1.W65" )
			)
			( pin "@baseboard_fab2_lib.baseboard_fab2(sch_1):page117_i9:pcieup_14_txp"
				( attribute "PN" "V63"
					( Origin gPackager )
				)
				( objectStatus "U7C1.V63" )
			)
			( pin "@baseboard_fab2_lib.baseboard_fab2(sch_1):page117_i9:pcieup_15_rxn"
				( attribute "PN" "D64"
					( Origin gPackager )
				)
				( objectStatus "U7C1.D64" )
			)
			( pin "@baseboard_fab2_lib.baseboard_fab2(sch_1):page117_i9:pcieup_15_rxp"
				( attribute "PN" "B64"
					( Origin gPackager )
				)
				( objectStatus "U7C1.B64" )
			)
			( pin "@baseboard_fab2_lib.baseboard_fab2(sch_1):page117_i9:pcieup_15_txn"
				( attribute "PN" "Y66"
					( Origin gPackager )
				)
				( objectStatus "U7C1.Y66" )
			)
			( pin "@baseboard_fab2_lib.baseboard_fab2(sch_1):page117_i9:pcieup_15_txp"
				( attribute "PN" "AA65"
					( Origin gPackager )
				)
				( objectStatus "U7C1.AA65" )
			)
			( pin "@baseboard_fab2_lib.baseboard_fab2(sch_1):page118_i66:a"
				( attribute "PN" "1"
					( Origin gPackager )
				)
				( objectStatus "R3N9.1" )
			)
			( pin "@baseboard_fab2_lib.baseboard_fab2(sch_1):page118_i66:b"
				( attribute "PN" "2"
					( Origin gPackager )
				)
				( objectStatus "R3N9.2" )
			)
			( pin "@baseboard_fab2_lib.baseboard_fab2(sch_1):page118_i67:a"
				( attribute "PN" "1"
					( Origin gPackager )
				)
				( objectStatus "R3N14.1" )
			)
			( pin "@baseboard_fab2_lib.baseboard_fab2(sch_1):page118_i67:b"
				( attribute "PN" "2"
					( Origin gPackager )
				)
				( objectStatus "R3N14.2" )
			)
			( pin "@baseboard_fab2_lib.baseboard_fab2(sch_1):page118_i71:a"
				( attribute "PN" "1"
					( Origin gPackager )
				)
				( objectStatus "R3N13.1" )
			)
			( pin "@baseboard_fab2_lib.baseboard_fab2(sch_1):page118_i71:b"
				( attribute "PN" "2"
					( Origin gPackager )
				)
				( objectStatus "R3N13.2" )
			)
			( pin "@baseboard_fab2_lib.baseboard_fab2(sch_1):page118_i73:cpu_trst_n"
				( attribute "PN" "AT56"
					( Origin gPackager )
				)
				( objectStatus "U7C1.AT56" )
			)
			( pin "@baseboard_fab2_lib.baseboard_fab2(sch_1):page118_i73:dsw_pwrok"
				( attribute "PN" "K13"
					( Origin gPackager )
				)
				( objectStatus "U7C1.K13" )
			)
			( pin "@baseboard_fab2_lib.baseboard_fab2(sch_1):page118_i73:gpd0"
				( attribute "PN" "G15"
					( Origin gPackager )
				)
				( objectStatus "U7C1.G15" )
			)
			( pin "@baseboard_fab2_lib.baseboard_fab2(sch_1):page118_i73:gpd1_acpresent"
				( attribute "PN" "H13"
					( Origin gPackager )
				)
				( objectStatus "U7C1.H13" )
			)
			( pin "@baseboard_fab2_lib.baseboard_fab2(sch_1):page118_i73:gpd2_gbe_wake_n"
				( attribute "PN" "M11"
					( Origin gPackager )
				)
				( objectStatus "U7C1.M11" )
			)
			( pin "@baseboard_fab2_lib.baseboard_fab2(sch_1):page118_i73:gpd3_pwrbtn_n"
				( attribute "PN" "C15"
					( Origin gPackager )
				)
				( objectStatus "U7C1.C15" )
			)
			( pin "@baseboard_fab2_lib.baseboard_fab2(sch_1):page118_i73:gpd4_slp_s3_n"
				( attribute "PN" "D14"
					( Origin gPackager )
				)
				( objectStatus "U7C1.D14" )
			)
			( pin "@baseboard_fab2_lib.baseboard_fab2(sch_1):page118_i73:gpd5_slp_s4_n"
				( attribute "PN" "B16"
					( Origin gPackager )
				)
				( objectStatus "U7C1.B16" )
			)
			( pin "@baseboard_fab2_lib.baseboard_fab2(sch_1):page118_i73:gpd6_slp_a_n"
				( attribute "PN" "G11"
					( Origin gPackager )
				)
				( objectStatus "U7C1.G11" )
			)
			( pin "@baseboard_fab2_lib.baseboard_fab2(sch_1):page118_i73:gpd7"
				( attribute "PN" "H9"
					( Origin gPackager )
				)
				( objectStatus "U7C1.H9" )
			)
			( pin "@baseboard_fab2_lib.baseboard_fab2(sch_1):page118_i73:gpd8_susclk"
				( attribute "PN" "C13"
					( Origin gPackager )
				)
				( objectStatus "U7C1.C13" )
			)
			( pin "@baseboard_fab2_lib.baseboard_fab2(sch_1):page118_i73:gpd9"
				( attribute "PN" "A15"
					( Origin gPackager )
				)
				( objectStatus "U7C1.A15" )
			)
			( pin "@baseboard_fab2_lib.baseboard_fab2(sch_1):page118_i73:gpd10_slp_s5_n"
				( attribute "PN" "B14"
					( Origin gPackager )
				)
				( objectStatus "U7C1.B14" )
			)
			( pin "@baseboard_fab2_lib.baseboard_fab2(sch_1):page118_i73:gpd11_gbephy"
				( attribute "PN" "A13"
					( Origin gPackager )
				)
				( objectStatus "U7C1.A13" )
			)
			( pin "@baseboard_fab2_lib.baseboard_fab2(sch_1):page118_i73:itp_pmode"
				( attribute "PN" "AR54"
					( Origin gPackager )
				)
				( objectStatus "U7C1.AR54" )
			)
			( pin "@baseboard_fab2_lib.baseboard_fab2(sch_1):page118_i73:jtag_tck"
				( attribute "PN" "AL56"
					( Origin gPackager )
				)
				( objectStatus "U7C1.AL56" )
			)
			( pin "@baseboard_fab2_lib.baseboard_fab2(sch_1):page118_i73:jtag_tdi"
				( attribute "PN" "AN54"
					( Origin gPackager )
				)
				( objectStatus "U7C1.AN54" )
			)
			( pin "@baseboard_fab2_lib.baseboard_fab2(sch_1):page118_i73:jtag_tdo"
				( attribute "PN" "AP56"
					( Origin gPackager )
				)
				( objectStatus "U7C1.AP56" )
			)
			( pin "@baseboard_fab2_lib.baseboard_fab2(sch_1):page118_i73:jtag_tms"
				( attribute "PN" "AH54"
					( Origin gPackager )
				)
				( objectStatus "U7C1.AH54" )
			)
			( pin "@baseboard_fab2_lib.baseboard_fab2(sch_1):page118_i73:jtagx"
				( attribute "PN" "AF54"
					( Origin gPackager )
				)
				( objectStatus "U7C1.AF54" )
			)
			( pin "@baseboard_fab2_lib.baseboard_fab2(sch_1):page118_i73:lan_rbias_0"
				( attribute "PN" "BB29"
					( Origin gPackager )
				)
				( objectStatus "U7C1.BB29" )
			)
			( pin "@baseboard_fab2_lib.baseboard_fab2(sch_1):page118_i73:lan_rbias_1"
				( attribute "PN" "BD42"
					( Origin gPackager )
				)
				( objectStatus "U7C1.BD42" )
			)
			( pin "@baseboard_fab2_lib.baseboard_fab2(sch_1):page118_i73:lan_rx_p0n"
				( attribute "PN" "BH31"
					( Origin gPackager )
				)
				( objectStatus "U7C1.BH31" )
			)
			( pin "@baseboard_fab2_lib.baseboard_fab2(sch_1):page118_i73:lan_rx_p0p"
				( attribute "PN" "BF31"
					( Origin gPackager )
				)
				( objectStatus "U7C1.BF31" )
			)
			( pin "@baseboard_fab2_lib.baseboard_fab2(sch_1):page118_i73:lan_rx_p1n"
				( attribute "PN" "BG29"
					( Origin gPackager )
				)
				( objectStatus "U7C1.BG29" )
			)
			( pin "@baseboard_fab2_lib.baseboard_fab2(sch_1):page118_i73:lan_rx_p1p"
				( attribute "PN" "BJ29"
					( Origin gPackager )
				)
				( objectStatus "U7C1.BJ29" )
			)
			( pin "@baseboard_fab2_lib.baseboard_fab2(sch_1):page118_i73:lan_rx_p2n"
				( attribute "PN" "BJ37"
					( Origin gPackager )
				)
				( objectStatus "U7C1.BJ37" )
			)
			( pin "@baseboard_fab2_lib.baseboard_fab2(sch_1):page118_i73:lan_rx_p2p"
				( attribute "PN" "BG37"
					( Origin gPackager )
				)
				( objectStatus "U7C1.BG37" )
			)
			( pin "@baseboard_fab2_lib.baseboard_fab2(sch_1):page118_i73:lan_rx_p3n"
				( attribute "PN" "BF35"
					( Origin gPackager )
				)
				( objectStatus "U7C1.BF35" )
			)
			( pin "@baseboard_fab2_lib.baseboard_fab2(sch_1):page118_i73:lan_rx_p3p"
				( attribute "PN" "BH35"
					( Origin gPackager )
				)
				( objectStatus "U7C1.BH35" )
			)
			( pin "@baseboard_fab2_lib.baseboard_fab2(sch_1):page118_i73:lan_tx_p0n"
				( attribute "PN" "BM27"
					( Origin gPackager )
				)
				( objectStatus "U7C1.BM27" )
			)
			( pin "@baseboard_fab2_lib.baseboard_fab2(sch_1):page118_i73:lan_tx_p0p"
				( attribute "PN" "BR27"
					( Origin gPackager )
				)
				( objectStatus "U7C1.BR27" )
			)
			( pin "@baseboard_fab2_lib.baseboard_fab2(sch_1):page118_i73:lan_tx_p1n"
				( attribute "PN" "BM24"
					( Origin gPackager )
				)
				( objectStatus "U7C1.BM24" )
			)
			( pin "@baseboard_fab2_lib.baseboard_fab2(sch_1):page118_i73:lan_tx_p1p"
				( attribute "PN" "BR24"
					( Origin gPackager )
				)
				( objectStatus "U7C1.BR24" )
			)
			( pin "@baseboard_fab2_lib.baseboard_fab2(sch_1):page118_i73:lan_tx_p2n"
				( attribute "PN" "BM35"
					( Origin gPackager )
				)
				( objectStatus "U7C1.BM35" )
			)
			( pin "@baseboard_fab2_lib.baseboard_fab2(sch_1):page118_i73:lan_tx_p2p"
				( attribute "PN" "BR35"
					( Origin gPackager )
				)
				( objectStatus "U7C1.BR35" )
			)
			( pin "@baseboard_fab2_lib.baseboard_fab2(sch_1):page118_i73:lan_tx_p3n"
				( attribute "PN" "BR31"
					( Origin gPackager )
				)
				( objectStatus "U7C1.BR31" )
			)
			( pin "@baseboard_fab2_lib.baseboard_fab2(sch_1):page118_i73:lan_tx_p3p"
				( attribute "PN" "BM31"
					( Origin gPackager )
				)
				( objectStatus "U7C1.BM31" )
			)
			( pin "@baseboard_fab2_lib.baseboard_fab2(sch_1):page118_i73:lan_xtal_in"
				( attribute "PN" "BV16"
					( Origin gPackager )
				)
				( objectStatus "U7C1.BV16" )
			)
			( pin "@baseboard_fab2_lib.baseboard_fab2(sch_1):page118_i73:lan_xtal_out"
				( attribute "PN" "BY16"
					( Origin gPackager )
				)
				( objectStatus "U7C1.BY16" )
			)
			( pin "@baseboard_fab2_lib.baseboard_fab2(sch_1):page118_i73:pch_pwrok"
				( attribute "PN" "R17"
					( Origin gPackager )
				)
				( objectStatus "U7C1.R17" )
			)
			( pin "@baseboard_fab2_lib.baseboard_fab2(sch_1):page118_i73:peci"
				( attribute "PN" "U9"
					( Origin gPackager )
				)
				( objectStatus "U7C1.U9" )
			)
			( pin "@baseboard_fab2_lib.baseboard_fab2(sch_1):page118_i73:pltrst_cpu_n"
				( attribute "PN" "U17"
					( Origin gPackager )
				)
				( objectStatus "U7C1.U17" )
			)
			( pin "@baseboard_fab2_lib.baseboard_fab2(sch_1):page118_i73:pm_sync"
				( attribute "PN" "U13"
					( Origin gPackager )
				)
				( objectStatus "U7C1.U13" )
			)
			( pin "@baseboard_fab2_lib.baseboard_fab2(sch_1):page118_i73:pm_sync2"
				( attribute "PN" "V7"
					( Origin gPackager )
				)
				( objectStatus "U7C1.V7" )
			)
			( pin "@baseboard_fab2_lib.baseboard_fab2(sch_1):page118_i73:prdy_n"
				( attribute "PN" "AD54"
					( Origin gPackager )
				)
				( objectStatus "U7C1.AD54" )
			)
			( pin "@baseboard_fab2_lib.baseboard_fab2(sch_1):page118_i73:preq_n"
				( attribute "PN" "U54"
					( Origin gPackager )
				)
				( objectStatus "U7C1.U54" )
			)
			( pin "@baseboard_fab2_lib.baseboard_fab2(sch_1):page118_i73:proc_pwrgd"
				( attribute "PN" "R9"
					( Origin gPackager )
				)
				( objectStatus "U7C1.R9" )
			)
			( pin "@baseboard_fab2_lib.baseboard_fab2(sch_1):page118_i73:rsmrst_n"
				( attribute "PN" "P15"
					( Origin gPackager )
				)
				( objectStatus "U7C1.P15" )
			)
			( pin "@baseboard_fab2_lib.baseboard_fab2(sch_1):page118_i73:rsvd(32)"
				( attribute "PN" "AA54"
					( Origin gPackager )
				)
				( objectStatus "U7C1.AA54" )
			)
			( pin "@baseboard_fab2_lib.baseboard_fab2(sch_1):page118_i73:rsvd(33)"
				( attribute "PN" "V56"
					( Origin gPackager )
				)
				( objectStatus "U7C1.V56" )
			)
			( pin "@baseboard_fab2_lib.baseboard_fab2(sch_1):page118_i73:rsvd(34)"
				( attribute "PN" "Y56"
					( Origin gPackager )
				)
				( objectStatus "U7C1.Y56" )
			)
			( pin "@baseboard_fab2_lib.baseboard_fab2(sch_1):page118_i73:rsvd(35)"
				( attribute "PN" "W54"
					( Origin gPackager )
				)
				( objectStatus "U7C1.W54" )
			)
			( pin "@baseboard_fab2_lib.baseboard_fab2(sch_1):page118_i73:rsvd(36)"
				( attribute "PN" "AK54"
					( Origin gPackager )
				)
				( objectStatus "U7C1.AK54" )
			)
			( pin "@baseboard_fab2_lib.baseboard_fab2(sch_1):page118_i73:rsvd(37)"
				( attribute "PN" "BN29"
					( Origin gPackager )
				)
				( objectStatus "U7C1.BN29" )
			)
			( pin "@baseboard_fab2_lib.baseboard_fab2(sch_1):page118_i73:rsvd(38)"
				( attribute "PN" "BL29"
					( Origin gPackager )
				)
				( objectStatus "U7C1.BL29" )
			)
			( pin "@baseboard_fab2_lib.baseboard_fab2(sch_1):page118_i73:rsvd(39)"
				( attribute "PN" "BL26"
					( Origin gPackager )
				)
				( objectStatus "U7C1.BL26" )
			)
			( pin "@baseboard_fab2_lib.baseboard_fab2(sch_1):page118_i73:rsvd(40)"
				( attribute "PN" "BN26"
					( Origin gPackager )
				)
				( objectStatus "U7C1.BN26" )
			)
			( pin "@baseboard_fab2_lib.baseboard_fab2(sch_1):page118_i73:rsvd(41)"
				( attribute "PN" "BJ40"
					( Origin gPackager )
				)
				( objectStatus "U7C1.BJ40" )
			)
			( pin "@baseboard_fab2_lib.baseboard_fab2(sch_1):page118_i73:rsvd(42)"
				( attribute "PN" "BG40"
					( Origin gPackager )
				)
				( objectStatus "U7C1.BG40" )
			)
			( pin "@baseboard_fab2_lib.baseboard_fab2(sch_1):page118_i73:rsvd(43)"
				( attribute "PN" "BL33"
					( Origin gPackager )
				)
				( objectStatus "U7C1.BL33" )
			)
			( pin "@baseboard_fab2_lib.baseboard_fab2(sch_1):page118_i73:rsvd(44)"
				( attribute "PN" "BN33"
					( Origin gPackager )
				)
				( objectStatus "U7C1.BN33" )
			)
			( pin "@baseboard_fab2_lib.baseboard_fab2(sch_1):page118_i73:rsvd(45)"
				( attribute "PN" "P22"
					( Origin gPackager )
				)
				( objectStatus "U7C1.P22" )
			)
			( pin "@baseboard_fab2_lib.baseboard_fab2(sch_1):page118_i73:rsvd(46)"
				( attribute "CDS_NOT_ON_SYM" "TRUE"
					( Origin gFrontEnd )
				)
			)
			( pin "@baseboard_fab2_lib.baseboard_fab2(sch_1):page118_i73:rsvd(47)"
				( attribute "CDS_NOT_ON_SYM" "TRUE"
					( Origin gFrontEnd )
				)
			)
			( pin "@baseboard_fab2_lib.baseboard_fab2(sch_1):page118_i73:rsvd(48)"
				( attribute "CDS_NOT_ON_SYM" "TRUE"
					( Origin gFrontEnd )
				)
			)
			( pin "@baseboard_fab2_lib.baseboard_fab2(sch_1):page118_i73:rsvd(49)"
				( attribute "CDS_NOT_ON_SYM" "TRUE"
					( Origin gFrontEnd )
				)
			)
			( pin "@baseboard_fab2_lib.baseboard_fab2(sch_1):page118_i73:rsvd(50)"
				( attribute "CDS_NOT_ON_SYM" "TRUE"
					( Origin gFrontEnd )
				)
			)
			( pin "@baseboard_fab2_lib.baseboard_fab2(sch_1):page118_i73:rsvd(51)"
				( attribute "CDS_NOT_ON_SYM" "TRUE"
					( Origin gFrontEnd )
				)
			)
			( pin "@baseboard_fab2_lib.baseboard_fab2(sch_1):page118_i73:rsvd(52)"
				( attribute "CDS_NOT_ON_SYM" "TRUE"
					( Origin gFrontEnd )
				)
			)
			( pin "@baseboard_fab2_lib.baseboard_fab2(sch_1):page118_i73:rsvd(53)"
				( attribute "PN" "P26"
					( Origin gPackager )
				)
				( objectStatus "U7C1.P26" )
			)
			( pin "@baseboard_fab2_lib.baseboard_fab2(sch_1):page118_i73:rsvd(54)"
				( attribute "PN" "R24"
					( Origin gPackager )
				)
				( objectStatus "U7C1.R24" )
			)
			( pin "@baseboard_fab2_lib.baseboard_fab2(sch_1):page118_i73:slp_gbe_n"
				( attribute "PN" "M15"
					( Origin gPackager )
				)
				( objectStatus "U7C1.M15" )
			)
			( pin "@baseboard_fab2_lib.baseboard_fab2(sch_1):page118_i73:slp_sus_n"
				( attribute "PN" "P7"
					( Origin gPackager )
				)
				( objectStatus "U7C1.P7" )
			)
			( pin "@baseboard_fab2_lib.baseboard_fab2(sch_1):page118_i73:sys_pwrok"
				( attribute "PN" "BY19"
					( Origin gPackager )
				)
				( objectStatus "U7C1.BY19" )
			)
			( pin "@baseboard_fab2_lib.baseboard_fab2(sch_1):page118_i73:sys_reset_n"
				( attribute "PN" "BV19"
					( Origin gPackager )
				)
				( objectStatus "U7C1.BV19" )
			)
			( pin "@baseboard_fab2_lib.baseboard_fab2(sch_1):page118_i73:thrmtrip_n"
				( attribute "PN" "V15"
					( Origin gPackager )
				)
				( objectStatus "U7C1.V15" )
			)
			( pin "@baseboard_fab2_lib.baseboard_fab2(sch_1):page118_i73:trigger_in"
				( attribute "PN" "M7"
					( Origin gPackager )
				)
				( objectStatus "U7C1.M7" )
			)
			( pin "@baseboard_fab2_lib.baseboard_fab2(sch_1):page118_i73:trigger_out"
				( attribute "PN" "R13"
					( Origin gPackager )
				)
				( objectStatus "U7C1.R13" )
			)
			( pin "@baseboard_fab2_lib.baseboard_fab2(sch_1):page118_i73:wake_n"
				( attribute "PN" "K9"
					( Origin gPackager )
				)
				( objectStatus "U7C1.K9" )
			)
			( pin "@baseboard_fab2_lib.baseboard_fab2(sch_1):page118_i76:a"
				( attribute "PN" "1"
					( Origin gPackager )
				)
				( objectStatus "Y8C1.1" )
			)
			( pin "@baseboard_fab2_lib.baseboard_fab2(sch_1):page118_i76:b"
				( attribute "PN" "3"
					( Origin gPackager )
				)
				( objectStatus "Y8C1.3" )
			)
			( pin "@baseboard_fab2_lib.baseboard_fab2(sch_1):page118_i96:a"
				( attribute "PN" "1"
					( Origin gPackager )
				)
				( objectStatus "R2N4.1" )
			)
			( pin "@baseboard_fab2_lib.baseboard_fab2(sch_1):page118_i96:b"
				( attribute "PN" "2"
					( Origin gPackager )
				)
				( objectStatus "R2N4.2" )
			)
			( pin "@baseboard_fab2_lib.baseboard_fab2(sch_1):page118_i99:a"
				( attribute "PN" "1"
					( Origin gPackager )
				)
				( objectStatus "R2M6.1" )
			)
			( pin "@baseboard_fab2_lib.baseboard_fab2(sch_1):page118_i99:b"
				( attribute "PN" "2"
					( Origin gPackager )
				)
				( objectStatus "R2M6.2" )
			)
			( pin "@baseboard_fab2_lib.baseboard_fab2(sch_1):page118_i120:a"
				( attribute "PN" "1"
					( Origin gPackager )
				)
				( objectStatus "R8C24.1" )
			)
			( pin "@baseboard_fab2_lib.baseboard_fab2(sch_1):page118_i120:b"
				( attribute "PN" "2"
					( Origin gPackager )
				)
				( objectStatus "R8C24.2" )
			)
			( pin "@baseboard_fab2_lib.baseboard_fab2(sch_1):page118_i125:a"
				( attribute "PN" "1"
					( Origin gPackager )
				)
				( objectStatus "R8C23.1" )
			)
			( pin "@baseboard_fab2_lib.baseboard_fab2(sch_1):page118_i125:b"
				( attribute "PN" "2"
					( Origin gPackager )
				)
				( objectStatus "R8C23.2" )
			)
			( pin "@baseboard_fab2_lib.baseboard_fab2(sch_1):page118_i128:a"
				( attribute "PN" "1"
					( Origin gPackager )
				)
				( objectStatus "R2N6.1" )
			)
			( pin "@baseboard_fab2_lib.baseboard_fab2(sch_1):page118_i128:b"
				( attribute "PN" "2"
					( Origin gPackager )
				)
				( objectStatus "R2N6.2" )
			)
			( pin "@baseboard_fab2_lib.baseboard_fab2(sch_1):page118_i131:a"
				( attribute "PN" "1"
					( Origin gPackager )
				)
				( objectStatus "R7D23.1" )
			)
			( pin "@baseboard_fab2_lib.baseboard_fab2(sch_1):page118_i131:b"
				( attribute "PN" "2"
					( Origin gPackager )
				)
				( objectStatus "R7D23.2" )
			)
			( pin "@baseboard_fab2_lib.baseboard_fab2(sch_1):page118_i136:a"
				( attribute "PN" "1"
					( Origin gPackager )
				)
				( objectStatus "C7D1.1" )
			)
			( pin "@baseboard_fab2_lib.baseboard_fab2(sch_1):page118_i136:b"
				( attribute "PN" "2"
					( Origin gPackager )
				)
				( objectStatus "C7D1.2" )
			)
			( pin "@baseboard_fab2_lib.baseboard_fab2(sch_1):page118_i142:a"
				( attribute "PN" "2"
					( Origin gPackager )
				)
				( objectStatus "U7D1.2" )
			)
			( pin "@baseboard_fab2_lib.baseboard_fab2(sch_1):page118_i142:b"
				( attribute "PN" "4"
					( Origin gPackager )
				)
				( objectStatus "U7D1.4" )
			)
			( pin "@baseboard_fab2_lib.baseboard_fab2(sch_1):page118_i142:oe_n"
				( attribute "PN" "1"
					( Origin gPackager )
				)
				( objectStatus "U7D1.1" )
			)
			( pin "@baseboard_fab2_lib.baseboard_fab2(sch_1):page118_i144:a"
				( attribute "PN" "1"
					( Origin gPackager )
				)
				( objectStatus "R7C23.1" )
			)
			( pin "@baseboard_fab2_lib.baseboard_fab2(sch_1):page118_i144:b"
				( attribute "PN" "2"
					( Origin gPackager )
				)
				( objectStatus "R7C23.2" )
			)
			( pin "@baseboard_fab2_lib.baseboard_fab2(sch_1):page119_i115:gpp_a0_rcin_n_espi_alert1_n"
				( attribute "PN" "N3"
					( Origin gPackager )
				)
				( objectStatus "U7C1.N3" )
			)
			( pin "@baseboard_fab2_lib.baseboard_fab2(sch_1):page119_i115:gpp_a1_lad0_espi_io0"
				( attribute "PN" "Y3"
					( Origin gPackager )
				)
				( objectStatus "U7C1.Y3" )
			)
			( pin "@baseboard_fab2_lib.baseboard_fab2(sch_1):page119_i115:gpp_a2_lad1_espi_io1"
				( attribute "PN" "N1"
					( Origin gPackager )
				)
				( objectStatus "U7C1.N1" )
			)
			( pin "@baseboard_fab2_lib.baseboard_fab2(sch_1):page119_i115:gpp_a3_lad2_espi_io2"
				( attribute "PN" "W2"
					( Origin gPackager )
				)
				( objectStatus "U7C1.W2" )
			)
			( pin "@baseboard_fab2_lib.baseboard_fab2(sch_1):page119_i115:gpp_a4_lad3_espi_io3"
				( attribute "PN" "Y1"
					( Origin gPackager )
				)
				( objectStatus "U7C1.Y1" )
			)
			( pin "@baseboard_fab2_lib.baseboard_fab2(sch_1):page119_i115:gpp_a5_lframe_n_espi_cs0_n"
				( attribute "PN" "P4"
					( Origin gPackager )
				)
				( objectStatus "U7C1.P4" )
			)
			( pin "@baseboard_fab2_lib.baseboard_fab2(sch_1):page119_i115:gpp_a6_serirq_espi_cs1_n"
				( attribute "PN" "P2"
					( Origin gPackager )
				)
				( objectStatus "U7C1.P2" )
			)
			( pin "@baseboard_fab2_lib.baseboard_fab2(sch_1):page119_i115:gpp_a7_pirqa_n_espi_alert0_n"
				( attribute "PN" "AA2"
					( Origin gPackager )
				)
				( objectStatus "U7C1.AA2" )
			)
			( pin "@baseboard_fab2_lib.baseboard_fab2(sch_1):page119_i115:gpp_a8_clkrun_n"
				( attribute "PN" "AB1"
					( Origin gPackager )
				)
				( objectStatus "U7C1.AB1" )
			)
			( pin "@baseboard_fab2_lib.baseboard_fab2(sch_1):page119_i115:gpp_a9_clkout_lpc0_espi_clk"
				( attribute "PN" "R3"
					( Origin gPackager )
				)
				( objectStatus "U7C1.R3" )
			)
			( pin "@baseboard_fab2_lib.baseboard_fab2(sch_1):page119_i115:gpp_a10_clkout_lpc1"
				( attribute "PN" "AA4"
					( Origin gPackager )
				)
				( objectStatus "U7C1.AA4" )
			)
			( pin "@baseboard_fab2_lib.baseboard_fab2(sch_1):page119_i115:gpp_a11_pme_n"
				( attribute "PN" "AC2"
					( Origin gPackager )
				)
				( objectStatus "U7C1.AC2" )
			)
			( pin "@baseboard_fab2_lib.baseboard_fab2(sch_1):page119_i115:gpp_a12_bmbusy_n_sxexithldoff_n"
				( attribute "PN" "R1"
					( Origin gPackager )
				)
				( objectStatus "U7C1.R1" )
			)
			( pin "@baseboard_fab2_lib.baseboard_fab2(sch_1):page119_i115:gpp_a13_suswarn_n_suspwrdnack"
				( attribute "PN" "T4"
					( Origin gPackager )
				)
				( objectStatus "U7C1.T4" )
			)
			( pin "@baseboard_fab2_lib.baseboard_fab2(sch_1):page119_i115:gpp_a14_espi_reset_n"
				( attribute "PN" "AB3"
					( Origin gPackager )
				)
				( objectStatus "U7C1.AB3" )
			)
			( pin "@baseboard_fab2_lib.baseboard_fab2(sch_1):page119_i115:gpp_a15_susack_n"
				( attribute "PN" "AC4"
					( Origin gPackager )
				)
				( objectStatus "U7C1.AC4" )
			)
			( pin "@baseboard_fab2_lib.baseboard_fab2(sch_1):page119_i115:gpp_a16_clkout_lpc2"
				( attribute "PN" "T2"
					( Origin gPackager )
				)
				( objectStatus "U7C1.T2" )
			)
			( pin "@baseboard_fab2_lib.baseboard_fab2(sch_1):page119_i115:gpp_a17"
				( attribute "PN" "AD1"
					( Origin gPackager )
				)
				( objectStatus "U7C1.AD1" )
			)
			( pin "@baseboard_fab2_lib.baseboard_fab2(sch_1):page119_i115:gpp_a18"
				( attribute "PN" "AD3"
					( Origin gPackager )
				)
				( objectStatus "U7C1.AD3" )
			)
			( pin "@baseboard_fab2_lib.baseboard_fab2(sch_1):page119_i115:gpp_a19"
				( attribute "PN" "V3"
					( Origin gPackager )
				)
				( objectStatus "U7C1.V3" )
			)
			( pin "@baseboard_fab2_lib.baseboard_fab2(sch_1):page119_i115:gpp_a20"
				( attribute "PN" "W4"
					( Origin gPackager )
				)
				( objectStatus "U7C1.W4" )
			)
			( pin "@baseboard_fab2_lib.baseboard_fab2(sch_1):page119_i115:gpp_a21"
				( attribute "PN" "AE2"
					( Origin gPackager )
				)
				( objectStatus "U7C1.AE2" )
			)
			( pin "@baseboard_fab2_lib.baseboard_fab2(sch_1):page119_i115:gpp_a22"
				( attribute "PN" "AE4"
					( Origin gPackager )
				)
				( objectStatus "U7C1.AE4" )
			)
			( pin "@baseboard_fab2_lib.baseboard_fab2(sch_1):page119_i115:gpp_a23"
				( attribute "PN" "V1"
					( Origin gPackager )
				)
				( objectStatus "U7C1.V1" )
			)
			( pin "@baseboard_fab2_lib.baseboard_fab2(sch_1):page119_i115:gpp_b0_core_vid0"
				( attribute "PN" "BL7"
					( Origin gPackager )
				)
				( objectStatus "U7C1.BL7" )
			)
			( pin "@baseboard_fab2_lib.baseboard_fab2(sch_1):page119_i115:gpp_b1_core_vid1"
				( attribute "PN" "BH9"
					( Origin gPackager )
				)
				( objectStatus "U7C1.BH9" )
			)
			( pin "@baseboard_fab2_lib.baseboard_fab2(sch_1):page119_i115:gpp_b2"
				( attribute "PN" "BN15"
					( Origin gPackager )
				)
				( objectStatus "U7C1.BN15" )
			)
			( pin "@baseboard_fab2_lib.baseboard_fab2(sch_1):page119_i115:gpp_b3_cpu_gp2"
				( attribute "PN" "BR9"
					( Origin gPackager )
				)
				( objectStatus "U7C1.BR9" )
			)
			( pin "@baseboard_fab2_lib.baseboard_fab2(sch_1):page119_i115:gpp_b4_cpu_gp3"
				( attribute "PN" "BN7"
					( Origin gPackager )
				)
				( objectStatus "U7C1.BN7" )
			)
			( pin "@baseboard_fab2_lib.baseboard_fab2(sch_1):page119_i115:gpp_b5_srcclkreq0_n"
				( attribute "PN" "BK17"
					( Origin gPackager )
				)
				( objectStatus "U7C1.BK17" )
			)
			( pin "@baseboard_fab2_lib.baseboard_fab2(sch_1):page119_i115:gpp_b6_srcclkreq1_n"
				( attribute "PN" "BG18"
					( Origin gPackager )
				)
				( objectStatus "U7C1.BG18" )
			)
			( pin "@baseboard_fab2_lib.baseboard_fab2(sch_1):page119_i115:gpp_b7_srcclkreq2_n"
				( attribute "PN" "BR13"
					( Origin gPackager )
				)
				( objectStatus "U7C1.BR13" )
			)
			( pin "@baseboard_fab2_lib.baseboard_fab2(sch_1):page119_i115:gpp_b8_srcclkreq3_n"
				( attribute "PN" "BN11"
					( Origin gPackager )
				)
				( objectStatus "U7C1.BN11" )
			)
			( pin "@baseboard_fab2_lib.baseboard_fab2(sch_1):page119_i115:gpp_b9_srcclkreq4_n"
				( attribute "PN" "BH20"
					( Origin gPackager )
				)
				( objectStatus "U7C1.BH20" )
			)
			( pin "@baseboard_fab2_lib.baseboard_fab2(sch_1):page119_i115:gpp_b10_srcclkreq5_n"
				( attribute "PN" "BL11"
					( Origin gPackager )
				)
				( objectStatus "U7C1.BL11" )
			)
			( pin "@baseboard_fab2_lib.baseboard_fab2(sch_1):page119_i115:gpp_b11"
				( attribute "PN" "BK9"
					( Origin gPackager )
				)
				( objectStatus "U7C1.BK9" )
			)
			( pin "@baseboard_fab2_lib.baseboard_fab2(sch_1):page119_i115:gpp_b12_glb_rst_warn_n"
				( attribute "PN" "BL18"
					( Origin gPackager )
				)
				( objectStatus "U7C1.BL18" )
			)
			( pin "@baseboard_fab2_lib.baseboard_fab2(sch_1):page119_i115:gpp_b13_pltrst_n"
				( attribute "PN" "BN18"
					( Origin gPackager )
				)
				( objectStatus "U7C1.BN18" )
			)
			( pin "@baseboard_fab2_lib.baseboard_fab2(sch_1):page119_i115:gpp_b14_spkr"
				( attribute "PN" "BH13"
					( Origin gPackager )
				)
				( objectStatus "U7C1.BH13" )
			)
			( pin "@baseboard_fab2_lib.baseboard_fab2(sch_1):page119_i115:gpp_b15"
				( attribute "PN" "BK13"
					( Origin gPackager )
				)
				( objectStatus "U7C1.BK13" )
			)
			( pin "@baseboard_fab2_lib.baseboard_fab2(sch_1):page119_i115:gpp_b16"
				( attribute "PN" "BG22"
					( Origin gPackager )
				)
				( objectStatus "U7C1.BG22" )
			)
			( pin "@baseboard_fab2_lib.baseboard_fab2(sch_1):page119_i115:gpp_b17"
				( attribute "PN" "BG15"
					( Origin gPackager )
				)
				( objectStatus "U7C1.BG15" )
			)
			( pin "@baseboard_fab2_lib.baseboard_fab2(sch_1):page119_i115:gpp_b18"
				( attribute "PN" "BL15"
					( Origin gPackager )
				)
				( objectStatus "U7C1.BL15" )
			)
			( pin "@baseboard_fab2_lib.baseboard_fab2(sch_1):page119_i115:gpp_b19"
				( attribute "PN" "BK20"
					( Origin gPackager )
				)
				( objectStatus "U7C1.BK20" )
			)
			( pin "@baseboard_fab2_lib.baseboard_fab2(sch_1):page119_i115:gpp_b20"
				( attribute "PN" "BJ22"
					( Origin gPackager )
				)
				( objectStatus "U7C1.BJ22" )
			)
			( pin "@baseboard_fab2_lib.baseboard_fab2(sch_1):page119_i115:gpp_b21"
				( attribute "PN" "BH17"
					( Origin gPackager )
				)
				( objectStatus "U7C1.BH17" )
			)
			( pin "@baseboard_fab2_lib.baseboard_fab2(sch_1):page119_i115:gpp_b22"
				( attribute "PN" "BR17"
					( Origin gPackager )
				)
				( objectStatus "U7C1.BR17" )
			)
			( pin "@baseboard_fab2_lib.baseboard_fab2(sch_1):page119_i115:gpp_b23_meie_sml1alrt_n_phot_n"
				( attribute "PN" "BM20"
					( Origin gPackager )
				)
				( objectStatus "U7C1.BM20" )
			)
			( pin "@baseboard_fab2_lib.baseboard_fab2(sch_1):page119_i115:gpp_c0_smbclk"
				( attribute "PN" "BW28"
					( Origin gPackager )
				)
				( objectStatus "U7C1.BW28" )
			)
			( pin "@baseboard_fab2_lib.baseboard_fab2(sch_1):page119_i115:gpp_c1_smbdata"
				( attribute "PN" "BV27"
					( Origin gPackager )
				)
				( objectStatus "U7C1.BV27" )
			)
			( pin "@baseboard_fab2_lib.baseboard_fab2(sch_1):page119_i115:gpp_c2_smbalert_n"
				( attribute "PN" "BY27"
					( Origin gPackager )
				)
				( objectStatus "U7C1.BY27" )
			)
			( pin "@baseboard_fab2_lib.baseboard_fab2(sch_1):page119_i115:gpp_c3_sml0clk_ie"
				( attribute "PN" "BV29"
					( Origin gPackager )
				)
				( objectStatus "U7C1.BV29" )
			)
			( pin "@baseboard_fab2_lib.baseboard_fab2(sch_1):page119_i115:gpp_c4_sml0data_ie"
				( attribute "PN" "BW30"
					( Origin gPackager )
				)
				( objectStatus "U7C1.BW30" )
			)
			( pin "@baseboard_fab2_lib.baseboard_fab2(sch_1):page119_i115:gpp_c5_sml0alert_ie_n"
				( attribute "PN" "BW34"
					( Origin gPackager )
				)
				( objectStatus "U7C1.BW34" )
			)
			( pin "@baseboard_fab2_lib.baseboard_fab2(sch_1):page119_i115:gpp_c6_sml1clk_ie"
				( attribute "PN" "CA28"
					( Origin gPackager )
				)
				( objectStatus "U7C1.CA28" )
			)
			( pin "@baseboard_fab2_lib.baseboard_fab2(sch_1):page119_i115:gpp_c7_sml1data_ie"
				( attribute "PN" "BV35"
					( Origin gPackager )
				)
				( objectStatus "U7C1.BV35" )
			)
			( pin "@baseboard_fab2_lib.baseboard_fab2(sch_1):page119_i115:gpp_c8"
				( attribute "PN" "BW32"
					( Origin gPackager )
				)
				( objectStatus "U7C1.BW32" )
			)
			( pin "@baseboard_fab2_lib.baseboard_fab2(sch_1):page119_i115:gpp_c9"
				( attribute "PN" "BY29"
					( Origin gPackager )
				)
				( objectStatus "U7C1.BY29" )
			)
			( pin "@baseboard_fab2_lib.baseboard_fab2(sch_1):page119_i115:gpp_c10"
				( attribute "PN" "BV31"
					( Origin gPackager )
				)
				( objectStatus "U7C1.BV31" )
			)
			( pin "@baseboard_fab2_lib.baseboard_fab2(sch_1):page119_i115:gpp_c11"
				( attribute "PN" "BV33"
					( Origin gPackager )
				)
				( objectStatus "U7C1.BV33" )
			)
			( pin "@baseboard_fab2_lib.baseboard_fab2(sch_1):page119_i115:gpp_c12"
				( attribute "PN" "CA30"
					( Origin gPackager )
				)
				( objectStatus "U7C1.CA30" )
			)
			( pin "@baseboard_fab2_lib.baseboard_fab2(sch_1):page119_i115:gpp_c13"
				( attribute "PN" "BV38"
					( Origin gPackager )
				)
				( objectStatus "U7C1.BV38" )
			)
			( pin "@baseboard_fab2_lib.baseboard_fab2(sch_1):page119_i115:gpp_c14"
				( attribute "PN" "BY38"
					( Origin gPackager )
				)
				( objectStatus "U7C1.BY38" )
			)
			( pin "@baseboard_fab2_lib.baseboard_fab2(sch_1):page119_i115:gpp_c15"
				( attribute "PN" "CA32"
					( Origin gPackager )
				)
				( objectStatus "U7C1.CA32" )
			)
			( pin "@baseboard_fab2_lib.baseboard_fab2(sch_1):page119_i115:gpp_c16"
				( attribute "PN" "BW37"
					( Origin gPackager )
				)
				( objectStatus "U7C1.BW37" )
			)
			( pin "@baseboard_fab2_lib.baseboard_fab2(sch_1):page119_i115:gpp_c17"
				( attribute "PN" "BY31"
					( Origin gPackager )
				)
				( objectStatus "U7C1.BY31" )
			)
			( pin "@baseboard_fab2_lib.baseboard_fab2(sch_1):page119_i115:gpp_c18"
				( attribute "PN" "BY35"
					( Origin gPackager )
				)
				( objectStatus "U7C1.BY35" )
			)
			( pin "@baseboard_fab2_lib.baseboard_fab2(sch_1):page119_i115:gpp_c19"
				( attribute "PN" "BW39"
					( Origin gPackager )
				)
				( objectStatus "U7C1.BW39" )
			)
			( pin "@baseboard_fab2_lib.baseboard_fab2(sch_1):page119_i115:gpp_c20"
				( attribute "PN" "CA39"
					( Origin gPackager )
				)
				( objectStatus "U7C1.CA39" )
			)
			( pin "@baseboard_fab2_lib.baseboard_fab2(sch_1):page119_i115:gpp_c21"
				( attribute "PN" "BY33"
					( Origin gPackager )
				)
				( objectStatus "U7C1.BY33" )
			)
			( pin "@baseboard_fab2_lib.baseboard_fab2(sch_1):page119_i115:gpp_c22"
				( attribute "PN" "CA34"
					( Origin gPackager )
				)
				( objectStatus "U7C1.CA34" )
			)
			( pin "@baseboard_fab2_lib.baseboard_fab2(sch_1):page119_i115:gpp_c23"
				( attribute "PN" "CA37"
					( Origin gPackager )
				)
				( objectStatus "U7C1.CA37" )
			)
			( pin "@baseboard_fab2_lib.baseboard_fab2(sch_1):page119_i115:gpp_d0"
				( attribute "PN" "BR42"
					( Origin gPackager )
				)
				( objectStatus "U7C1.BR42" )
			)
			( pin "@baseboard_fab2_lib.baseboard_fab2(sch_1):page119_i115:gpp_d1"
				( attribute "PN" "BK46"
					( Origin gPackager )
				)
				( objectStatus "U7C1.BK46" )
			)
			( pin "@baseboard_fab2_lib.baseboard_fab2(sch_1):page119_i115:gpp_d2"
				( attribute "PN" "BJ44"
					( Origin gPackager )
				)
				( objectStatus "U7C1.BJ44" )
			)
			( pin "@baseboard_fab2_lib.baseboard_fab2(sch_1):page119_i115:gpp_d3"
				( attribute "PN" "BW45"
					( Origin gPackager )
				)
				( objectStatus "U7C1.BW45" )
			)
			( pin "@baseboard_fab2_lib.baseboard_fab2(sch_1):page119_i115:gpp_d4"
				( attribute "PN" "BM42"
					( Origin gPackager )
				)
				( objectStatus "U7C1.BM42" )
			)
			( pin "@baseboard_fab2_lib.baseboard_fab2(sch_1):page119_i115:gpp_d5"
				( attribute "PN" "BM38"
					( Origin gPackager )
				)
				( objectStatus "U7C1.BM38" )
			)
			( pin "@baseboard_fab2_lib.baseboard_fab2(sch_1):page119_i115:gpp_d6"
				( attribute "PN" "BW41"
					( Origin gPackager )
				)
				( objectStatus "U7C1.BW41" )
			)
			( pin "@baseboard_fab2_lib.baseboard_fab2(sch_1):page119_i115:gpp_d7"
				( attribute "PN" "CA45"
					( Origin gPackager )
				)
				( objectStatus "U7C1.CA45" )
			)
			( pin "@baseboard_fab2_lib.baseboard_fab2(sch_1):page119_i115:gpp_d8"
				( attribute "PN" "BR38"
					( Origin gPackager )
				)
				( objectStatus "U7C1.BR38" )
			)
			( pin "@baseboard_fab2_lib.baseboard_fab2(sch_1):page119_i115:gpp_d9_ssata_devslp3"
				( attribute "PN" "BY42"
					( Origin gPackager )
				)
				( objectStatus "U7C1.BY42" )
			)
			( pin "@baseboard_fab2_lib.baseboard_fab2(sch_1):page119_i115:gpp_d10_ssata_devslp4"
				( attribute "PN" "BV47"
					( Origin gPackager )
				)
				( objectStatus "U7C1.BV47" )
			)
			( pin "@baseboard_fab2_lib.baseboard_fab2(sch_1):page119_i115:gpp_d11_ssata_devslp5"
				( attribute "PN" "BY47"
					( Origin gPackager )
				)
				( objectStatus "U7C1.BY47" )
			)
			( pin "@baseboard_fab2_lib.baseboard_fab2(sch_1):page119_i115:gpp_d12_ssata_sdataout1"
				( attribute "PN" "BN40"
					( Origin gPackager )
				)
				( objectStatus "U7C1.BN40" )
			)
			( pin "@baseboard_fab2_lib.baseboard_fab2(sch_1):page119_i115:gpp_d13_sml0bclk_ie"
				( attribute "PN" "BY44"
					( Origin gPackager )
				)
				( objectStatus "U7C1.BY44" )
			)
			( pin "@baseboard_fab2_lib.baseboard_fab2(sch_1):page119_i115:gpp_d14_sml0bdata_ie"
				( attribute "PN" "BL44"
					( Origin gPackager )
				)
				( objectStatus "U7C1.BL44" )
			)
			( pin "@baseboard_fab2_lib.baseboard_fab2(sch_1):page119_i115:gpp_d15_ssata_sdataout0"
				( attribute "PN" "BW43"
					( Origin gPackager )
				)
				( objectStatus "U7C1.BW43" )
			)
			( pin "@baseboard_fab2_lib.baseboard_fab2(sch_1):page119_i115:gpp_d16_sml0balert_ie_n"
				( attribute "PN" "BV42"
					( Origin gPackager )
				)
				( objectStatus "U7C1.BV42" )
			)
			( pin "@baseboard_fab2_lib.baseboard_fab2(sch_1):page119_i115:gpp_d17"
				( attribute "PN" "BW48"
					( Origin gPackager )
				)
				( objectStatus "U7C1.BW48" )
			)
			( pin "@baseboard_fab2_lib.baseboard_fab2(sch_1):page119_i115:gpp_d18"
				( attribute "PN" "CA41"
					( Origin gPackager )
				)
				( objectStatus "U7C1.CA41" )
			)
			( pin "@baseboard_fab2_lib.baseboard_fab2(sch_1):page119_i115:gpp_d19"
				( attribute "PN" "CA43"
					( Origin gPackager )
				)
				( objectStatus "U7C1.CA43" )
			)
			( pin "@baseboard_fab2_lib.baseboard_fab2(sch_1):page119_i115:gpp_d20"
				( attribute "PN" "CA48"
					( Origin gPackager )
				)
				( objectStatus "U7C1.CA48" )
			)
			( pin "@baseboard_fab2_lib.baseboard_fab2(sch_1):page119_i115:gpp_d21_ie_uart_rx"
				( attribute "PN" "BV44"
					( Origin gPackager )
				)
				( objectStatus "U7C1.BV44" )
			)
			( pin "@baseboard_fab2_lib.baseboard_fab2(sch_1):page119_i115:gpp_d22_ie_uart_tx"
				( attribute "PN" "BR46"
					( Origin gPackager )
				)
				( objectStatus "U7C1.BR46" )
			)
			( pin "@baseboard_fab2_lib.baseboard_fab2(sch_1):page119_i115:gpp_d23"
				( attribute "PN" "BN44"
					( Origin gPackager )
				)
				( objectStatus "U7C1.BN44" )
			)
			( pin "@baseboard_fab2_lib.baseboard_fab2(sch_1):page119_i172:a"
				( attribute "PN" "1"
					( Origin gPackager )
				)
				( objectStatus "R2M3.1" )
			)
			( pin "@baseboard_fab2_lib.baseboard_fab2(sch_1):page119_i172:b"
				( attribute "PN" "2"
					( Origin gPackager )
				)
				( objectStatus "R2M3.2" )
			)
			( pin "@baseboard_fab2_lib.baseboard_fab2(sch_1):page119_i173:a"
				( attribute "PN" "1"
					( Origin gPackager )
				)
				( objectStatus "R2N1.1" )
			)
			( pin "@baseboard_fab2_lib.baseboard_fab2(sch_1):page119_i173:b"
				( attribute "PN" "2"
					( Origin gPackager )
				)
				( objectStatus "R2N1.2" )
			)
			( pin "@baseboard_fab2_lib.baseboard_fab2(sch_1):page119_i174:a"
				( attribute "PN" "1"
					( Origin gPackager )
				)
				( objectStatus "R2M7.1" )
			)
			( pin "@baseboard_fab2_lib.baseboard_fab2(sch_1):page119_i174:b"
				( attribute "PN" "2"
					( Origin gPackager )
				)
				( objectStatus "R2M7.2" )
			)
			( pin "@baseboard_fab2_lib.baseboard_fab2(sch_1):page119_i175:drain(0)"
				( attribute "PN" "6"
					( Origin gPackager )
				)
				( objectStatus "Q9A2.6" )
			)
			( pin "@baseboard_fab2_lib.baseboard_fab2(sch_1):page119_i175:gate(0)"
				( attribute "PN" "2"
					( Origin gPackager )
				)
				( objectStatus "Q9A2.2" )
			)
			( pin "@baseboard_fab2_lib.baseboard_fab2(sch_1):page119_i175:source(0)"
				( attribute "PN" "1"
					( Origin gPackager )
				)
				( objectStatus "Q9A2.1" )
			)
			( pin "@baseboard_fab2_lib.baseboard_fab2(sch_1):page119_i178:a"
				( attribute "PN" "1"
					( Origin gPackager )
				)
				( objectStatus "R9A20.1" )
			)
			( pin "@baseboard_fab2_lib.baseboard_fab2(sch_1):page119_i178:b"
				( attribute "PN" "2"
					( Origin gPackager )
				)
				( objectStatus "R9A20.2" )
			)
			( pin "@baseboard_fab2_lib.baseboard_fab2(sch_1):page119_i179:a"
				( attribute "PN" "1"
					( Origin gPackager )
				)
				( objectStatus "DS9A5.1" )
			)
			( pin "@baseboard_fab2_lib.baseboard_fab2(sch_1):page119_i179:c"
				( attribute "PN" "2"
					( Origin gPackager )
				)
				( objectStatus "DS9A5.2" )
			)
			( pin "@baseboard_fab2_lib.baseboard_fab2(sch_1):page119_i180:drain(0)"
				( attribute "PN" "3"
					( Origin gPackager )
				)
				( objectStatus "Q9A2.3" )
			)
			( pin "@baseboard_fab2_lib.baseboard_fab2(sch_1):page119_i180:gate(0)"
				( attribute "PN" "5"
					( Origin gPackager )
				)
				( objectStatus "Q9A2.5" )
			)
			( pin "@baseboard_fab2_lib.baseboard_fab2(sch_1):page119_i180:source(0)"
				( attribute "PN" "4"
					( Origin gPackager )
				)
				( objectStatus "Q9A2.4" )
			)
			( pin "@baseboard_fab2_lib.baseboard_fab2(sch_1):page119_i183:a"
				( attribute "PN" "1"
					( Origin gPackager )
				)
				( objectStatus "R9A18.1" )
			)
			( pin "@baseboard_fab2_lib.baseboard_fab2(sch_1):page119_i183:b"
				( attribute "PN" "2"
					( Origin gPackager )
				)
				( objectStatus "R9A18.2" )
			)
			( pin "@baseboard_fab2_lib.baseboard_fab2(sch_1):page119_i186:a"
				( attribute "PN" "1"
					( Origin gPackager )
				)
				( objectStatus "R9A21.1" )
			)
			( pin "@baseboard_fab2_lib.baseboard_fab2(sch_1):page119_i186:b"
				( attribute "PN" "2"
					( Origin gPackager )
				)
				( objectStatus "R9A21.2" )
			)
			( pin "@baseboard_fab2_lib.baseboard_fab2(sch_1):page119_i189:a"
				( attribute "PN" "1"
					( Origin gPackager )
				)
				( objectStatus "R7C26.1" )
			)
			( pin "@baseboard_fab2_lib.baseboard_fab2(sch_1):page119_i189:b"
				( attribute "PN" "2"
					( Origin gPackager )
				)
				( objectStatus "R7C26.2" )
			)
			( pin "@baseboard_fab2_lib.baseboard_fab2(sch_1):page119_i213:a"
				( attribute "PN" "1"
					( Origin gPackager )
				)
				( objectStatus "R2U48.1" )
			)
			( pin "@baseboard_fab2_lib.baseboard_fab2(sch_1):page119_i213:b"
				( attribute "PN" "2"
					( Origin gPackager )
				)
				( objectStatus "R2U48.2" )
			)
			( pin "@baseboard_fab2_lib.baseboard_fab2(sch_1):page119_i229:a"
				( attribute "PN" "1"
					( Origin gPackager )
				)
				( objectStatus "R7W17.1" )
			)
			( pin "@baseboard_fab2_lib.baseboard_fab2(sch_1):page119_i229:b"
				( attribute "PN" "2"
					( Origin gPackager )
				)
				( objectStatus "R7W17.2" )
			)
			( pin "@baseboard_fab2_lib.baseboard_fab2(sch_1):page120_i147:gpio_rcomp_3p3"
				( attribute "PN" "BY25"
					( Origin gPackager )
				)
				( objectStatus "U7C1.BY25" )
			)
			( pin "@baseboard_fab2_lib.baseboard_fab2(sch_1):page120_i147:gpp_e0_sataxpcie0_satagp0"
				( attribute "PN" "BH50"
					( Origin gPackager )
				)
				( objectStatus "U7C1.BH50" )
			)
			( pin "@baseboard_fab2_lib.baseboard_fab2(sch_1):page120_i147:gpp_e1_sataxpcie1_satagp1"
				( attribute "PN" "AY52"
					( Origin gPackager )
				)
				( objectStatus "U7C1.AY52" )
			)
			( pin "@baseboard_fab2_lib.baseboard_fab2(sch_1):page120_i147:gpp_e2_sataxpcie2_satagp2"
				( attribute "PN" "BG52"
					( Origin gPackager )
				)
				( objectStatus "U7C1.BG52" )
			)
			( pin "@baseboard_fab2_lib.baseboard_fab2(sch_1):page120_i147:gpp_e3_cpu_gp0"
				( attribute "PN" "BE52"
					( Origin gPackager )
				)
				( objectStatus "U7C1.BE52" )
			)
			( pin "@baseboard_fab2_lib.baseboard_fab2(sch_1):page120_i147:gpp_e4_sata_devslp0"
				( attribute "PN" "AV52"
					( Origin gPackager )
				)
				( objectStatus "U7C1.AV52" )
			)
			( pin "@baseboard_fab2_lib.baseboard_fab2(sch_1):page120_i147:gpp_e5_sata_devslp1"
				( attribute "PN" "AT52"
					( Origin gPackager )
				)
				( objectStatus "U7C1.AT52" )
			)
			( pin "@baseboard_fab2_lib.baseboard_fab2(sch_1):page120_i147:gpp_e6_sata_devslp2"
				( attribute "PN" "BB52"
					( Origin gPackager )
				)
				( objectStatus "U7C1.BB52" )
			)
			( pin "@baseboard_fab2_lib.baseboard_fab2(sch_1):page120_i147:gpp_e7_cpu_gp1"
				( attribute "PN" "BJ48"
					( Origin gPackager )
				)
				( objectStatus "U7C1.BJ48" )
			)
			( pin "@baseboard_fab2_lib.baseboard_fab2(sch_1):page120_i147:gpp_e8_sata_led_n"
				( attribute "PN" "AV56"
					( Origin gPackager )
				)
				( objectStatus "U7C1.AV56" )
			)
			( pin "@baseboard_fab2_lib.baseboard_fab2(sch_1):page120_i147:gpp_e9_usb2_oc0_n"
				( attribute "PN" "BL48"
					( Origin gPackager )
				)
				( objectStatus "U7C1.BL48" )
			)
			( pin "@baseboard_fab2_lib.baseboard_fab2(sch_1):page120_i147:gpp_e10_usb2_oc1_n"
				( attribute "PN" "BN48"
					( Origin gPackager )
				)
				( objectStatus "U7C1.BN48" )
			)
			( pin "@baseboard_fab2_lib.baseboard_fab2(sch_1):page120_i147:gpp_e11_usb2_oc2_n"
				( attribute "PN" "AW54"
					( Origin gPackager )
				)
				( objectStatus "U7C1.AW54" )
			)
			( pin "@baseboard_fab2_lib.baseboard_fab2(sch_1):page120_i147:gpp_e12_usb2_oc3_n"
				( attribute "PN" "AU58"
					( Origin gPackager )
				)
				( objectStatus "U7C1.AU58" )
			)
			( pin "@baseboard_fab2_lib.baseboard_fab2(sch_1):page120_i147:gpp_f0_sataxpcie3_satagp3"
				( attribute "PN" "AG7"
					( Origin gPackager )
				)
				( objectStatus "U7C1.AG7" )
			)
			( pin "@baseboard_fab2_lib.baseboard_fab2(sch_1):page120_i147:gpp_f1_sataxpcie4_satagp4"
				( attribute "PN" "AK9"
					( Origin gPackager )
				)
				( objectStatus "U7C1.AK9" )
			)
			( pin "@baseboard_fab2_lib.baseboard_fab2(sch_1):page120_i147:gpp_f2_sataxpcie5_satagp5"
				( attribute "PN" "AK20"
					( Origin gPackager )
				)
				( objectStatus "U7C1.AK20" )
			)
			( pin "@baseboard_fab2_lib.baseboard_fab2(sch_1):page120_i147:gpp_f3_sataxpcie6_satagp6"
				( attribute "PN" "AK13"
					( Origin gPackager )
				)
				( objectStatus "U7C1.AK13" )
			)
			( pin "@baseboard_fab2_lib.baseboard_fab2(sch_1):page120_i147:gpp_f4_sataxpcie7_satagp7"
				( attribute "PN" "AH13"
					( Origin gPackager )
				)
				( objectStatus "U7C1.AH13" )
			)
			( pin "@baseboard_fab2_lib.baseboard_fab2(sch_1):page120_i147:gpp_f5_sata_devslp3"
				( attribute "PN" "AH17"
					( Origin gPackager )
				)
				( objectStatus "U7C1.AH17" )
			)
			( pin "@baseboard_fab2_lib.baseboard_fab2(sch_1):page120_i147:gpp_f6_sata_devslp4"
				( attribute "PN" "AL18"
					( Origin gPackager )
				)
				( objectStatus "U7C1.AL18" )
			)
			( pin "@baseboard_fab2_lib.baseboard_fab2(sch_1):page120_i147:gpp_f7_sata_devslp5"
				( attribute "PN" "AK17"
					( Origin gPackager )
				)
				( objectStatus "U7C1.AK17" )
			)
			( pin "@baseboard_fab2_lib.baseboard_fab2(sch_1):page120_i147:gpp_f8_sata_devslp6"
				( attribute "PN" "AH9"
					( Origin gPackager )
				)
				( objectStatus "U7C1.AH9" )
			)
			( pin "@baseboard_fab2_lib.baseboard_fab2(sch_1):page120_i147:gpp_f9_sata_devslp7"
				( attribute "PN" "AR20"
					( Origin gPackager )
				)
				( objectStatus "U7C1.AR20" )
			)
			( pin "@baseboard_fab2_lib.baseboard_fab2(sch_1):page120_i147:gpp_f10_sata_sclock"
				( attribute "PN" "AL7"
					( Origin gPackager )
				)
				( objectStatus "U7C1.AL7" )
			)
			( pin "@baseboard_fab2_lib.baseboard_fab2(sch_1):page120_i147:gpp_f11_sata_sload"
				( attribute "PN" "AR9"
					( Origin gPackager )
				)
				( objectStatus "U7C1.AR9" )
			)
			( pin "@baseboard_fab2_lib.baseboard_fab2(sch_1):page120_i147:gpp_f12_sata_sdataout1"
				( attribute "PN" "AP7"
					( Origin gPackager )
				)
				( objectStatus "U7C1.AP7" )
			)
			( pin "@baseboard_fab2_lib.baseboard_fab2(sch_1):page120_i147:gpp_f13_sata_sdataout0"
				( attribute "PN" "AP11"
					( Origin gPackager )
				)
				( objectStatus "U7C1.AP11" )
			)
			( pin "@baseboard_fab2_lib.baseboard_fab2(sch_1):page120_i147:gpp_f14_ssata_led_n"
				( attribute "PN" "AL11"
					( Origin gPackager )
				)
				( objectStatus "U7C1.AL11" )
			)
			( pin "@baseboard_fab2_lib.baseboard_fab2(sch_1):page120_i147:gpp_f15_usb2_oc4_n"
				( attribute "PN" "AR13"
					( Origin gPackager )
				)
				( objectStatus "U7C1.AR13" )
			)
			( pin "@baseboard_fab2_lib.baseboard_fab2(sch_1):page120_i147:gpp_f16_usb2_oc5_n"
				( attribute "PN" "AU13"
					( Origin gPackager )
				)
				( objectStatus "U7C1.AU13" )
			)
			( pin "@baseboard_fab2_lib.baseboard_fab2(sch_1):page120_i147:gpp_f17_usb2_oc6_n"
				( attribute "PN" "AP15"
					( Origin gPackager )
				)
				( objectStatus "U7C1.AP15" )
			)
			( pin "@baseboard_fab2_lib.baseboard_fab2(sch_1):page120_i147:gpp_f18_usb2_oc7_n"
				( attribute "PN" "AL15"
					( Origin gPackager )
				)
				( objectStatus "U7C1.AL15" )
			)
			( pin "@baseboard_fab2_lib.baseboard_fab2(sch_1):page120_i147:gpp_f19_lan_smbclk"
				( attribute "PN" "AU9"
					( Origin gPackager )
				)
				( objectStatus "U7C1.AU9" )
			)
			( pin "@baseboard_fab2_lib.baseboard_fab2(sch_1):page120_i147:gpp_f20_lan_smbdata"
				( attribute "PN" "AU20"
					( Origin gPackager )
				)
				( objectStatus "U7C1.AU20" )
			)
			( pin "@baseboard_fab2_lib.baseboard_fab2(sch_1):page120_i147:gpp_f21_lan_smbalrt_n"
				( attribute "PN" "AR17"
					( Origin gPackager )
				)
				( objectStatus "U7C1.AR17" )
			)
			( pin "@baseboard_fab2_lib.baseboard_fab2(sch_1):page120_i147:gpp_f22_ssata_sclock"
				( attribute "PN" "AP18"
					( Origin gPackager )
				)
				( objectStatus "U7C1.AP18" )
			)
			( pin "@baseboard_fab2_lib.baseboard_fab2(sch_1):page120_i147:gpp_f23_ssata_sload"
				( attribute "PN" "AU17"
					( Origin gPackager )
				)
				( objectStatus "U7C1.AU17" )
			)
			( pin "@baseboard_fab2_lib.baseboard_fab2(sch_1):page120_i147:gpp_g0_fantach0_fantach0ie"
				( attribute "PN" "AY11"
					( Origin gPackager )
				)
				( objectStatus "U7C1.AY11" )
			)
			( pin "@baseboard_fab2_lib.baseboard_fab2(sch_1):page120_i147:gpp_g1_fantach1_fantach1ie"
				( attribute "PN" "AV15"
					( Origin gPackager )
				)
				( objectStatus "U7C1.AV15" )
			)
			( pin "@baseboard_fab2_lib.baseboard_fab2(sch_1):page120_i147:gpp_g2_fantach2_fantach2ie"
				( attribute "PN" "BE22"
					( Origin gPackager )
				)
				( objectStatus "U7C1.BE22" )
			)
			( pin "@baseboard_fab2_lib.baseboard_fab2(sch_1):page120_i147:gpp_g3_fantach3_fantach3ie"
				( attribute "PN" "AY7"
					( Origin gPackager )
				)
				( objectStatus "U7C1.AY7" )
			)
			( pin "@baseboard_fab2_lib.baseboard_fab2(sch_1):page120_i147:gpp_g4_fantach4_fantach4ie"
				( attribute "PN" "BA9"
					( Origin gPackager )
				)
				( objectStatus "U7C1.BA9" )
			)
			( pin "@baseboard_fab2_lib.baseboard_fab2(sch_1):page120_i147:gpp_g5_fantach5_fantach5ie"
				( attribute "PN" "AW20"
					( Origin gPackager )
				)
				( objectStatus "U7C1.AW20" )
			)
			( pin "@baseboard_fab2_lib.baseboard_fab2(sch_1):page120_i147:gpp_g6_fantach6_fantach6ie"
				( attribute "PN" "AV18"
					( Origin gPackager )
				)
				( objectStatus "U7C1.AV18" )
			)
			( pin "@baseboard_fab2_lib.baseboard_fab2(sch_1):page120_i147:gpp_g7_fantach7_fantach7ie"
				( attribute "PN" "AY15"
					( Origin gPackager )
				)
				( objectStatus "U7C1.AY15" )
			)
			( pin "@baseboard_fab2_lib.baseboard_fab2(sch_1):page120_i147:gpp_g8_fanpwm0_fanpwm0ie"
				( attribute "PN" "BG11"
					( Origin gPackager )
				)
				( objectStatus "U7C1.BG11" )
			)
			( pin "@baseboard_fab2_lib.baseboard_fab2(sch_1):page120_i147:gpp_g9_fanpwm1_fampwm1ie"
				( attribute "PN" "AV11"
					( Origin gPackager )
				)
				( objectStatus "U7C1.AV11" )
			)
			( pin "@baseboard_fab2_lib.baseboard_fab2(sch_1):page120_i147:gpp_g10_fanpwm2_fanpwm2ie"
				( attribute "PN" "BE11"
					( Origin gPackager )
				)
				( objectStatus "U7C1.BE11" )
			)
			( pin "@baseboard_fab2_lib.baseboard_fab2(sch_1):page120_i147:gpp_g11_fanpwm3_fanpmw3ie"
				( attribute "PN" "BA20"
					( Origin gPackager )
				)
				( objectStatus "U7C1.BA20" )
			)
			( pin "@baseboard_fab2_lib.baseboard_fab2(sch_1):page120_i147:gpp_g12"
				( attribute "PN" "BD13"
					( Origin gPackager )
				)
				( objectStatus "U7C1.BD13" )
			)
			( pin "@baseboard_fab2_lib.baseboard_fab2(sch_1):page120_i147:gpp_g13"
				( attribute "PN" "AY18"
					( Origin gPackager )
				)
				( objectStatus "U7C1.AY18" )
			)
			( pin "@baseboard_fab2_lib.baseboard_fab2(sch_1):page120_i147:gpp_g14"
				( attribute "PN" "AV7"
					( Origin gPackager )
				)
				( objectStatus "U7C1.AV7" )
			)
			( pin "@baseboard_fab2_lib.baseboard_fab2(sch_1):page120_i147:gpp_g15"
				( attribute "PN" "BE18"
					( Origin gPackager )
				)
				( objectStatus "U7C1.BE18" )
			)
			( pin "@baseboard_fab2_lib.baseboard_fab2(sch_1):page120_i147:gpp_g16"
				( attribute "PN" "BD17"
					( Origin gPackager )
				)
				( objectStatus "U7C1.BD17" )
			)
			( pin "@baseboard_fab2_lib.baseboard_fab2(sch_1):page120_i147:gpp_g17_adr_complete"
				( attribute "PN" "BD9"
					( Origin gPackager )
				)
				( objectStatus "U7C1.BD9" )
			)
			( pin "@baseboard_fab2_lib.baseboard_fab2(sch_1):page120_i147:gpp_g18_nmi_n"
				( attribute "PN" "BE7"
					( Origin gPackager )
				)
				( objectStatus "U7C1.BE7" )
			)
			( pin "@baseboard_fab2_lib.baseboard_fab2(sch_1):page120_i147:gpp_g19_smi_n"
				( attribute "PN" "BE15"
					( Origin gPackager )
				)
				( objectStatus "U7C1.BE15" )
			)
			( pin "@baseboard_fab2_lib.baseboard_fab2(sch_1):page120_i147:gpp_g20_ssata_devslp0"
				( attribute "PN" "BA17"
					( Origin gPackager )
				)
				( objectStatus "U7C1.BA17" )
			)
			( pin "@baseboard_fab2_lib.baseboard_fab2(sch_1):page120_i147:gpp_g21_ssata_devslp1"
				( attribute "PN" "BG7"
					( Origin gPackager )
				)
				( objectStatus "U7C1.BG7" )
			)
			( pin "@baseboard_fab2_lib.baseboard_fab2(sch_1):page120_i147:gpp_g22_ssata_devslp2"
				( attribute "PN" "BD20"
					( Origin gPackager )
				)
				( objectStatus "U7C1.BD20" )
			)
			( pin "@baseboard_fab2_lib.baseboard_fab2(sch_1):page120_i147:gpp_g23_ssataxpcie0_ssatagp0"
				( attribute "PN" "BA13"
					( Origin gPackager )
				)
				( objectStatus "U7C1.BA13" )
			)
			( pin "@baseboard_fab2_lib.baseboard_fab2(sch_1):page120_i147:gpp_h0_srcclkreq6_n"
				( attribute "PN" "AT4"
					( Origin gPackager )
				)
				( objectStatus "U7C1.AT4" )
			)
			( pin "@baseboard_fab2_lib.baseboard_fab2(sch_1):page120_i147:gpp_h1_srcclkreq7_n"
				( attribute "PN" "AW4"
					( Origin gPackager )
				)
				( objectStatus "U7C1.AW4" )
			)
			( pin "@baseboard_fab2_lib.baseboard_fab2(sch_1):page120_i147:gpp_h2_srcclkreq8_n"
				( attribute "PN" "AV3"
					( Origin gPackager )
				)
				( objectStatus "U7C1.AV3" )
			)
			( pin "@baseboard_fab2_lib.baseboard_fab2(sch_1):page120_i147:gpp_h3_srcclkreq9_n"
				( attribute "PN" "AR1"
					( Origin gPackager )
				)
				( objectStatus "U7C1.AR1" )
			)
			( pin "@baseboard_fab2_lib.baseboard_fab2(sch_1):page120_i147:gpp_h4_srcclkreq10_n"
				( attribute "PN" "AT2"
					( Origin gPackager )
				)
				( objectStatus "U7C1.AT2" )
			)
			( pin "@baseboard_fab2_lib.baseboard_fab2(sch_1):page120_i147:gpp_h5_srcclkreq11_n"
				( attribute "PN" "AY3"
					( Origin gPackager )
				)
				( objectStatus "U7C1.AY3" )
			)
			( pin "@baseboard_fab2_lib.baseboard_fab2(sch_1):page120_i147:gpp_h6_srcclkreq12_n"
				( attribute "PN" "AW2"
					( Origin gPackager )
				)
				( objectStatus "U7C1.AW2" )
			)
			( pin "@baseboard_fab2_lib.baseboard_fab2(sch_1):page120_i147:gpp_h7_srcclkreq13_n"
				( attribute "PN" "AV1"
					( Origin gPackager )
				)
				( objectStatus "U7C1.AV1" )
			)
			( pin "@baseboard_fab2_lib.baseboard_fab2(sch_1):page120_i147:gpp_h8_srcclkreq14_n"
				( attribute "PN" "AR3"
					( Origin gPackager )
				)
				( objectStatus "U7C1.AR3" )
			)
			( pin "@baseboard_fab2_lib.baseboard_fab2(sch_1):page120_i147:gpp_h9_srcclkreq15_n"
				( attribute "PN" "BE2"
					( Origin gPackager )
				)
				( objectStatus "U7C1.BE2" )
			)
			( pin "@baseboard_fab2_lib.baseboard_fab2(sch_1):page120_i147:gpp_h10_sml2clk_ie"
				( attribute "PN" "BA4"
					( Origin gPackager )
				)
				( objectStatus "U7C1.BA4" )
			)
			( pin "@baseboard_fab2_lib.baseboard_fab2(sch_1):page120_i147:gpp_h11_sml2data_ie"
				( attribute "PN" "BD1"
					( Origin gPackager )
				)
				( objectStatus "U7C1.BD1" )
			)
			( pin "@baseboard_fab2_lib.baseboard_fab2(sch_1):page120_i147:gpp_h12_sml2alert_n_ie_n"
				( attribute "PN" "BB1"
					( Origin gPackager )
				)
				( objectStatus "U7C1.BB1" )
			)
			( pin "@baseboard_fab2_lib.baseboard_fab2(sch_1):page120_i147:gpp_h13_sml3clk_ie"
				( attribute "PN" "AY1"
					( Origin gPackager )
				)
				( objectStatus "U7C1.AY1" )
			)
			( pin "@baseboard_fab2_lib.baseboard_fab2(sch_1):page120_i147:gpp_h14_sml3data_ie"
				( attribute "PN" "BC2"
					( Origin gPackager )
				)
				( objectStatus "U7C1.BC2" )
			)
			( pin "@baseboard_fab2_lib.baseboard_fab2(sch_1):page120_i147:gpp_h15_sml3alert_n_ie_n"
				( attribute "PN" "BB3"
					( Origin gPackager )
				)
				( objectStatus "U7C1.BB3" )
			)
			( pin "@baseboard_fab2_lib.baseboard_fab2(sch_1):page120_i147:gpp_h16_sml4clk_ie"
				( attribute "PN" "BF1"
					( Origin gPackager )
				)
				( objectStatus "U7C1.BF1" )
			)
			( pin "@baseboard_fab2_lib.baseboard_fab2(sch_1):page120_i147:gpp_h17_sml4data_ie"
				( attribute "PN" "BE4"
					( Origin gPackager )
				)
				( objectStatus "U7C1.BE4" )
			)
			( pin "@baseboard_fab2_lib.baseboard_fab2(sch_1):page120_i147:gpp_h18_sml4alert_n_ie_n"
				( attribute "PN" "BC4"
					( Origin gPackager )
				)
				( objectStatus "U7C1.BC4" )
			)
			( pin "@baseboard_fab2_lib.baseboard_fab2(sch_1):page120_i147:gpp_h19_ssataxpcie1_ssatagp1"
				( attribute "PN" "BD3"
					( Origin gPackager )
				)
				( objectStatus "U7C1.BD3" )
			)
			( pin "@baseboard_fab2_lib.baseboard_fab2(sch_1):page120_i147:gpp_h20_ssataxpcie2_ssatagp2"
				( attribute "PN" "BF3"
					( Origin gPackager )
				)
				( objectStatus "U7C1.BF3" )
			)
			( pin "@baseboard_fab2_lib.baseboard_fab2(sch_1):page120_i147:gpp_h21_ssataxpcie3_ssatagp3"
				( attribute "PN" "BA2"
					( Origin gPackager )
				)
				( objectStatus "U7C1.BA2" )
			)
			( pin "@baseboard_fab2_lib.baseboard_fab2(sch_1):page120_i147:gpp_h22_ssataxpcie4_ssatagp4"
				( attribute "PN" "BH2"
					( Origin gPackager )
				)
				( objectStatus "U7C1.BH2" )
			)
			( pin "@baseboard_fab2_lib.baseboard_fab2(sch_1):page120_i147:gpp_h23_ssataxpcie5_ssatagp5"
				( attribute "PN" "BH4"
					( Origin gPackager )
				)
				( objectStatus "U7C1.BH4" )
			)
			( pin "@baseboard_fab2_lib.baseboard_fab2(sch_1):page120_i147:gpp_i0_lan_tdo"
				( attribute "PN" "CA20"
					( Origin gPackager )
				)
				( objectStatus "U7C1.CA20" )
			)
			( pin "@baseboard_fab2_lib.baseboard_fab2(sch_1):page120_i147:gpp_i1_lan_tck"
				( attribute "PN" "BV21"
					( Origin gPackager )
				)
				( objectStatus "U7C1.BV21" )
			)
			( pin "@baseboard_fab2_lib.baseboard_fab2(sch_1):page120_i147:gpp_i2_lan_tms"
				( attribute "PN" "CA22"
					( Origin gPackager )
				)
				( objectStatus "U7C1.CA22" )
			)
			( pin "@baseboard_fab2_lib.baseboard_fab2(sch_1):page120_i147:gpp_i3_lan_tdi"
				( attribute "PN" "BY23"
					( Origin gPackager )
				)
				( objectStatus "U7C1.BY23" )
			)
			( pin "@baseboard_fab2_lib.baseboard_fab2(sch_1):page120_i147:gpp_i4_do_reset_in_n"
				( attribute "PN" "BW20"
					( Origin gPackager )
				)
				( objectStatus "U7C1.BW20" )
			)
			( pin "@baseboard_fab2_lib.baseboard_fab2(sch_1):page120_i147:gpp_i5_do_reset_out_n"
				( attribute "PN" "BW24"
					( Origin gPackager )
				)
				( objectStatus "U7C1.BW24" )
			)
			( pin "@baseboard_fab2_lib.baseboard_fab2(sch_1):page120_i147:gpp_i6_reset_done"
				( attribute "PN" "BV23"
					( Origin gPackager )
				)
				( objectStatus "U7C1.BV23" )
			)
			( pin "@baseboard_fab2_lib.baseboard_fab2(sch_1):page120_i147:gpp_i7_lan_trst_n"
				( attribute "PN" "CA24"
					( Origin gPackager )
				)
				( objectStatus "U7C1.CA24" )
			)
			( pin "@baseboard_fab2_lib.baseboard_fab2(sch_1):page120_i147:gpp_i8_pci_dis_n"
				( attribute "PN" "BW22"
					( Origin gPackager )
				)
				( objectStatus "U7C1.BW22" )
			)
			( pin "@baseboard_fab2_lib.baseboard_fab2(sch_1):page120_i147:gpp_i9_lan_dis_n"
				( attribute "PN" "BY21"
					( Origin gPackager )
				)
				( objectStatus "U7C1.BY21" )
			)
			( pin "@baseboard_fab2_lib.baseboard_fab2(sch_1):page120_i147:gpp_i10"
				( attribute "PN" "BV25"
					( Origin gPackager )
				)
				( objectStatus "U7C1.BV25" )
			)
			( pin "@baseboard_fab2_lib.baseboard_fab2(sch_1):page120_i147:gpp_j0_lan_led_p0_0"
				( attribute "PN" "BL1"
					( Origin gPackager )
				)
				( objectStatus "U7C1.BL1" )
			)
			( pin "@baseboard_fab2_lib.baseboard_fab2(sch_1):page120_i147:gpp_j1_lan_led_p0_1"
				( attribute "PN" "BK4"
					( Origin gPackager )
				)
				( objectStatus "U7C1.BK4" )
			)
			( pin "@baseboard_fab2_lib.baseboard_fab2(sch_1):page120_i147:gpp_j2_lan_led_p1_0"
				( attribute "PN" "BP4"
					( Origin gPackager )
				)
				( objectStatus "U7C1.BP4" )
			)
			( pin "@baseboard_fab2_lib.baseboard_fab2(sch_1):page120_i147:gpp_j3_lan_led_p1_1"
				( attribute "PN" "BK2"
					( Origin gPackager )
				)
				( objectStatus "U7C1.BK2" )
			)
			( pin "@baseboard_fab2_lib.baseboard_fab2(sch_1):page120_i147:gpp_j4_lan_led_p2_0"
				( attribute "PN" "BL3"
					( Origin gPackager )
				)
				( objectStatus "U7C1.BL3" )
			)
			( pin "@baseboard_fab2_lib.baseboard_fab2(sch_1):page120_i147:gpp_j5_lan_led_p2_1"
				( attribute "PN" "BU6"
					( Origin gPackager )
				)
				( objectStatus "U7C1.BU6" )
			)
			( pin "@baseboard_fab2_lib.baseboard_fab2(sch_1):page120_i147:gpp_j6_lan_led_p3_0"
				( attribute "PN" "CA13"
					( Origin gPackager )
				)
				( objectStatus "U7C1.CA13" )
			)
			( pin "@baseboard_fab2_lib.baseboard_fab2(sch_1):page120_i147:gpp_j7_lan_led_p3_1"
				( attribute "PN" "BM2"
					( Origin gPackager )
				)
				( objectStatus "U7C1.BM2" )
			)
			( pin "@baseboard_fab2_lib.baseboard_fab2(sch_1):page120_i147:gpp_j8_lan_i2c_scl_mdc_p0"
				( attribute "PN" "BM4"
					( Origin gPackager )
				)
				( objectStatus "U7C1.BM4" )
			)
			( pin "@baseboard_fab2_lib.baseboard_fab2(sch_1):page120_i147:gpp_j9_lan_i2c_sda_mdio_p0"
				( attribute "PN" "BN3"
					( Origin gPackager )
				)
				( objectStatus "U7C1.BN3" )
			)
			( pin "@baseboard_fab2_lib.baseboard_fab2(sch_1):page120_i147:gpp_j10_lan_i2c_scl_mdc_p1"
				( attribute "PN" "BW5"
					( Origin gPackager )
				)
				( objectStatus "U7C1.BW5" )
			)
			( pin "@baseboard_fab2_lib.baseboard_fab2(sch_1):page120_i147:gpp_j11_lan_i2c_sda_mdio_p1"
				( attribute "PN" "BV8"
					( Origin gPackager )
				)
				( objectStatus "U7C1.BV8" )
			)
			( pin "@baseboard_fab2_lib.baseboard_fab2(sch_1):page120_i147:gpp_j12_lan_i2c_scl_mdc_p2"
				( attribute "PN" "BT5"
					( Origin gPackager )
				)
				( objectStatus "U7C1.BT5" )
			)
			( pin "@baseboard_fab2_lib.baseboard_fab2(sch_1):page120_i147:gpp_j13_lan_i2c_sda_mdio_p2"
				( attribute "PN" "BW11"
					( Origin gPackager )
				)
				( objectStatus "U7C1.BW11" )
			)
			( pin "@baseboard_fab2_lib.baseboard_fab2(sch_1):page120_i147:gpp_j14_lan_i2c_scl_mdc_p3"
				( attribute "PN" "BW6"
					( Origin gPackager )
				)
				( objectStatus "U7C1.BW6" )
			)
			( pin "@baseboard_fab2_lib.baseboard_fab2(sch_1):page120_i147:gpp_j15_lan_i2c_sda_mdio_p3"
				( attribute "PN" "BW9"
					( Origin gPackager )
				)
				( objectStatus "U7C1.BW9" )
			)
			( pin "@baseboard_fab2_lib.baseboard_fab2(sch_1):page120_i147:gpp_j16_lan_sdp_p0_0"
				( attribute "PN" "BV10"
					( Origin gPackager )
				)
				( objectStatus "U7C1.BV10" )
			)
			( pin "@baseboard_fab2_lib.baseboard_fab2(sch_1):page120_i147:gpp_j17_lan_sdp_p0_1"
				( attribute "PN" "CA11"
					( Origin gPackager )
				)
				( objectStatus "U7C1.CA11" )
			)
			( pin "@baseboard_fab2_lib.baseboard_fab2(sch_1):page120_i147:gpp_j18_lan_sdp_p1_0"
				( attribute "PN" "BY10"
					( Origin gPackager )
				)
				( objectStatus "U7C1.BY10" )
			)
			( pin "@baseboard_fab2_lib.baseboard_fab2(sch_1):page120_i147:gpp_j19_lan_sdp_p1_1"
				( attribute "PN" "BY14"
					( Origin gPackager )
				)
				( objectStatus "U7C1.BY14" )
			)
			( pin "@baseboard_fab2_lib.baseboard_fab2(sch_1):page120_i147:gpp_j20_lan_sdp_p2_0"
				( attribute "PN" "BW13"
					( Origin gPackager )
				)
				( objectStatus "U7C1.BW13" )
			)
			( pin "@baseboard_fab2_lib.baseboard_fab2(sch_1):page120_i147:gpp_j21_lan_sdp_p2_1"
				( attribute "PN" "BV12"
					( Origin gPackager )
				)
				( objectStatus "U7C1.BV12" )
			)
			( pin "@baseboard_fab2_lib.baseboard_fab2(sch_1):page120_i147:gpp_j22_lan_sdp_p3_0"
				( attribute "PN" "BY12"
					( Origin gPackager )
				)
				( objectStatus "U7C1.BY12" )
			)
			( pin "@baseboard_fab2_lib.baseboard_fab2(sch_1):page120_i147:gpp_j23_lan_sdp_p3_1"
				( attribute "PN" "BV14"
					( Origin gPackager )
				)
				( objectStatus "U7C1.BV14" )
			)
			( pin "@baseboard_fab2_lib.baseboard_fab2(sch_1):page120_i276:a"
				( attribute "PN" "1"
					( Origin gPackager )
				)
				( objectStatus "R7W16.1" )
			)
			( pin "@baseboard_fab2_lib.baseboard_fab2(sch_1):page120_i276:b"
				( attribute "PN" "2"
					( Origin gPackager )
				)
				( objectStatus "R7W16.2" )
			)
			( pin "@baseboard_fab2_lib.baseboard_fab2(sch_1):page120_i218:a"
				( attribute "PN" "1"
					( Origin gPackager )
				)
				( objectStatus "R2M1.1" )
			)
			( pin "@baseboard_fab2_lib.baseboard_fab2(sch_1):page120_i218:b"
				( attribute "PN" "2"
					( Origin gPackager )
				)
				( objectStatus "R2M1.2" )
			)
			( pin "@baseboard_fab2_lib.baseboard_fab2(sch_1):page120_i219:a"
				( attribute "PN" "1"
					( Origin gPackager )
				)
				( objectStatus "R2N26.1" )
			)
			( pin "@baseboard_fab2_lib.baseboard_fab2(sch_1):page120_i219:b"
				( attribute "PN" "2"
					( Origin gPackager )
				)
				( objectStatus "R2N26.2" )
			)
			( pin "@baseboard_fab2_lib.baseboard_fab2(sch_1):page121_i31:a"
				( attribute "PN" "1"
					( Origin gPackager )
				)
				( objectStatus "R7C15.1" )
			)
			( pin "@baseboard_fab2_lib.baseboard_fab2(sch_1):page121_i31:b"
				( attribute "PN" "2"
					( Origin gPackager )
				)
				( objectStatus "R7C15.2" )
			)
			( pin "@baseboard_fab2_lib.baseboard_fab2(sch_1):page121_i33:a"
				( attribute "PN" "1"
					( Origin gPackager )
				)
				( objectStatus "R7C16.1" )
			)
			( pin "@baseboard_fab2_lib.baseboard_fab2(sch_1):page121_i33:b"
				( attribute "PN" "2"
					( Origin gPackager )
				)
				( objectStatus "R7C16.2" )
			)
			( pin "@baseboard_fab2_lib.baseboard_fab2(sch_1):page121_i34:cgc_dut_detect_n"
				( attribute "PN" "C70"
					( Origin gPackager )
				)
				( objectStatus "U7C1.C70" )
			)
			( pin "@baseboard_fab2_lib.baseboard_fab2(sch_1):page121_i34:gpio_rcomp_1p8_3p3"
				( attribute "PN" "AM4"
					( Origin gPackager )
				)
				( objectStatus "U7C1.AM4" )
			)
			( pin "@baseboard_fab2_lib.baseboard_fab2(sch_1):page121_i34:gpp_k0_lan_ncsi_clk_in"
				( attribute "PN" "AJ1"
					( Origin gPackager )
				)
				( objectStatus "U7C1.AJ1" )
			)
			( pin "@baseboard_fab2_lib.baseboard_fab2(sch_1):page121_i34:gpp_k1_lan_ncsi_txd0"
				( attribute "PN" "AM2"
					( Origin gPackager )
				)
				( objectStatus "U7C1.AM2" )
			)
			( pin "@baseboard_fab2_lib.baseboard_fab2(sch_1):page121_i34:gpp_k2_lan_ncsi_txd1"
				( attribute "PN" "AK2"
					( Origin gPackager )
				)
				( objectStatus "U7C1.AK2" )
			)
			( pin "@baseboard_fab2_lib.baseboard_fab2(sch_1):page121_i34:gpp_k3_lan_ncsi_tx_en"
				( attribute "PN" "AL3"
					( Origin gPackager )
				)
				( objectStatus "U7C1.AL3" )
			)
			( pin "@baseboard_fab2_lib.baseboard_fab2(sch_1):page121_i34:gpp_k4_lan_ncsi_crs_dv"
				( attribute "PN" "AN3"
					( Origin gPackager )
				)
				( objectStatus "U7C1.AN3" )
			)
			( pin "@baseboard_fab2_lib.baseboard_fab2(sch_1):page121_i34:gpp_k5_lan_ncsi_rxd0"
				( attribute "PN" "AL1"
					( Origin gPackager )
				)
				( objectStatus "U7C1.AL1" )
			)
			( pin "@baseboard_fab2_lib.baseboard_fab2(sch_1):page121_i34:gpp_k6_lan_ncsi_rxd1"
				( attribute "PN" "AN1"
					( Origin gPackager )
				)
				( objectStatus "U7C1.AN1" )
			)
			( pin "@baseboard_fab2_lib.baseboard_fab2(sch_1):page121_i34:gpp_k7"
				( attribute "PN" "AH2"
					( Origin gPackager )
				)
				( objectStatus "U7C1.AH2" )
			)
			( pin "@baseboard_fab2_lib.baseboard_fab2(sch_1):page121_i34:gpp_k8_lan_ncsi_arb_in"
				( attribute "PN" "AJ3"
					( Origin gPackager )
				)
				( objectStatus "U7C1.AJ3" )
			)
			( pin "@baseboard_fab2_lib.baseboard_fab2(sch_1):page121_i34:gpp_k9_lan_ncsi_arb_out"
				( attribute "PN" "AK4"
					( Origin gPackager )
				)
				( objectStatus "U7C1.AK4" )
			)
			( pin "@baseboard_fab2_lib.baseboard_fab2(sch_1):page121_i34:gpp_k10_pe_rst_n"
				( attribute "PN" "AH4"
					( Origin gPackager )
				)
				( objectStatus "U7C1.AH4" )
			)
			( pin "@baseboard_fab2_lib.baseboard_fab2(sch_1):page121_i34:gpp_l2_testch0_d0"
				( attribute "PN" "AE18"
					( Origin gPackager )
				)
				( objectStatus "U7C1.AE18" )
			)
			( pin "@baseboard_fab2_lib.baseboard_fab2(sch_1):page121_i34:gpp_l3_testch0_d1"
				( attribute "PN" "AE15"
					( Origin gPackager )
				)
				( objectStatus "U7C1.AE15" )
			)
			( pin "@baseboard_fab2_lib.baseboard_fab2(sch_1):page121_i34:gpp_l4_testch0_d2"
				( attribute "PN" "AE11"
					( Origin gPackager )
				)
				( objectStatus "U7C1.AE11" )
			)
			( pin "@baseboard_fab2_lib.baseboard_fab2(sch_1):page121_i34:gpp_l5_testch0_d3"
				( attribute "PN" "Y18"
					( Origin gPackager )
				)
				( objectStatus "U7C1.Y18" )
			)
			( pin "@baseboard_fab2_lib.baseboard_fab2(sch_1):page121_i34:gpp_l6_testch0_d4"
				( attribute "PN" "AA20"
					( Origin gPackager )
				)
				( objectStatus "U7C1.AA20" )
			)
			( pin "@baseboard_fab2_lib.baseboard_fab2(sch_1):page121_i34:gpp_l7_testch0_d5"
				( attribute "PN" "AA17"
					( Origin gPackager )
				)
				( objectStatus "U7C1.AA17" )
			)
			( pin "@baseboard_fab2_lib.baseboard_fab2(sch_1):page121_i34:gpp_l8_testch0_d6"
				( attribute "PN" "AD9"
					( Origin gPackager )
				)
				( objectStatus "U7C1.AD9" )
			)
			( pin "@baseboard_fab2_lib.baseboard_fab2(sch_1):page121_i34:gpp_l9_testch0_d7"
				( attribute "PN" "AD17"
					( Origin gPackager )
				)
				( objectStatus "U7C1.AD17" )
			)
			( pin "@baseboard_fab2_lib.baseboard_fab2(sch_1):page121_i34:gpp_l10_testch0_clk"
				( attribute "PN" "AF20"
					( Origin gPackager )
				)
				( objectStatus "U7C1.AF20" )
			)
			( pin "@baseboard_fab2_lib.baseboard_fab2(sch_1):page121_i34:gpp_l11_testch1_d0"
				( attribute "PN" "AD20"
					( Origin gPackager )
				)
				( objectStatus "U7C1.AD20" )
			)
			( pin "@baseboard_fab2_lib.baseboard_fab2(sch_1):page121_i34:gpp_l12_testch1_d1"
				( attribute "PN" "Y15"
					( Origin gPackager )
				)
				( objectStatus "U7C1.Y15" )
			)
			( pin "@baseboard_fab2_lib.baseboard_fab2(sch_1):page121_i34:gpp_l13_testch1_d2"
				( attribute "PN" "AD13"
					( Origin gPackager )
				)
				( objectStatus "U7C1.AD13" )
			)
			( pin "@baseboard_fab2_lib.baseboard_fab2(sch_1):page121_i34:gpp_l14_testch1_d3"
				( attribute "PN" "AA13"
					( Origin gPackager )
				)
				( objectStatus "U7C1.AA13" )
			)
			( pin "@baseboard_fab2_lib.baseboard_fab2(sch_1):page121_i34:gpp_l15_testch1_d4"
				( attribute "PN" "Y11"
					( Origin gPackager )
				)
				( objectStatus "U7C1.Y11" )
			)
			( pin "@baseboard_fab2_lib.baseboard_fab2(sch_1):page121_i34:gpp_l16_testch1_d5"
				( attribute "PN" "Y7"
					( Origin gPackager )
				)
				( objectStatus "U7C1.Y7" )
			)
			( pin "@baseboard_fab2_lib.baseboard_fab2(sch_1):page121_i34:gpp_l17_testch1_d6"
				( attribute "PN" "AA9"
					( Origin gPackager )
				)
				( objectStatus "U7C1.AA9" )
			)
			( pin "@baseboard_fab2_lib.baseboard_fab2(sch_1):page121_i34:gpp_l18_testch1_d7"
				( attribute "PN" "AE7"
					( Origin gPackager )
				)
				( objectStatus "U7C1.AE7" )
			)
			( pin "@baseboard_fab2_lib.baseboard_fab2(sch_1):page121_i34:gpp_l19_testch1_clk"
				( attribute "PN" "AG11"
					( Origin gPackager )
				)
				( objectStatus "U7C1.AG11" )
			)
			( pin "@baseboard_fab2_lib.baseboard_fab2(sch_1):page121_i34:hda_bclk"
				( attribute "PN" "P18"
					( Origin gPackager )
				)
				( objectStatus "U7C1.P18" )
			)
			( pin "@baseboard_fab2_lib.baseboard_fab2(sch_1):page121_i34:hda_rst_n"
				( attribute "PN" "M18"
					( Origin gPackager )
				)
				( objectStatus "U7C1.M18" )
			)
			( pin "@baseboard_fab2_lib.baseboard_fab2(sch_1):page121_i34:hda_sdi_0"
				( attribute "PN" "K20"
					( Origin gPackager )
				)
				( objectStatus "U7C1.K20" )
			)
			( pin "@baseboard_fab2_lib.baseboard_fab2(sch_1):page121_i34:hda_sdi_1"
				( attribute "PN" "V18"
					( Origin gPackager )
				)
				( objectStatus "U7C1.V18" )
			)
			( pin "@baseboard_fab2_lib.baseboard_fab2(sch_1):page121_i34:hda_sdo"
				( attribute "PN" "U24"
					( Origin gPackager )
				)
				( objectStatus "U7C1.U24" )
			)
			( pin "@baseboard_fab2_lib.baseboard_fab2(sch_1):page121_i34:hda_sync"
				( attribute "PN" "H20"
					( Origin gPackager )
				)
				( objectStatus "U7C1.H20" )
			)
			( pin "@baseboard_fab2_lib.baseboard_fab2(sch_1):page121_i34:intruder_n"
				( attribute "PN" "AG18"
					( Origin gPackager )
				)
				( objectStatus "U7C1.AG18" )
			)
			( pin "@baseboard_fab2_lib.baseboard_fab2(sch_1):page121_i34:rsvd(0)"
				( attribute "PN" "AF61"
					( Origin gPackager )
				)
				( objectStatus "U7C1.AF61" )
			)
			( pin "@baseboard_fab2_lib.baseboard_fab2(sch_1):page121_i34:rsvd(1)"
				( attribute "PN" "AC56"
					( Origin gPackager )
				)
				( objectStatus "U7C1.AC56" )
			)
			( pin "@baseboard_fab2_lib.baseboard_fab2(sch_1):page121_i34:rsvd(2)"
				( attribute "PN" "AA58"
					( Origin gPackager )
				)
				( objectStatus "U7C1.AA58" )
			)
			( pin "@baseboard_fab2_lib.baseboard_fab2(sch_1):page121_i34:rsvd(3)"
				( attribute "PN" "V11"
					( Origin gPackager )
				)
				( objectStatus "U7C1.V11" )
			)
			( pin "@baseboard_fab2_lib.baseboard_fab2(sch_1):page121_i34:rsvd(4)"
				( attribute "PN" "P37"
					( Origin gPackager )
				)
				( objectStatus "U7C1.P37" )
			)
			( pin "@baseboard_fab2_lib.baseboard_fab2(sch_1):page121_i34:rsvd(5)"
				( attribute "PN" "AG15"
					( Origin gPackager )
				)
				( objectStatus "U7C1.AG15" )
			)
			( pin "@baseboard_fab2_lib.baseboard_fab2(sch_1):page121_i34:rsvd(6)"
				( attribute "PN" "AT69"
					( Origin gPackager )
				)
				( objectStatus "U7C1.AT69" )
			)
			( pin "@baseboard_fab2_lib.baseboard_fab2(sch_1):page121_i34:rsvd(7)"
				( attribute "PN" "F8"
					( Origin gPackager )
				)
				( objectStatus "U7C1.F8" )
			)
			( pin "@baseboard_fab2_lib.baseboard_fab2(sch_1):page121_i34:rsvd(8)"
				( attribute "PN" "F69"
					( Origin gPackager )
				)
				( objectStatus "U7C1.F69" )
			)
			( pin "@baseboard_fab2_lib.baseboard_fab2(sch_1):page121_i34:rsvd(9)"
				( attribute "PN" "F66"
					( Origin gPackager )
				)
				( objectStatus "U7C1.F66" )
			)
			( pin "@baseboard_fab2_lib.baseboard_fab2(sch_1):page121_i34:rsvd(10)"
				( attribute "PN" "D8"
					( Origin gPackager )
				)
				( objectStatus "U7C1.D8" )
			)
			( pin "@baseboard_fab2_lib.baseboard_fab2(sch_1):page121_i34:rsvd(11)"
				( attribute "PN" "C18"
					( Origin gPackager )
				)
				( objectStatus "U7C1.C18" )
			)
			( pin "@baseboard_fab2_lib.baseboard_fab2(sch_1):page121_i34:rsvd(12)"
				( attribute "PN" "C68"
					( Origin gPackager )
				)
				( objectStatus "U7C1.C68" )
			)
			( pin "@baseboard_fab2_lib.baseboard_fab2(sch_1):page121_i34:rsvd(13)"
				( attribute "PN" "C67"
					( Origin gPackager )
				)
				( objectStatus "U7C1.C67" )
			)
			( pin "@baseboard_fab2_lib.baseboard_fab2(sch_1):page121_i34:rsvd(14)"
				( attribute "PN" "E18"
					( Origin gPackager )
				)
				( objectStatus "U7C1.E18" )
			)
			( pin "@baseboard_fab2_lib.baseboard_fab2(sch_1):page121_i34:rsvd(15)"
				( attribute "PN" "C6"
					( Origin gPackager )
				)
				( objectStatus "U7C1.C6" )
			)
			( pin "@baseboard_fab2_lib.baseboard_fab2(sch_1):page121_i34:rsvd(16)"
				( attribute "PN" "C5"
					( Origin gPackager )
				)
				( objectStatus "U7C1.C5" )
			)
			( pin "@baseboard_fab2_lib.baseboard_fab2(sch_1):page121_i34:rsvd(17)"
				( attribute "PN" "B10"
					( Origin gPackager )
				)
				( objectStatus "U7C1.B10" )
			)
			( pin "@baseboard_fab2_lib.baseboard_fab2(sch_1):page121_i34:rsvd(18)"
				( attribute "PN" "C11"
					( Origin gPackager )
				)
				( objectStatus "U7C1.C11" )
			)
			( pin "@baseboard_fab2_lib.baseboard_fab2(sch_1):page121_i34:rsvd(19)"
				( attribute "PN" "C9"
					( Origin gPackager )
				)
				( objectStatus "U7C1.C9" )
			)
			( pin "@baseboard_fab2_lib.baseboard_fab2(sch_1):page121_i34:rsvd(20)"
				( attribute "PN" "D10"
					( Origin gPackager )
				)
				( objectStatus "U7C1.D10" )
			)
			( pin "@baseboard_fab2_lib.baseboard_fab2(sch_1):page121_i34:rsvd(21)"
				( attribute "PN" "A11"
					( Origin gPackager )
				)
				( objectStatus "U7C1.A11" )
			)
			( pin "@baseboard_fab2_lib.baseboard_fab2(sch_1):page121_i34:rsvd(22)"
				( attribute "PN" "AT71"
					( Origin gPackager )
				)
				( objectStatus "U7C1.AT71" )
			)
			( pin "@baseboard_fab2_lib.baseboard_fab2(sch_1):page121_i34:rsvd(23)"
				( attribute "PN" "P40"
					( Origin gPackager )
				)
				( objectStatus "U7C1.P40" )
			)
			( pin "@baseboard_fab2_lib.baseboard_fab2(sch_1):page121_i34:rsvd(24)"
				( attribute "PN" "P44"
					( Origin gPackager )
				)
				( objectStatus "U7C1.P44" )
			)
			( pin "@baseboard_fab2_lib.baseboard_fab2(sch_1):page121_i34:rsvd(25)"
				( attribute "PN" "P48"
					( Origin gPackager )
				)
				( objectStatus "U7C1.P48" )
			)
			( pin "@baseboard_fab2_lib.baseboard_fab2(sch_1):page121_i34:rsvd(26)"
				( attribute "PN" "BH24"
					( Origin gPackager )
				)
				( objectStatus "U7C1.BH24" )
			)
			( pin "@baseboard_fab2_lib.baseboard_fab2(sch_1):page121_i34:rsvd(27)"
				( attribute "PN" "BG26"
					( Origin gPackager )
				)
				( objectStatus "U7C1.BG26" )
			)
			( pin "@baseboard_fab2_lib.baseboard_fab2(sch_1):page121_i34:rsvd(28)"
				( attribute "CDS_NOT_ON_SYM" "TRUE"
					( Origin gFrontEnd )
				)
			)
			( pin "@baseboard_fab2_lib.baseboard_fab2(sch_1):page121_i34:rsvd(29)"
				( attribute "CDS_NOT_ON_SYM" "TRUE"
					( Origin gFrontEnd )
				)
			)
			( pin "@baseboard_fab2_lib.baseboard_fab2(sch_1):page121_i34:rsvd(30)"
				( attribute "CDS_NOT_ON_SYM" "TRUE"
					( Origin gFrontEnd )
				)
			)
			( pin "@baseboard_fab2_lib.baseboard_fab2(sch_1):page121_i34:rsvd(31)"
				( attribute "CDS_NOT_ON_SYM" "TRUE"
					( Origin gFrontEnd )
				)
			)
			( pin "@baseboard_fab2_lib.baseboard_fab2(sch_1):page121_i34:rsvd(32)"
				( attribute "CDS_NOT_ON_SYM" "TRUE"
					( Origin gFrontEnd )
				)
			)
			( pin "@baseboard_fab2_lib.baseboard_fab2(sch_1):page121_i34:rsvd(33)"
				( attribute "CDS_NOT_ON_SYM" "TRUE"
					( Origin gFrontEnd )
				)
			)
			( pin "@baseboard_fab2_lib.baseboard_fab2(sch_1):page121_i34:rsvd(34)"
				( attribute "CDS_NOT_ON_SYM" "TRUE"
					( Origin gFrontEnd )
				)
			)
			( pin "@baseboard_fab2_lib.baseboard_fab2(sch_1):page121_i34:rsvd(35)"
				( attribute "CDS_NOT_ON_SYM" "TRUE"
					( Origin gFrontEnd )
				)
			)
			( pin "@baseboard_fab2_lib.baseboard_fab2(sch_1):page121_i34:rsvd(36)"
				( attribute "CDS_NOT_ON_SYM" "TRUE"
					( Origin gFrontEnd )
				)
			)
			( pin "@baseboard_fab2_lib.baseboard_fab2(sch_1):page121_i34:rsvd(37)"
				( attribute "CDS_NOT_ON_SYM" "TRUE"
					( Origin gFrontEnd )
				)
			)
			( pin "@baseboard_fab2_lib.baseboard_fab2(sch_1):page121_i34:rsvd(38)"
				( attribute "CDS_NOT_ON_SYM" "TRUE"
					( Origin gFrontEnd )
				)
			)
			( pin "@baseboard_fab2_lib.baseboard_fab2(sch_1):page121_i34:rsvd(39)"
				( attribute "CDS_NOT_ON_SYM" "TRUE"
					( Origin gFrontEnd )
				)
			)
			( pin "@baseboard_fab2_lib.baseboard_fab2(sch_1):page121_i34:rsvd(40)"
				( attribute "CDS_NOT_ON_SYM" "TRUE"
					( Origin gFrontEnd )
				)
			)
			( pin "@baseboard_fab2_lib.baseboard_fab2(sch_1):page121_i34:rsvd(41)"
				( attribute "CDS_NOT_ON_SYM" "TRUE"
					( Origin gFrontEnd )
				)
			)
			( pin "@baseboard_fab2_lib.baseboard_fab2(sch_1):page121_i34:rsvd(42)"
				( attribute "CDS_NOT_ON_SYM" "TRUE"
					( Origin gFrontEnd )
				)
			)
			( pin "@baseboard_fab2_lib.baseboard_fab2(sch_1):page121_i34:rsvd(43)"
				( attribute "CDS_NOT_ON_SYM" "TRUE"
					( Origin gFrontEnd )
				)
			)
			( pin "@baseboard_fab2_lib.baseboard_fab2(sch_1):page121_i34:rsvd(44)"
				( attribute "CDS_NOT_ON_SYM" "TRUE"
					( Origin gFrontEnd )
				)
			)
			( pin "@baseboard_fab2_lib.baseboard_fab2(sch_1):page121_i34:rsvd(45)"
				( attribute "CDS_NOT_ON_SYM" "TRUE"
					( Origin gFrontEnd )
				)
			)
			( pin "@baseboard_fab2_lib.baseboard_fab2(sch_1):page121_i34:rsvd(46)"
				( attribute "PN" "BW3"
					( Origin gPackager )
				)
				( objectStatus "U7C1.BW3" )
			)
			( pin "@baseboard_fab2_lib.baseboard_fab2(sch_1):page121_i34:rsvd(47)"
				( attribute "CDS_NOT_ON_SYM" "TRUE"
					( Origin gFrontEnd )
				)
			)
			( pin "@baseboard_fab2_lib.baseboard_fab2(sch_1):page121_i34:rsvd(48)"
				( attribute "CDS_NOT_ON_SYM" "TRUE"
					( Origin gFrontEnd )
				)
			)
			( pin "@baseboard_fab2_lib.baseboard_fab2(sch_1):page121_i34:rsvd(49)"
				( attribute "CDS_NOT_ON_SYM" "TRUE"
					( Origin gFrontEnd )
				)
			)
			( pin "@baseboard_fab2_lib.baseboard_fab2(sch_1):page121_i34:rsvd(50)"
				( attribute "CDS_NOT_ON_SYM" "TRUE"
					( Origin gFrontEnd )
				)
			)
			( pin "@baseboard_fab2_lib.baseboard_fab2(sch_1):page121_i34:rsvd(51)"
				( attribute "CDS_NOT_ON_SYM" "TRUE"
					( Origin gFrontEnd )
				)
			)
			( pin "@baseboard_fab2_lib.baseboard_fab2(sch_1):page121_i34:rsvd(52)"
				( attribute "CDS_NOT_ON_SYM" "TRUE"
					( Origin gFrontEnd )
				)
			)
			( pin "@baseboard_fab2_lib.baseboard_fab2(sch_1):page121_i34:rsvd(53)"
				( attribute "CDS_NOT_ON_SYM" "TRUE"
					( Origin gFrontEnd )
				)
			)
			( pin "@baseboard_fab2_lib.baseboard_fab2(sch_1):page121_i34:rsvd(54)"
				( attribute "CDS_NOT_ON_SYM" "TRUE"
					( Origin gFrontEnd )
				)
			)
			( pin "@baseboard_fab2_lib.baseboard_fab2(sch_1):page121_i34:rsvd(55)"
				( attribute "CDS_NOT_ON_SYM" "TRUE"
					( Origin gFrontEnd )
				)
			)
			( pin "@baseboard_fab2_lib.baseboard_fab2(sch_1):page121_i34:rsvd(56)"
				( attribute "CDS_NOT_ON_SYM" "TRUE"
					( Origin gFrontEnd )
				)
			)
			( pin "@baseboard_fab2_lib.baseboard_fab2(sch_1):page121_i34:rsvd(57)"
				( attribute "CDS_NOT_ON_SYM" "TRUE"
					( Origin gFrontEnd )
				)
			)
			( pin "@baseboard_fab2_lib.baseboard_fab2(sch_1):page121_i34:rsvd(58)"
				( attribute "CDS_NOT_ON_SYM" "TRUE"
					( Origin gFrontEnd )
				)
			)
			( pin "@baseboard_fab2_lib.baseboard_fab2(sch_1):page121_i34:rsvd(59)"
				( attribute "CDS_NOT_ON_SYM" "TRUE"
					( Origin gFrontEnd )
				)
			)
			( pin "@baseboard_fab2_lib.baseboard_fab2(sch_1):page121_i34:rsvd(60)"
				( attribute "CDS_NOT_ON_SYM" "TRUE"
					( Origin gFrontEnd )
				)
			)
			( pin "@baseboard_fab2_lib.baseboard_fab2(sch_1):page121_i34:rsvd(61)"
				( attribute "CDS_NOT_ON_SYM" "TRUE"
					( Origin gFrontEnd )
				)
			)
			( pin "@baseboard_fab2_lib.baseboard_fab2(sch_1):page121_i34:rsvd(62)"
				( attribute "CDS_NOT_ON_SYM" "TRUE"
					( Origin gFrontEnd )
				)
			)
			( pin "@baseboard_fab2_lib.baseboard_fab2(sch_1):page121_i34:rsvd(63)"
				( attribute "CDS_NOT_ON_SYM" "TRUE"
					( Origin gFrontEnd )
				)
			)
			( pin "@baseboard_fab2_lib.baseboard_fab2(sch_1):page121_i34:rsvd(64)"
				( attribute "CDS_NOT_ON_SYM" "TRUE"
					( Origin gFrontEnd )
				)
			)
			( pin "@baseboard_fab2_lib.baseboard_fab2(sch_1):page121_i34:rsvd(65)"
				( attribute "CDS_NOT_ON_SYM" "TRUE"
					( Origin gFrontEnd )
				)
			)
			( pin "@baseboard_fab2_lib.baseboard_fab2(sch_1):page121_i34:rsvd(66)"
				( attribute "PN" "U20"
					( Origin gPackager )
				)
				( objectStatus "U7C1.U20" )
			)
			( pin "@baseboard_fab2_lib.baseboard_fab2(sch_1):page121_i34:rsvd(67)"
				( attribute "PN" "R20"
					( Origin gPackager )
				)
				( objectStatus "U7C1.R20" )
			)
			( pin "@baseboard_fab2_lib.baseboard_fab2(sch_1):page121_i34:rsvd(68)"
				( attribute "PN" "V22"
					( Origin gPackager )
				)
				( objectStatus "U7C1.V22" )
			)
			( pin "@baseboard_fab2_lib.baseboard_fab2(sch_1):page121_i34:rtcrst_n"
				( attribute "PN" "P11"
					( Origin gPackager )
				)
				( objectStatus "U7C1.P11" )
			)
			( pin "@baseboard_fab2_lib.baseboard_fab2(sch_1):page121_i34:spi0_clk"
				( attribute "PN" "K2"
					( Origin gPackager )
				)
				( objectStatus "U7C1.K2" )
			)
			( pin "@baseboard_fab2_lib.baseboard_fab2(sch_1):page121_i34:spi0_flash_cs0_n"
				( attribute "PN" "J3"
					( Origin gPackager )
				)
				( objectStatus "U7C1.J3" )
			)
			( pin "@baseboard_fab2_lib.baseboard_fab2(sch_1):page121_i34:spi0_flash_cs1_n"
				( attribute "PN" "G7"
					( Origin gPackager )
				)
				( objectStatus "U7C1.G7" )
			)
			( pin "@baseboard_fab2_lib.baseboard_fab2(sch_1):page121_i34:spi0_io2"
				( attribute "PN" "F5"
					( Origin gPackager )
				)
				( objectStatus "U7C1.F5" )
			)
			( pin "@baseboard_fab2_lib.baseboard_fab2(sch_1):page121_i34:spi0_io3"
				( attribute "PN" "L1"
					( Origin gPackager )
				)
				( objectStatus "U7C1.L1" )
			)
			( pin "@baseboard_fab2_lib.baseboard_fab2(sch_1):page121_i34:spi0_miso_io1"
				( attribute "PN" "L3"
					( Origin gPackager )
				)
				( objectStatus "U7C1.L3" )
			)
			( pin "@baseboard_fab2_lib.baseboard_fab2(sch_1):page121_i34:spi0_mosi_io0"
				( attribute "PN" "H4"
					( Origin gPackager )
				)
				( objectStatus "U7C1.H4" )
			)
			( pin "@baseboard_fab2_lib.baseboard_fab2(sch_1):page121_i34:spi0_tpm_cs_n"
				( attribute "PN" "K4"
					( Origin gPackager )
				)
				( objectStatus "U7C1.K4" )
			)
			( pin "@baseboard_fab2_lib.baseboard_fab2(sch_1):page121_i34:srtcrst_n"
				( attribute "PN" "G18"
					( Origin gPackager )
				)
				( objectStatus "U7C1.G18" )
			)
			( pin "@baseboard_fab2_lib.baseboard_fab2(sch_1):page121_i35:a"
				( attribute "PN" "1"
					( Origin gPackager )
				)
				( objectStatus "R8C26.1" )
			)
			( pin "@baseboard_fab2_lib.baseboard_fab2(sch_1):page121_i35:b"
				( attribute "PN" "2"
					( Origin gPackager )
				)
				( objectStatus "R8C26.2" )
			)
			( pin "@baseboard_fab2_lib.baseboard_fab2(sch_1):page121_i37:a"
				( attribute "PN" "1"
					( Origin gPackager )
				)
				( objectStatus "R3N10.1" )
			)
			( pin "@baseboard_fab2_lib.baseboard_fab2(sch_1):page121_i37:b"
				( attribute "PN" "2"
					( Origin gPackager )
				)
				( objectStatus "R3N10.2" )
			)
			( pin "@baseboard_fab2_lib.baseboard_fab2(sch_1):page121_i73:a"
				( attribute "PN" "1"
					( Origin gPackager )
				)
				( objectStatus "R7C20.1" )
			)
			( pin "@baseboard_fab2_lib.baseboard_fab2(sch_1):page121_i73:b"
				( attribute "PN" "2"
					( Origin gPackager )
				)
				( objectStatus "R7C20.2" )
			)
			( pin "@baseboard_fab2_lib.baseboard_fab2(sch_1):page121_i89:a"
				( attribute "PN" "1"
					( Origin gPackager )
				)
				( objectStatus "R3P3.1" )
			)
			( pin "@baseboard_fab2_lib.baseboard_fab2(sch_1):page121_i89:b"
				( attribute "PN" "2"
					( Origin gPackager )
				)
				( objectStatus "R3P3.2" )
			)
			( pin "@baseboard_fab2_lib.baseboard_fab2(sch_1):page121_i90:a"
				( attribute "PN" "1"
					( Origin gPackager )
				)
				( objectStatus "R3P2.1" )
			)
			( pin "@baseboard_fab2_lib.baseboard_fab2(sch_1):page121_i90:b"
				( attribute "PN" "2"
					( Origin gPackager )
				)
				( objectStatus "R3P2.2" )
			)
			( pin "@baseboard_fab2_lib.baseboard_fab2(sch_1):page121_i91:a"
				( attribute "PN" "1"
					( Origin gPackager )
				)
				( objectStatus "R2P1.1" )
			)
			( pin "@baseboard_fab2_lib.baseboard_fab2(sch_1):page121_i91:b"
				( attribute "PN" "2"
					( Origin gPackager )
				)
				( objectStatus "R2P1.2" )
			)
			( pin "@baseboard_fab2_lib.baseboard_fab2(sch_1):page121_i98:a"
				( attribute "PN" "1"
					( Origin gPackager )
				)
				( objectStatus "R7C14.1" )
			)
			( pin "@baseboard_fab2_lib.baseboard_fab2(sch_1):page121_i98:b"
				( attribute "PN" "2"
					( Origin gPackager )
				)
				( objectStatus "R7C14.2" )
			)
			( pin "@baseboard_fab2_lib.baseboard_fab2(sch_1):page121_i101:a"
				( attribute "PN" "1"
					( Origin gPackager )
				)
				( objectStatus "R8D11.1" )
			)
			( pin "@baseboard_fab2_lib.baseboard_fab2(sch_1):page121_i101:b"
				( attribute "PN" "2"
					( Origin gPackager )
				)
				( objectStatus "R8D11.2" )
			)
			( pin "@baseboard_fab2_lib.baseboard_fab2(sch_1):page122_i63:rsvd(28)"
				( attribute "PN" "R35"
					( Origin gPackager )
				)
				( objectStatus "U7C1.R35" )
			)
			( pin "@baseboard_fab2_lib.baseboard_fab2(sch_1):page122_i63:rsvd(29)"
				( attribute "PN" "P33"
					( Origin gPackager )
				)
				( objectStatus "U7C1.P33" )
			)
			( pin "@baseboard_fab2_lib.baseboard_fab2(sch_1):page122_i63:rsvd(30)"
				( attribute "PN" "R31"
					( Origin gPackager )
				)
				( objectStatus "U7C1.R31" )
			)
			( pin "@baseboard_fab2_lib.baseboard_fab2(sch_1):page122_i63:rsvd(31)"
				( attribute "PN" "P29"
					( Origin gPackager )
				)
				( objectStatus "U7C1.P29" )
			)
			( pin "@baseboard_fab2_lib.baseboard_fab2(sch_1):page122_i63:rsvd(32)"
				( attribute "CDS_NOT_ON_SYM" "TRUE"
					( Origin gFrontEnd )
				)
			)
			( pin "@baseboard_fab2_lib.baseboard_fab2(sch_1):page122_i63:rsvd(33)"
				( attribute "CDS_NOT_ON_SYM" "TRUE"
					( Origin gFrontEnd )
				)
			)
			( pin "@baseboard_fab2_lib.baseboard_fab2(sch_1):page122_i63:rsvd(34)"
				( attribute "CDS_NOT_ON_SYM" "TRUE"
					( Origin gFrontEnd )
				)
			)
			( pin "@baseboard_fab2_lib.baseboard_fab2(sch_1):page122_i63:rsvd(35)"
				( attribute "CDS_NOT_ON_SYM" "TRUE"
					( Origin gFrontEnd )
				)
			)
			( pin "@baseboard_fab2_lib.baseboard_fab2(sch_1):page122_i63:rsvd(36)"
				( attribute "CDS_NOT_ON_SYM" "TRUE"
					( Origin gFrontEnd )
				)
			)
			( pin "@baseboard_fab2_lib.baseboard_fab2(sch_1):page122_i63:rsvd(37)"
				( attribute "CDS_NOT_ON_SYM" "TRUE"
					( Origin gFrontEnd )
				)
			)
			( pin "@baseboard_fab2_lib.baseboard_fab2(sch_1):page122_i63:rsvd(38)"
				( attribute "CDS_NOT_ON_SYM" "TRUE"
					( Origin gFrontEnd )
				)
			)
			( pin "@baseboard_fab2_lib.baseboard_fab2(sch_1):page122_i63:rsvd(39)"
				( attribute "CDS_NOT_ON_SYM" "TRUE"
					( Origin gFrontEnd )
				)
			)
			( pin "@baseboard_fab2_lib.baseboard_fab2(sch_1):page122_i63:rsvd(40)"
				( attribute "CDS_NOT_ON_SYM" "TRUE"
					( Origin gFrontEnd )
				)
			)
			( pin "@baseboard_fab2_lib.baseboard_fab2(sch_1):page122_i63:rsvd(41)"
				( attribute "CDS_NOT_ON_SYM" "TRUE"
					( Origin gFrontEnd )
				)
			)
			( pin "@baseboard_fab2_lib.baseboard_fab2(sch_1):page122_i63:rsvd(42)"
				( attribute "CDS_NOT_ON_SYM" "TRUE"
					( Origin gFrontEnd )
				)
			)
			( pin "@baseboard_fab2_lib.baseboard_fab2(sch_1):page122_i63:rsvd(43)"
				( attribute "CDS_NOT_ON_SYM" "TRUE"
					( Origin gFrontEnd )
				)
			)
			( pin "@baseboard_fab2_lib.baseboard_fab2(sch_1):page122_i63:rsvd(44)"
				( attribute "CDS_NOT_ON_SYM" "TRUE"
					( Origin gFrontEnd )
				)
			)
			( pin "@baseboard_fab2_lib.baseboard_fab2(sch_1):page122_i63:rsvd(45)"
				( attribute "CDS_NOT_ON_SYM" "TRUE"
					( Origin gFrontEnd )
				)
			)
			( pin "@baseboard_fab2_lib.baseboard_fab2(sch_1):page122_i63:rsvd(46)"
				( attribute "CDS_NOT_ON_SYM" "TRUE"
					( Origin gFrontEnd )
				)
			)
			( pin "@baseboard_fab2_lib.baseboard_fab2(sch_1):page122_i63:rsvd(47)"
				( attribute "CDS_NOT_ON_SYM" "TRUE"
					( Origin gFrontEnd )
				)
			)
			( pin "@baseboard_fab2_lib.baseboard_fab2(sch_1):page122_i63:rsvd(48)"
				( attribute "CDS_NOT_ON_SYM" "TRUE"
					( Origin gFrontEnd )
				)
			)
			( pin "@baseboard_fab2_lib.baseboard_fab2(sch_1):page122_i63:rsvd(49)"
				( attribute "CDS_NOT_ON_SYM" "TRUE"
					( Origin gFrontEnd )
				)
			)
			( pin "@baseboard_fab2_lib.baseboard_fab2(sch_1):page122_i63:rsvd(50)"
				( attribute "CDS_NOT_ON_SYM" "TRUE"
					( Origin gFrontEnd )
				)
			)
			( pin "@baseboard_fab2_lib.baseboard_fab2(sch_1):page122_i63:rsvd(51)"
				( attribute "CDS_NOT_ON_SYM" "TRUE"
					( Origin gFrontEnd )
				)
			)
			( pin "@baseboard_fab2_lib.baseboard_fab2(sch_1):page122_i63:rsvd(52)"
				( attribute "CDS_NOT_ON_SYM" "TRUE"
					( Origin gFrontEnd )
				)
			)
			( pin "@baseboard_fab2_lib.baseboard_fab2(sch_1):page122_i63:rsvd(53)"
				( attribute "CDS_NOT_ON_SYM" "TRUE"
					( Origin gFrontEnd )
				)
			)
			( pin "@baseboard_fab2_lib.baseboard_fab2(sch_1):page122_i63:rsvd(54)"
				( attribute "CDS_NOT_ON_SYM" "TRUE"
					( Origin gFrontEnd )
				)
			)
			( pin "@baseboard_fab2_lib.baseboard_fab2(sch_1):page122_i63:rsvd(55)"
				( attribute "CDS_NOT_ON_SYM" "TRUE"
					( Origin gFrontEnd )
				)
			)
			( pin "@baseboard_fab2_lib.baseboard_fab2(sch_1):page122_i63:rsvd(56)"
				( attribute "CDS_NOT_ON_SYM" "TRUE"
					( Origin gFrontEnd )
				)
			)
			( pin "@baseboard_fab2_lib.baseboard_fab2(sch_1):page122_i63:rsvd(57)"
				( attribute "CDS_NOT_ON_SYM" "TRUE"
					( Origin gFrontEnd )
				)
			)
			( pin "@baseboard_fab2_lib.baseboard_fab2(sch_1):page122_i63:rsvd(58)"
				( attribute "PN" "AP27"
					( Origin gPackager )
				)
				( objectStatus "U7C1.AP27" )
			)
			( pin "@baseboard_fab2_lib.baseboard_fab2(sch_1):page122_i63:rsvd(59)"
				( attribute "PN" "AT27"
					( Origin gPackager )
				)
				( objectStatus "U7C1.AT27" )
			)
			( pin "@baseboard_fab2_lib.baseboard_fab2(sch_1):page122_i63:vcca_clkfilt_1p05(0)"
				( attribute "PN" "W50"
					( Origin gPackager )
				)
				( objectStatus "U7C1.W50" )
			)
			( pin "@baseboard_fab2_lib.baseboard_fab2(sch_1):page122_i63:vcca_clkfilt_1p05(1)"
				( attribute "PN" "AG45"
					( Origin gPackager )
				)
				( objectStatus "U7C1.AG45" )
			)
			( pin "@baseboard_fab2_lib.baseboard_fab2(sch_1):page122_i63:vcca_clkfilt_1p05(2)"
				( attribute "PN" "AJ46"
					( Origin gPackager )
				)
				( objectStatus "U7C1.AJ46" )
			)
			( pin "@baseboard_fab2_lib.baseboard_fab2(sch_1):page122_i63:vcca_clkfilt_1p05(3)"
				( attribute "PN" "AJ48"
					( Origin gPackager )
				)
				( objectStatus "U7C1.AJ48" )
			)
			( pin "@baseboard_fab2_lib.baseboard_fab2(sch_1):page122_i63:vcca_clkfilt_1p05(4)"
				( attribute "PN" "AE46"
					( Origin gPackager )
				)
				( objectStatus "U7C1.AE46" )
			)
			( pin "@baseboard_fab2_lib.baseboard_fab2(sch_1):page122_i63:vcca_clkunf_1p05(0)"
				( attribute "PN" "AH50"
					( Origin gPackager )
				)
				( objectStatus "U7C1.AH50" )
			)
			( pin "@baseboard_fab2_lib.baseboard_fab2(sch_1):page122_i63:vcca_clkunf_1p05(1)"
				( attribute "PN" "U50"
					( Origin gPackager )
				)
				( objectStatus "U7C1.U50" )
			)
			( pin "@baseboard_fab2_lib.baseboard_fab2(sch_1):page122_i63:vcca_clkxtal_1p05"
				( attribute "PN" "AD50"
					( Origin gPackager )
				)
				( objectStatus "U7C1.AD50" )
			)
			( pin "@baseboard_fab2_lib.baseboard_fab2(sch_1):page122_i63:vcca_pll0_1p05"
				( attribute "PN" "AG48"
					( Origin gPackager )
				)
				( objectStatus "U7C1.AG48" )
			)
			( pin "@baseboard_fab2_lib.baseboard_fab2(sch_1):page122_i63:vcca_pll1_1p05"
				( attribute "PN" "AE45"
					( Origin gPackager )
				)
				( objectStatus "U7C1.AE45" )
			)
			( pin "@baseboard_fab2_lib.baseboard_fab2(sch_1):page122_i63:vccmphy_1p05(0)"
				( attribute "PN" "AW45"
					( Origin gPackager )
				)
				( objectStatus "U7C1.AW45" )
			)
			( pin "@baseboard_fab2_lib.baseboard_fab2(sch_1):page122_i63:vccmphy_1p05(1)"
				( attribute "PN" "AW43"
					( Origin gPackager )
				)
				( objectStatus "U7C1.AW43" )
			)
			( pin "@baseboard_fab2_lib.baseboard_fab2(sch_1):page122_i63:vccmphy_1p05(2)"
				( attribute "PN" "AJ43"
					( Origin gPackager )
				)
				( objectStatus "U7C1.AJ43" )
			)
			( pin "@baseboard_fab2_lib.baseboard_fab2(sch_1):page122_i63:vccmphy_1p05(3)"
				( attribute "PN" "AU45"
					( Origin gPackager )
				)
				( objectStatus "U7C1.AU45" )
			)
			( pin "@baseboard_fab2_lib.baseboard_fab2(sch_1):page122_i63:vccmphy_1p05(4)"
				( attribute "PN" "AU43"
					( Origin gPackager )
				)
				( objectStatus "U7C1.AU43" )
			)
			( pin "@baseboard_fab2_lib.baseboard_fab2(sch_1):page122_i63:vccmphy_1p05(5)"
				( attribute "PN" "AT45"
					( Origin gPackager )
				)
				( objectStatus "U7C1.AT45" )
			)
			( pin "@baseboard_fab2_lib.baseboard_fab2(sch_1):page122_i63:vccmphy_1p05(6)"
				( attribute "PN" "AT43"
					( Origin gPackager )
				)
				( objectStatus "U7C1.AT43" )
			)
			( pin "@baseboard_fab2_lib.baseboard_fab2(sch_1):page122_i63:vccmphy_1p05(7)"
				( attribute "PN" "AP45"
					( Origin gPackager )
				)
				( objectStatus "U7C1.AP45" )
			)
			( pin "@baseboard_fab2_lib.baseboard_fab2(sch_1):page122_i63:vccmphy_1p05(8)"
				( attribute "PN" "AP43"
					( Origin gPackager )
				)
				( objectStatus "U7C1.AP43" )
			)
			( pin "@baseboard_fab2_lib.baseboard_fab2(sch_1):page122_i63:vccmphy_1p05(9)"
				( attribute "PN" "AM45"
					( Origin gPackager )
				)
				( objectStatus "U7C1.AM45" )
			)
			( pin "@baseboard_fab2_lib.baseboard_fab2(sch_1):page122_i63:vccmphy_1p05(10)"
				( attribute "PN" "AM43"
					( Origin gPackager )
				)
				( objectStatus "U7C1.AM43" )
			)
			( pin "@baseboard_fab2_lib.baseboard_fab2(sch_1):page122_i63:vccmphy_1p05(11)"
				( attribute "PN" "AK45"
					( Origin gPackager )
				)
				( objectStatus "U7C1.AK45" )
			)
			( pin "@baseboard_fab2_lib.baseboard_fab2(sch_1):page122_i63:vccmphy_1p05(12)"
				( attribute "PN" "AK43"
					( Origin gPackager )
				)
				( objectStatus "U7C1.AK43" )
			)
			( pin "@baseboard_fab2_lib.baseboard_fab2(sch_1):page122_i63:vccp10gbe_hv_1p8(0)"
				( attribute "PN" "BA29"
					( Origin gPackager )
				)
				( objectStatus "U7C1.BA29" )
			)
			( pin "@baseboard_fab2_lib.baseboard_fab2(sch_1):page122_i63:vccp10gbe_hv_1p8(1)"
				( attribute "PN" "BA27"
					( Origin gPackager )
				)
				( objectStatus "U7C1.BA27" )
			)
			( pin "@baseboard_fab2_lib.baseboard_fab2(sch_1):page122_i63:vccp10gbe_lv_1p05(0)"
				( attribute "PN" "BB37"
					( Origin gPackager )
				)
				( objectStatus "U7C1.BB37" )
			)
			( pin "@baseboard_fab2_lib.baseboard_fab2(sch_1):page122_i63:vccp10gbe_lv_1p05(1)"
				( attribute "PN" "BB33"
					( Origin gPackager )
				)
				( objectStatus "U7C1.BB33" )
			)
			( pin "@baseboard_fab2_lib.baseboard_fab2(sch_1):page122_i63:vccp10gbe_lv_1p05(2)"
				( attribute "PN" "BA37"
					( Origin gPackager )
				)
				( objectStatus "U7C1.BA37" )
			)
			( pin "@baseboard_fab2_lib.baseboard_fab2(sch_1):page122_i63:vccp10gbe_lv_1p05(3)"
				( attribute "PN" "BA36"
					( Origin gPackager )
				)
				( objectStatus "U7C1.BA36" )
			)
			( pin "@baseboard_fab2_lib.baseboard_fab2(sch_1):page122_i63:vccp10gbe_lv_1p05(4)"
				( attribute "PN" "BA34"
					( Origin gPackager )
				)
				( objectStatus "U7C1.BA34" )
			)
			( pin "@baseboard_fab2_lib.baseboard_fab2(sch_1):page122_i63:vccp10gbe_lv_1p05(5)"
				( attribute "PN" "BA32"
					( Origin gPackager )
				)
				( objectStatus "U7C1.BA32" )
			)
			( pin "@baseboard_fab2_lib.baseboard_fab2(sch_1):page122_i63:vccp10gbe_lv_1p05(6)"
				( attribute "PN" "BA30"
					( Origin gPackager )
				)
				( objectStatus "U7C1.BA30" )
			)
			( pin "@baseboard_fab2_lib.baseboard_fab2(sch_1):page122_i63:vccp10gbepll_1p05(0)"
				( attribute "PN" "BD38"
					( Origin gPackager )
				)
				( objectStatus "U7C1.BD38" )
			)
			( pin "@baseboard_fab2_lib.baseboard_fab2(sch_1):page122_i63:vccp10gbepll_1p05(1)"
				( attribute "PN" "BB40"
					( Origin gPackager )
				)
				( objectStatus "U7C1.BB40" )
			)
			( pin "@baseboard_fab2_lib.baseboard_fab2(sch_1):page122_i63:vccp10gbepll_1p05(2)"
				( attribute "PN" "BA41"
					( Origin gPackager )
				)
				( objectStatus "U7C1.BA41" )
			)
			( pin "@baseboard_fab2_lib.baseboard_fab2(sch_1):page122_i63:vccp10gbepll_1p05(3)"
				( attribute "PN" "BA39"
					( Origin gPackager )
				)
				( objectStatus "U7C1.BA39" )
			)
			( pin "@baseboard_fab2_lib.baseboard_fab2(sch_1):page122_i63:vccp_1p8(0)"
				( attribute "PN" "BD46"
					( Origin gPackager )
				)
				( objectStatus "U7C1.BD46" )
			)
			( pin "@baseboard_fab2_lib.baseboard_fab2(sch_1):page122_i63:vccp_1p8(1)"
				( attribute "PN" "AE26"
					( Origin gPackager )
				)
				( objectStatus "U7C1.AE26" )
			)
			( pin "@baseboard_fab2_lib.baseboard_fab2(sch_1):page122_i63:vccp_3p3(0)"
				( attribute "PN" "BA46"
					( Origin gPackager )
				)
				( objectStatus "U7C1.BA46" )
			)
			( pin "@baseboard_fab2_lib.baseboard_fab2(sch_1):page122_i63:vccp_3p3(1)"
				( attribute "PN" "BA45"
					( Origin gPackager )
				)
				( objectStatus "U7C1.BA45" )
			)
			( pin "@baseboard_fab2_lib.baseboard_fab2(sch_1):page122_i63:vccp_3p3(2)"
				( attribute "PN" "AD24"
					( Origin gPackager )
				)
				( objectStatus "U7C1.AD24" )
			)
			( pin "@baseboard_fab2_lib.baseboard_fab2(sch_1):page122_i63:vccp_3p3(3)"
				( attribute "CDS_NOT_ON_SYM" "TRUE"
					( Origin gFrontEnd )
				)
			)
			( pin "@baseboard_fab2_lib.baseboard_fab2(sch_1):page122_i63:vccp_3p3(4)"
				( attribute "CDS_NOT_ON_SYM" "TRUE"
					( Origin gFrontEnd )
				)
			)
			( pin "@baseboard_fab2_lib.baseboard_fab2(sch_1):page122_i63:vccp_3p3(5)"
				( attribute "PN" "AN24"
					( Origin gPackager )
				)
				( objectStatus "U7C1.AN24" )
			)
			( pin "@baseboard_fab2_lib.baseboard_fab2(sch_1):page122_i63:vccp_hsiopll_1p05(0)"
				( attribute "PN" "AW48"
					( Origin gPackager )
				)
				( objectStatus "U7C1.AW48" )
			)
			( pin "@baseboard_fab2_lib.baseboard_fab2(sch_1):page122_i63:vccp_hsiopll_1p05(1)"
				( attribute "CDS_NOT_ON_SYM" "TRUE"
					( Origin gFrontEnd )
				)
			)
			( pin "@baseboard_fab2_lib.baseboard_fab2(sch_1):page122_i63:vccp_hsiopll_1p05(2)"
				( attribute "PN" "AU48"
					( Origin gPackager )
				)
				( objectStatus "U7C1.AU48" )
			)
			( pin "@baseboard_fab2_lib.baseboard_fab2(sch_1):page122_i63:vccp_hsiopll_1p05(3)"
				( attribute "PN" "AP48"
					( Origin gPackager )
				)
				( objectStatus "U7C1.AP48" )
			)
			( pin "@baseboard_fab2_lib.baseboard_fab2(sch_1):page122_i63:vccp_hsiopllunf_1p05"
				( attribute "PN" "AT48"
					( Origin gPackager )
				)
				( objectStatus "U7C1.AT48" )
			)
			( pin "@baseboard_fab2_lib.baseboard_fab2(sch_1):page122_i63:vccp_uppll_1p05(0)"
				( attribute "PN" "AN50"
					( Origin gPackager )
				)
				( objectStatus "U7C1.AN50" )
			)
			( pin "@baseboard_fab2_lib.baseboard_fab2(sch_1):page122_i63:vccp_uppll_1p05(1)"
				( attribute "CDS_NOT_ON_SYM" "TRUE"
					( Origin gFrontEnd )
				)
			)
			( pin "@baseboard_fab2_lib.baseboard_fab2(sch_1):page122_i63:vccp_uppll_1p05(2)"
				( attribute "PN" "AK50"
					( Origin gPackager )
				)
				( objectStatus "U7C1.AK50" )
			)
			( pin "@baseboard_fab2_lib.baseboard_fab2(sch_1):page122_i63:vccp_uppllunf_1p05"
				( attribute "PN" "AM48"
					( Origin gPackager )
				)
				( objectStatus "U7C1.AM48" )
			)
			( pin "@baseboard_fab2_lib.baseboard_fab2(sch_1):page122_i63:vccpdsw_3p3"
				( attribute "PN" "AH24"
					( Origin gPackager )
				)
				( objectStatus "U7C1.AH24" )
			)
			( pin "@baseboard_fab2_lib.baseboard_fab2(sch_1):page122_i63:vccpgpp_1p8(0)"
				( attribute "PN" "AU29"
					( Origin gPackager )
				)
				( objectStatus "U7C1.AU29" )
			)
			( pin "@baseboard_fab2_lib.baseboard_fab2(sch_1):page122_i63:vccpgpp_1p8(1)"
				( attribute "PN" "AW29"
					( Origin gPackager )
				)
				( objectStatus "U7C1.AW29" )
			)
			( pin "@baseboard_fab2_lib.baseboard_fab2(sch_1):page122_i63:vccpgpp_1p8(2)"
				( attribute "PN" "AT29"
					( Origin gPackager )
				)
				( objectStatus "U7C1.AT29" )
			)
			( pin "@baseboard_fab2_lib.baseboard_fab2(sch_1):page122_i63:vccpgpp_1p8(3)"
				( attribute "PN" "AM29"
					( Origin gPackager )
				)
				( objectStatus "U7C1.AM29" )
			)
			( pin "@baseboard_fab2_lib.baseboard_fab2(sch_1):page122_i63:vccpgpp_1p8(4)"
				( attribute "PN" "AP29"
					( Origin gPackager )
				)
				( objectStatus "U7C1.AP29" )
			)
			( pin "@baseboard_fab2_lib.baseboard_fab2(sch_1):page122_i63:vccpgpp_1p8(5)"
				( attribute "PN" "AW27"
					( Origin gPackager )
				)
				( objectStatus "U7C1.AW27" )
			)
			( pin "@baseboard_fab2_lib.baseboard_fab2(sch_1):page122_i63:vccpgpp_1p8(6)"
				( attribute "PN" "AK24"
					( Origin gPackager )
				)
				( objectStatus "U7C1.AK24" )
			)
			( pin "@baseboard_fab2_lib.baseboard_fab2(sch_1):page122_i63:vccpgppa"
				( attribute "PN" "AW24"
					( Origin gPackager )
				)
				( objectStatus "U7C1.AW24" )
			)
			( pin "@baseboard_fab2_lib.baseboard_fab2(sch_1):page122_i63:vccpgppb"
				( attribute "PN" "BE26"
					( Origin gPackager )
				)
				( objectStatus "U7C1.BE26" )
			)
			( pin "@baseboard_fab2_lib.baseboard_fab2(sch_1):page122_i63:vccpgppc"
				( attribute "PN" "BE40"
					( Origin gPackager )
				)
				( objectStatus "U7C1.BE40" )
			)
			( pin "@baseboard_fab2_lib.baseboard_fab2(sch_1):page122_i63:vccpgppd"
				( attribute "PN" "BA43"
					( Origin gPackager )
				)
				( objectStatus "U7C1.BA43" )
			)
			( pin "@baseboard_fab2_lib.baseboard_fab2(sch_1):page122_i63:vccpgppe"
				( attribute "PN" "BE44"
					( Origin gPackager )
				)
				( objectStatus "U7C1.BE44" )
			)
			( pin "@baseboard_fab2_lib.baseboard_fab2(sch_1):page122_i63:vccpgppf"
				( attribute "PN" "AU27"
					( Origin gPackager )
				)
				( objectStatus "U7C1.AU27" )
			)
			( pin "@baseboard_fab2_lib.baseboard_fab2(sch_1):page122_i63:vccpgppg"
				( attribute "PN" "BA26"
					( Origin gPackager )
				)
				( objectStatus "U7C1.BA26" )
			)
			( pin "@baseboard_fab2_lib.baseboard_fab2(sch_1):page122_i63:vccpgpph"
				( attribute "PN" "BA24"
					( Origin gPackager )
				)
				( objectStatus "U7C1.BA24" )
			)
			( pin "@baseboard_fab2_lib.baseboard_fab2(sch_1):page122_i63:vccpgppj"
				( attribute "PN" "BB26"
					( Origin gPackager )
				)
				( objectStatus "U7C1.BB26" )
			)
			( pin "@baseboard_fab2_lib.baseboard_fab2(sch_1):page122_i63:vccpgppk"
				( attribute "PN" "AU24"
					( Origin gPackager )
				)
				( objectStatus "U7C1.AU24" )
			)
			( pin "@baseboard_fab2_lib.baseboard_fab2(sch_1):page122_i63:vccphda_1p8"
				( attribute "PN" "AG27"
					( Origin gPackager )
				)
				( objectStatus "U7C1.AG27" )
			)
			( pin "@baseboard_fab2_lib.baseboard_fab2(sch_1):page122_i63:vccprim_1p05(0)"
				( attribute "PN" "BF46"
					( Origin gPackager )
				)
				( objectStatus "U7C1.BF46" )
			)
			( pin "@baseboard_fab2_lib.baseboard_fab2(sch_1):page122_i63:vccprim_1p05(1)"
				( attribute "PN" "BE48"
					( Origin gPackager )
				)
				( objectStatus "U7C1.BE48" )
			)
			( pin "@baseboard_fab2_lib.baseboard_fab2(sch_1):page122_i63:vccprim_1p05(2)"
				( attribute "PN" "AU39"
					( Origin gPackager )
				)
				( objectStatus "U7C1.AU39" )
			)
			( pin "@baseboard_fab2_lib.baseboard_fab2(sch_1):page122_i63:vccprim_1p05(3)"
				( attribute "PN" "AU37"
					( Origin gPackager )
				)
				( objectStatus "U7C1.AU37" )
			)
			( pin "@baseboard_fab2_lib.baseboard_fab2(sch_1):page122_i63:vccprim_1p05(4)"
				( attribute "PN" "AT39"
					( Origin gPackager )
				)
				( objectStatus "U7C1.AT39" )
			)
			( pin "@baseboard_fab2_lib.baseboard_fab2(sch_1):page122_i63:vccprim_1p05(5)"
				( attribute "PN" "AM27"
					( Origin gPackager )
				)
				( objectStatus "U7C1.AM27" )
			)
			( pin "@baseboard_fab2_lib.baseboard_fab2(sch_1):page122_i63:vccprim_1p05(6)"
				( attribute "PN" "AJ29"
					( Origin gPackager )
				)
				( objectStatus "U7C1.AJ29" )
			)
			( pin "@baseboard_fab2_lib.baseboard_fab2(sch_1):page122_i63:vccprim_1p05(7)"
				( attribute "PN" "AC26"
					( Origin gPackager )
				)
				( objectStatus "U7C1.AC26" )
			)
			( pin "@baseboard_fab2_lib.baseboard_fab2(sch_1):page122_i63:vccprim_1p05(8)"
				( attribute "PN" "AA46"
					( Origin gPackager )
				)
				( objectStatus "U7C1.AA46" )
			)
			( pin "@baseboard_fab2_lib.baseboard_fab2(sch_1):page122_i63:vccprim_1p05(9)"
				( attribute "PN" "AA45"
					( Origin gPackager )
				)
				( objectStatus "U7C1.AA45" )
			)
			( pin "@baseboard_fab2_lib.baseboard_fab2(sch_1):page122_i63:vccprim_1p05(10)"
				( attribute "PN" "Y46"
					( Origin gPackager )
				)
				( objectStatus "U7C1.Y46" )
			)
			( pin "@baseboard_fab2_lib.baseboard_fab2(sch_1):page122_i63:vccprim_1p05(11)"
				( attribute "PN" "Y45"
					( Origin gPackager )
				)
				( objectStatus "U7C1.Y45" )
			)
			( pin "@baseboard_fab2_lib.baseboard_fab2(sch_1):page122_i63:vccprim_1p05(12)"
				( attribute "PN" "V44"
					( Origin gPackager )
				)
				( objectStatus "U7C1.V44" )
			)
			( pin "@baseboard_fab2_lib.baseboard_fab2(sch_1):page122_i63:vccprim_1p05(13)"
				( attribute "PN" "U46"
					( Origin gPackager )
				)
				( objectStatus "U7C1.U46" )
			)
			( pin "@baseboard_fab2_lib.baseboard_fab2(sch_1):page122_i63:vccprim_1p05(14)"
				( attribute "PN" "T44"
					( Origin gPackager )
				)
				( objectStatus "U7C1.T44" )
			)
			( pin "@baseboard_fab2_lib.baseboard_fab2(sch_1):page122_i63:vccprim_1p05(15)"
				( attribute "PN" "R46"
					( Origin gPackager )
				)
				( objectStatus "U7C1.R46" )
			)
			( pin "@baseboard_fab2_lib.baseboard_fab2(sch_1):page122_i63:vccprim_1p05(16)"
				( attribute "PN" "R42"
					( Origin gPackager )
				)
				( objectStatus "U7C1.R42" )
			)
			( pin "@baseboard_fab2_lib.baseboard_fab2(sch_1):page122_i63:vccprim_1p05(17)"
				( attribute "PN" "AK27"
					( Origin gPackager )
				)
				( objectStatus "U7C1.AK27" )
			)
			( pin "@baseboard_fab2_lib.baseboard_fab2(sch_1):page122_i63:vccprim_1p05(18)"
				( attribute "PN" "AA24"
					( Origin gPackager )
				)
				( objectStatus "U7C1.AA24" )
			)
			( pin "@baseboard_fab2_lib.baseboard_fab2(sch_1):page122_i63:vccprim_1p05(19)"
				( attribute "PN" "Y26"
					( Origin gPackager )
				)
				( objectStatus "U7C1.Y26" )
			)
			( pin "@baseboard_fab2_lib.baseboard_fab2(sch_1):page122_i63:vccprtc"
				( attribute "PN" "AJ27"
					( Origin gPackager )
				)
				( objectStatus "U7C1.AJ27" )
			)
			( pin "@baseboard_fab2_lib.baseboard_fab2(sch_1):page122_i63:vccprtcprim_3p3"
				( attribute "PN" "AG29"
					( Origin gPackager )
				)
				( objectStatus "U7C1.AG29" )
			)
			( pin "@baseboard_fab2_lib.baseboard_fab2(sch_1):page122_i63:vccpspi"
				( attribute "PN" "AR24"
					( Origin gPackager )
				)
				( objectStatus "U7C1.AR24" )
			)
			( pin "@baseboard_fab2_lib.baseboard_fab2(sch_1):page122_i63:vccpspi_1p8"
				( attribute "PN" "AK29"
					( Origin gPackager )
				)
				( objectStatus "U7C1.AK29" )
			)
			( pin "@baseboard_fab2_lib.baseboard_fab2(sch_1):page122_i63:vccpusbdsw_3p3"
				( attribute "PN" "BA48"
					( Origin gPackager )
				)
				( objectStatus "U7C1.BA48" )
			)
			( pin "@baseboard_fab2_lib.baseboard_fab2(sch_1):page122_i63:vccrtcext"
				( attribute "PN" "AG22"
					( Origin gPackager )
				)
				( objectStatus "U7C1.AG22" )
			)
			( pin "@baseboard_fab2_lib.baseboard_fab2(sch_1):page123_i13:vss(355)"
				( attribute "PN" "N31"
					( Origin gPackager )
				)
				( objectStatus "U7C1.N31" )
			)
			( pin "@baseboard_fab2_lib.baseboard_fab2(sch_1):page123_i13:vss(356)"
				( attribute "PN" "N27"
					( Origin gPackager )
				)
				( objectStatus "U7C1.N27" )
			)
			( pin "@baseboard_fab2_lib.baseboard_fab2(sch_1):page123_i13:vss(357)"
				( attribute "PN" "N24"
					( Origin gPackager )
				)
				( objectStatus "U7C1.N24" )
			)
			( pin "@baseboard_fab2_lib.baseboard_fab2(sch_1):page123_i13:vss(358)"
				( attribute "PN" "N20"
					( Origin gPackager )
				)
				( objectStatus "U7C1.N20" )
			)
			( pin "@baseboard_fab2_lib.baseboard_fab2(sch_1):page123_i13:vss(359)"
				( attribute "PN" "N17"
					( Origin gPackager )
				)
				( objectStatus "U7C1.N17" )
			)
			( pin "@baseboard_fab2_lib.baseboard_fab2(sch_1):page123_i13:vss(360)"
				( attribute "PN" "N13"
					( Origin gPackager )
				)
				( objectStatus "U7C1.N13" )
			)
			( pin "@baseboard_fab2_lib.baseboard_fab2(sch_1):page123_i13:vss(361)"
				( attribute "PN" "M48"
					( Origin gPackager )
				)
				( objectStatus "U7C1.M48" )
			)
			( pin "@baseboard_fab2_lib.baseboard_fab2(sch_1):page123_i13:vss(362)"
				( attribute "PN" "M44"
					( Origin gPackager )
				)
				( objectStatus "U7C1.M44" )
			)
			( pin "@baseboard_fab2_lib.baseboard_fab2(sch_1):page123_i13:vss(363)"
				( attribute "PN" "N50"
					( Origin gPackager )
				)
				( objectStatus "U7C1.N50" )
			)
			( pin "@baseboard_fab2_lib.baseboard_fab2(sch_1):page123_i13:vss(364)"
				( attribute "PN" "N42"
					( Origin gPackager )
				)
				( objectStatus "U7C1.N42" )
			)
			( pin "@baseboard_fab2_lib.baseboard_fab2(sch_1):page123_i13:vss(365)"
				( attribute "PN" "M40"
					( Origin gPackager )
				)
				( objectStatus "U7C1.M40" )
			)
			( pin "@baseboard_fab2_lib.baseboard_fab2(sch_1):page123_i13:vss(366)"
				( attribute "PN" "M4"
					( Origin gPackager )
				)
				( objectStatus "U7C1.M4" )
			)
			( pin "@baseboard_fab2_lib.baseboard_fab2(sch_1):page123_i13:vss(367)"
				( attribute "PN" "M37"
					( Origin gPackager )
				)
				( objectStatus "U7C1.M37" )
			)
			( pin "@baseboard_fab2_lib.baseboard_fab2(sch_1):page123_i13:vss(368)"
				( attribute "PN" "M33"
					( Origin gPackager )
				)
				( objectStatus "U7C1.M33" )
			)
			( pin "@baseboard_fab2_lib.baseboard_fab2(sch_1):page123_i13:vss(369)"
				( attribute "PN" "M29"
					( Origin gPackager )
				)
				( objectStatus "U7C1.M29" )
			)
			( pin "@baseboard_fab2_lib.baseboard_fab2(sch_1):page123_i13:vss(370)"
				( attribute "PN" "M26"
					( Origin gPackager )
				)
				( objectStatus "U7C1.M26" )
			)
			( pin "@baseboard_fab2_lib.baseboard_fab2(sch_1):page123_i13:vss(371)"
				( attribute "PN" "M22"
					( Origin gPackager )
				)
				( objectStatus "U7C1.M22" )
			)
			( pin "@baseboard_fab2_lib.baseboard_fab2(sch_1):page123_i13:vss(372)"
				( attribute "PN" "M2"
					( Origin gPackager )
				)
				( objectStatus "U7C1.M2" )
			)
			( pin "@baseboard_fab2_lib.baseboard_fab2(sch_1):page123_i13:vss(373)"
				( attribute "PN" "L68"
					( Origin gPackager )
				)
				( objectStatus "U7C1.L68" )
			)
			( pin "@baseboard_fab2_lib.baseboard_fab2(sch_1):page123_i13:vss(374)"
				( attribute "PN" "L5"
					( Origin gPackager )
				)
				( objectStatus "U7C1.L5" )
			)
			( pin "@baseboard_fab2_lib.baseboard_fab2(sch_1):page123_i13:vss(375)"
				( attribute "PN" "K71"
					( Origin gPackager )
				)
				( objectStatus "U7C1.K71" )
			)
			( pin "@baseboard_fab2_lib.baseboard_fab2(sch_1):page123_i13:vss(376)"
				( attribute "PN" "K69"
					( Origin gPackager )
				)
				( objectStatus "U7C1.K69" )
			)
			( pin "@baseboard_fab2_lib.baseboard_fab2(sch_1):page123_i13:vss(377)"
				( attribute "PN" "K54"
					( Origin gPackager )
				)
				( objectStatus "U7C1.K54" )
			)
			( pin "@baseboard_fab2_lib.baseboard_fab2(sch_1):page123_i13:vss(378)"
				( attribute "PN" "J70"
					( Origin gPackager )
				)
				( objectStatus "U7C1.J70" )
			)
			( pin "@baseboard_fab2_lib.baseboard_fab2(sch_1):page123_i13:vss(379)"
				( attribute "PN" "J68"
					( Origin gPackager )
				)
				( objectStatus "U7C1.J68" )
			)
			( pin "@baseboard_fab2_lib.baseboard_fab2(sch_1):page123_i13:vss(380)"
				( attribute "PN" "J59"
					( Origin gPackager )
				)
				( objectStatus "U7C1.J59" )
			)
			( pin "@baseboard_fab2_lib.baseboard_fab2(sch_1):page123_i13:vss(381)"
				( attribute "PN" "J44"
					( Origin gPackager )
				)
				( objectStatus "U7C1.J44" )
			)
			( pin "@baseboard_fab2_lib.baseboard_fab2(sch_1):page123_i13:vss(382)"
				( attribute "PN" "J37"
					( Origin gPackager )
				)
				( objectStatus "U7C1.J37" )
			)
			( pin "@baseboard_fab2_lib.baseboard_fab2(sch_1):page123_i13:vss(383)"
				( attribute "PN" "J22"
					( Origin gPackager )
				)
				( objectStatus "U7C1.J22" )
			)
			( pin "@baseboard_fab2_lib.baseboard_fab2(sch_1):page123_i13:vss(384)"
				( attribute "PN" "J15"
					( Origin gPackager )
				)
				( objectStatus "U7C1.J15" )
			)
			( pin "@baseboard_fab2_lib.baseboard_fab2(sch_1):page123_i13:vss(385)"
				( attribute "PN" "J11"
					( Origin gPackager )
				)
				( objectStatus "U7C1.J11" )
			)
			( pin "@baseboard_fab2_lib.baseboard_fab2(sch_1):page123_i13:vss(386)"
				( attribute "PN" "H65"
					( Origin gPackager )
				)
				( objectStatus "U7C1.H65" )
			)
			( pin "@baseboard_fab2_lib.baseboard_fab2(sch_1):page123_i13:vss(387)"
				( attribute "PN" "J7"
					( Origin gPackager )
				)
				( objectStatus "U7C1.J7" )
			)
			( pin "@baseboard_fab2_lib.baseboard_fab2(sch_1):page123_i13:vss(388)"
				( attribute "PN" "J5"
					( Origin gPackager )
				)
				( objectStatus "U7C1.J5" )
			)
			( pin "@baseboard_fab2_lib.baseboard_fab2(sch_1):page123_i13:vss(389)"
				( attribute "PN" "J29"
					( Origin gPackager )
				)
				( objectStatus "U7C1.J29" )
			)
			( pin "@baseboard_fab2_lib.baseboard_fab2(sch_1):page123_i13:vss(390)"
				( attribute "PN" "H58"
					( Origin gPackager )
				)
				( objectStatus "U7C1.H58" )
			)
			( pin "@baseboard_fab2_lib.baseboard_fab2(sch_1):page123_i13:vss(391)"
				( attribute "PN" "G66"
					( Origin gPackager )
				)
				( objectStatus "U7C1.G66" )
			)
			( pin "@baseboard_fab2_lib.baseboard_fab2(sch_1):page123_i13:vss(392)"
				( attribute "PN" "G63"
					( Origin gPackager )
				)
				( objectStatus "U7C1.G63" )
			)
			( pin "@baseboard_fab2_lib.baseboard_fab2(sch_1):page123_i13:vss(393)"
				( attribute "PN" "G6"
					( Origin gPackager )
				)
				( objectStatus "U7C1.G6" )
			)
			( pin "@baseboard_fab2_lib.baseboard_fab2(sch_1):page123_i13:vss(394)"
				( attribute "PN" "G48"
					( Origin gPackager )
				)
				( objectStatus "U7C1.G48" )
			)
			( pin "@baseboard_fab2_lib.baseboard_fab2(sch_1):page123_i13:vss(395)"
				( attribute "PN" "G37"
					( Origin gPackager )
				)
				( objectStatus "U7C1.G37" )
			)
			( pin "@baseboard_fab2_lib.baseboard_fab2(sch_1):page123_i13:vss(396)"
				( attribute "PN" "G29"
					( Origin gPackager )
				)
				( objectStatus "U7C1.G29" )
			)
			( pin "@baseboard_fab2_lib.baseboard_fab2(sch_1):page123_i13:vss(397)"
				( attribute "PN" "G22"
					( Origin gPackager )
				)
				( objectStatus "U7C1.G22" )
			)
			( pin "@baseboard_fab2_lib.baseboard_fab2(sch_1):page123_i13:vss(398)"
				( attribute "PN" "E9"
					( Origin gPackager )
				)
				( objectStatus "U7C1.E9" )
			)
			( pin "@baseboard_fab2_lib.baseboard_fab2(sch_1):page123_i13:vss(399)"
				( attribute "PN" "G59"
					( Origin gPackager )
				)
				( objectStatus "U7C1.G59" )
			)
			( pin "@baseboard_fab2_lib.baseboard_fab2(sch_1):page123_i13:vss(400)"
				( attribute "PN" "E63"
					( Origin gPackager )
				)
				( objectStatus "U7C1.E63" )
			)
			( pin "@baseboard_fab2_lib.baseboard_fab2(sch_1):page123_i13:vss(401)"
				( attribute "PN" "E61"
					( Origin gPackager )
				)
				( objectStatus "U7C1.E61" )
			)
			( pin "@baseboard_fab2_lib.baseboard_fab2(sch_1):page123_i13:vss(402)"
				( attribute "PN" "E6"
					( Origin gPackager )
				)
				( objectStatus "U7C1.E6" )
			)
			( pin "@baseboard_fab2_lib.baseboard_fab2(sch_1):page123_i13:vss(403)"
				( attribute "PN" "E57"
					( Origin gPackager )
				)
				( objectStatus "U7C1.E57" )
			)
			( pin "@baseboard_fab2_lib.baseboard_fab2(sch_1):page123_i13:vss(404)"
				( attribute "PN" "E54"
					( Origin gPackager )
				)
				( objectStatus "U7C1.E54" )
			)
			( pin "@baseboard_fab2_lib.baseboard_fab2(sch_1):page123_i13:vss(405)"
				( attribute "PN" "E52"
					( Origin gPackager )
				)
				( objectStatus "U7C1.E52" )
			)
			( pin "@baseboard_fab2_lib.baseboard_fab2(sch_1):page123_i13:vss(406)"
				( attribute "PN" "E50"
					( Origin gPackager )
				)
				( objectStatus "U7C1.E50" )
			)
			( pin "@baseboard_fab2_lib.baseboard_fab2(sch_1):page123_i13:vss(407)"
				( attribute "PN" "E48"
					( Origin gPackager )
				)
				( objectStatus "U7C1.E48" )
			)
			( pin "@baseboard_fab2_lib.baseboard_fab2(sch_1):page123_i13:vss(408)"
				( attribute "PN" "E45"
					( Origin gPackager )
				)
				( objectStatus "U7C1.E45" )
			)
			( pin "@baseboard_fab2_lib.baseboard_fab2(sch_1):page123_i13:vss(409)"
				( attribute "PN" "E43"
					( Origin gPackager )
				)
				( objectStatus "U7C1.E43" )
			)
			( pin "@baseboard_fab2_lib.baseboard_fab2(sch_1):page123_i13:vss(410)"
				( attribute "PN" "E41"
					( Origin gPackager )
				)
				( objectStatus "U7C1.E41" )
			)
			( pin "@baseboard_fab2_lib.baseboard_fab2(sch_1):page123_i13:vss(411)"
				( attribute "PN" "E39"
					( Origin gPackager )
				)
				( objectStatus "U7C1.E39" )
			)
			( pin "@baseboard_fab2_lib.baseboard_fab2(sch_1):page123_i13:vss(412)"
				( attribute "PN" "E37"
					( Origin gPackager )
				)
				( objectStatus "U7C1.E37" )
			)
			( pin "@baseboard_fab2_lib.baseboard_fab2(sch_1):page123_i13:vss(413)"
				( attribute "PN" "E34"
					( Origin gPackager )
				)
				( objectStatus "U7C1.E34" )
			)
			( pin "@baseboard_fab2_lib.baseboard_fab2(sch_1):page123_i13:vss(414)"
				( attribute "PN" "E32"
					( Origin gPackager )
				)
				( objectStatus "U7C1.E32" )
			)
			( pin "@baseboard_fab2_lib.baseboard_fab2(sch_1):page123_i13:vss(415)"
				( attribute "PN" "E30"
					( Origin gPackager )
				)
				( objectStatus "U7C1.E30" )
			)
			( pin "@baseboard_fab2_lib.baseboard_fab2(sch_1):page123_i13:vss(416)"
				( attribute "PN" "E28"
					( Origin gPackager )
				)
				( objectStatus "U7C1.E28" )
			)
			( pin "@baseboard_fab2_lib.baseboard_fab2(sch_1):page123_i13:vss(417)"
				( attribute "PN" "E26"
					( Origin gPackager )
				)
				( objectStatus "U7C1.E26" )
			)
			( pin "@baseboard_fab2_lib.baseboard_fab2(sch_1):page123_i13:vss(418)"
				( attribute "PN" "E24"
					( Origin gPackager )
				)
				( objectStatus "U7C1.E24" )
			)
			( pin "@baseboard_fab2_lib.baseboard_fab2(sch_1):page123_i13:vss(419)"
				( attribute "PN" "E22"
					( Origin gPackager )
				)
				( objectStatus "U7C1.E22" )
			)
			( pin "@baseboard_fab2_lib.baseboard_fab2(sch_1):page123_i13:vss(420)"
				( attribute "PN" "E20"
					( Origin gPackager )
				)
				( objectStatus "U7C1.E20" )
			)
			( pin "@baseboard_fab2_lib.baseboard_fab2(sch_1):page123_i13:vss(421)"
				( attribute "PN" "E15"
					( Origin gPackager )
				)
				( objectStatus "U7C1.E15" )
			)
			( pin "@baseboard_fab2_lib.baseboard_fab2(sch_1):page123_i13:vss(422)"
				( attribute "PN" "E13"
					( Origin gPackager )
				)
				( objectStatus "U7C1.E13" )
			)
			( pin "@baseboard_fab2_lib.baseboard_fab2(sch_1):page123_i13:vss(423)"
				( attribute "PN" "E11"
					( Origin gPackager )
				)
				( objectStatus "U7C1.E11" )
			)
			( pin "@baseboard_fab2_lib.baseboard_fab2(sch_1):page123_i13:vss(424)"
				( attribute "PN" "D47"
					( Origin gPackager )
				)
				( objectStatus "U7C1.D47" )
			)
			( pin "@baseboard_fab2_lib.baseboard_fab2(sch_1):page123_i13:vss(425)"
				( attribute "PN" "E65"
					( Origin gPackager )
				)
				( objectStatus "U7C1.E65" )
			)
			( pin "@baseboard_fab2_lib.baseboard_fab2(sch_1):page123_i13:vss(426)"
				( attribute "PN" "E59"
					( Origin gPackager )
				)
				( objectStatus "U7C1.E59" )
			)
			( pin "@baseboard_fab2_lib.baseboard_fab2(sch_1):page123_i13:vss(427)"
				( attribute "PN" "D27"
					( Origin gPackager )
				)
				( objectStatus "U7C1.D27" )
			)
			( pin "@baseboard_fab2_lib.baseboard_fab2(sch_1):page123_i13:vss(428)"
				( attribute "PN" "D25"
					( Origin gPackager )
				)
				( objectStatus "U7C1.D25" )
			)
			( pin "@baseboard_fab2_lib.baseboard_fab2(sch_1):page123_i13:vss(429)"
				( attribute "PN" "D19"
					( Origin gPackager )
				)
				( objectStatus "U7C1.D19" )
			)
			( pin "@baseboard_fab2_lib.baseboard_fab2(sch_1):page123_i13:vss(430)"
				( attribute "PN" "D16"
					( Origin gPackager )
				)
				( objectStatus "U7C1.D16" )
			)
			( pin "@baseboard_fab2_lib.baseboard_fab2(sch_1):page123_i13:vss(431)"
				( attribute "PN" "D12"
					( Origin gPackager )
				)
				( objectStatus "U7C1.D12" )
			)
			( pin "@baseboard_fab2_lib.baseboard_fab2(sch_1):page123_i13:vss(432)"
				( attribute "PN" "C65"
					( Origin gPackager )
				)
				( objectStatus "U7C1.C65" )
			)
			( pin "@baseboard_fab2_lib.baseboard_fab2(sch_1):page123_i13:vss(433)"
				( attribute "PN" "C41"
					( Origin gPackager )
				)
				( objectStatus "U7C1.C41" )
			)
			( pin "@baseboard_fab2_lib.baseboard_fab2(sch_1):page123_i13:vss(434)"
				( attribute "PN" "C37"
					( Origin gPackager )
				)
				( objectStatus "U7C1.C37" )
			)
			( pin "@baseboard_fab2_lib.baseboard_fab2(sch_1):page123_i13:vss(435)"
				( attribute "PN" "C34"
					( Origin gPackager )
				)
				( objectStatus "U7C1.C34" )
			)
			( pin "@baseboard_fab2_lib.baseboard_fab2(sch_1):page123_i13:vss(436)"
				( attribute "PN" "C30"
					( Origin gPackager )
				)
				( objectStatus "U7C1.C30" )
			)
			( pin "@baseboard_fab2_lib.baseboard_fab2(sch_1):page123_i13:vss(437)"
				( attribute "PN" "C22"
					( Origin gPackager )
				)
				( objectStatus "U7C1.C22" )
			)
			( pin "@baseboard_fab2_lib.baseboard_fab2(sch_1):page123_i13:vss(438)"
				( attribute "PN" "B47"
					( Origin gPackager )
				)
				( objectStatus "U7C1.B47" )
			)
			( pin "@baseboard_fab2_lib.baseboard_fab2(sch_1):page123_i13:vss(439)"
				( attribute "PN" "B27"
					( Origin gPackager )
				)
				( objectStatus "U7C1.B27" )
			)
			( pin "@baseboard_fab2_lib.baseboard_fab2(sch_1):page123_i13:vss(440)"
				( attribute "PN" "B25"
					( Origin gPackager )
				)
				( objectStatus "U7C1.B25" )
			)
			( pin "@baseboard_fab2_lib.baseboard_fab2(sch_1):page123_i13:vss(441)"
				( attribute "PN" "B19"
					( Origin gPackager )
				)
				( objectStatus "U7C1.B19" )
			)
			( pin "@baseboard_fab2_lib.baseboard_fab2(sch_1):page123_i13:vss(442)"
				( attribute "PN" "B12"
					( Origin gPackager )
				)
				( objectStatus "U7C1.B12" )
			)
			( pin "@baseboard_fab2_lib.baseboard_fab2(sch_1):page123_i13:vss(443)"
				( attribute "PN" "A41"
					( Origin gPackager )
				)
				( objectStatus "U7C1.A41" )
			)
			( pin "@baseboard_fab2_lib.baseboard_fab2(sch_1):page123_i13:vss(444)"
				( attribute "PN" "A37"
					( Origin gPackager )
				)
				( objectStatus "U7C1.A37" )
			)
			( pin "@baseboard_fab2_lib.baseboard_fab2(sch_1):page123_i13:vss(445)"
				( attribute "PN" "A34"
					( Origin gPackager )
				)
				( objectStatus "U7C1.A34" )
			)
			( pin "@baseboard_fab2_lib.baseboard_fab2(sch_1):page123_i13:vss(446)"
				( attribute "PN" "A30"
					( Origin gPackager )
				)
				( objectStatus "U7C1.A30" )
			)
			( pin "@baseboard_fab2_lib.baseboard_fab2(sch_1):page123_i13:vss(447)"
				( attribute "PN" "A22"
					( Origin gPackager )
				)
				( objectStatus "U7C1.A22" )
			)
			( pin "@baseboard_fab2_lib.baseboard_fab2(sch_1):page123_i13:vss(448)"
				( attribute "PN" "A18"
					( Origin gPackager )
				)
				( objectStatus "U7C1.A18" )
			)
			( pin "@baseboard_fab2_lib.baseboard_fab2(sch_1):page123_i13:vss(449)"
				( attribute "PN" "Y70"
					( Origin gPackager )
				)
				( objectStatus "U7C1.Y70" )
			)
			( pin "@baseboard_fab2_lib.baseboard_fab2(sch_1):page123_i13:vss(450)"
				( attribute "PN" "Y72"
					( Origin gPackager )
				)
				( objectStatus "U7C1.Y72" )
			)
			( pin "@baseboard_fab2_lib.baseboard_fab2(sch_1):page123_i13:vss(451)"
				( attribute "PN" "AT37"
					( Origin gPackager )
				)
				( objectStatus "U7C1.AT37" )
			)
			( pin "@baseboard_fab2_lib.baseboard_fab2(sch_1):page123_i13:vss(452)"
				( attribute "PN" "BB48"
					( Origin gPackager )
				)
				( objectStatus "U7C1.BB48" )
			)
			( pin "@baseboard_fab2_lib.baseboard_fab2(sch_1):page123_i13:vss(453)"
				( attribute "PN" "CA70"
					( Origin gPackager )
				)
				( objectStatus "U7C1.CA70" )
			)
			( pin "@baseboard_fab2_lib.baseboard_fab2(sch_1):page123_i13:vss(454)"
				( attribute "PN" "BW72"
					( Origin gPackager )
				)
				( objectStatus "U7C1.BW72" )
			)
			( pin "@baseboard_fab2_lib.baseboard_fab2(sch_1):page123_i13:vss(455)"
				( attribute "PN" "BW70"
					( Origin gPackager )
				)
				( objectStatus "U7C1.BW70" )
			)
			( pin "@baseboard_fab2_lib.baseboard_fab2(sch_1):page123_i13:vss(456)"
				( attribute "PN" "BU72"
					( Origin gPackager )
				)
				( objectStatus "U7C1.BU72" )
			)
			( pin "@baseboard_fab2_lib.baseboard_fab2(sch_1):page123_i13:vss(457)"
				( attribute "PN" "BR72"
					( Origin gPackager )
				)
				( objectStatus "U7C1.BR72" )
			)
			( pin "@baseboard_fab2_lib.baseboard_fab2(sch_1):page123_i13:vss(458)"
				( attribute "PN" "G72"
					( Origin gPackager )
				)
				( objectStatus "U7C1.G72" )
			)
			( pin "@baseboard_fab2_lib.baseboard_fab2(sch_1):page123_i13:vss(459)"
				( attribute "PN" "G1"
					( Origin gPackager )
				)
				( objectStatus "U7C1.G1" )
			)
			( pin "@baseboard_fab2_lib.baseboard_fab2(sch_1):page123_i13:vss(460)"
				( attribute "PN" "E72"
					( Origin gPackager )
				)
				( objectStatus "U7C1.E72" )
			)
			( pin "@baseboard_fab2_lib.baseboard_fab2(sch_1):page123_i13:vss(461)"
				( attribute "PN" "E1"
					( Origin gPackager )
				)
				( objectStatus "U7C1.E1" )
			)
			( pin "@baseboard_fab2_lib.baseboard_fab2(sch_1):page123_i13:vss(462)"
				( attribute "PN" "C72"
					( Origin gPackager )
				)
				( objectStatus "U7C1.C72" )
			)
			( pin "@baseboard_fab2_lib.baseboard_fab2(sch_1):page123_i13:vss(463)"
				( attribute "PN" "C3"
					( Origin gPackager )
				)
				( objectStatus "U7C1.C3" )
			)
			( pin "@baseboard_fab2_lib.baseboard_fab2(sch_1):page123_i13:vss(464)"
				( attribute "PN" "BR1"
					( Origin gPackager )
				)
				( objectStatus "U7C1.BR1" )
			)
			( pin "@baseboard_fab2_lib.baseboard_fab2(sch_1):page123_i13:vss(465)"
				( attribute "PN" "BU1"
					( Origin gPackager )
				)
				( objectStatus "U7C1.BU1" )
			)
			( pin "@baseboard_fab2_lib.baseboard_fab2(sch_1):page123_i13:vss(466)"
				( attribute "PN" "BW1"
					( Origin gPackager )
				)
				( objectStatus "U7C1.BW1" )
			)
			( pin "@baseboard_fab2_lib.baseboard_fab2(sch_1):page123_i13:vss(467)"
				( attribute "PN" "CA3"
					( Origin gPackager )
				)
				( objectStatus "U7C1.CA3" )
			)
			( pin "@baseboard_fab2_lib.baseboard_fab2(sch_1):page123_i13:vss(468)"
				( attribute "PN" "A70"
					( Origin gPackager )
				)
				( objectStatus "U7C1.A70" )
			)
			( pin "@baseboard_fab2_lib.baseboard_fab2(sch_1):page123_i13:vss(469)"
				( attribute "PN" "CA5"
					( Origin gPackager )
				)
				( objectStatus "U7C1.CA5" )
			)
			( pin "@baseboard_fab2_lib.baseboard_fab2(sch_1):page123_i13:vss(470)"
				( attribute "PN" "CA7"
					( Origin gPackager )
				)
				( objectStatus "U7C1.CA7" )
			)
			( pin "@baseboard_fab2_lib.baseboard_fab2(sch_1):page123_i13:vss(471)"
				( attribute "PN" "CA9"
					( Origin gPackager )
				)
				( objectStatus "U7C1.CA9" )
			)
			( pin "@baseboard_fab2_lib.baseboard_fab2(sch_1):page123_i13:vss(472)"
				( attribute "PN" "CA65"
					( Origin gPackager )
				)
				( objectStatus "U7C1.CA65" )
			)
			( pin "@baseboard_fab2_lib.baseboard_fab2(sch_1):page123_i13:vss(473)"
				( attribute "PN" "CA66"
					( Origin gPackager )
				)
				( objectStatus "U7C1.CA66" )
			)
			( pin "@baseboard_fab2_lib.baseboard_fab2(sch_1):page123_i13:vss(474)"
				( attribute "PN" "CA68"
					( Origin gPackager )
				)
				( objectStatus "U7C1.CA68" )
			)
			( pin "@baseboard_fab2_lib.baseboard_fab2(sch_1):page123_i13:vss(475)"
				( attribute "PN" "BN72"
					( Origin gPackager )
				)
				( objectStatus "U7C1.BN72" )
			)
			( pin "@baseboard_fab2_lib.baseboard_fab2(sch_1):page123_i13:vss(476)"
				( attribute "PN" "BN1"
					( Origin gPackager )
				)
				( objectStatus "U7C1.BN1" )
			)
			( pin "@baseboard_fab2_lib.baseboard_fab2(sch_1):page123_i13:vss(477)"
				( attribute "PN" "J72"
					( Origin gPackager )
				)
				( objectStatus "U7C1.J72" )
			)
			( pin "@baseboard_fab2_lib.baseboard_fab2(sch_1):page123_i13:vss(478)"
				( attribute "PN" "J1"
					( Origin gPackager )
				)
				( objectStatus "U7C1.J1" )
			)
			( pin "@baseboard_fab2_lib.baseboard_fab2(sch_1):page123_i13:vss(479)"
				( attribute "PN" "A68"
					( Origin gPackager )
				)
				( objectStatus "U7C1.A68" )
			)
			( pin "@baseboard_fab2_lib.baseboard_fab2(sch_1):page123_i13:vss(480)"
				( attribute "PN" "A66"
					( Origin gPackager )
				)
				( objectStatus "U7C1.A66" )
			)
			( pin "@baseboard_fab2_lib.baseboard_fab2(sch_1):page123_i13:vss(481)"
				( attribute "PN" "A65"
					( Origin gPackager )
				)
				( objectStatus "U7C1.A65" )
			)
			( pin "@baseboard_fab2_lib.baseboard_fab2(sch_1):page123_i13:vss(482)"
				( attribute "PN" "A9"
					( Origin gPackager )
				)
				( objectStatus "U7C1.A9" )
			)
			( pin "@baseboard_fab2_lib.baseboard_fab2(sch_1):page123_i13:vss(483)"
				( attribute "PN" "A7"
					( Origin gPackager )
				)
				( objectStatus "U7C1.A7" )
			)
			( pin "@baseboard_fab2_lib.baseboard_fab2(sch_1):page123_i13:vss(484)"
				( attribute "PN" "A5"
					( Origin gPackager )
				)
				( objectStatus "U7C1.A5" )
			)
			( pin "@baseboard_fab2_lib.baseboard_fab2(sch_1):page123_i13:vss(485)"
				( attribute "PN" "E3"
					( Origin gPackager )
				)
				( objectStatus "U7C1.E3" )
			)
			( pin "@baseboard_fab2_lib.baseboard_fab2(sch_1):page123_i13:vss(486)"
				( attribute "PN" "F3"
					( Origin gPackager )
				)
				( objectStatus "U7C1.F3" )
			)
			( pin "@baseboard_fab2_lib.baseboard_fab2(sch_1):page123_i13:vss(487)"
				( attribute "PN" "BR3"
					( Origin gPackager )
				)
				( objectStatus "U7C1.BR3" )
			)
			( pin "@baseboard_fab2_lib.baseboard_fab2(sch_1):page123_i13:vss(488)"
				( attribute "PN" "BU3"
					( Origin gPackager )
				)
				( objectStatus "U7C1.BU3" )
			)
			( pin "@baseboard_fab2_lib.baseboard_fab2(sch_1):page123_i13:vss(489)"
				( attribute "PN" "E70"
					( Origin gPackager )
				)
				( objectStatus "U7C1.E70" )
			)
			( pin "@baseboard_fab2_lib.baseboard_fab2(sch_1):page123_i13:vss(490)"
				( attribute "PN" "F70"
					( Origin gPackager )
				)
				( objectStatus "U7C1.F70" )
			)
			( pin "@baseboard_fab2_lib.baseboard_fab2(sch_1):page123_i13:vss(491)"
				( attribute "PN" "BR70"
					( Origin gPackager )
				)
				( objectStatus "U7C1.BR70" )
			)
			( pin "@baseboard_fab2_lib.baseboard_fab2(sch_1):page123_i13:vss(492)"
				( attribute "PN" "BU70"
					( Origin gPackager )
				)
				( objectStatus "U7C1.BU70" )
			)
			( pin "@baseboard_fab2_lib.baseboard_fab2(sch_1):page123_i13:vss(493)"
				( attribute "PN" "BT69"
					( Origin gPackager )
				)
				( objectStatus "U7C1.BT69" )
			)
			( pin "@baseboard_fab2_lib.baseboard_fab2(sch_1):page123_i13:vss(494)"
				( attribute "PN" "BP69"
					( Origin gPackager )
				)
				( objectStatus "U7C1.BP69" )
			)
			( pin "@baseboard_fab2_lib.baseboard_fab2(sch_1):page123_i21:vccmphy_1p05(13)"
				( attribute "PN" "AE27"
					( Origin gPackager )
				)
				( objectStatus "U7C1.AE27" )
			)
			( pin "@baseboard_fab2_lib.baseboard_fab2(sch_1):page123_i21:vccprim_avid(0)"
				( attribute "PN" "AU36"
					( Origin gPackager )
				)
				( objectStatus "U7C1.AU36" )
			)
			( pin "@baseboard_fab2_lib.baseboard_fab2(sch_1):page123_i21:vccprim_avid(1)"
				( attribute "PN" "AU34"
					( Origin gPackager )
				)
				( objectStatus "U7C1.AU34" )
			)
			( pin "@baseboard_fab2_lib.baseboard_fab2(sch_1):page123_i21:vccprim_avid(2)"
				( attribute "PN" "AU32"
					( Origin gPackager )
				)
				( objectStatus "U7C1.AU32" )
			)
			( pin "@baseboard_fab2_lib.baseboard_fab2(sch_1):page123_i21:vccprim_avid(3)"
				( attribute "PN" "AT36"
					( Origin gPackager )
				)
				( objectStatus "U7C1.AT36" )
			)
			( pin "@baseboard_fab2_lib.baseboard_fab2(sch_1):page123_i21:vccprim_avid(4)"
				( attribute "PN" "AT34"
					( Origin gPackager )
				)
				( objectStatus "U7C1.AT34" )
			)
			( pin "@baseboard_fab2_lib.baseboard_fab2(sch_1):page123_i21:vccprim_avid(5)"
				( attribute "PN" "AT32"
					( Origin gPackager )
				)
				( objectStatus "U7C1.AT32" )
			)
			( pin "@baseboard_fab2_lib.baseboard_fab2(sch_1):page123_i21:vccprim_avid(6)"
				( attribute "PN" "AP39"
					( Origin gPackager )
				)
				( objectStatus "U7C1.AP39" )
			)
			( pin "@baseboard_fab2_lib.baseboard_fab2(sch_1):page123_i21:vccprim_avid(7)"
				( attribute "PN" "AP37"
					( Origin gPackager )
				)
				( objectStatus "U7C1.AP37" )
			)
			( pin "@baseboard_fab2_lib.baseboard_fab2(sch_1):page123_i21:vccprim_avid(8)"
				( attribute "PN" "AP36"
					( Origin gPackager )
				)
				( objectStatus "U7C1.AP36" )
			)
			( pin "@baseboard_fab2_lib.baseboard_fab2(sch_1):page123_i21:vccprim_avid(9)"
				( attribute "PN" "AP34"
					( Origin gPackager )
				)
				( objectStatus "U7C1.AP34" )
			)
			( pin "@baseboard_fab2_lib.baseboard_fab2(sch_1):page123_i21:vccprim_avid(10)"
				( attribute "PN" "AP32"
					( Origin gPackager )
				)
				( objectStatus "U7C1.AP32" )
			)
			( pin "@baseboard_fab2_lib.baseboard_fab2(sch_1):page123_i21:vccprim_avid(11)"
				( attribute "PN" "AM39"
					( Origin gPackager )
				)
				( objectStatus "U7C1.AM39" )
			)
			( pin "@baseboard_fab2_lib.baseboard_fab2(sch_1):page123_i21:vccprim_avid(12)"
				( attribute "PN" "AM37"
					( Origin gPackager )
				)
				( objectStatus "U7C1.AM37" )
			)
			( pin "@baseboard_fab2_lib.baseboard_fab2(sch_1):page123_i21:vccprim_avid(13)"
				( attribute "PN" "AM36"
					( Origin gPackager )
				)
				( objectStatus "U7C1.AM36" )
			)
			( pin "@baseboard_fab2_lib.baseboard_fab2(sch_1):page123_i21:vccprim_avid(14)"
				( attribute "PN" "AM34"
					( Origin gPackager )
				)
				( objectStatus "U7C1.AM34" )
			)
			( pin "@baseboard_fab2_lib.baseboard_fab2(sch_1):page123_i21:vccprim_avid(15)"
				( attribute "PN" "AM32"
					( Origin gPackager )
				)
				( objectStatus "U7C1.AM32" )
			)
			( pin "@baseboard_fab2_lib.baseboard_fab2(sch_1):page123_i21:vccprim_avid(16)"
				( attribute "PN" "AK39"
					( Origin gPackager )
				)
				( objectStatus "U7C1.AK39" )
			)
			( pin "@baseboard_fab2_lib.baseboard_fab2(sch_1):page123_i21:vccprim_avid(17)"
				( attribute "PN" "AK37"
					( Origin gPackager )
				)
				( objectStatus "U7C1.AK37" )
			)
			( pin "@baseboard_fab2_lib.baseboard_fab2(sch_1):page123_i21:vccprim_avid(18)"
				( attribute "PN" "AK34"
					( Origin gPackager )
				)
				( objectStatus "U7C1.AK34" )
			)
			( pin "@baseboard_fab2_lib.baseboard_fab2(sch_1):page123_i21:vccprim_avid(19)"
				( attribute "PN" "AG39"
					( Origin gPackager )
				)
				( objectStatus "U7C1.AG39" )
			)
			( pin "@baseboard_fab2_lib.baseboard_fab2(sch_1):page123_i21:vccprim_avid(20)"
				( attribute "PN" "AG37"
					( Origin gPackager )
				)
				( objectStatus "U7C1.AG37" )
			)
			( pin "@baseboard_fab2_lib.baseboard_fab2(sch_1):page123_i21:vccprim_avid(21)"
				( attribute "PN" "AG36"
					( Origin gPackager )
				)
				( objectStatus "U7C1.AG36" )
			)
			( pin "@baseboard_fab2_lib.baseboard_fab2(sch_1):page123_i21:vccprim_avid(22)"
				( attribute "PN" "AG34"
					( Origin gPackager )
				)
				( objectStatus "U7C1.AG34" )
			)
			( pin "@baseboard_fab2_lib.baseboard_fab2(sch_1):page123_i21:vccprim_avid(23)"
				( attribute "PN" "AG32"
					( Origin gPackager )
				)
				( objectStatus "U7C1.AG32" )
			)
			( pin "@baseboard_fab2_lib.baseboard_fab2(sch_1):page123_i21:vccprim_avid(24)"
				( attribute "PN" "AE41"
					( Origin gPackager )
				)
				( objectStatus "U7C1.AE41" )
			)
			( pin "@baseboard_fab2_lib.baseboard_fab2(sch_1):page123_i21:vccprim_avid(25)"
				( attribute "PN" "AE39"
					( Origin gPackager )
				)
				( objectStatus "U7C1.AE39" )
			)
			( pin "@baseboard_fab2_lib.baseboard_fab2(sch_1):page123_i21:vccprim_avid(26)"
				( attribute "PN" "AE37"
					( Origin gPackager )
				)
				( objectStatus "U7C1.AE37" )
			)
			( pin "@baseboard_fab2_lib.baseboard_fab2(sch_1):page123_i21:vccprim_avid(27)"
				( attribute "PN" "AE36"
					( Origin gPackager )
				)
				( objectStatus "U7C1.AE36" )
			)
			( pin "@baseboard_fab2_lib.baseboard_fab2(sch_1):page123_i21:vccprim_avid(28)"
				( attribute "PN" "AE34"
					( Origin gPackager )
				)
				( objectStatus "U7C1.AE34" )
			)
			( pin "@baseboard_fab2_lib.baseboard_fab2(sch_1):page123_i21:vccprim_avid(29)"
				( attribute "PN" "AE32"
					( Origin gPackager )
				)
				( objectStatus "U7C1.AE32" )
			)
			( pin "@baseboard_fab2_lib.baseboard_fab2(sch_1):page123_i21:vccprim_avid(30)"
				( attribute "PN" "AE30"
					( Origin gPackager )
				)
				( objectStatus "U7C1.AE30" )
			)
			( pin "@baseboard_fab2_lib.baseboard_fab2(sch_1):page123_i21:vccprim_avid(31)"
				( attribute "PN" "U27"
					( Origin gPackager )
				)
				( objectStatus "U7C1.U27" )
			)
			( pin "@baseboard_fab2_lib.baseboard_fab2(sch_1):page123_i21:vccprim_avid(32)"
				( attribute "PN" "AC41"
					( Origin gPackager )
				)
				( objectStatus "U7C1.AC41" )
			)
			( pin "@baseboard_fab2_lib.baseboard_fab2(sch_1):page123_i21:vccprim_avid(33)"
				( attribute "PN" "AC39"
					( Origin gPackager )
				)
				( objectStatus "U7C1.AC39" )
			)
			( pin "@baseboard_fab2_lib.baseboard_fab2(sch_1):page123_i21:vccprim_avid(34)"
				( attribute "PN" "AC37"
					( Origin gPackager )
				)
				( objectStatus "U7C1.AC37" )
			)
			( pin "@baseboard_fab2_lib.baseboard_fab2(sch_1):page123_i21:vccprim_avid(35)"
				( attribute "PN" "AC36"
					( Origin gPackager )
				)
				( objectStatus "U7C1.AC36" )
			)
			( pin "@baseboard_fab2_lib.baseboard_fab2(sch_1):page123_i21:vccprim_avid(36)"
				( attribute "PN" "AC34"
					( Origin gPackager )
				)
				( objectStatus "U7C1.AC34" )
			)
			( pin "@baseboard_fab2_lib.baseboard_fab2(sch_1):page123_i21:vccprim_avid(37)"
				( attribute "PN" "AC32"
					( Origin gPackager )
				)
				( objectStatus "U7C1.AC32" )
			)
			( pin "@baseboard_fab2_lib.baseboard_fab2(sch_1):page123_i21:vccprim_avid(38)"
				( attribute "PN" "AC30"
					( Origin gPackager )
				)
				( objectStatus "U7C1.AC30" )
			)
			( pin "@baseboard_fab2_lib.baseboard_fab2(sch_1):page123_i21:vccprim_avid(39)"
				( attribute "PN" "AC29"
					( Origin gPackager )
				)
				( objectStatus "U7C1.AC29" )
			)
			( pin "@baseboard_fab2_lib.baseboard_fab2(sch_1):page123_i21:vccprim_avid(40)"
				( attribute "PN" "AA41"
					( Origin gPackager )
				)
				( objectStatus "U7C1.AA41" )
			)
			( pin "@baseboard_fab2_lib.baseboard_fab2(sch_1):page123_i21:vccprim_avid(41)"
				( attribute "PN" "AA39"
					( Origin gPackager )
				)
				( objectStatus "U7C1.AA39" )
			)
			( pin "@baseboard_fab2_lib.baseboard_fab2(sch_1):page123_i21:vccprim_avid(42)"
				( attribute "PN" "AA37"
					( Origin gPackager )
				)
				( objectStatus "U7C1.AA37" )
			)
			( pin "@baseboard_fab2_lib.baseboard_fab2(sch_1):page123_i21:vccprim_avid(43)"
				( attribute "PN" "AA36"
					( Origin gPackager )
				)
				( objectStatus "U7C1.AA36" )
			)
			( pin "@baseboard_fab2_lib.baseboard_fab2(sch_1):page123_i21:vccprim_avid(44)"
				( attribute "PN" "AA34"
					( Origin gPackager )
				)
				( objectStatus "U7C1.AA34" )
			)
			( pin "@baseboard_fab2_lib.baseboard_fab2(sch_1):page123_i21:vccprim_avid(45)"
				( attribute "PN" "AA32"
					( Origin gPackager )
				)
				( objectStatus "U7C1.AA32" )
			)
			( pin "@baseboard_fab2_lib.baseboard_fab2(sch_1):page123_i21:vccprim_avid(46)"
				( attribute "PN" "AA30"
					( Origin gPackager )
				)
				( objectStatus "U7C1.AA30" )
			)
			( pin "@baseboard_fab2_lib.baseboard_fab2(sch_1):page123_i21:vccprim_avid(47)"
				( attribute "PN" "AA29"
					( Origin gPackager )
				)
				( objectStatus "U7C1.AA29" )
			)
			( pin "@baseboard_fab2_lib.baseboard_fab2(sch_1):page123_i21:vccprim_avid(48)"
				( attribute "PN" "Y41"
					( Origin gPackager )
				)
				( objectStatus "U7C1.Y41" )
			)
			( pin "@baseboard_fab2_lib.baseboard_fab2(sch_1):page123_i21:vccprim_avid(49)"
				( attribute "PN" "Y39"
					( Origin gPackager )
				)
				( objectStatus "U7C1.Y39" )
			)
			( pin "@baseboard_fab2_lib.baseboard_fab2(sch_1):page123_i21:vccprim_avid(50)"
				( attribute "PN" "Y37"
					( Origin gPackager )
				)
				( objectStatus "U7C1.Y37" )
			)
			( pin "@baseboard_fab2_lib.baseboard_fab2(sch_1):page123_i21:vccprim_avid(51)"
				( attribute "PN" "Y36"
					( Origin gPackager )
				)
				( objectStatus "U7C1.Y36" )
			)
			( pin "@baseboard_fab2_lib.baseboard_fab2(sch_1):page123_i21:vccprim_avid(52)"
				( attribute "PN" "Y34"
					( Origin gPackager )
				)
				( objectStatus "U7C1.Y34" )
			)
			( pin "@baseboard_fab2_lib.baseboard_fab2(sch_1):page123_i21:vccprim_avid(53)"
				( attribute "PN" "Y32"
					( Origin gPackager )
				)
				( objectStatus "U7C1.Y32" )
			)
			( pin "@baseboard_fab2_lib.baseboard_fab2(sch_1):page123_i21:vccprim_avid(54)"
				( attribute "PN" "Y30"
					( Origin gPackager )
				)
				( objectStatus "U7C1.Y30" )
			)
			( pin "@baseboard_fab2_lib.baseboard_fab2(sch_1):page123_i21:vccprim_avid(55)"
				( attribute "PN" "Y29"
					( Origin gPackager )
				)
				( objectStatus "U7C1.Y29" )
			)
			( pin "@baseboard_fab2_lib.baseboard_fab2(sch_1):page123_i21:vccprim_avid(56)"
				( attribute "PN" "V40"
					( Origin gPackager )
				)
				( objectStatus "U7C1.V40" )
			)
			( pin "@baseboard_fab2_lib.baseboard_fab2(sch_1):page123_i21:vccprim_avid(57)"
				( attribute "PN" "V33"
					( Origin gPackager )
				)
				( objectStatus "U7C1.V33" )
			)
			( pin "@baseboard_fab2_lib.baseboard_fab2(sch_1):page123_i21:vccprim_avid(58)"
				( attribute "PN" "V29"
					( Origin gPackager )
				)
				( objectStatus "U7C1.V29" )
			)
			( pin "@baseboard_fab2_lib.baseboard_fab2(sch_1):page123_i21:vccprim_avid(59)"
				( attribute "PN" "U38"
					( Origin gPackager )
				)
				( objectStatus "U7C1.U38" )
			)
			( pin "@baseboard_fab2_lib.baseboard_fab2(sch_1):page123_i21:vccprim_avid(60)"
				( attribute "PN" "U35"
					( Origin gPackager )
				)
				( objectStatus "U7C1.U35" )
			)
			( pin "@baseboard_fab2_lib.baseboard_fab2(sch_1):page123_i21:vccprim_avid(61)"
				( attribute "PN" "U31"
					( Origin gPackager )
				)
				( objectStatus "U7C1.U31" )
			)
			( pin "@baseboard_fab2_lib.baseboard_fab2(sch_1):page123_i21:vccprim_avid(62)"
				( attribute "PN" "AK32"
					( Origin gPackager )
				)
				( objectStatus "U7C1.AK32" )
			)
			( pin "@baseboard_fab2_lib.baseboard_fab2(sch_1):page123_i21:vccprim_avid_qat_sense"
				( attribute "PN" "V37"
					( Origin gPackager )
				)
				( objectStatus "U7C1.V37" )
			)
			( pin "@baseboard_fab2_lib.baseboard_fab2(sch_1):page123_i21:vccprim_avid_sense"
				( attribute "PN" "AK36"
					( Origin gPackager )
				)
				( objectStatus "U7C1.AK36" )
			)
			( pin "@baseboard_fab2_lib.baseboard_fab2(sch_1):page124_i15:vss(0)"
				( attribute "PN" "CA52"
					( Origin gPackager )
				)
				( objectStatus "U7C1.CA52" )
			)
			( pin "@baseboard_fab2_lib.baseboard_fab2(sch_1):page124_i15:vss(1)"
				( attribute "PN" "CA50"
					( Origin gPackager )
				)
				( objectStatus "U7C1.CA50" )
			)
			( pin "@baseboard_fab2_lib.baseboard_fab2(sch_1):page124_i15:vss(2)"
				( attribute "PN" "CA26"
					( Origin gPackager )
				)
				( objectStatus "U7C1.CA26" )
			)
			( pin "@baseboard_fab2_lib.baseboard_fab2(sch_1):page124_i15:vss(3)"
				( attribute "PN" "CA18"
					( Origin gPackager )
				)
				( objectStatus "U7C1.CA18" )
			)
			( pin "@baseboard_fab2_lib.baseboard_fab2(sch_1):page124_i15:vss(4)"
				( attribute "PN" "CA15"
					( Origin gPackager )
				)
				( objectStatus "U7C1.CA15" )
			)
			( pin "@baseboard_fab2_lib.baseboard_fab2(sch_1):page124_i15:vss(5)"
				( attribute "PN" "BY49"
					( Origin gPackager )
				)
				( objectStatus "U7C1.BY49" )
			)
			( pin "@baseboard_fab2_lib.baseboard_fab2(sch_1):page124_i15:vss(6)"
				( attribute "PN" "BY40"
					( Origin gPackager )
				)
				( objectStatus "U7C1.BY40" )
			)
			( pin "@baseboard_fab2_lib.baseboard_fab2(sch_1):page124_i15:vss(7)"
				( attribute "PN" "BW52"
					( Origin gPackager )
				)
				( objectStatus "U7C1.BW52" )
			)
			( pin "@baseboard_fab2_lib.baseboard_fab2(sch_1):page124_i15:vss(8)"
				( attribute "PN" "BW26"
					( Origin gPackager )
				)
				( objectStatus "U7C1.BW26" )
			)
			( pin "@baseboard_fab2_lib.baseboard_fab2(sch_1):page124_i15:vss(9)"
				( attribute "PN" "BW18"
					( Origin gPackager )
				)
				( objectStatus "U7C1.BW18" )
			)
			( pin "@baseboard_fab2_lib.baseboard_fab2(sch_1):page124_i15:vss(10)"
				( attribute "PN" "BW15"
					( Origin gPackager )
				)
				( objectStatus "U7C1.BW15" )
			)
			( pin "@baseboard_fab2_lib.baseboard_fab2(sch_1):page124_i15:vss(11)"
				( attribute "PN" "BV40"
					( Origin gPackager )
				)
				( objectStatus "U7C1.BV40" )
			)
			( pin "@baseboard_fab2_lib.baseboard_fab2(sch_1):page124_i15:vss(12)"
				( attribute "PN" "BU9"
					( Origin gPackager )
				)
				( objectStatus "U7C1.BU9" )
			)
			( pin "@baseboard_fab2_lib.baseboard_fab2(sch_1):page124_i15:vss(13)"
				( attribute "PN" "BU63"
					( Origin gPackager )
				)
				( objectStatus "U7C1.BU63" )
			)
			( pin "@baseboard_fab2_lib.baseboard_fab2(sch_1):page124_i15:vss(14)"
				( attribute "PN" "BU61"
					( Origin gPackager )
				)
				( objectStatus "U7C1.BU61" )
			)
			( pin "@baseboard_fab2_lib.baseboard_fab2(sch_1):page124_i15:vss(15)"
				( attribute "PN" "BU59"
					( Origin gPackager )
				)
				( objectStatus "U7C1.BU59" )
			)
			( pin "@baseboard_fab2_lib.baseboard_fab2(sch_1):page124_i15:vss(16)"
				( attribute "PN" "BU57"
					( Origin gPackager )
				)
				( objectStatus "U7C1.BU57" )
			)
			( pin "@baseboard_fab2_lib.baseboard_fab2(sch_1):page124_i15:vss(17)"
				( attribute "PN" "BU54"
					( Origin gPackager )
				)
				( objectStatus "U7C1.BU54" )
			)
			( pin "@baseboard_fab2_lib.baseboard_fab2(sch_1):page124_i15:vss(18)"
				( attribute "PN" "BU52"
					( Origin gPackager )
				)
				( objectStatus "U7C1.BU52" )
			)
			( pin "@baseboard_fab2_lib.baseboard_fab2(sch_1):page124_i15:vss(19)"
				( attribute "PN" "BU50"
					( Origin gPackager )
				)
				( objectStatus "U7C1.BU50" )
			)
			( pin "@baseboard_fab2_lib.baseboard_fab2(sch_1):page124_i15:vss(20)"
				( attribute "PN" "BU48"
					( Origin gPackager )
				)
				( objectStatus "U7C1.BU48" )
			)
			( pin "@baseboard_fab2_lib.baseboard_fab2(sch_1):page124_i15:vss(21)"
				( attribute "PN" "BU45"
					( Origin gPackager )
				)
				( objectStatus "U7C1.BU45" )
			)
			( pin "@baseboard_fab2_lib.baseboard_fab2(sch_1):page124_i15:vss(22)"
				( attribute "PN" "BU43"
					( Origin gPackager )
				)
				( objectStatus "U7C1.BU43" )
			)
			( pin "@baseboard_fab2_lib.baseboard_fab2(sch_1):page124_i15:vss(23)"
				( attribute "PN" "BU41"
					( Origin gPackager )
				)
				( objectStatus "U7C1.BU41" )
			)
			( pin "@baseboard_fab2_lib.baseboard_fab2(sch_1):page124_i15:vss(24)"
				( attribute "PN" "BU39"
					( Origin gPackager )
				)
				( objectStatus "U7C1.BU39" )
			)
			( pin "@baseboard_fab2_lib.baseboard_fab2(sch_1):page124_i15:vss(25)"
				( attribute "PN" "BU37"
					( Origin gPackager )
				)
				( objectStatus "U7C1.BU37" )
			)
			( pin "@baseboard_fab2_lib.baseboard_fab2(sch_1):page124_i15:vss(26)"
				( attribute "PN" "BU34"
					( Origin gPackager )
				)
				( objectStatus "U7C1.BU34" )
			)
			( pin "@baseboard_fab2_lib.baseboard_fab2(sch_1):page124_i15:vss(27)"
				( attribute "PN" "BU32"
					( Origin gPackager )
				)
				( objectStatus "U7C1.BU32" )
			)
			( pin "@baseboard_fab2_lib.baseboard_fab2(sch_1):page124_i15:vss(28)"
				( attribute "PN" "BU30"
					( Origin gPackager )
				)
				( objectStatus "U7C1.BU30" )
			)
			( pin "@baseboard_fab2_lib.baseboard_fab2(sch_1):page124_i15:vss(29)"
				( attribute "PN" "BU28"
					( Origin gPackager )
				)
				( objectStatus "U7C1.BU28" )
			)
			( pin "@baseboard_fab2_lib.baseboard_fab2(sch_1):page124_i15:vss(30)"
				( attribute "PN" "BU26"
					( Origin gPackager )
				)
				( objectStatus "U7C1.BU26" )
			)
			( pin "@baseboard_fab2_lib.baseboard_fab2(sch_1):page124_i15:vss(31)"
				( attribute "PN" "BU24"
					( Origin gPackager )
				)
				( objectStatus "U7C1.BU24" )
			)
			( pin "@baseboard_fab2_lib.baseboard_fab2(sch_1):page124_i15:vss(32)"
				( attribute "PN" "BU22"
					( Origin gPackager )
				)
				( objectStatus "U7C1.BU22" )
			)
			( pin "@baseboard_fab2_lib.baseboard_fab2(sch_1):page124_i15:vss(33)"
				( attribute "PN" "BU20"
					( Origin gPackager )
				)
				( objectStatus "U7C1.BU20" )
			)
			( pin "@baseboard_fab2_lib.baseboard_fab2(sch_1):page124_i15:vss(34)"
				( attribute "PN" "BU18"
					( Origin gPackager )
				)
				( objectStatus "U7C1.BU18" )
			)
			( pin "@baseboard_fab2_lib.baseboard_fab2(sch_1):page124_i15:vss(35)"
				( attribute "PN" "BU15"
					( Origin gPackager )
				)
				( objectStatus "U7C1.BU15" )
			)
			( pin "@baseboard_fab2_lib.baseboard_fab2(sch_1):page124_i15:vss(36)"
				( attribute "PN" "BV49"
					( Origin gPackager )
				)
				( objectStatus "U7C1.BV49" )
			)
			( pin "@baseboard_fab2_lib.baseboard_fab2(sch_1):page124_i15:vss(37)"
				( attribute "PN" "BU11"
					( Origin gPackager )
				)
				( objectStatus "U7C1.BU11" )
			)
			( pin "@baseboard_fab2_lib.baseboard_fab2(sch_1):page124_i15:vss(38)"
				( attribute "PN" "BU13"
					( Origin gPackager )
				)
				( objectStatus "U7C1.BU13" )
			)
			( pin "@baseboard_fab2_lib.baseboard_fab2(sch_1):page124_i15:vss(39)"
				( attribute "PN" "BT66"
					( Origin gPackager )
				)
				( objectStatus "U7C1.BT66" )
			)
			( pin "@baseboard_fab2_lib.baseboard_fab2(sch_1):page124_i15:vss(40)"
				( attribute "PN" "BR6"
					( Origin gPackager )
				)
				( objectStatus "U7C1.BR6" )
			)
			( pin "@baseboard_fab2_lib.baseboard_fab2(sch_1):page124_i15:vss(41)"
				( attribute "PN" "BR58"
					( Origin gPackager )
				)
				( objectStatus "U7C1.BR58" )
			)
			( pin "@baseboard_fab2_lib.baseboard_fab2(sch_1):page124_i15:vss(42)"
				( attribute "PN" "BR54"
					( Origin gPackager )
				)
				( objectStatus "U7C1.BR54" )
			)
			( pin "@baseboard_fab2_lib.baseboard_fab2(sch_1):page124_i15:vss(43)"
				( attribute "PN" "BT8"
					( Origin gPackager )
				)
				( objectStatus "U7C1.BT8" )
			)
			( pin "@baseboard_fab2_lib.baseboard_fab2(sch_1):page124_i15:vss(44)"
				( attribute "PN" "BR50"
					( Origin gPackager )
				)
				( objectStatus "U7C1.BR50" )
			)
			( pin "@baseboard_fab2_lib.baseboard_fab2(sch_1):page124_i15:vss(45)"
				( attribute "PN" "BR20"
					( Origin gPackager )
				)
				( objectStatus "U7C1.BR20" )
			)
			( pin "@baseboard_fab2_lib.baseboard_fab2(sch_1):page124_i15:vss(46)"
				( attribute "PN" "BN66"
					( Origin gPackager )
				)
				( objectStatus "U7C1.BN66" )
			)
			( pin "@baseboard_fab2_lib.baseboard_fab2(sch_1):page124_i15:vss(47)"
				( attribute "PN" "BN52"
					( Origin gPackager )
				)
				( objectStatus "U7C1.BN52" )
			)
			( pin "@baseboard_fab2_lib.baseboard_fab2(sch_1):page124_i15:vss(48)"
				( attribute "PN" "BN5"
					( Origin gPackager )
				)
				( objectStatus "U7C1.BN5" )
			)
			( pin "@baseboard_fab2_lib.baseboard_fab2(sch_1):page124_i15:vss(49)"
				( attribute "PN" "BN59"
					( Origin gPackager )
				)
				( objectStatus "U7C1.BN59" )
			)
			( pin "@baseboard_fab2_lib.baseboard_fab2(sch_1):page124_i15:vss(50)"
				( attribute "PN" "BN22"
					( Origin gPackager )
				)
				( objectStatus "U7C1.BN22" )
			)
			( pin "@baseboard_fab2_lib.baseboard_fab2(sch_1):page124_i15:vss(51)"
				( attribute "PN" "BM9"
					( Origin gPackager )
				)
				( objectStatus "U7C1.BM9" )
			)
			( pin "@baseboard_fab2_lib.baseboard_fab2(sch_1):page124_i15:vss(52)"
				( attribute "PN" "BM71"
					( Origin gPackager )
				)
				( objectStatus "U7C1.BM71" )
			)
			( pin "@baseboard_fab2_lib.baseboard_fab2(sch_1):page124_i15:vss(53)"
				( attribute "PN" "BM69"
					( Origin gPackager )
				)
				( objectStatus "U7C1.BM69" )
			)
			( pin "@baseboard_fab2_lib.baseboard_fab2(sch_1):page124_i15:vss(54)"
				( attribute "PN" "BM58"
					( Origin gPackager )
				)
				( objectStatus "U7C1.BM58" )
			)
			( pin "@baseboard_fab2_lib.baseboard_fab2(sch_1):page124_i15:vss(55)"
				( attribute "PN" "BM50"
					( Origin gPackager )
				)
				( objectStatus "U7C1.BM50" )
			)
			( pin "@baseboard_fab2_lib.baseboard_fab2(sch_1):page124_i15:vss(56)"
				( attribute "PN" "BM46"
					( Origin gPackager )
				)
				( objectStatus "U7C1.BM46" )
			)
			( pin "@baseboard_fab2_lib.baseboard_fab2(sch_1):page124_i15:vss(57)"
				( attribute "PN" "BN37"
					( Origin gPackager )
				)
				( objectStatus "U7C1.BN37" )
			)
			( pin "@baseboard_fab2_lib.baseboard_fab2(sch_1):page124_i15:vss(58)"
				( attribute "PN" "BM17"
					( Origin gPackager )
				)
				( objectStatus "U7C1.BM17" )
			)
			( pin "@baseboard_fab2_lib.baseboard_fab2(sch_1):page124_i15:vss(59)"
				( attribute "PN" "BM13"
					( Origin gPackager )
				)
				( objectStatus "U7C1.BM13" )
			)
			( pin "@baseboard_fab2_lib.baseboard_fab2(sch_1):page124_i15:vss(60)"
				( attribute "PN" "BL72"
					( Origin gPackager )
				)
				( objectStatus "U7C1.BL72" )
			)
			( pin "@baseboard_fab2_lib.baseboard_fab2(sch_1):page124_i15:vss(61)"
				( attribute "PN" "BL70"
					( Origin gPackager )
				)
				( objectStatus "U7C1.BL70" )
			)
			( pin "@baseboard_fab2_lib.baseboard_fab2(sch_1):page124_i15:vss(62)"
				( attribute "PN" "BL63"
					( Origin gPackager )
				)
				( objectStatus "U7C1.BL63" )
			)
			( pin "@baseboard_fab2_lib.baseboard_fab2(sch_1):page124_i15:vss(63)"
				( attribute "PN" "BL5"
					( Origin gPackager )
				)
				( objectStatus "U7C1.BL5" )
			)
			( pin "@baseboard_fab2_lib.baseboard_fab2(sch_1):page124_i15:vss(64)"
				( attribute "PN" "BL37"
					( Origin gPackager )
				)
				( objectStatus "U7C1.BL37" )
			)
			( pin "@baseboard_fab2_lib.baseboard_fab2(sch_1):page124_i15:vss(65)"
				( attribute "PN" "BL68"
					( Origin gPackager )
				)
				( objectStatus "U7C1.BL68" )
			)
			( pin "@baseboard_fab2_lib.baseboard_fab2(sch_1):page124_i15:vss(66)"
				( attribute "PN" "BL40"
					( Origin gPackager )
				)
				( objectStatus "U7C1.BL40" )
			)
			( pin "@baseboard_fab2_lib.baseboard_fab2(sch_1):page124_i15:vss(67)"
				( attribute "PN" "BL22"
					( Origin gPackager )
				)
				( objectStatus "U7C1.BL22" )
			)
			( pin "@baseboard_fab2_lib.baseboard_fab2(sch_1):page124_i15:vss(68)"
				( attribute "PN" "BK50"
					( Origin gPackager )
				)
				( objectStatus "U7C1.BK50" )
			)
			( pin "@baseboard_fab2_lib.baseboard_fab2(sch_1):page124_i15:vss(69)"
				( attribute "PN" "BK42"
					( Origin gPackager )
				)
				( objectStatus "U7C1.BK42" )
			)
			( pin "@baseboard_fab2_lib.baseboard_fab2(sch_1):page124_i15:vss(70)"
				( attribute "PN" "BK38"
					( Origin gPackager )
				)
				( objectStatus "U7C1.BK38" )
			)
			( pin "@baseboard_fab2_lib.baseboard_fab2(sch_1):page124_i15:vss(71)"
				( attribute "PN" "BK35"
					( Origin gPackager )
				)
				( objectStatus "U7C1.BK35" )
			)
			( pin "@baseboard_fab2_lib.baseboard_fab2(sch_1):page124_i15:vss(72)"
				( attribute "PN" "BK31"
					( Origin gPackager )
				)
				( objectStatus "U7C1.BK31" )
			)
			( pin "@baseboard_fab2_lib.baseboard_fab2(sch_1):page124_i15:vss(73)"
				( attribute "PN" "BK27"
					( Origin gPackager )
				)
				( objectStatus "U7C1.BK27" )
			)
			( pin "@baseboard_fab2_lib.baseboard_fab2(sch_1):page124_i15:vss(74)"
				( attribute "PN" "BK24"
					( Origin gPackager )
				)
				( objectStatus "U7C1.BK24" )
			)
			( pin "@baseboard_fab2_lib.baseboard_fab2(sch_1):page124_i16:vss(75)"
				( attribute "PN" "BJ68"
					( Origin gPackager )
				)
				( objectStatus "U7C1.BJ68" )
			)
			( pin "@baseboard_fab2_lib.baseboard_fab2(sch_1):page124_i16:vss(76)"
				( attribute "PN" "BJ52"
					( Origin gPackager )
				)
				( objectStatus "U7C1.BJ52" )
			)
			( pin "@baseboard_fab2_lib.baseboard_fab2(sch_1):page124_i16:vss(77)"
				( attribute "PN" "BJ33"
					( Origin gPackager )
				)
				( objectStatus "U7C1.BJ33" )
			)
			( pin "@baseboard_fab2_lib.baseboard_fab2(sch_1):page124_i16:vss(78)"
				( attribute "PN" "BJ3"
					( Origin gPackager )
				)
				( objectStatus "U7C1.BJ3" )
			)
			( pin "@baseboard_fab2_lib.baseboard_fab2(sch_1):page124_i16:vss(79)"
				( attribute "PN" "BJ26"
					( Origin gPackager )
				)
				( objectStatus "U7C1.BJ26" )
			)
			( pin "@baseboard_fab2_lib.baseboard_fab2(sch_1):page124_i16:vss(80)"
				( attribute "PN" "BJ18"
					( Origin gPackager )
				)
				( objectStatus "U7C1.BJ18" )
			)
			( pin "@baseboard_fab2_lib.baseboard_fab2(sch_1):page124_i16:vss(81)"
				( attribute "PN" "BJ15"
					( Origin gPackager )
				)
				( objectStatus "U7C1.BJ15" )
			)
			( pin "@baseboard_fab2_lib.baseboard_fab2(sch_1):page124_i16:vss(82)"
				( attribute "PN" "BJ7"
					( Origin gPackager )
				)
				( objectStatus "U7C1.BJ7" )
			)
			( pin "@baseboard_fab2_lib.baseboard_fab2(sch_1):page124_i16:vss(83)"
				( attribute "PN" "BJ5"
					( Origin gPackager )
				)
				( objectStatus "U7C1.BJ5" )
			)
			( pin "@baseboard_fab2_lib.baseboard_fab2(sch_1):page124_i16:vss(84)"
				( attribute "PN" "BJ11"
					( Origin gPackager )
				)
				( objectStatus "U7C1.BJ11" )
			)
			( pin "@baseboard_fab2_lib.baseboard_fab2(sch_1):page124_i16:vss(85)"
				( attribute "PN" "BJ1"
					( Origin gPackager )
				)
				( objectStatus "U7C1.BJ1" )
			)
			( pin "@baseboard_fab2_lib.baseboard_fab2(sch_1):page124_i16:vss(86)"
				( attribute "PN" "BH54"
					( Origin gPackager )
				)
				( objectStatus "U7C1.BH54" )
			)
			( pin "@baseboard_fab2_lib.baseboard_fab2(sch_1):page124_i16:vss(87)"
				( attribute "PN" "BH46"
					( Origin gPackager )
				)
				( objectStatus "U7C1.BH46" )
			)
			( pin "@baseboard_fab2_lib.baseboard_fab2(sch_1):page124_i16:vss(88)"
				( attribute "PN" "BH42"
					( Origin gPackager )
				)
				( objectStatus "U7C1.BH42" )
			)
			( pin "@baseboard_fab2_lib.baseboard_fab2(sch_1):page124_i16:vss(89)"
				( attribute "PN" "BH38"
					( Origin gPackager )
				)
				( objectStatus "U7C1.BH38" )
			)
			( pin "@baseboard_fab2_lib.baseboard_fab2(sch_1):page124_i16:vss(90)"
				( attribute "PN" "BH27"
					( Origin gPackager )
				)
				( objectStatus "U7C1.BH27" )
			)
			( pin "@baseboard_fab2_lib.baseboard_fab2(sch_1):page124_i16:vss(91)"
				( attribute "PN" "BG63"
					( Origin gPackager )
				)
				( objectStatus "U7C1.BG63" )
			)
			( pin "@baseboard_fab2_lib.baseboard_fab2(sch_1):page124_i16:vss(92)"
				( attribute "PN" "BG59"
					( Origin gPackager )
				)
				( objectStatus "U7C1.BG59" )
			)
			( pin "@baseboard_fab2_lib.baseboard_fab2(sch_1):page124_i16:vss(93)"
				( attribute "PN" "BG48"
					( Origin gPackager )
				)
				( objectStatus "U7C1.BG48" )
			)
			( pin "@baseboard_fab2_lib.baseboard_fab2(sch_1):page124_i16:vss(94)"
				( attribute "PN" "BG33"
					( Origin gPackager )
				)
				( objectStatus "U7C1.BG33" )
			)
			( pin "@baseboard_fab2_lib.baseboard_fab2(sch_1):page124_i16:vss(95)"
				( attribute "PN" "BF9"
					( Origin gPackager )
				)
				( objectStatus "U7C1.BF9" )
			)
			( pin "@baseboard_fab2_lib.baseboard_fab2(sch_1):page124_i16:vss(96)"
				( attribute "PN" "BF68"
					( Origin gPackager )
				)
				( objectStatus "U7C1.BF68" )
			)
			( pin "@baseboard_fab2_lib.baseboard_fab2(sch_1):page124_i16:vss(97)"
				( attribute "PN" "BF65"
					( Origin gPackager )
				)
				( objectStatus "U7C1.BF65" )
			)
			( pin "@baseboard_fab2_lib.baseboard_fab2(sch_1):page124_i16:vss(98)"
				( attribute "PN" "BF61"
					( Origin gPackager )
				)
				( objectStatus "U7C1.BF61" )
			)
			( pin "@baseboard_fab2_lib.baseboard_fab2(sch_1):page124_i16:vss(99)"
				( attribute "PN" "BF58"
					( Origin gPackager )
				)
				( objectStatus "U7C1.BF58" )
			)
			( pin "@baseboard_fab2_lib.baseboard_fab2(sch_1):page124_i16:vss(100)"
				( attribute "PN" "BF50"
					( Origin gPackager )
				)
				( objectStatus "U7C1.BF50" )
			)
			( pin "@baseboard_fab2_lib.baseboard_fab2(sch_1):page124_i16:vss(101)"
				( attribute "PN" "BF5"
					( Origin gPackager )
				)
				( objectStatus "U7C1.BF5" )
			)
			( pin "@baseboard_fab2_lib.baseboard_fab2(sch_1):page124_i16:vss(102)"
				( attribute "PN" "BF42"
					( Origin gPackager )
				)
				( objectStatus "U7C1.BF42" )
			)
			( pin "@baseboard_fab2_lib.baseboard_fab2(sch_1):page124_i16:vss(103)"
				( attribute "PN" "BF38"
					( Origin gPackager )
				)
				( objectStatus "U7C1.BF38" )
			)
			( pin "@baseboard_fab2_lib.baseboard_fab2(sch_1):page124_i16:vss(104)"
				( attribute "PN" "BF27"
					( Origin gPackager )
				)
				( objectStatus "U7C1.BF27" )
			)
			( pin "@baseboard_fab2_lib.baseboard_fab2(sch_1):page124_i16:vss(105)"
				( attribute "PN" "BF24"
					( Origin gPackager )
				)
				( objectStatus "U7C1.BF24" )
			)
			( pin "@baseboard_fab2_lib.baseboard_fab2(sch_1):page124_i16:vss(106)"
				( attribute "PN" "BF20"
					( Origin gPackager )
				)
				( objectStatus "U7C1.BF20" )
			)
			( pin "@baseboard_fab2_lib.baseboard_fab2(sch_1):page124_i16:vss(107)"
				( attribute "PN" "BG44"
					( Origin gPackager )
				)
				( objectStatus "U7C1.BG44" )
			)
			( pin "@baseboard_fab2_lib.baseboard_fab2(sch_1):page124_i16:vss(108)"
				( attribute "PN" "BF54"
					( Origin gPackager )
				)
				( objectStatus "U7C1.BF54" )
			)
			( pin "@baseboard_fab2_lib.baseboard_fab2(sch_1):page124_i16:vss(109)"
				( attribute "PN" "BF17"
					( Origin gPackager )
				)
				( objectStatus "U7C1.BF17" )
			)
			( pin "@baseboard_fab2_lib.baseboard_fab2(sch_1):page124_i16:vss(110)"
				( attribute "PN" "BF13"
					( Origin gPackager )
				)
				( objectStatus "U7C1.BF13" )
			)
			( pin "@baseboard_fab2_lib.baseboard_fab2(sch_1):page124_i16:vss(111)"
				( attribute "PN" "BE66"
					( Origin gPackager )
				)
				( objectStatus "U7C1.BE66" )
			)
			( pin "@baseboard_fab2_lib.baseboard_fab2(sch_1):page124_i16:vss(112)"
				( attribute "PN" "BE63"
					( Origin gPackager )
				)
				( objectStatus "U7C1.BE63" )
			)
			( pin "@baseboard_fab2_lib.baseboard_fab2(sch_1):page124_i16:vss(113)"
				( attribute "PN" "BE59"
					( Origin gPackager )
				)
				( objectStatus "U7C1.BE59" )
			)
			( pin "@baseboard_fab2_lib.baseboard_fab2(sch_1):page124_i16:vss(114)"
				( attribute "PN" "BE56"
					( Origin gPackager )
				)
				( objectStatus "U7C1.BE56" )
			)
			( pin "@baseboard_fab2_lib.baseboard_fab2(sch_1):page124_i16:vss(115)"
				( attribute "PN" "BE37"
					( Origin gPackager )
				)
				( objectStatus "U7C1.BE37" )
			)
			( pin "@baseboard_fab2_lib.baseboard_fab2(sch_1):page124_i16:vss(116)"
				( attribute "PN" "BE33"
					( Origin gPackager )
				)
				( objectStatus "U7C1.BE33" )
			)
			( pin "@baseboard_fab2_lib.baseboard_fab2(sch_1):page124_i16:vss(117)"
				( attribute "PN" "BE29"
					( Origin gPackager )
				)
				( objectStatus "U7C1.BE29" )
			)
			( pin "@baseboard_fab2_lib.baseboard_fab2(sch_1):page124_i16:vss(118)"
				( attribute "PN" "BD68"
					( Origin gPackager )
				)
				( objectStatus "U7C1.BD68" )
			)
			( pin "@baseboard_fab2_lib.baseboard_fab2(sch_1):page124_i16:vss(119)"
				( attribute "PN" "BD54"
					( Origin gPackager )
				)
				( objectStatus "U7C1.BD54" )
			)
			( pin "@baseboard_fab2_lib.baseboard_fab2(sch_1):page124_i16:vss(120)"
				( attribute "PN" "BD50"
					( Origin gPackager )
				)
				( objectStatus "U7C1.BD50" )
			)
			( pin "@baseboard_fab2_lib.baseboard_fab2(sch_1):page124_i16:vss(121)"
				( attribute "PN" "BD5"
					( Origin gPackager )
				)
				( objectStatus "U7C1.BD5" )
			)
			( pin "@baseboard_fab2_lib.baseboard_fab2(sch_1):page124_i16:vss(122)"
				( attribute "PN" "BD35"
					( Origin gPackager )
				)
				( objectStatus "U7C1.BD35" )
			)
			( pin "@baseboard_fab2_lib.baseboard_fab2(sch_1):page124_i16:vss(123)"
				( attribute "PN" "BD31"
					( Origin gPackager )
				)
				( objectStatus "U7C1.BD31" )
			)
			( pin "@baseboard_fab2_lib.baseboard_fab2(sch_1):page124_i16:vss(124)"
				( attribute "PN" "BD27"
					( Origin gPackager )
				)
				( objectStatus "U7C1.BD27" )
			)
			( pin "@baseboard_fab2_lib.baseboard_fab2(sch_1):page124_i16:vss(125)"
				( attribute "PN" "BD24"
					( Origin gPackager )
				)
				( objectStatus "U7C1.BD24" )
			)
			( pin "@baseboard_fab2_lib.baseboard_fab2(sch_1):page124_i16:vss(126)"
				( attribute "PN" "BC71"
					( Origin gPackager )
				)
				( objectStatus "U7C1.BC71" )
			)
			( pin "@baseboard_fab2_lib.baseboard_fab2(sch_1):page124_i16:vss(127)"
				( attribute "PN" "BC69"
					( Origin gPackager )
				)
				( objectStatus "U7C1.BC69" )
			)
			( pin "@baseboard_fab2_lib.baseboard_fab2(sch_1):page124_i16:vss(128)"
				( attribute "PN" "BB72"
					( Origin gPackager )
				)
				( objectStatus "U7C1.BB72" )
			)
			( pin "@baseboard_fab2_lib.baseboard_fab2(sch_1):page124_i16:vss(129)"
				( attribute "PN" "BB70"
					( Origin gPackager )
				)
				( objectStatus "U7C1.BB70" )
			)
			( pin "@baseboard_fab2_lib.baseboard_fab2(sch_1):page124_i16:vss(130)"
				( attribute "PN" "BB68"
					( Origin gPackager )
				)
				( objectStatus "U7C1.BB68" )
			)
			( pin "@baseboard_fab2_lib.baseboard_fab2(sch_1):page124_i16:vss(131)"
				( attribute "PN" "BB66"
					( Origin gPackager )
				)
				( objectStatus "U7C1.BB66" )
			)
			( pin "@baseboard_fab2_lib.baseboard_fab2(sch_1):page124_i16:vss(132)"
				( attribute "PN" "BB59"
					( Origin gPackager )
				)
				( objectStatus "U7C1.BB59" )
			)
			( pin "@baseboard_fab2_lib.baseboard_fab2(sch_1):page124_i16:vss(133)"
				( attribute "PN" "BB44"
					( Origin gPackager )
				)
				( objectStatus "U7C1.BB44" )
			)
			( pin "@baseboard_fab2_lib.baseboard_fab2(sch_1):page124_i16:vss(134)"
				( attribute "PN" "BB22"
					( Origin gPackager )
				)
				( objectStatus "U7C1.BB22" )
			)
			( pin "@baseboard_fab2_lib.baseboard_fab2(sch_1):page124_i16:vss(135)"
				( attribute "PN" "BB18"
					( Origin gPackager )
				)
				( objectStatus "U7C1.BB18" )
			)
			( pin "@baseboard_fab2_lib.baseboard_fab2(sch_1):page124_i16:vss(136)"
				( attribute "PN" "BB15"
					( Origin gPackager )
				)
				( objectStatus "U7C1.BB15" )
			)
			( pin "@baseboard_fab2_lib.baseboard_fab2(sch_1):page124_i16:vss(137)"
				( attribute "PN" "BB11"
					( Origin gPackager )
				)
				( objectStatus "U7C1.BB11" )
			)
			( pin "@baseboard_fab2_lib.baseboard_fab2(sch_1):page124_i16:vss(138)"
				( attribute "PN" "BB7"
					( Origin gPackager )
				)
				( objectStatus "U7C1.BB7" )
			)
			( pin "@baseboard_fab2_lib.baseboard_fab2(sch_1):page124_i16:vss(139)"
				( attribute "PN" "BB5"
					( Origin gPackager )
				)
				( objectStatus "U7C1.BB5" )
			)
			( pin "@baseboard_fab2_lib.baseboard_fab2(sch_1):page124_i16:vss(140)"
				( attribute "PN" "BA58"
					( Origin gPackager )
				)
				( objectStatus "U7C1.BA58" )
			)
			( pin "@baseboard_fab2_lib.baseboard_fab2(sch_1):page124_i16:vss(141)"
				( attribute "PN" "BA54"
					( Origin gPackager )
				)
				( objectStatus "U7C1.BA54" )
			)
			( pin "@baseboard_fab2_lib.baseboard_fab2(sch_1):page124_i16:vss(142)"
				( attribute "PN" "BA50"
					( Origin gPackager )
				)
				( objectStatus "U7C1.BA50" )
			)
			( pin "@baseboard_fab2_lib.baseboard_fab2(sch_1):page124_i16:vss(143)"
				( attribute "PN" "AY68"
					( Origin gPackager )
				)
				( objectStatus "U7C1.AY68" )
			)
			( pin "@baseboard_fab2_lib.baseboard_fab2(sch_1):page124_i16:vss(144)"
				( attribute "PN" "AY63"
					( Origin gPackager )
				)
				( objectStatus "U7C1.AY63" )
			)
			( pin "@baseboard_fab2_lib.baseboard_fab2(sch_1):page124_i16:vss(145)"
				( attribute "PN" "AY56"
					( Origin gPackager )
				)
				( objectStatus "U7C1.AY56" )
			)
			( pin "@baseboard_fab2_lib.baseboard_fab2(sch_1):page124_i16:vss(146)"
				( attribute "PN" "AY22"
					( Origin gPackager )
				)
				( objectStatus "U7C1.AY22" )
			)
			( pin "@baseboard_fab2_lib.baseboard_fab2(sch_1):page124_i16:vss(147)"
				( attribute "PN" "AY5"
					( Origin gPackager )
				)
				( objectStatus "U7C1.AY5" )
			)
			( pin "@baseboard_fab2_lib.baseboard_fab2(sch_1):page124_i16:vss(148)"
				( attribute "PN" "AW61"
					( Origin gPackager )
				)
				( objectStatus "U7C1.AW61" )
			)
			( pin "@baseboard_fab2_lib.baseboard_fab2(sch_1):page124_i16:vss(149)"
				( attribute "PN" "AW58"
					( Origin gPackager )
				)
				( objectStatus "U7C1.AW58" )
			)
			( pin "@baseboard_fab2_lib.baseboard_fab2(sch_1):page124_i16:vss(150)"
				( attribute "PN" "AW50"
					( Origin gPackager )
				)
				( objectStatus "U7C1.AW50" )
			)
			( pin "@baseboard_fab2_lib.baseboard_fab2(sch_1):page124_i16:vss(151)"
				( attribute "PN" "AW46"
					( Origin gPackager )
				)
				( objectStatus "U7C1.AW46" )
			)
			( pin "@baseboard_fab2_lib.baseboard_fab2(sch_1):page124_i16:vss(152)"
				( attribute "PN" "AW41"
					( Origin gPackager )
				)
				( objectStatus "U7C1.AW41" )
			)
			( pin "@baseboard_fab2_lib.baseboard_fab2(sch_1):page124_i16:vss(153)"
				( attribute "PN" "AW39"
					( Origin gPackager )
				)
				( objectStatus "U7C1.AW39" )
			)
			( pin "@baseboard_fab2_lib.baseboard_fab2(sch_1):page124_i16:vss(154)"
				( attribute "PN" "AW37"
					( Origin gPackager )
				)
				( objectStatus "U7C1.AW37" )
			)
			( pin "@baseboard_fab2_lib.baseboard_fab2(sch_1):page124_i16:vss(155)"
				( attribute "PN" "AW36"
					( Origin gPackager )
				)
				( objectStatus "U7C1.AW36" )
			)
			( pin "@baseboard_fab2_lib.baseboard_fab2(sch_1):page124_i16:vss(156)"
				( attribute "PN" "AW34"
					( Origin gPackager )
				)
				( objectStatus "U7C1.AW34" )
			)
			( pin "@baseboard_fab2_lib.baseboard_fab2(sch_1):page124_i16:vss(157)"
				( attribute "PN" "AW32"
					( Origin gPackager )
				)
				( objectStatus "U7C1.AW32" )
			)
			( pin "@baseboard_fab2_lib.baseboard_fab2(sch_1):page124_i16:vss(158)"
				( attribute "PN" "AW30"
					( Origin gPackager )
				)
				( objectStatus "U7C1.AW30" )
			)
			( pin "@baseboard_fab2_lib.baseboard_fab2(sch_1):page124_i16:vss(159)"
				( attribute "PN" "AW26"
					( Origin gPackager )
				)
				( objectStatus "U7C1.AW26" )
			)
			( pin "@baseboard_fab2_lib.baseboard_fab2(sch_1):page124_i16:vss(160)"
				( attribute "PN" "AW17"
					( Origin gPackager )
				)
				( objectStatus "U7C1.AW17" )
			)
			( pin "@baseboard_fab2_lib.baseboard_fab2(sch_1):page124_i16:vss(161)"
				( attribute "PN" "AW13"
					( Origin gPackager )
				)
				( objectStatus "U7C1.AW13" )
			)
			( pin "@baseboard_fab2_lib.baseboard_fab2(sch_1):page124_i16:vss(162)"
				( attribute "PN" "AW9"
					( Origin gPackager )
				)
				( objectStatus "U7C1.AW9" )
			)
			( pin "@baseboard_fab2_lib.baseboard_fab2(sch_1):page124_i16:vss(163)"
				( attribute "PN" "AV68"
					( Origin gPackager )
				)
				( objectStatus "U7C1.AV68" )
			)
			( pin "@baseboard_fab2_lib.baseboard_fab2(sch_1):page124_i16:vss(164)"
				( attribute "PN" "AV59"
					( Origin gPackager )
				)
				( objectStatus "U7C1.AV59" )
			)
			( pin "@baseboard_fab2_lib.baseboard_fab2(sch_1):page124_i16:vss(165)"
				( attribute "PN" "AV22"
					( Origin gPackager )
				)
				( objectStatus "U7C1.AV22" )
			)
			( pin "@baseboard_fab2_lib.baseboard_fab2(sch_1):page124_i16:vss(166)"
				( attribute "PN" "AV5"
					( Origin gPackager )
				)
				( objectStatus "U7C1.AV5" )
			)
			( pin "@baseboard_fab2_lib.baseboard_fab2(sch_1):page124_i16:vss(167)"
				( attribute "PN" "AU61"
					( Origin gPackager )
				)
				( objectStatus "U7C1.AU61" )
			)
			( pin "@baseboard_fab2_lib.baseboard_fab2(sch_1):page124_i16:vss(168)"
				( attribute "PN" "AU54"
					( Origin gPackager )
				)
				( objectStatus "U7C1.AU54" )
			)
			( pin "@baseboard_fab2_lib.baseboard_fab2(sch_1):page124_i16:vss(169)"
				( attribute "PN" "AU50"
					( Origin gPackager )
				)
				( objectStatus "U7C1.AU50" )
			)
			( pin "@baseboard_fab2_lib.baseboard_fab2(sch_1):page124_i16:vss(170)"
				( attribute "PN" "AU46"
					( Origin gPackager )
				)
				( objectStatus "U7C1.AU46" )
			)
			( pin "@baseboard_fab2_lib.baseboard_fab2(sch_1):page124_i16:vss(171)"
				( attribute "PN" "AU41"
					( Origin gPackager )
				)
				( objectStatus "U7C1.AU41" )
			)
			( pin "@baseboard_fab2_lib.baseboard_fab2(sch_1):page124_i16:vss(172)"
				( attribute "PN" "AE22"
					( Origin gPackager )
				)
				( objectStatus "U7C1.AE22" )
			)
			( pin "@baseboard_fab2_lib.baseboard_fab2(sch_1):page124_i16:vss(173)"
				( attribute "PN" "AU30"
					( Origin gPackager )
				)
				( objectStatus "U7C1.AU30" )
			)
			( pin "@baseboard_fab2_lib.baseboard_fab2(sch_1):page124_i16:vss(174)"
				( attribute "PN" "AU26"
					( Origin gPackager )
				)
				( objectStatus "U7C1.AU26" )
			)
			( pin "@baseboard_fab2_lib.baseboard_fab2(sch_1):page124_i16:vss(175)"
				( attribute "PN" "AT59"
					( Origin gPackager )
				)
				( objectStatus "U7C1.AT59" )
			)
			( pin "@baseboard_fab2_lib.baseboard_fab2(sch_1):page124_i16:vss(176)"
				( attribute "PN" "AT46"
					( Origin gPackager )
				)
				( objectStatus "U7C1.AT46" )
			)
			( pin "@baseboard_fab2_lib.baseboard_fab2(sch_1):page124_i16:vss(177)"
				( attribute "PN" "AT41"
					( Origin gPackager )
				)
				( objectStatus "U7C1.AT41" )
			)
			( pin "@baseboard_fab2_lib.baseboard_fab2(sch_1):page124_i16:vss(178)"
				( attribute "PN" "AT30"
					( Origin gPackager )
				)
				( objectStatus "U7C1.AT30" )
			)
			( pin "@baseboard_fab2_lib.baseboard_fab2(sch_1):page124_i16:vss(179)"
				( attribute "PN" "AT26"
					( Origin gPackager )
				)
				( objectStatus "U7C1.AT26" )
			)
			( pin "@baseboard_fab2_lib.baseboard_fab2(sch_1):page124_i16:vss(180)"
				( attribute "PN" "AT22"
					( Origin gPackager )
				)
				( objectStatus "U7C1.AT22" )
			)
			( pin "@baseboard_fab2_lib.baseboard_fab2(sch_1):page124_i16:vss(181)"
				( attribute "PN" "AT18"
					( Origin gPackager )
				)
				( objectStatus "U7C1.AT18" )
			)
			( pin "@baseboard_fab2_lib.baseboard_fab2(sch_1):page124_i16:vss(182)"
				( attribute "PN" "AT15"
					( Origin gPackager )
				)
				( objectStatus "U7C1.AT15" )
			)
			( pin "@baseboard_fab2_lib.baseboard_fab2(sch_1):page124_i16:vss(183)"
				( attribute "PN" "AT11"
					( Origin gPackager )
				)
				( objectStatus "U7C1.AT11" )
			)
			( pin "@baseboard_fab2_lib.baseboard_fab2(sch_1):page124_i16:vss(184)"
				( attribute "PN" "AT7"
					( Origin gPackager )
				)
				( objectStatus "U7C1.AT7" )
			)
			( pin "@baseboard_fab2_lib.baseboard_fab2(sch_1):page124_i16:vss(185)"
				( attribute "PN" "AR72"
					( Origin gPackager )
				)
				( objectStatus "U7C1.AR72" )
			)
			( pin "@baseboard_fab2_lib.baseboard_fab2(sch_1):page124_i16:vss(186)"
				( attribute "PN" "AR70"
					( Origin gPackager )
				)
				( objectStatus "U7C1.AR70" )
			)
			( pin "@baseboard_fab2_lib.baseboard_fab2(sch_1):page124_i16:vss(187)"
				( attribute "PN" "AR68"
					( Origin gPackager )
				)
				( objectStatus "U7C1.AR68" )
			)
			( pin "@baseboard_fab2_lib.baseboard_fab2(sch_1):page124_i16:vss(188)"
				( attribute "PN" "AR65"
					( Origin gPackager )
				)
				( objectStatus "U7C1.AR65" )
			)
			( pin "@baseboard_fab2_lib.baseboard_fab2(sch_1):page124_i16:vss(189)"
				( attribute "PN" "AR58"
					( Origin gPackager )
				)
				( objectStatus "U7C1.AR58" )
			)
			( pin "@baseboard_fab2_lib.baseboard_fab2(sch_1):page124_i16:vss(190)"
				( attribute "PN" "AR50"
					( Origin gPackager )
				)
				( objectStatus "U7C1.AR50" )
			)
			( pin "@baseboard_fab2_lib.baseboard_fab2(sch_1):page124_i16:vss(191)"
				( attribute "PN" "AR5"
					( Origin gPackager )
				)
				( objectStatus "U7C1.AR5" )
			)
			( pin "@baseboard_fab2_lib.baseboard_fab2(sch_1):page124_i16:vss(192)"
				( attribute "PN" "AP66"
					( Origin gPackager )
				)
				( objectStatus "U7C1.AP66" )
			)
			( pin "@baseboard_fab2_lib.baseboard_fab2(sch_1):page124_i16:vss(193)"
				( attribute "PN" "AP52"
					( Origin gPackager )
				)
				( objectStatus "U7C1.AP52" )
			)
			( pin "@baseboard_fab2_lib.baseboard_fab2(sch_1):page124_i16:vss(194)"
				( attribute "PN" "AP46"
					( Origin gPackager )
				)
				( objectStatus "U7C1.AP46" )
			)
			( pin "@baseboard_fab2_lib.baseboard_fab2(sch_1):page124_i16:vss(195)"
				( attribute "PN" "AP41"
					( Origin gPackager )
				)
				( objectStatus "U7C1.AP41" )
			)
			( pin "@baseboard_fab2_lib.baseboard_fab2(sch_1):page124_i16:vss(196)"
				( attribute "PN" "AP4"
					( Origin gPackager )
				)
				( objectStatus "U7C1.AP4" )
			)
			( pin "@baseboard_fab2_lib.baseboard_fab2(sch_1):page124_i16:vss(197)"
				( attribute "PN" "AP30"
					( Origin gPackager )
				)
				( objectStatus "U7C1.AP30" )
			)
			( pin "@baseboard_fab2_lib.baseboard_fab2(sch_1):page124_i16:vss(198)"
				( attribute "PN" "AP26"
					( Origin gPackager )
				)
				( objectStatus "U7C1.AP26" )
			)
			( pin "@baseboard_fab2_lib.baseboard_fab2(sch_1):page124_i16:vss(199)"
				( attribute "PN" "AP2"
					( Origin gPackager )
				)
				( objectStatus "U7C1.AP2" )
			)
			( pin "@baseboard_fab2_lib.baseboard_fab2(sch_1):page124_i16:vss(200)"
				( attribute "PN" "AN9"
					( Origin gPackager )
				)
				( objectStatus "U7C1.AN9" )
			)
			( pin "@baseboard_fab2_lib.baseboard_fab2(sch_1):page124_i16:vss(201)"
				( attribute "PN" "AN58"
					( Origin gPackager )
				)
				( objectStatus "U7C1.AN58" )
			)
			( pin "@baseboard_fab2_lib.baseboard_fab2(sch_1):page124_i16:vss(202)"
				( attribute "PN" "AN5"
					( Origin gPackager )
				)
				( objectStatus "U7C1.AN5" )
			)
			( pin "@baseboard_fab2_lib.baseboard_fab2(sch_1):page124_i16:vss(203)"
				( attribute "PN" "AN20"
					( Origin gPackager )
				)
				( objectStatus "U7C1.AN20" )
			)
			( pin "@baseboard_fab2_lib.baseboard_fab2(sch_1):page124_i16:vss(204)"
				( attribute "PN" "AP22"
					( Origin gPackager )
				)
				( objectStatus "U7C1.AP22" )
			)
			( pin "@baseboard_fab2_lib.baseboard_fab2(sch_1):page124_i16:vss(205)"
				( attribute "PN" "AN68"
					( Origin gPackager )
				)
				( objectStatus "U7C1.AN68" )
			)
			( pin "@baseboard_fab2_lib.baseboard_fab2(sch_1):page124_i16:vss(206)"
				( attribute "PN" "AN17"
					( Origin gPackager )
				)
				( objectStatus "U7C1.AN17" )
			)
			( pin "@baseboard_fab2_lib.baseboard_fab2(sch_1):page124_i16:vss(207)"
				( attribute "PN" "AN13"
					( Origin gPackager )
				)
				( objectStatus "U7C1.AN13" )
			)
			( pin "@baseboard_fab2_lib.baseboard_fab2(sch_1):page124_i16:vss(208)"
				( attribute "PN" "AM46"
					( Origin gPackager )
				)
				( objectStatus "U7C1.AM46" )
			)
			( pin "@baseboard_fab2_lib.baseboard_fab2(sch_1):page124_i16:vss(209)"
				( attribute "PN" "AM41"
					( Origin gPackager )
				)
				( objectStatus "U7C1.AM41" )
			)
			( pin "@baseboard_fab2_lib.baseboard_fab2(sch_1):page124_i16:vss(210)"
				( attribute "PN" "AM30"
					( Origin gPackager )
				)
				( objectStatus "U7C1.AM30" )
			)
			( pin "@baseboard_fab2_lib.baseboard_fab2(sch_1):page124_i16:vss(211)"
				( attribute "PN" "AM26"
					( Origin gPackager )
				)
				( objectStatus "U7C1.AM26" )
			)
			( pin "@baseboard_fab2_lib.baseboard_fab2(sch_1):page124_i16:vss(212)"
				( attribute "PN" "AL72"
					( Origin gPackager )
				)
				( objectStatus "U7C1.AL72" )
			)
			( pin "@baseboard_fab2_lib.baseboard_fab2(sch_1):page124_i16:vss(213)"
				( attribute "PN" "AL70"
					( Origin gPackager )
				)
				( objectStatus "U7C1.AL70" )
			)
			( pin "@baseboard_fab2_lib.baseboard_fab2(sch_1):page124_i16:vss(214)"
				( attribute "PN" "AL68"
					( Origin gPackager )
				)
				( objectStatus "U7C1.AL68" )
			)
			( pin "@baseboard_fab2_lib.baseboard_fab2(sch_1):page124_i17:vss(215)"
				( attribute "PN" "AL59"
					( Origin gPackager )
				)
				( objectStatus "U7C1.AL59" )
			)
			( pin "@baseboard_fab2_lib.baseboard_fab2(sch_1):page124_i17:vss(216)"
				( attribute "PN" "AL52"
					( Origin gPackager )
				)
				( objectStatus "U7C1.AL52" )
			)
			( pin "@baseboard_fab2_lib.baseboard_fab2(sch_1):page124_i17:vss(217)"
				( attribute "PN" "AL5"
					( Origin gPackager )
				)
				( objectStatus "U7C1.AL5" )
			)
			( pin "@baseboard_fab2_lib.baseboard_fab2(sch_1):page124_i17:vss(218)"
				( attribute "PN" "AL22"
					( Origin gPackager )
				)
				( objectStatus "U7C1.AL22" )
			)
			( pin "@baseboard_fab2_lib.baseboard_fab2(sch_1):page124_i17:vss(219)"
				( attribute "PN" "AK71"
					( Origin gPackager )
				)
				( objectStatus "U7C1.AK71" )
			)
			( pin "@baseboard_fab2_lib.baseboard_fab2(sch_1):page124_i17:vss(220)"
				( attribute "PN" "AK69"
					( Origin gPackager )
				)
				( objectStatus "U7C1.AK69" )
			)
			( pin "@baseboard_fab2_lib.baseboard_fab2(sch_1):page124_i17:vss(221)"
				( attribute "PN" "AK61"
					( Origin gPackager )
				)
				( objectStatus "U7C1.AK61" )
			)
			( pin "@baseboard_fab2_lib.baseboard_fab2(sch_1):page124_i17:vss(222)"
				( attribute "PN" "AK58"
					( Origin gPackager )
				)
				( objectStatus "U7C1.AK58" )
			)
			( pin "@baseboard_fab2_lib.baseboard_fab2(sch_1):page124_i17:vss(223)"
				( attribute "PN" "AK48"
					( Origin gPackager )
				)
				( objectStatus "U7C1.AK48" )
			)
			( pin "@baseboard_fab2_lib.baseboard_fab2(sch_1):page124_i17:vss(224)"
				( attribute "PN" "AK46"
					( Origin gPackager )
				)
				( objectStatus "U7C1.AK46" )
			)
			( pin "@baseboard_fab2_lib.baseboard_fab2(sch_1):page124_i17:vss(225)"
				( attribute "PN" "AK41"
					( Origin gPackager )
				)
				( objectStatus "U7C1.AK41" )
			)
			( pin "@baseboard_fab2_lib.baseboard_fab2(sch_1):page124_i17:vss(226)"
				( attribute "PN" "AK26"
					( Origin gPackager )
				)
				( objectStatus "U7C1.AK26" )
			)
			( pin "@baseboard_fab2_lib.baseboard_fab2(sch_1):page124_i17:vss(227)"
				( attribute "PN" "AJ7"
					( Origin gPackager )
				)
				( objectStatus "U7C1.AJ7" )
			)
			( pin "@baseboard_fab2_lib.baseboard_fab2(sch_1):page124_i17:vss(228)"
				( attribute "PN" "AJ68"
					( Origin gPackager )
				)
				( objectStatus "U7C1.AJ68" )
			)
			( pin "@baseboard_fab2_lib.baseboard_fab2(sch_1):page124_i17:vss(229)"
				( attribute "PN" "AJ66"
					( Origin gPackager )
				)
				( objectStatus "U7C1.AJ66" )
			)
			( pin "@baseboard_fab2_lib.baseboard_fab2(sch_1):page124_i17:vss(230)"
				( attribute "PN" "AJ59"
					( Origin gPackager )
				)
				( objectStatus "U7C1.AJ59" )
			)
			( pin "@baseboard_fab2_lib.baseboard_fab2(sch_1):page124_i17:vss(231)"
				( attribute "PN" "AJ52"
					( Origin gPackager )
				)
				( objectStatus "U7C1.AJ52" )
			)
			( pin "@baseboard_fab2_lib.baseboard_fab2(sch_1):page124_i17:vss(232)"
				( attribute "PN" "AJ5"
					( Origin gPackager )
				)
				( objectStatus "U7C1.AJ5" )
			)
			( pin "@baseboard_fab2_lib.baseboard_fab2(sch_1):page124_i17:vss(233)"
				( attribute "PN" "AJ41"
					( Origin gPackager )
				)
				( objectStatus "U7C1.AJ41" )
			)
			( pin "@baseboard_fab2_lib.baseboard_fab2(sch_1):page124_i17:vss(234)"
				( attribute "PN" "AJ39"
					( Origin gPackager )
				)
				( objectStatus "U7C1.AJ39" )
			)
			( pin "@baseboard_fab2_lib.baseboard_fab2(sch_1):page124_i17:vss(235)"
				( attribute "PN" "AJ37"
					( Origin gPackager )
				)
				( objectStatus "U7C1.AJ37" )
			)
			( pin "@baseboard_fab2_lib.baseboard_fab2(sch_1):page124_i17:vss(236)"
				( attribute "PN" "AJ36"
					( Origin gPackager )
				)
				( objectStatus "U7C1.AJ36" )
			)
			( pin "@baseboard_fab2_lib.baseboard_fab2(sch_1):page124_i17:vss(237)"
				( attribute "PN" "AJ34"
					( Origin gPackager )
				)
				( objectStatus "U7C1.AJ34" )
			)
			( pin "@baseboard_fab2_lib.baseboard_fab2(sch_1):page124_i17:vss(238)"
				( attribute "PN" "AJ30"
					( Origin gPackager )
				)
				( objectStatus "U7C1.AJ30" )
			)
			( pin "@baseboard_fab2_lib.baseboard_fab2(sch_1):page124_i17:vss(239)"
				( attribute "PN" "AJ26"
					( Origin gPackager )
				)
				( objectStatus "U7C1.AJ26" )
			)
			( pin "@baseboard_fab2_lib.baseboard_fab2(sch_1):page124_i17:vss(240)"
				( attribute "PN" "AJ22"
					( Origin gPackager )
				)
				( objectStatus "U7C1.AJ22" )
			)
			( pin "@baseboard_fab2_lib.baseboard_fab2(sch_1):page124_i17:vss(241)"
				( attribute "PN" "AJ18"
					( Origin gPackager )
				)
				( objectStatus "U7C1.AJ18" )
			)
			( pin "@baseboard_fab2_lib.baseboard_fab2(sch_1):page124_i17:vss(242)"
				( attribute "PN" "AJ15"
					( Origin gPackager )
				)
				( objectStatus "U7C1.AJ15" )
			)
			( pin "@baseboard_fab2_lib.baseboard_fab2(sch_1):page124_i17:vss(243)"
				( attribute "PN" "AK30"
					( Origin gPackager )
				)
				( objectStatus "U7C1.AK30" )
			)
			( pin "@baseboard_fab2_lib.baseboard_fab2(sch_1):page124_i17:vss(244)"
				( attribute "PN" "AJ56"
					( Origin gPackager )
				)
				( objectStatus "U7C1.AJ56" )
			)
			( pin "@baseboard_fab2_lib.baseboard_fab2(sch_1):page124_i17:vss(245)"
				( attribute "PN" "AJ32"
					( Origin gPackager )
				)
				( objectStatus "U7C1.AJ32" )
			)
			( pin "@baseboard_fab2_lib.baseboard_fab2(sch_1):page124_i17:vss(246)"
				( attribute "PN" "AJ11"
					( Origin gPackager )
				)
				( objectStatus "U7C1.AJ11" )
			)
			( pin "@baseboard_fab2_lib.baseboard_fab2(sch_1):page124_i17:vss(247)"
				( attribute "PN" "AH20"
					( Origin gPackager )
				)
				( objectStatus "U7C1.AH20" )
			)
			( pin "@baseboard_fab2_lib.baseboard_fab2(sch_1):page124_i17:vss(248)"
				( attribute "PN" "AG66"
					( Origin gPackager )
				)
				( objectStatus "U7C1.AG66" )
			)
			( pin "@baseboard_fab2_lib.baseboard_fab2(sch_1):page124_i17:vss(249)"
				( attribute "PN" "AG59"
					( Origin gPackager )
				)
				( objectStatus "U7C1.AG59" )
			)
			( pin "@baseboard_fab2_lib.baseboard_fab2(sch_1):page124_i17:vss(250)"
				( attribute "PN" "AG56"
					( Origin gPackager )
				)
				( objectStatus "U7C1.AG56" )
			)
			( pin "@baseboard_fab2_lib.baseboard_fab2(sch_1):page124_i17:vss(251)"
				( attribute "PN" "AG52"
					( Origin gPackager )
				)
				( objectStatus "U7C1.AG52" )
			)
			( pin "@baseboard_fab2_lib.baseboard_fab2(sch_1):page124_i17:vss(252)"
				( attribute "PN" "AG43"
					( Origin gPackager )
				)
				( objectStatus "U7C1.AG43" )
			)
			( pin "@baseboard_fab2_lib.baseboard_fab2(sch_1):page124_i17:vss(253)"
				( attribute "PN" "AG41"
					( Origin gPackager )
				)
				( objectStatus "U7C1.AG41" )
			)
			( pin "@baseboard_fab2_lib.baseboard_fab2(sch_1):page124_i17:vss(254)"
				( attribute "PN" "AG30"
					( Origin gPackager )
				)
				( objectStatus "U7C1.AG30" )
			)
			( pin "@baseboard_fab2_lib.baseboard_fab2(sch_1):page124_i17:vss(255)"
				( attribute "PN" "AG26"
					( Origin gPackager )
				)
				( objectStatus "U7C1.AG26" )
			)
			( pin "@baseboard_fab2_lib.baseboard_fab2(sch_1):page124_i17:vss(256)"
				( attribute "PN" "AF68"
					( Origin gPackager )
				)
				( objectStatus "U7C1.AF68" )
			)
			( pin "@baseboard_fab2_lib.baseboard_fab2(sch_1):page124_i17:vss(257)"
				( attribute "PN" "AF3"
					( Origin gPackager )
				)
				( objectStatus "U7C1.AF3" )
			)
			( pin "@baseboard_fab2_lib.baseboard_fab2(sch_1):page124_i17:vss(258)"
				( attribute "PN" "AF24"
					( Origin gPackager )
				)
				( objectStatus "U7C1.AF24" )
			)
			( pin "@baseboard_fab2_lib.baseboard_fab2(sch_1):page124_i17:vss(259)"
				( attribute "PN" "AF17"
					( Origin gPackager )
				)
				( objectStatus "U7C1.AF17" )
			)
			( pin "@baseboard_fab2_lib.baseboard_fab2(sch_1):page124_i17:vss(260)"
				( attribute "PN" "AF9"
					( Origin gPackager )
				)
				( objectStatus "U7C1.AF9" )
			)
			( pin "@baseboard_fab2_lib.baseboard_fab2(sch_1):page124_i17:vss(261)"
				( attribute "PN" "AF5"
					( Origin gPackager )
				)
				( objectStatus "U7C1.AF5" )
			)
			( pin "@baseboard_fab2_lib.baseboard_fab2(sch_1):page124_i17:vss(262)"
				( attribute "PN" "AF13"
					( Origin gPackager )
				)
				( objectStatus "U7C1.AF13" )
			)
			( pin "@baseboard_fab2_lib.baseboard_fab2(sch_1):page124_i17:vss(263)"
				( attribute "PN" "AF1"
					( Origin gPackager )
				)
				( objectStatus "U7C1.AF1" )
			)
			( pin "@baseboard_fab2_lib.baseboard_fab2(sch_1):page124_i17:vss(264)"
				( attribute "PN" "AE66"
					( Origin gPackager )
				)
				( objectStatus "U7C1.AE66" )
			)
			( pin "@baseboard_fab2_lib.baseboard_fab2(sch_1):page124_i17:vss(265)"
				( attribute "PN" "AE63"
					( Origin gPackager )
				)
				( objectStatus "U7C1.AE63" )
			)
			( pin "@baseboard_fab2_lib.baseboard_fab2(sch_1):page124_i17:vss(266)"
				( attribute "PN" "AE59"
					( Origin gPackager )
				)
				( objectStatus "U7C1.AE59" )
			)
			( pin "@baseboard_fab2_lib.baseboard_fab2(sch_1):page124_i17:vss(267)"
				( attribute "PN" "AE56"
					( Origin gPackager )
				)
				( objectStatus "U7C1.AE56" )
			)
			( pin "@baseboard_fab2_lib.baseboard_fab2(sch_1):page124_i17:vss(268)"
				( attribute "PN" "AE52"
					( Origin gPackager )
				)
				( objectStatus "U7C1.AE52" )
			)
			( pin "@baseboard_fab2_lib.baseboard_fab2(sch_1):page124_i17:vss(269)"
				( attribute "PN" "AE48"
					( Origin gPackager )
				)
				( objectStatus "U7C1.AE48" )
			)
			( pin "@baseboard_fab2_lib.baseboard_fab2(sch_1):page124_i17:vss(270)"
				( attribute "PN" "J18"
					( Origin gPackager )
				)
				( objectStatus "U7C1.J18" )
			)
			( pin "@baseboard_fab2_lib.baseboard_fab2(sch_1):page124_i17:vss(271)"
				( attribute "PN" "AE29"
					( Origin gPackager )
				)
				( objectStatus "U7C1.AE29" )
			)
			( pin "@baseboard_fab2_lib.baseboard_fab2(sch_1):page124_i17:vss(272)"
				( attribute "PN" "AD68"
					( Origin gPackager )
				)
				( objectStatus "U7C1.AD68" )
			)
			( pin "@baseboard_fab2_lib.baseboard_fab2(sch_1):page124_i17:vss(273)"
				( attribute "PN" "AD65"
					( Origin gPackager )
				)
				( objectStatus "U7C1.AD65" )
			)
			( pin "@baseboard_fab2_lib.baseboard_fab2(sch_1):page124_i17:vss(274)"
				( attribute "PN" "AD5"
					( Origin gPackager )
				)
				( objectStatus "U7C1.AD5" )
			)
			( pin "@baseboard_fab2_lib.baseboard_fab2(sch_1):page124_i17:vss(275)"
				( attribute "PN" "AC7"
					( Origin gPackager )
				)
				( objectStatus "U7C1.AC7" )
			)
			( pin "@baseboard_fab2_lib.baseboard_fab2(sch_1):page124_i17:vss(276)"
				( attribute "PN" "AC66"
					( Origin gPackager )
				)
				( objectStatus "U7C1.AC66" )
			)
			( pin "@baseboard_fab2_lib.baseboard_fab2(sch_1):page124_i17:vss(277)"
				( attribute "PN" "AC63"
					( Origin gPackager )
				)
				( objectStatus "U7C1.AC63" )
			)
			( pin "@baseboard_fab2_lib.baseboard_fab2(sch_1):page124_i17:vss(278)"
				( attribute "PN" "AC59"
					( Origin gPackager )
				)
				( objectStatus "U7C1.AC59" )
			)
			( pin "@baseboard_fab2_lib.baseboard_fab2(sch_1):page124_i17:vss(279)"
				( attribute "PN" "AC52"
					( Origin gPackager )
				)
				( objectStatus "U7C1.AC52" )
			)
			( pin "@baseboard_fab2_lib.baseboard_fab2(sch_1):page124_i17:vss(280)"
				( attribute "PN" "AC48"
					( Origin gPackager )
				)
				( objectStatus "U7C1.AC48" )
			)
			( pin "@baseboard_fab2_lib.baseboard_fab2(sch_1):page124_i17:vss(281)"
				( attribute "PN" "AC46"
					( Origin gPackager )
				)
				( objectStatus "U7C1.AC46" )
			)
			( pin "@baseboard_fab2_lib.baseboard_fab2(sch_1):page124_i17:vss(282)"
				( attribute "PN" "AC43"
					( Origin gPackager )
				)
				( objectStatus "U7C1.AC43" )
			)
			( pin "@baseboard_fab2_lib.baseboard_fab2(sch_1):page124_i17:vss(283)"
				( attribute "PN" "AC27"
					( Origin gPackager )
				)
				( objectStatus "U7C1.AC27" )
			)
			( pin "@baseboard_fab2_lib.baseboard_fab2(sch_1):page124_i17:vss(284)"
				( attribute "PN" "AD58"
					( Origin gPackager )
				)
				( objectStatus "U7C1.AD58" )
			)
			( pin "@baseboard_fab2_lib.baseboard_fab2(sch_1):page124_i17:vss(285)"
				( attribute "PN" "AC45"
					( Origin gPackager )
				)
				( objectStatus "U7C1.AC45" )
			)
			( pin "@baseboard_fab2_lib.baseboard_fab2(sch_1):page124_i17:vss(286)"
				( attribute "PN" "AC22"
					( Origin gPackager )
				)
				( objectStatus "U7C1.AC22" )
			)
			( pin "@baseboard_fab2_lib.baseboard_fab2(sch_1):page124_i17:vss(287)"
				( attribute "PN" "AC18"
					( Origin gPackager )
				)
				( objectStatus "U7C1.AC18" )
			)
			( pin "@baseboard_fab2_lib.baseboard_fab2(sch_1):page124_i17:vss(288)"
				( attribute "PN" "AC15"
					( Origin gPackager )
				)
				( objectStatus "U7C1.AC15" )
			)
			( pin "@baseboard_fab2_lib.baseboard_fab2(sch_1):page124_i17:vss(289)"
				( attribute "PN" "AC11"
					( Origin gPackager )
				)
				( objectStatus "U7C1.AC11" )
			)
			( pin "@baseboard_fab2_lib.baseboard_fab2(sch_1):page124_i17:vss(290)"
				( attribute "PN" "AB72"
					( Origin gPackager )
				)
				( objectStatus "U7C1.AB72" )
			)
			( pin "@baseboard_fab2_lib.baseboard_fab2(sch_1):page124_i17:vss(291)"
				( attribute "PN" "AB70"
					( Origin gPackager )
				)
				( objectStatus "U7C1.AB70" )
			)
			( pin "@baseboard_fab2_lib.baseboard_fab2(sch_1):page124_i17:vss(292)"
				( attribute "PN" "AB68"
					( Origin gPackager )
				)
				( objectStatus "U7C1.AB68" )
			)
			( pin "@baseboard_fab2_lib.baseboard_fab2(sch_1):page124_i17:vss(293)"
				( attribute "PN" "AB5"
					( Origin gPackager )
				)
				( objectStatus "U7C1.AB5" )
			)
			( pin "@baseboard_fab2_lib.baseboard_fab2(sch_1):page124_i17:vss(294)"
				( attribute "PN" "AA48"
					( Origin gPackager )
				)
				( objectStatus "U7C1.AA48" )
			)
			( pin "@baseboard_fab2_lib.baseboard_fab2(sch_1):page124_i17:vss(295)"
				( attribute "PN" "AA43"
					( Origin gPackager )
				)
				( objectStatus "U7C1.AA43" )
			)
			( pin "@baseboard_fab2_lib.baseboard_fab2(sch_1):page124_i17:vss(296)"
				( attribute "PN" "AA27"
					( Origin gPackager )
				)
				( objectStatus "U7C1.AA27" )
			)
			( pin "@baseboard_fab2_lib.baseboard_fab2(sch_1):page124_i17:vss(297)"
				( attribute "PN" "AA26"
					( Origin gPackager )
				)
				( objectStatus "U7C1.AA26" )
			)
			( pin "@baseboard_fab2_lib.baseboard_fab2(sch_1):page124_i17:vss(298)"
				( attribute "PN" "Y68"
					( Origin gPackager )
				)
				( objectStatus "U7C1.Y68" )
			)
			( pin "@baseboard_fab2_lib.baseboard_fab2(sch_1):page124_i17:vss(299)"
				( attribute "PN" "Y63"
					( Origin gPackager )
				)
				( objectStatus "U7C1.Y63" )
			)
			( pin "@baseboard_fab2_lib.baseboard_fab2(sch_1):page124_i17:vss(300)"
				( attribute "PN" "Y59"
					( Origin gPackager )
				)
				( objectStatus "U7C1.Y59" )
			)
			( pin "@baseboard_fab2_lib.baseboard_fab2(sch_1):page124_i17:vss(301)"
				( attribute "PN" "Y52"
					( Origin gPackager )
				)
				( objectStatus "U7C1.Y52" )
			)
			( pin "@baseboard_fab2_lib.baseboard_fab2(sch_1):page124_i17:vss(302)"
				( attribute "PN" "Y5"
					( Origin gPackager )
				)
				( objectStatus "U7C1.Y5" )
			)
			( pin "@baseboard_fab2_lib.baseboard_fab2(sch_1):page124_i17:vss(303)"
				( attribute "PN" "Y48"
					( Origin gPackager )
				)
				( objectStatus "U7C1.Y48" )
			)
			( pin "@baseboard_fab2_lib.baseboard_fab2(sch_1):page124_i17:vss(304)"
				( attribute "PN" "Y27"
					( Origin gPackager )
				)
				( objectStatus "U7C1.Y27" )
			)
			( pin "@baseboard_fab2_lib.baseboard_fab2(sch_1):page124_i17:vss(305)"
				( attribute "PN" "Y22"
					( Origin gPackager )
				)
				( objectStatus "U7C1.Y22" )
			)
			( pin "@baseboard_fab2_lib.baseboard_fab2(sch_1):page124_i17:vss(306)"
				( attribute "PN" "W9"
					( Origin gPackager )
				)
				( objectStatus "U7C1.W9" )
			)
			( pin "@baseboard_fab2_lib.baseboard_fab2(sch_1):page124_i17:vss(307)"
				( attribute "PN" "W61"
					( Origin gPackager )
				)
				( objectStatus "U7C1.W61" )
			)
			( pin "@baseboard_fab2_lib.baseboard_fab2(sch_1):page124_i17:vss(308)"
				( attribute "PN" "Y43"
					( Origin gPackager )
				)
				( objectStatus "U7C1.Y43" )
			)
			( pin "@baseboard_fab2_lib.baseboard_fab2(sch_1):page124_i17:vss(309)"
				( attribute "PN" "AA50"
					( Origin gPackager )
				)
				( objectStatus "U7C1.AA50" )
			)
			( pin "@baseboard_fab2_lib.baseboard_fab2(sch_1):page124_i17:vss(310)"
				( attribute "PN" "W24"
					( Origin gPackager )
				)
				( objectStatus "U7C1.W24" )
			)
			( pin "@baseboard_fab2_lib.baseboard_fab2(sch_1):page124_i17:vss(311)"
				( attribute "PN" "W20"
					( Origin gPackager )
				)
				( objectStatus "U7C1.W20" )
			)
			( pin "@baseboard_fab2_lib.baseboard_fab2(sch_1):page124_i17:vss(312)"
				( attribute "PN" "W17"
					( Origin gPackager )
				)
				( objectStatus "U7C1.W17" )
			)
			( pin "@baseboard_fab2_lib.baseboard_fab2(sch_1):page124_i17:vss(313)"
				( attribute "PN" "W13"
					( Origin gPackager )
				)
				( objectStatus "U7C1.W13" )
			)
			( pin "@baseboard_fab2_lib.baseboard_fab2(sch_1):page124_i17:vss(314)"
				( attribute "PN" "V68"
					( Origin gPackager )
				)
				( objectStatus "U7C1.V68" )
			)
			( pin "@baseboard_fab2_lib.baseboard_fab2(sch_1):page124_i17:vss(315)"
				( attribute "PN" "V66"
					( Origin gPackager )
				)
				( objectStatus "U7C1.V66" )
			)
			( pin "@baseboard_fab2_lib.baseboard_fab2(sch_1):page124_i17:vss(316)"
				( attribute "PN" "W58"
					( Origin gPackager )
				)
				( objectStatus "U7C1.W58" )
			)
			( pin "@baseboard_fab2_lib.baseboard_fab2(sch_1):page124_i17:vss(317)"
				( attribute "PN" "V52"
					( Origin gPackager )
				)
				( objectStatus "U7C1.V52" )
			)
			( pin "@baseboard_fab2_lib.baseboard_fab2(sch_1):page124_i17:vss(318)"
				( attribute "PN" "V5"
					( Origin gPackager )
				)
				( objectStatus "U7C1.V5" )
			)
			( pin "@baseboard_fab2_lib.baseboard_fab2(sch_1):page124_i17:vss(319)"
				( attribute "PN" "V48"
					( Origin gPackager )
				)
				( objectStatus "U7C1.V48" )
			)
			( pin "@baseboard_fab2_lib.baseboard_fab2(sch_1):page124_i17:vss(320)"
				( attribute "PN" "V26"
					( Origin gPackager )
				)
				( objectStatus "U7C1.V26" )
			)
			( pin "@baseboard_fab2_lib.baseboard_fab2(sch_1):page124_i17:vss(321)"
				( attribute "PN" "U58"
					( Origin gPackager )
				)
				( objectStatus "U7C1.U58" )
			)
			( pin "@baseboard_fab2_lib.baseboard_fab2(sch_1):page124_i17:vss(322)"
				( attribute "PN" "AG46"
					( Origin gPackager )
				)
				( objectStatus "U7C1.AG46" )
			)
			( pin "@baseboard_fab2_lib.baseboard_fab2(sch_1):page124_i17:vss(323)"
				( attribute "PN" "AF50"
					( Origin gPackager )
				)
				( objectStatus "U7C1.AF50" )
			)
			( pin "@baseboard_fab2_lib.baseboard_fab2(sch_1):page124_i17:vss(324)"
				( attribute "PN" "T7"
					( Origin gPackager )
				)
				( objectStatus "U7C1.T7" )
			)
			( pin "@baseboard_fab2_lib.baseboard_fab2(sch_1):page124_i17:vss(325)"
				( attribute "PN" "T66"
					( Origin gPackager )
				)
				( objectStatus "U7C1.T66" )
			)
			( pin "@baseboard_fab2_lib.baseboard_fab2(sch_1):page124_i17:vss(326)"
				( attribute "PN" "T52"
					( Origin gPackager )
				)
				( objectStatus "U7C1.T52" )
			)
			( pin "@baseboard_fab2_lib.baseboard_fab2(sch_1):page124_i17:vss(327)"
				( attribute "PN" "T48"
					( Origin gPackager )
				)
				( objectStatus "U7C1.T48" )
			)
			( pin "@baseboard_fab2_lib.baseboard_fab2(sch_1):page124_i17:vss(328)"
				( attribute "PN" "AJ45"
					( Origin gPackager )
				)
				( objectStatus "U7C1.AJ45" )
			)
			( pin "@baseboard_fab2_lib.baseboard_fab2(sch_1):page124_i17:vss(329)"
				( attribute "PN" "T40"
					( Origin gPackager )
				)
				( objectStatus "U7C1.T40" )
			)
			( pin "@baseboard_fab2_lib.baseboard_fab2(sch_1):page124_i17:vss(330)"
				( attribute "PN" "T37"
					( Origin gPackager )
				)
				( objectStatus "U7C1.T37" )
			)
			( pin "@baseboard_fab2_lib.baseboard_fab2(sch_1):page124_i17:vss(331)"
				( attribute "PN" "T33"
					( Origin gPackager )
				)
				( objectStatus "U7C1.T33" )
			)
			( pin "@baseboard_fab2_lib.baseboard_fab2(sch_1):page124_i17:vss(332)"
				( attribute "PN" "T29"
					( Origin gPackager )
				)
				( objectStatus "U7C1.T29" )
			)
			( pin "@baseboard_fab2_lib.baseboard_fab2(sch_1):page124_i17:vss(333)"
				( attribute "PN" "T26"
					( Origin gPackager )
				)
				( objectStatus "U7C1.T26" )
			)
			( pin "@baseboard_fab2_lib.baseboard_fab2(sch_1):page124_i17:vss(334)"
				( attribute "PN" "T22"
					( Origin gPackager )
				)
				( objectStatus "U7C1.T22" )
			)
			( pin "@baseboard_fab2_lib.baseboard_fab2(sch_1):page124_i17:vss(335)"
				( attribute "PN" "T18"
					( Origin gPackager )
				)
				( objectStatus "U7C1.T18" )
			)
			( pin "@baseboard_fab2_lib.baseboard_fab2(sch_1):page124_i17:vss(336)"
				( attribute "PN" "T15"
					( Origin gPackager )
				)
				( objectStatus "U7C1.T15" )
			)
			( pin "@baseboard_fab2_lib.baseboard_fab2(sch_1):page124_i17:vss(337)"
				( attribute "PN" "T11"
					( Origin gPackager )
				)
				( objectStatus "U7C1.T11" )
			)
			( pin "@baseboard_fab2_lib.baseboard_fab2(sch_1):page124_i17:vss(338)"
				( attribute "PN" "R68"
					( Origin gPackager )
				)
				( objectStatus "U7C1.R68" )
			)
			( pin "@baseboard_fab2_lib.baseboard_fab2(sch_1):page124_i17:vss(339)"
				( attribute "PN" "R58"
					( Origin gPackager )
				)
				( objectStatus "U7C1.R58" )
			)
			( pin "@baseboard_fab2_lib.baseboard_fab2(sch_1):page124_i17:vss(340)"
				( attribute "PN" "T56"
					( Origin gPackager )
				)
				( objectStatus "U7C1.T56" )
			)
			( pin "@baseboard_fab2_lib.baseboard_fab2(sch_1):page124_i17:vss(341)"
				( attribute "PN" "R54"
					( Origin gPackager )
				)
				( objectStatus "U7C1.R54" )
			)
			( pin "@baseboard_fab2_lib.baseboard_fab2(sch_1):page124_i17:vss(342)"
				( attribute "PN" "R50"
					( Origin gPackager )
				)
				( objectStatus "U7C1.R50" )
			)
			( pin "@baseboard_fab2_lib.baseboard_fab2(sch_1):page124_i17:vss(343)"
				( attribute "PN" "R5"
					( Origin gPackager )
				)
				( objectStatus "U7C1.R5" )
			)
			( pin "@baseboard_fab2_lib.baseboard_fab2(sch_1):page124_i17:vss(344)"
				( attribute "PN" "U42"
					( Origin gPackager )
				)
				( objectStatus "U7C1.U42" )
			)
			( pin "@baseboard_fab2_lib.baseboard_fab2(sch_1):page124_i17:vss(345)"
				( attribute "PN" "R27"
					( Origin gPackager )
				)
				( objectStatus "U7C1.R27" )
			)
			( pin "@baseboard_fab2_lib.baseboard_fab2(sch_1):page124_i17:vss(346)"
				( attribute "PN" "P63"
					( Origin gPackager )
				)
				( objectStatus "U7C1.P63" )
			)
			( pin "@baseboard_fab2_lib.baseboard_fab2(sch_1):page124_i17:vss(347)"
				( attribute "PN" "AE43"
					( Origin gPackager )
				)
				( objectStatus "U7C1.AE43" )
			)
			( pin "@baseboard_fab2_lib.baseboard_fab2(sch_1):page124_i17:vss(348)"
				( attribute "PN" "N9"
					( Origin gPackager )
				)
				( objectStatus "U7C1.N9" )
			)
			( pin "@baseboard_fab2_lib.baseboard_fab2(sch_1):page124_i17:vss(349)"
				( attribute "PN" "N68"
					( Origin gPackager )
				)
				( objectStatus "U7C1.N68" )
			)
			( pin "@baseboard_fab2_lib.baseboard_fab2(sch_1):page124_i17:vss(350)"
				( attribute "PN" "R38"
					( Origin gPackager )
				)
				( objectStatus "U7C1.R38" )
			)
			( pin "@baseboard_fab2_lib.baseboard_fab2(sch_1):page124_i17:vss(351)"
				( attribute "PN" "N5"
					( Origin gPackager )
				)
				( objectStatus "U7C1.N5" )
			)
			( pin "@baseboard_fab2_lib.baseboard_fab2(sch_1):page124_i17:vss(352)"
				( attribute "PN" "N46"
					( Origin gPackager )
				)
				( objectStatus "U7C1.N46" )
			)
			( pin "@baseboard_fab2_lib.baseboard_fab2(sch_1):page124_i17:vss(353)"
				( attribute "PN" "N38"
					( Origin gPackager )
				)
				( objectStatus "U7C1.N38" )
			)
			( pin "@baseboard_fab2_lib.baseboard_fab2(sch_1):page124_i17:vss(354)"
				( attribute "PN" "N35"
					( Origin gPackager )
				)
				( objectStatus "U7C1.N35" )
			)
			( pin "@baseboard_fab2_lib.baseboard_fab2(sch_1):page125_i11:a"
				( attribute "PN" "1"
					( Origin gPackager )
				)
				( objectStatus "R2R11.1" )
			)
			( pin "@baseboard_fab2_lib.baseboard_fab2(sch_1):page125_i11:b"
				( attribute "PN" "2"
					( Origin gPackager )
				)
				( objectStatus "R2R11.2" )
			)
			( pin "@baseboard_fab2_lib.baseboard_fab2(sch_1):page125_i21:a"
				( attribute "PN" "1"
					( Origin gPackager )
				)
				( objectStatus "R8E6.1" )
			)
			( pin "@baseboard_fab2_lib.baseboard_fab2(sch_1):page125_i21:b"
				( attribute "PN" "2"
					( Origin gPackager )
				)
				( objectStatus "R8E6.2" )
			)
			( pin "@baseboard_fab2_lib.baseboard_fab2(sch_1):page125_i24:a"
				( attribute "PN" "1"
					( Origin gPackager )
				)
				( objectStatus "R8E4.1" )
			)
			( pin "@baseboard_fab2_lib.baseboard_fab2(sch_1):page125_i24:b"
				( attribute "PN" "2"
					( Origin gPackager )
				)
				( objectStatus "R8E4.2" )
			)
			( pin "@baseboard_fab2_lib.baseboard_fab2(sch_1):page125_i40:a"
				( attribute "PN" "1"
					( Origin gPackager )
				)
				( objectStatus "R8C18.1" )
			)
			( pin "@baseboard_fab2_lib.baseboard_fab2(sch_1):page125_i40:b"
				( attribute "PN" "2"
					( Origin gPackager )
				)
				( objectStatus "R8C18.2" )
			)
			( pin "@baseboard_fab2_lib.baseboard_fab2(sch_1):page125_i41:a"
				( attribute "PN" "1"
					( Origin gPackager )
				)
				( objectStatus "R8C17.1" )
			)
			( pin "@baseboard_fab2_lib.baseboard_fab2(sch_1):page125_i41:b"
				( attribute "PN" "2"
					( Origin gPackager )
				)
				( objectStatus "R8C17.2" )
			)
			( pin "@baseboard_fab2_lib.baseboard_fab2(sch_1):page125_i50:a"
				( attribute "PN" "1"
					( Origin gPackager )
				)
				( objectStatus "R8D5.1" )
			)
			( pin "@baseboard_fab2_lib.baseboard_fab2(sch_1):page125_i50:b"
				( attribute "PN" "2"
					( Origin gPackager )
				)
				( objectStatus "R8D5.2" )
			)
			( pin "@baseboard_fab2_lib.baseboard_fab2(sch_1):page125_i60:a"
				( attribute "PN" "1"
					( Origin gPackager )
				)
				( objectStatus "R7D13.1" )
			)
			( pin "@baseboard_fab2_lib.baseboard_fab2(sch_1):page125_i60:b"
				( attribute "PN" "2"
					( Origin gPackager )
				)
				( objectStatus "R7D13.2" )
			)
			( pin "@baseboard_fab2_lib.baseboard_fab2(sch_1):page145_i160:a"
				( attribute "PN" "1"
					( Origin gPackager )
				)
				( objectStatus "R25W141.1" )
			)
			( pin "@baseboard_fab2_lib.baseboard_fab2(sch_1):page145_i160:b"
				( attribute "PN" "2"
					( Origin gPackager )
				)
				( objectStatus "R25W141.2" )
			)
			( pin "@baseboard_fab2_lib.baseboard_fab2(sch_1):page125_i72:a"
				( attribute "PN" "1"
					( Origin gPackager )
				)
				( objectStatus "R3N2.1" )
			)
			( pin "@baseboard_fab2_lib.baseboard_fab2(sch_1):page125_i72:b"
				( attribute "PN" "2"
					( Origin gPackager )
				)
				( objectStatus "R3N2.2" )
			)
			( pin "@baseboard_fab2_lib.baseboard_fab2(sch_1):page125_i78:a"
				( attribute "PN" "1"
					( Origin gPackager )
				)
				( objectStatus "R3N17.1" )
			)
			( pin "@baseboard_fab2_lib.baseboard_fab2(sch_1):page125_i78:b"
				( attribute "PN" "2"
					( Origin gPackager )
				)
				( objectStatus "R3N17.2" )
			)
			( pin "@baseboard_fab2_lib.baseboard_fab2(sch_1):page125_i83:a"
				( attribute "PN" "1"
					( Origin gPackager )
				)
				( objectStatus "R2N14.1" )
			)
			( pin "@baseboard_fab2_lib.baseboard_fab2(sch_1):page125_i83:b"
				( attribute "PN" "2"
					( Origin gPackager )
				)
				( objectStatus "R2N14.2" )
			)
			( pin "@baseboard_fab2_lib.baseboard_fab2(sch_1):page126_i6:a"
				( attribute "PN" "1"
					( Origin gPackager )
				)
				( objectStatus "R7D19.1" )
			)
			( pin "@baseboard_fab2_lib.baseboard_fab2(sch_1):page126_i6:b"
				( attribute "PN" "2"
					( Origin gPackager )
				)
				( objectStatus "R7D19.2" )
			)
			( pin "@baseboard_fab2_lib.baseboard_fab2(sch_1):page197_i110:\1\"
				( attribute "PN" "1"
					( Origin gPackager )
				)
				( objectStatus "R12W20.1" )
			)
			( pin "@baseboard_fab2_lib.baseboard_fab2(sch_1):page197_i110:\2\"
				( attribute "PN" "2"
					( Origin gPackager )
				)
				( objectStatus "R12W20.2" )
			)
			( pin "@baseboard_fab2_lib.baseboard_fab2(sch_1):page126_i12:a"
				( attribute "PN" "1"
					( Origin gPackager )
				)
				( objectStatus "R1D35.1" )
			)
			( pin "@baseboard_fab2_lib.baseboard_fab2(sch_1):page126_i12:b"
				( attribute "PN" "2"
					( Origin gPackager )
				)
				( objectStatus "R1D35.2" )
			)
			( pin "@baseboard_fab2_lib.baseboard_fab2(sch_1):page126_i13:drn"
				( attribute "PN" "3"
					( Origin gPackager )
				)
				( objectStatus "Q8E2.3" )
			)
			( pin "@baseboard_fab2_lib.baseboard_fab2(sch_1):page126_i13:gate"
				( attribute "PN" "1"
					( Origin gPackager )
				)
				( objectStatus "Q8E2.1" )
			)
			( pin "@baseboard_fab2_lib.baseboard_fab2(sch_1):page126_i13:src"
				( attribute "PN" "2"
					( Origin gPackager )
				)
				( objectStatus "Q8E2.2" )
			)
			( pin "@baseboard_fab2_lib.baseboard_fab2(sch_1):page126_i20:a"
				( attribute "PN" "1"
					( Origin gPackager )
				)
				( objectStatus "R8C9.1" )
			)
			( pin "@baseboard_fab2_lib.baseboard_fab2(sch_1):page126_i20:b"
				( attribute "PN" "2"
					( Origin gPackager )
				)
				( objectStatus "R8C9.2" )
			)
			( pin "@baseboard_fab2_lib.baseboard_fab2(sch_1):page126_i22:a"
				( attribute "PN" "1"
					( Origin gPackager )
				)
				( objectStatus "R3P62.1" )
			)
			( pin "@baseboard_fab2_lib.baseboard_fab2(sch_1):page126_i22:b"
				( attribute "PN" "2"
					( Origin gPackager )
				)
				( objectStatus "R3P62.2" )
			)
			( pin "@baseboard_fab2_lib.baseboard_fab2(sch_1):page126_i23:a"
				( attribute "PN" "1"
					( Origin gPackager )
				)
				( objectStatus "R3P64.1" )
			)
			( pin "@baseboard_fab2_lib.baseboard_fab2(sch_1):page126_i23:b"
				( attribute "PN" "2"
					( Origin gPackager )
				)
				( objectStatus "R3P64.2" )
			)
			( pin "@baseboard_fab2_lib.baseboard_fab2(sch_1):page127_i8:a"
				( attribute "PN" "1"
					( Origin gPackager )
				)
				( objectStatus "FB3M1.1" )
			)
			( pin "@baseboard_fab2_lib.baseboard_fab2(sch_1):page127_i8:b"
				( attribute "PN" "2"
					( Origin gPackager )
				)
				( objectStatus "FB3M1.2" )
			)
			( pin "@baseboard_fab2_lib.baseboard_fab2(sch_1):page127_i9:a"
				( attribute "PN" "1"
					( Origin gPackager )
				)
				( objectStatus "C3M21.1" )
			)
			( pin "@baseboard_fab2_lib.baseboard_fab2(sch_1):page127_i9:b"
				( attribute "PN" "2"
					( Origin gPackager )
				)
				( objectStatus "C3M21.2" )
			)
			( pin "@baseboard_fab2_lib.baseboard_fab2(sch_1):page127_i17:a"
				( attribute "PN" "1"
					( Origin gPackager )
				)
				( objectStatus "FB3M2.1" )
			)
			( pin "@baseboard_fab2_lib.baseboard_fab2(sch_1):page127_i17:b"
				( attribute "PN" "2"
					( Origin gPackager )
				)
				( objectStatus "FB3M2.2" )
			)
			( pin "@baseboard_fab2_lib.baseboard_fab2(sch_1):page127_i18:a"
				( attribute "PN" "1"
					( Origin gPackager )
				)
				( objectStatus "C3M22.1" )
			)
			( pin "@baseboard_fab2_lib.baseboard_fab2(sch_1):page127_i18:b"
				( attribute "PN" "2"
					( Origin gPackager )
				)
				( objectStatus "C3M22.2" )
			)
			( pin "@baseboard_fab2_lib.baseboard_fab2(sch_1):page127_i26:a"
				( attribute "PN" "1"
					( Origin gPackager )
				)
				( objectStatus "FB3M3.1" )
			)
			( pin "@baseboard_fab2_lib.baseboard_fab2(sch_1):page127_i26:b"
				( attribute "PN" "2"
					( Origin gPackager )
				)
				( objectStatus "FB3M3.2" )
			)
			( pin "@baseboard_fab2_lib.baseboard_fab2(sch_1):page127_i27:a"
				( attribute "PN" "1"
					( Origin gPackager )
				)
				( objectStatus "C3M30.1" )
			)
			( pin "@baseboard_fab2_lib.baseboard_fab2(sch_1):page127_i27:b"
				( attribute "PN" "2"
					( Origin gPackager )
				)
				( objectStatus "C3M30.2" )
			)
			( pin "@baseboard_fab2_lib.baseboard_fab2(sch_1):page127_i43:a"
				( attribute "PN" "1"
					( Origin gPackager )
				)
				( objectStatus "C2M5.1" )
			)
			( pin "@baseboard_fab2_lib.baseboard_fab2(sch_1):page127_i43:b"
				( attribute "PN" "2"
					( Origin gPackager )
				)
				( objectStatus "C2M5.2" )
			)
			( pin "@baseboard_fab2_lib.baseboard_fab2(sch_1):page127_i44:a"
				( attribute "PN" "1"
					( Origin gPackager )
				)
				( objectStatus "C2M7.1" )
			)
			( pin "@baseboard_fab2_lib.baseboard_fab2(sch_1):page127_i44:b"
				( attribute "PN" "2"
					( Origin gPackager )
				)
				( objectStatus "C2M7.2" )
			)
			( pin "@baseboard_fab2_lib.baseboard_fab2(sch_1):page127_i46:a"
				( attribute "PN" "1"
					( Origin gPackager )
				)
				( objectStatus "FB2M1.1" )
			)
			( pin "@baseboard_fab2_lib.baseboard_fab2(sch_1):page127_i46:b"
				( attribute "PN" "2"
					( Origin gPackager )
				)
				( objectStatus "FB2M1.2" )
			)
			( pin "@baseboard_fab2_lib.baseboard_fab2(sch_1):page127_i49:a"
				( attribute "PN" "1"
					( Origin gPackager )
				)
				( objectStatus "C2M10.1" )
			)
			( pin "@baseboard_fab2_lib.baseboard_fab2(sch_1):page127_i49:b"
				( attribute "PN" "2"
					( Origin gPackager )
				)
				( objectStatus "C2M10.2" )
			)
			( pin "@baseboard_fab2_lib.baseboard_fab2(sch_1):page127_i50:a"
				( attribute "PN" "1"
					( Origin gPackager )
				)
				( objectStatus "C2M9.1" )
			)
			( pin "@baseboard_fab2_lib.baseboard_fab2(sch_1):page127_i50:b"
				( attribute "PN" "2"
					( Origin gPackager )
				)
				( objectStatus "C2M9.2" )
			)
			( pin "@baseboard_fab2_lib.baseboard_fab2(sch_1):page127_i56:a"
				( attribute "PN" "1"
					( Origin gPackager )
				)
				( objectStatus "FB3M4.1" )
			)
			( pin "@baseboard_fab2_lib.baseboard_fab2(sch_1):page127_i56:b"
				( attribute "PN" "2"
					( Origin gPackager )
				)
				( objectStatus "FB3M4.2" )
			)
			( pin "@baseboard_fab2_lib.baseboard_fab2(sch_1):page127_i57:a"
				( attribute "PN" "1"
					( Origin gPackager )
				)
				( objectStatus "C3M31.1" )
			)
			( pin "@baseboard_fab2_lib.baseboard_fab2(sch_1):page127_i57:b"
				( attribute "PN" "2"
					( Origin gPackager )
				)
				( objectStatus "C3M31.2" )
			)
			( pin "@baseboard_fab2_lib.baseboard_fab2(sch_1):page127_i64:a"
				( attribute "PN" "1"
					( Origin gPackager )
				)
				( objectStatus "C2N6.1" )
			)
			( pin "@baseboard_fab2_lib.baseboard_fab2(sch_1):page127_i64:b"
				( attribute "PN" "2"
					( Origin gPackager )
				)
				( objectStatus "C2N6.2" )
			)
			( pin "@baseboard_fab2_lib.baseboard_fab2(sch_1):page127_i65:a"
				( attribute "PN" "1"
					( Origin gPackager )
				)
				( objectStatus "C2N5.1" )
			)
			( pin "@baseboard_fab2_lib.baseboard_fab2(sch_1):page127_i65:b"
				( attribute "PN" "2"
					( Origin gPackager )
				)
				( objectStatus "C2N5.2" )
			)
			( pin "@baseboard_fab2_lib.baseboard_fab2(sch_1):page127_i69:a"
				( attribute "PN" "1"
					( Origin gPackager )
				)
				( objectStatus "FB2M2.1" )
			)
			( pin "@baseboard_fab2_lib.baseboard_fab2(sch_1):page127_i69:b"
				( attribute "PN" "2"
					( Origin gPackager )
				)
				( objectStatus "FB2M2.2" )
			)
			( pin "@baseboard_fab2_lib.baseboard_fab2(sch_1):page127_i71:ina"
				( attribute "PN" "1"
					( Origin gPackager )
				)
				( objectStatus "L2M1.1" )
			)
			( pin "@baseboard_fab2_lib.baseboard_fab2(sch_1):page127_i71:inb"
				( attribute "PN" "2"
					( Origin gPackager )
				)
				( objectStatus "L2M1.2" )
			)
			( pin "@baseboard_fab2_lib.baseboard_fab2(sch_1):page127_i74:a"
				( attribute "PN" "1"
					( Origin gPackager )
				)
				( objectStatus "C2M8.1" )
			)
			( pin "@baseboard_fab2_lib.baseboard_fab2(sch_1):page127_i74:b"
				( attribute "PN" "2"
					( Origin gPackager )
				)
				( objectStatus "C2M8.2" )
			)
			( pin "@baseboard_fab2_lib.baseboard_fab2(sch_1):page127_i76:a"
				( attribute "PN" "1"
					( Origin gPackager )
				)
				( objectStatus "C2M6.1" )
			)
			( pin "@baseboard_fab2_lib.baseboard_fab2(sch_1):page127_i76:b"
				( attribute "PN" "2"
					( Origin gPackager )
				)
				( objectStatus "C2M6.2" )
			)
			( pin "@baseboard_fab2_lib.baseboard_fab2(sch_1):page127_i78:a"
				( attribute "PN" "1"
					( Origin gPackager )
				)
				( objectStatus "C2M25.1" )
			)
			( pin "@baseboard_fab2_lib.baseboard_fab2(sch_1):page127_i78:b"
				( attribute "PN" "2"
					( Origin gPackager )
				)
				( objectStatus "C2M25.2" )
			)
			( pin "@baseboard_fab2_lib.baseboard_fab2(sch_1):page127_i80:a"
				( attribute "PN" "1"
					( Origin gPackager )
				)
				( objectStatus "C3M29.1" )
			)
			( pin "@baseboard_fab2_lib.baseboard_fab2(sch_1):page127_i80:b"
				( attribute "PN" "2"
					( Origin gPackager )
				)
				( objectStatus "C3M29.2" )
			)
			( pin "@baseboard_fab2_lib.baseboard_fab2(sch_1):page127_i81:a"
				( attribute "PN" "1"
					( Origin gPackager )
				)
				( objectStatus "C3M24.1" )
			)
			( pin "@baseboard_fab2_lib.baseboard_fab2(sch_1):page127_i81:b"
				( attribute "PN" "2"
					( Origin gPackager )
				)
				( objectStatus "C3M24.2" )
			)
			( pin "@baseboard_fab2_lib.baseboard_fab2(sch_1):page127_i82:a"
				( attribute "PN" "1"
					( Origin gPackager )
				)
				( objectStatus "C3M23.1" )
			)
			( pin "@baseboard_fab2_lib.baseboard_fab2(sch_1):page127_i82:b"
				( attribute "PN" "2"
					( Origin gPackager )
				)
				( objectStatus "C3M23.2" )
			)
			( pin "@baseboard_fab2_lib.baseboard_fab2(sch_1):page127_i83:a"
				( attribute "PN" "1"
					( Origin gPackager )
				)
				( objectStatus "C3M27.1" )
			)
			( pin "@baseboard_fab2_lib.baseboard_fab2(sch_1):page127_i83:b"
				( attribute "PN" "2"
					( Origin gPackager )
				)
				( objectStatus "C3M27.2" )
			)
			( pin "@baseboard_fab2_lib.baseboard_fab2(sch_1):page127_i84:a"
				( attribute "PN" "1"
					( Origin gPackager )
				)
				( objectStatus "C3M20.1" )
			)
			( pin "@baseboard_fab2_lib.baseboard_fab2(sch_1):page127_i84:b"
				( attribute "PN" "2"
					( Origin gPackager )
				)
				( objectStatus "C3M20.2" )
			)
			( pin "@baseboard_fab2_lib.baseboard_fab2(sch_1):page127_i85:a"
				( attribute "PN" "1"
					( Origin gPackager )
				)
				( objectStatus "C3M18.1" )
			)
			( pin "@baseboard_fab2_lib.baseboard_fab2(sch_1):page127_i85:b"
				( attribute "PN" "2"
					( Origin gPackager )
				)
				( objectStatus "C3M18.2" )
			)
			( pin "@baseboard_fab2_lib.baseboard_fab2(sch_1):page127_i86:a"
				( attribute "PN" "1"
					( Origin gPackager )
				)
				( objectStatus "C3M17.1" )
			)
			( pin "@baseboard_fab2_lib.baseboard_fab2(sch_1):page127_i86:b"
				( attribute "PN" "2"
					( Origin gPackager )
				)
				( objectStatus "C3M17.2" )
			)
			( pin "@baseboard_fab2_lib.baseboard_fab2(sch_1):page127_i87:a"
				( attribute "PN" "1"
					( Origin gPackager )
				)
				( objectStatus "C3M19.1" )
			)
			( pin "@baseboard_fab2_lib.baseboard_fab2(sch_1):page127_i87:b"
				( attribute "PN" "2"
					( Origin gPackager )
				)
				( objectStatus "C3M19.2" )
			)
			( pin "@baseboard_fab2_lib.baseboard_fab2(sch_1):page129_i35:a"
				( attribute "PN" "1"
					( Origin gPackager )
				)
				( objectStatus "C7B25.1" )
			)
			( pin "@baseboard_fab2_lib.baseboard_fab2(sch_1):page129_i35:b"
				( attribute "PN" "2"
					( Origin gPackager )
				)
				( objectStatus "C7B25.2" )
			)
			( pin "@baseboard_fab2_lib.baseboard_fab2(sch_1):page129_i69:a"
				( attribute "PN" "1"
					( Origin gPackager )
				)
				( objectStatus "C7B27.1" )
			)
			( pin "@baseboard_fab2_lib.baseboard_fab2(sch_1):page129_i69:b"
				( attribute "PN" "2"
					( Origin gPackager )
				)
				( objectStatus "C7B27.2" )
			)
			( pin "@baseboard_fab2_lib.baseboard_fab2(sch_1):page129_i70:a"
				( attribute "PN" "1"
					( Origin gPackager )
				)
				( objectStatus "C7B28.1" )
			)
			( pin "@baseboard_fab2_lib.baseboard_fab2(sch_1):page129_i70:b"
				( attribute "PN" "2"
					( Origin gPackager )
				)
				( objectStatus "C7B28.2" )
			)
			( pin "@baseboard_fab2_lib.baseboard_fab2(sch_1):page129_i71:a"
				( attribute "PN" "1"
					( Origin gPackager )
				)
				( objectStatus "C7C2.1" )
			)
			( pin "@baseboard_fab2_lib.baseboard_fab2(sch_1):page129_i71:b"
				( attribute "PN" "2"
					( Origin gPackager )
				)
				( objectStatus "C7C2.2" )
			)
			( pin "@baseboard_fab2_lib.baseboard_fab2(sch_1):page129_i72:a"
				( attribute "PN" "1"
					( Origin gPackager )
				)
				( objectStatus "C3M40.1" )
			)
			( pin "@baseboard_fab2_lib.baseboard_fab2(sch_1):page129_i72:b"
				( attribute "PN" "2"
					( Origin gPackager )
				)
				( objectStatus "C3M40.2" )
			)
			( pin "@baseboard_fab2_lib.baseboard_fab2(sch_1):page129_i73:a"
				( attribute "PN" "1"
					( Origin gPackager )
				)
				( objectStatus "C3M37.1" )
			)
			( pin "@baseboard_fab2_lib.baseboard_fab2(sch_1):page129_i73:b"
				( attribute "PN" "2"
					( Origin gPackager )
				)
				( objectStatus "C3M37.2" )
			)
			( pin "@baseboard_fab2_lib.baseboard_fab2(sch_1):page129_i74:a"
				( attribute "PN" "1"
					( Origin gPackager )
				)
				( objectStatus "C3N9.1" )
			)
			( pin "@baseboard_fab2_lib.baseboard_fab2(sch_1):page129_i74:b"
				( attribute "PN" "2"
					( Origin gPackager )
				)
				( objectStatus "C3N9.2" )
			)
			( pin "@baseboard_fab2_lib.baseboard_fab2(sch_1):page129_i75:a"
				( attribute "PN" "1"
					( Origin gPackager )
				)
				( objectStatus "C3N8.1" )
			)
			( pin "@baseboard_fab2_lib.baseboard_fab2(sch_1):page129_i75:b"
				( attribute "PN" "2"
					( Origin gPackager )
				)
				( objectStatus "C3N8.2" )
			)
			( pin "@baseboard_fab2_lib.baseboard_fab2(sch_1):page129_i76:a"
				( attribute "PN" "1"
					( Origin gPackager )
				)
				( objectStatus "C7C3.1" )
			)
			( pin "@baseboard_fab2_lib.baseboard_fab2(sch_1):page129_i76:b"
				( attribute "PN" "2"
					( Origin gPackager )
				)
				( objectStatus "C7C3.2" )
			)
			( pin "@baseboard_fab2_lib.baseboard_fab2(sch_1):page129_i77:a"
				( attribute "PN" "1"
					( Origin gPackager )
				)
				( objectStatus "C7C1.1" )
			)
			( pin "@baseboard_fab2_lib.baseboard_fab2(sch_1):page129_i77:b"
				( attribute "PN" "2"
					( Origin gPackager )
				)
				( objectStatus "C7C1.2" )
			)
			( pin "@baseboard_fab2_lib.baseboard_fab2(sch_1):page129_i78:a"
				( attribute "PN" "1"
					( Origin gPackager )
				)
				( objectStatus "C7B29.1" )
			)
			( pin "@baseboard_fab2_lib.baseboard_fab2(sch_1):page129_i78:b"
				( attribute "PN" "2"
					( Origin gPackager )
				)
				( objectStatus "C7B29.2" )
			)
			( pin "@baseboard_fab2_lib.baseboard_fab2(sch_1):page129_i79:a"
				( attribute "PN" "1"
					( Origin gPackager )
				)
				( objectStatus "C7B26.1" )
			)
			( pin "@baseboard_fab2_lib.baseboard_fab2(sch_1):page129_i79:b"
				( attribute "PN" "2"
					( Origin gPackager )
				)
				( objectStatus "C7B26.2" )
			)
			( pin "@baseboard_fab2_lib.baseboard_fab2(sch_1):page129_i80:a"
				( attribute "PN" "1"
					( Origin gPackager )
				)
				( objectStatus "C3M44.1" )
			)
			( pin "@baseboard_fab2_lib.baseboard_fab2(sch_1):page129_i80:b"
				( attribute "PN" "2"
					( Origin gPackager )
				)
				( objectStatus "C3M44.2" )
			)
			( pin "@baseboard_fab2_lib.baseboard_fab2(sch_1):page129_i81:a"
				( attribute "PN" "1"
					( Origin gPackager )
				)
				( objectStatus "C3M41.1" )
			)
			( pin "@baseboard_fab2_lib.baseboard_fab2(sch_1):page129_i81:b"
				( attribute "PN" "2"
					( Origin gPackager )
				)
				( objectStatus "C3M41.2" )
			)
			( pin "@baseboard_fab2_lib.baseboard_fab2(sch_1):page129_i82:a"
				( attribute "PN" "1"
					( Origin gPackager )
				)
				( objectStatus "C3M45.1" )
			)
			( pin "@baseboard_fab2_lib.baseboard_fab2(sch_1):page129_i82:b"
				( attribute "PN" "2"
					( Origin gPackager )
				)
				( objectStatus "C3M45.2" )
			)
			( pin "@baseboard_fab2_lib.baseboard_fab2(sch_1):page129_i83:a"
				( attribute "PN" "1"
					( Origin gPackager )
				)
				( objectStatus "C3N13.1" )
			)
			( pin "@baseboard_fab2_lib.baseboard_fab2(sch_1):page129_i83:b"
				( attribute "PN" "2"
					( Origin gPackager )
				)
				( objectStatus "C3N13.2" )
			)
			( pin "@baseboard_fab2_lib.baseboard_fab2(sch_1):page130_i2:a"
				( attribute "PN" "1"
					( Origin gPackager )
				)
				( objectStatus "C7D2.1" )
			)
			( pin "@baseboard_fab2_lib.baseboard_fab2(sch_1):page130_i2:b"
				( attribute "PN" "2"
					( Origin gPackager )
				)
				( objectStatus "C7D2.2" )
			)
			( pin "@baseboard_fab2_lib.baseboard_fab2(sch_1):page130_i4:a"
				( attribute "PN" "1"
					( Origin gPackager )
				)
				( objectStatus "C2N26.1" )
			)
			( pin "@baseboard_fab2_lib.baseboard_fab2(sch_1):page130_i4:b"
				( attribute "PN" "2"
					( Origin gPackager )
				)
				( objectStatus "C2N26.2" )
			)
			( pin "@baseboard_fab2_lib.baseboard_fab2(sch_1):page130_i7:a"
				( attribute "PN" "1"
					( Origin gPackager )
				)
				( objectStatus "C2N19.1" )
			)
			( pin "@baseboard_fab2_lib.baseboard_fab2(sch_1):page130_i7:b"
				( attribute "PN" "2"
					( Origin gPackager )
				)
				( objectStatus "C2N19.2" )
			)
			( pin "@baseboard_fab2_lib.baseboard_fab2(sch_1):page130_i8:a"
				( attribute "PN" "1"
					( Origin gPackager )
				)
				( objectStatus "C2N24.1" )
			)
			( pin "@baseboard_fab2_lib.baseboard_fab2(sch_1):page130_i8:b"
				( attribute "PN" "2"
					( Origin gPackager )
				)
				( objectStatus "C2N24.2" )
			)
			( pin "@baseboard_fab2_lib.baseboard_fab2(sch_1):page130_i9:a"
				( attribute "PN" "1"
					( Origin gPackager )
				)
				( objectStatus "C2N22.1" )
			)
			( pin "@baseboard_fab2_lib.baseboard_fab2(sch_1):page130_i9:b"
				( attribute "PN" "2"
					( Origin gPackager )
				)
				( objectStatus "C2N22.2" )
			)
			( pin "@baseboard_fab2_lib.baseboard_fab2(sch_1):page130_i12:a"
				( attribute "PN" "1"
					( Origin gPackager )
				)
				( objectStatus "C2N20.1" )
			)
			( pin "@baseboard_fab2_lib.baseboard_fab2(sch_1):page130_i12:b"
				( attribute "PN" "2"
					( Origin gPackager )
				)
				( objectStatus "C2N20.2" )
			)
			( pin "@baseboard_fab2_lib.baseboard_fab2(sch_1):page130_i15:a"
				( attribute "PN" "1"
					( Origin gPackager )
				)
				( objectStatus "C2N21.1" )
			)
			( pin "@baseboard_fab2_lib.baseboard_fab2(sch_1):page130_i15:b"
				( attribute "PN" "2"
					( Origin gPackager )
				)
				( objectStatus "C2N21.2" )
			)
			( pin "@baseboard_fab2_lib.baseboard_fab2(sch_1):page130_i16:a"
				( attribute "PN" "1"
					( Origin gPackager )
				)
				( objectStatus "C3N29.1" )
			)
			( pin "@baseboard_fab2_lib.baseboard_fab2(sch_1):page130_i16:b"
				( attribute "PN" "2"
					( Origin gPackager )
				)
				( objectStatus "C3N29.2" )
			)
			( pin "@baseboard_fab2_lib.baseboard_fab2(sch_1):page130_i19:a"
				( attribute "PN" "1"
					( Origin gPackager )
				)
				( objectStatus "C8C3.1" )
			)
			( pin "@baseboard_fab2_lib.baseboard_fab2(sch_1):page130_i19:b"
				( attribute "PN" "2"
					( Origin gPackager )
				)
				( objectStatus "C8C3.2" )
			)
			( pin "@baseboard_fab2_lib.baseboard_fab2(sch_1):page130_i20:a"
				( attribute "PN" "1"
					( Origin gPackager )
				)
				( objectStatus "C8C4.1" )
			)
			( pin "@baseboard_fab2_lib.baseboard_fab2(sch_1):page130_i20:b"
				( attribute "PN" "2"
					( Origin gPackager )
				)
				( objectStatus "C8C4.2" )
			)
			( pin "@baseboard_fab2_lib.baseboard_fab2(sch_1):page130_i21:a"
				( attribute "PN" "1"
					( Origin gPackager )
				)
				( objectStatus "C8C5.1" )
			)
			( pin "@baseboard_fab2_lib.baseboard_fab2(sch_1):page130_i21:b"
				( attribute "PN" "2"
					( Origin gPackager )
				)
				( objectStatus "C8C5.2" )
			)
			( pin "@baseboard_fab2_lib.baseboard_fab2(sch_1):page130_i22:a"
				( attribute "PN" "1"
					( Origin gPackager )
				)
				( objectStatus "C8C6.1" )
			)
			( pin "@baseboard_fab2_lib.baseboard_fab2(sch_1):page130_i22:b"
				( attribute "PN" "2"
					( Origin gPackager )
				)
				( objectStatus "C8C6.2" )
			)
			( pin "@baseboard_fab2_lib.baseboard_fab2(sch_1):page130_i24:a"
				( attribute "PN" "1"
					( Origin gPackager )
				)
				( objectStatus "C2N23.1" )
			)
			( pin "@baseboard_fab2_lib.baseboard_fab2(sch_1):page130_i24:b"
				( attribute "PN" "2"
					( Origin gPackager )
				)
				( objectStatus "C2N23.2" )
			)
			( pin "@baseboard_fab2_lib.baseboard_fab2(sch_1):page130_i25:a"
				( attribute "PN" "1"
					( Origin gPackager )
				)
				( objectStatus "C2N14.1" )
			)
			( pin "@baseboard_fab2_lib.baseboard_fab2(sch_1):page130_i25:b"
				( attribute "PN" "2"
					( Origin gPackager )
				)
				( objectStatus "C2N14.2" )
			)
			( pin "@baseboard_fab2_lib.baseboard_fab2(sch_1):page130_i28:a"
				( attribute "PN" "1"
					( Origin gPackager )
				)
				( objectStatus "C2N17.1" )
			)
			( pin "@baseboard_fab2_lib.baseboard_fab2(sch_1):page130_i28:b"
				( attribute "PN" "2"
					( Origin gPackager )
				)
				( objectStatus "C2N17.2" )
			)
			( pin "@baseboard_fab2_lib.baseboard_fab2(sch_1):page130_i29:a"
				( attribute "PN" "1"
					( Origin gPackager )
				)
				( objectStatus "C2N18.1" )
			)
			( pin "@baseboard_fab2_lib.baseboard_fab2(sch_1):page130_i29:b"
				( attribute "PN" "2"
					( Origin gPackager )
				)
				( objectStatus "C2N18.2" )
			)
			( pin "@baseboard_fab2_lib.baseboard_fab2(sch_1):page130_i30:a"
				( attribute "PN" "1"
					( Origin gPackager )
				)
				( objectStatus "C8B2.1" )
			)
			( pin "@baseboard_fab2_lib.baseboard_fab2(sch_1):page130_i30:b"
				( attribute "PN" "2"
					( Origin gPackager )
				)
				( objectStatus "C8B2.2" )
			)
			( pin "@baseboard_fab2_lib.baseboard_fab2(sch_1):page130_i32:a"
				( attribute "PN" "1"
					( Origin gPackager )
				)
				( objectStatus "C8B3.1" )
			)
			( pin "@baseboard_fab2_lib.baseboard_fab2(sch_1):page130_i32:b"
				( attribute "PN" "2"
					( Origin gPackager )
				)
				( objectStatus "C8B3.2" )
			)
			( pin "@baseboard_fab2_lib.baseboard_fab2(sch_1):page130_i34:a"
				( attribute "PN" "1"
					( Origin gPackager )
				)
				( objectStatus "C2N25.1" )
			)
			( pin "@baseboard_fab2_lib.baseboard_fab2(sch_1):page130_i34:b"
				( attribute "PN" "2"
					( Origin gPackager )
				)
				( objectStatus "C2N25.2" )
			)
			( pin "@baseboard_fab2_lib.baseboard_fab2(sch_1):page130_i37:a"
				( attribute "PN" "1"
					( Origin gPackager )
				)
				( objectStatus "C2M16.1" )
			)
			( pin "@baseboard_fab2_lib.baseboard_fab2(sch_1):page130_i37:b"
				( attribute "PN" "2"
					( Origin gPackager )
				)
				( objectStatus "C2M16.2" )
			)
			( pin "@baseboard_fab2_lib.baseboard_fab2(sch_1):page130_i38:a"
				( attribute "PN" "1"
					( Origin gPackager )
				)
				( objectStatus "C7D3.1" )
			)
			( pin "@baseboard_fab2_lib.baseboard_fab2(sch_1):page130_i38:b"
				( attribute "PN" "2"
					( Origin gPackager )
				)
				( objectStatus "C7D3.2" )
			)
			( pin "@baseboard_fab2_lib.baseboard_fab2(sch_1):page130_i39:a"
				( attribute "PN" "1"
					( Origin gPackager )
				)
				( objectStatus "C8B4.1" )
			)
			( pin "@baseboard_fab2_lib.baseboard_fab2(sch_1):page130_i39:b"
				( attribute "PN" "2"
					( Origin gPackager )
				)
				( objectStatus "C8B4.2" )
			)
			( pin "@baseboard_fab2_lib.baseboard_fab2(sch_1):page130_i41:a"
				( attribute "PN" "1"
					( Origin gPackager )
				)
				( objectStatus "C8B1.1" )
			)
			( pin "@baseboard_fab2_lib.baseboard_fab2(sch_1):page130_i41:b"
				( attribute "PN" "2"
					( Origin gPackager )
				)
				( objectStatus "C8B1.2" )
			)
			( pin "@baseboard_fab2_lib.baseboard_fab2(sch_1):page130_i42:a"
				( attribute "PN" "1"
					( Origin gPackager )
				)
				( objectStatus "C3N23.1" )
			)
			( pin "@baseboard_fab2_lib.baseboard_fab2(sch_1):page130_i42:b"
				( attribute "PN" "2"
					( Origin gPackager )
				)
				( objectStatus "C3N23.2" )
			)
			( pin "@baseboard_fab2_lib.baseboard_fab2(sch_1):page130_i43:a"
				( attribute "PN" "1"
					( Origin gPackager )
				)
				( objectStatus "C2M1.1" )
			)
			( pin "@baseboard_fab2_lib.baseboard_fab2(sch_1):page130_i43:b"
				( attribute "PN" "2"
					( Origin gPackager )
				)
				( objectStatus "C2M1.2" )
			)
			( pin "@baseboard_fab2_lib.baseboard_fab2(sch_1):page130_i45:a"
				( attribute "PN" "1"
					( Origin gPackager )
				)
				( objectStatus "C2M2.1" )
			)
			( pin "@baseboard_fab2_lib.baseboard_fab2(sch_1):page130_i45:b"
				( attribute "PN" "2"
					( Origin gPackager )
				)
				( objectStatus "C2M2.2" )
			)
			( pin "@baseboard_fab2_lib.baseboard_fab2(sch_1):page130_i47:a"
				( attribute "PN" "1"
					( Origin gPackager )
				)
				( objectStatus "C2N15.1" )
			)
			( pin "@baseboard_fab2_lib.baseboard_fab2(sch_1):page130_i47:b"
				( attribute "PN" "2"
					( Origin gPackager )
				)
				( objectStatus "C2N15.2" )
			)
			( pin "@baseboard_fab2_lib.baseboard_fab2(sch_1):page130_i49:a"
				( attribute "PN" "1"
					( Origin gPackager )
				)
				( objectStatus "C3N21.1" )
			)
			( pin "@baseboard_fab2_lib.baseboard_fab2(sch_1):page130_i49:b"
				( attribute "PN" "2"
					( Origin gPackager )
				)
				( objectStatus "C3N21.2" )
			)
			( pin "@baseboard_fab2_lib.baseboard_fab2(sch_1):page130_i50:a"
				( attribute "PN" "1"
					( Origin gPackager )
				)
				( objectStatus "C3N25.1" )
			)
			( pin "@baseboard_fab2_lib.baseboard_fab2(sch_1):page130_i50:b"
				( attribute "PN" "2"
					( Origin gPackager )
				)
				( objectStatus "C3N25.2" )
			)
			( pin "@baseboard_fab2_lib.baseboard_fab2(sch_1):page130_i52:a"
				( attribute "PN" "1"
					( Origin gPackager )
				)
				( objectStatus "C2N16.1" )
			)
			( pin "@baseboard_fab2_lib.baseboard_fab2(sch_1):page130_i52:b"
				( attribute "PN" "2"
					( Origin gPackager )
				)
				( objectStatus "C2N16.2" )
			)
			( pin "@baseboard_fab2_lib.baseboard_fab2(sch_1):page130_i53:a"
				( attribute "PN" "1"
					( Origin gPackager )
				)
				( objectStatus "C3N22.1" )
			)
			( pin "@baseboard_fab2_lib.baseboard_fab2(sch_1):page130_i53:b"
				( attribute "PN" "2"
					( Origin gPackager )
				)
				( objectStatus "C3N22.2" )
			)
			( pin "@baseboard_fab2_lib.baseboard_fab2(sch_1):page131_i1:a"
				( attribute "PN" "1"
					( Origin gPackager )
				)
				( objectStatus "C7B15.1" )
			)
			( pin "@baseboard_fab2_lib.baseboard_fab2(sch_1):page131_i1:b"
				( attribute "PN" "2"
					( Origin gPackager )
				)
				( objectStatus "C7B15.2" )
			)
			( pin "@baseboard_fab2_lib.baseboard_fab2(sch_1):page131_i2:a"
				( attribute "PN" "1"
					( Origin gPackager )
				)
				( objectStatus "C7B19.1" )
			)
			( pin "@baseboard_fab2_lib.baseboard_fab2(sch_1):page131_i2:b"
				( attribute "PN" "2"
					( Origin gPackager )
				)
				( objectStatus "C7B19.2" )
			)
			( pin "@baseboard_fab2_lib.baseboard_fab2(sch_1):page131_i3:a"
				( attribute "PN" "1"
					( Origin gPackager )
				)
				( objectStatus "C7B16.1" )
			)
			( pin "@baseboard_fab2_lib.baseboard_fab2(sch_1):page131_i3:b"
				( attribute "PN" "2"
					( Origin gPackager )
				)
				( objectStatus "C7B16.2" )
			)
			( pin "@baseboard_fab2_lib.baseboard_fab2(sch_1):page131_i4:a"
				( attribute "PN" "1"
					( Origin gPackager )
				)
				( objectStatus "C7B21.1" )
			)
			( pin "@baseboard_fab2_lib.baseboard_fab2(sch_1):page131_i4:b"
				( attribute "PN" "2"
					( Origin gPackager )
				)
				( objectStatus "C7B21.2" )
			)
			( pin "@baseboard_fab2_lib.baseboard_fab2(sch_1):page131_i6:a"
				( attribute "PN" "1"
					( Origin gPackager )
				)
				( objectStatus "C7B20.1" )
			)
			( pin "@baseboard_fab2_lib.baseboard_fab2(sch_1):page131_i6:b"
				( attribute "PN" "2"
					( Origin gPackager )
				)
				( objectStatus "C7B20.2" )
			)
			( pin "@baseboard_fab2_lib.baseboard_fab2(sch_1):page131_i7:a"
				( attribute "PN" "1"
					( Origin gPackager )
				)
				( objectStatus "C7B23.1" )
			)
			( pin "@baseboard_fab2_lib.baseboard_fab2(sch_1):page131_i7:b"
				( attribute "PN" "2"
					( Origin gPackager )
				)
				( objectStatus "C7B23.2" )
			)
			( pin "@baseboard_fab2_lib.baseboard_fab2(sch_1):page131_i8:a"
				( attribute "PN" "1"
					( Origin gPackager )
				)
				( objectStatus "C8B10.1" )
			)
			( pin "@baseboard_fab2_lib.baseboard_fab2(sch_1):page131_i8:b"
				( attribute "PN" "2"
					( Origin gPackager )
				)
				( objectStatus "C8B10.2" )
			)
			( pin "@baseboard_fab2_lib.baseboard_fab2(sch_1):page131_i10:a"
				( attribute "PN" "1"
					( Origin gPackager )
				)
				( objectStatus "C7B22.1" )
			)
			( pin "@baseboard_fab2_lib.baseboard_fab2(sch_1):page131_i10:b"
				( attribute "PN" "2"
					( Origin gPackager )
				)
				( objectStatus "C7B22.2" )
			)
			( pin "@baseboard_fab2_lib.baseboard_fab2(sch_1):page131_i11:a"
				( attribute "PN" "1"
					( Origin gPackager )
				)
				( objectStatus "C7B24.1" )
			)
			( pin "@baseboard_fab2_lib.baseboard_fab2(sch_1):page131_i11:b"
				( attribute "PN" "2"
					( Origin gPackager )
				)
				( objectStatus "C7B24.2" )
			)
			( pin "@baseboard_fab2_lib.baseboard_fab2(sch_1):page131_i12:a"
				( attribute "PN" "1"
					( Origin gPackager )
				)
				( objectStatus "C7B18.1" )
			)
			( pin "@baseboard_fab2_lib.baseboard_fab2(sch_1):page131_i12:b"
				( attribute "PN" "2"
					( Origin gPackager )
				)
				( objectStatus "C7B18.2" )
			)
			( pin "@baseboard_fab2_lib.baseboard_fab2(sch_1):page131_i14:a"
				( attribute "PN" "1"
					( Origin gPackager )
				)
				( objectStatus "C8B9.1" )
			)
			( pin "@baseboard_fab2_lib.baseboard_fab2(sch_1):page131_i14:b"
				( attribute "PN" "2"
					( Origin gPackager )
				)
				( objectStatus "C8B9.2" )
			)
			( pin "@baseboard_fab2_lib.baseboard_fab2(sch_1):page131_i15:a"
				( attribute "PN" "1"
					( Origin gPackager )
				)
				( objectStatus "C8B11.1" )
			)
			( pin "@baseboard_fab2_lib.baseboard_fab2(sch_1):page131_i15:b"
				( attribute "PN" "2"
					( Origin gPackager )
				)
				( objectStatus "C8B11.2" )
			)
			( pin "@baseboard_fab2_lib.baseboard_fab2(sch_1):page131_i16:a"
				( attribute "PN" "1"
					( Origin gPackager )
				)
				( objectStatus "C8B14.1" )
			)
			( pin "@baseboard_fab2_lib.baseboard_fab2(sch_1):page131_i16:b"
				( attribute "PN" "2"
					( Origin gPackager )
				)
				( objectStatus "C8B14.2" )
			)
			( pin "@baseboard_fab2_lib.baseboard_fab2(sch_1):page131_i18:a"
				( attribute "PN" "1"
					( Origin gPackager )
				)
				( objectStatus "C7B17.1" )
			)
			( pin "@baseboard_fab2_lib.baseboard_fab2(sch_1):page131_i18:b"
				( attribute "PN" "2"
					( Origin gPackager )
				)
				( objectStatus "C7B17.2" )
			)
			( pin "@baseboard_fab2_lib.baseboard_fab2(sch_1):page131_i20:a"
				( attribute "PN" "1"
					( Origin gPackager )
				)
				( objectStatus "C8B13.1" )
			)
			( pin "@baseboard_fab2_lib.baseboard_fab2(sch_1):page131_i20:b"
				( attribute "PN" "2"
					( Origin gPackager )
				)
				( objectStatus "C8B13.2" )
			)
			( pin "@baseboard_fab2_lib.baseboard_fab2(sch_1):page131_i22:a"
				( attribute "PN" "1"
					( Origin gPackager )
				)
				( objectStatus "C8B16.1" )
			)
			( pin "@baseboard_fab2_lib.baseboard_fab2(sch_1):page131_i22:b"
				( attribute "PN" "2"
					( Origin gPackager )
				)
				( objectStatus "C8B16.2" )
			)
			( pin "@baseboard_fab2_lib.baseboard_fab2(sch_1):page131_i24:a"
				( attribute "PN" "1"
					( Origin gPackager )
				)
				( objectStatus "C8B15.1" )
			)
			( pin "@baseboard_fab2_lib.baseboard_fab2(sch_1):page131_i24:b"
				( attribute "PN" "2"
					( Origin gPackager )
				)
				( objectStatus "C8B15.2" )
			)
			( pin "@baseboard_fab2_lib.baseboard_fab2(sch_1):page131_i27:a"
				( attribute "PN" "1"
					( Origin gPackager )
				)
				( objectStatus "C2M22.1" )
			)
			( pin "@baseboard_fab2_lib.baseboard_fab2(sch_1):page131_i27:b"
				( attribute "PN" "2"
					( Origin gPackager )
				)
				( objectStatus "C2M22.2" )
			)
			( pin "@baseboard_fab2_lib.baseboard_fab2(sch_1):page131_i28:a"
				( attribute "PN" "1"
					( Origin gPackager )
				)
				( objectStatus "C2M21.1" )
			)
			( pin "@baseboard_fab2_lib.baseboard_fab2(sch_1):page131_i28:b"
				( attribute "PN" "2"
					( Origin gPackager )
				)
				( objectStatus "C2M21.2" )
			)
			( pin "@baseboard_fab2_lib.baseboard_fab2(sch_1):page131_i29:a"
				( attribute "PN" "1"
					( Origin gPackager )
				)
				( objectStatus "C2M18.1" )
			)
			( pin "@baseboard_fab2_lib.baseboard_fab2(sch_1):page131_i29:b"
				( attribute "PN" "2"
					( Origin gPackager )
				)
				( objectStatus "C2M18.2" )
			)
			( pin "@baseboard_fab2_lib.baseboard_fab2(sch_1):page131_i31:a"
				( attribute "PN" "1"
					( Origin gPackager )
				)
				( objectStatus "C2M19.1" )
			)
			( pin "@baseboard_fab2_lib.baseboard_fab2(sch_1):page131_i31:b"
				( attribute "PN" "2"
					( Origin gPackager )
				)
				( objectStatus "C2M19.2" )
			)
			( pin "@baseboard_fab2_lib.baseboard_fab2(sch_1):page131_i32:a"
				( attribute "PN" "1"
					( Origin gPackager )
				)
				( objectStatus "C3M38.1" )
			)
			( pin "@baseboard_fab2_lib.baseboard_fab2(sch_1):page131_i32:b"
				( attribute "PN" "2"
					( Origin gPackager )
				)
				( objectStatus "C3M38.2" )
			)
			( pin "@baseboard_fab2_lib.baseboard_fab2(sch_1):page131_i34:a"
				( attribute "PN" "1"
					( Origin gPackager )
				)
				( objectStatus "C2M17.1" )
			)
			( pin "@baseboard_fab2_lib.baseboard_fab2(sch_1):page131_i34:b"
				( attribute "PN" "2"
					( Origin gPackager )
				)
				( objectStatus "C2M17.2" )
			)
			( pin "@baseboard_fab2_lib.baseboard_fab2(sch_1):page131_i35:a"
				( attribute "PN" "1"
					( Origin gPackager )
				)
				( objectStatus "C2M11.1" )
			)
			( pin "@baseboard_fab2_lib.baseboard_fab2(sch_1):page131_i35:b"
				( attribute "PN" "2"
					( Origin gPackager )
				)
				( objectStatus "C2M11.2" )
			)
			( pin "@baseboard_fab2_lib.baseboard_fab2(sch_1):page131_i37:a"
				( attribute "PN" "1"
					( Origin gPackager )
				)
				( objectStatus "C8A13.1" )
			)
			( pin "@baseboard_fab2_lib.baseboard_fab2(sch_1):page131_i37:b"
				( attribute "PN" "2"
					( Origin gPackager )
				)
				( objectStatus "C8A13.2" )
			)
			( pin "@baseboard_fab2_lib.baseboard_fab2(sch_1):page131_i39:a"
				( attribute "PN" "1"
					( Origin gPackager )
				)
				( objectStatus "C2M20.1" )
			)
			( pin "@baseboard_fab2_lib.baseboard_fab2(sch_1):page131_i39:b"
				( attribute "PN" "2"
					( Origin gPackager )
				)
				( objectStatus "C2M20.2" )
			)
			( pin "@baseboard_fab2_lib.baseboard_fab2(sch_1):page131_i40:a"
				( attribute "PN" "1"
					( Origin gPackager )
				)
				( objectStatus "C2N13.1" )
			)
			( pin "@baseboard_fab2_lib.baseboard_fab2(sch_1):page131_i40:b"
				( attribute "PN" "2"
					( Origin gPackager )
				)
				( objectStatus "C2N13.2" )
			)
			( pin "@baseboard_fab2_lib.baseboard_fab2(sch_1):page131_i41:a"
				( attribute "PN" "1"
					( Origin gPackager )
				)
				( objectStatus "C2N2.1" )
			)
			( pin "@baseboard_fab2_lib.baseboard_fab2(sch_1):page131_i41:b"
				( attribute "PN" "2"
					( Origin gPackager )
				)
				( objectStatus "C2N2.2" )
			)
			( pin "@baseboard_fab2_lib.baseboard_fab2(sch_1):page131_i42:a"
				( attribute "PN" "1"
					( Origin gPackager )
				)
				( objectStatus "C3M43.1" )
			)
			( pin "@baseboard_fab2_lib.baseboard_fab2(sch_1):page131_i42:b"
				( attribute "PN" "2"
					( Origin gPackager )
				)
				( objectStatus "C3M43.2" )
			)
			( pin "@baseboard_fab2_lib.baseboard_fab2(sch_1):page131_i43:a"
				( attribute "PN" "1"
					( Origin gPackager )
				)
				( objectStatus "C2N7.1" )
			)
			( pin "@baseboard_fab2_lib.baseboard_fab2(sch_1):page131_i43:b"
				( attribute "PN" "2"
					( Origin gPackager )
				)
				( objectStatus "C2N7.2" )
			)
			( pin "@baseboard_fab2_lib.baseboard_fab2(sch_1):page131_i44:a"
				( attribute "PN" "1"
					( Origin gPackager )
				)
				( objectStatus "C3M39.1" )
			)
			( pin "@baseboard_fab2_lib.baseboard_fab2(sch_1):page131_i44:b"
				( attribute "PN" "2"
					( Origin gPackager )
				)
				( objectStatus "C3M39.2" )
			)
			( pin "@baseboard_fab2_lib.baseboard_fab2(sch_1):page131_i45:a"
				( attribute "PN" "1"
					( Origin gPackager )
				)
				( objectStatus "C3M42.1" )
			)
			( pin "@baseboard_fab2_lib.baseboard_fab2(sch_1):page131_i45:b"
				( attribute "PN" "2"
					( Origin gPackager )
				)
				( objectStatus "C3M42.2" )
			)
			( pin "@baseboard_fab2_lib.baseboard_fab2(sch_1):page131_i47:a"
				( attribute "PN" "1"
					( Origin gPackager )
				)
				( objectStatus "C2N8.1" )
			)
			( pin "@baseboard_fab2_lib.baseboard_fab2(sch_1):page131_i47:b"
				( attribute "PN" "2"
					( Origin gPackager )
				)
				( objectStatus "C2N8.2" )
			)
			( pin "@baseboard_fab2_lib.baseboard_fab2(sch_1):page131_i48:a"
				( attribute "PN" "1"
					( Origin gPackager )
				)
				( objectStatus "C2M13.1" )
			)
			( pin "@baseboard_fab2_lib.baseboard_fab2(sch_1):page131_i48:b"
				( attribute "PN" "2"
					( Origin gPackager )
				)
				( objectStatus "C2M13.2" )
			)
			( pin "@baseboard_fab2_lib.baseboard_fab2(sch_1):page131_i50:a"
				( attribute "PN" "1"
					( Origin gPackager )
				)
				( objectStatus "C2N10.1" )
			)
			( pin "@baseboard_fab2_lib.baseboard_fab2(sch_1):page131_i50:b"
				( attribute "PN" "2"
					( Origin gPackager )
				)
				( objectStatus "C2N10.2" )
			)
			( pin "@baseboard_fab2_lib.baseboard_fab2(sch_1):page131_i52:a"
				( attribute "PN" "1"
					( Origin gPackager )
				)
				( objectStatus "C2M12.1" )
			)
			( pin "@baseboard_fab2_lib.baseboard_fab2(sch_1):page131_i52:b"
				( attribute "PN" "2"
					( Origin gPackager )
				)
				( objectStatus "C2M12.2" )
			)
			( pin "@baseboard_fab2_lib.baseboard_fab2(sch_1):page132_i1:a"
				( attribute "PN" "1"
					( Origin gPackager )
				)
				( objectStatus "C3L25.1" )
			)
			( pin "@baseboard_fab2_lib.baseboard_fab2(sch_1):page132_i1:b"
				( attribute "PN" "2"
					( Origin gPackager )
				)
				( objectStatus "C3L25.2" )
			)
			( pin "@baseboard_fab2_lib.baseboard_fab2(sch_1):page132_i2:a"
				( attribute "PN" "1"
					( Origin gPackager )
				)
				( objectStatus "C3M7.1" )
			)
			( pin "@baseboard_fab2_lib.baseboard_fab2(sch_1):page132_i2:b"
				( attribute "PN" "2"
					( Origin gPackager )
				)
				( objectStatus "C3M7.2" )
			)
			( pin "@baseboard_fab2_lib.baseboard_fab2(sch_1):page132_i3:a"
				( attribute "PN" "1"
					( Origin gPackager )
				)
				( objectStatus "C3L26.1" )
			)
			( pin "@baseboard_fab2_lib.baseboard_fab2(sch_1):page132_i3:b"
				( attribute "PN" "2"
					( Origin gPackager )
				)
				( objectStatus "C3L26.2" )
			)
			( pin "@baseboard_fab2_lib.baseboard_fab2(sch_1):page132_i4:a"
				( attribute "PN" "1"
					( Origin gPackager )
				)
				( objectStatus "C3L27.1" )
			)
			( pin "@baseboard_fab2_lib.baseboard_fab2(sch_1):page132_i4:b"
				( attribute "PN" "2"
					( Origin gPackager )
				)
				( objectStatus "C3L27.2" )
			)
			( pin "@baseboard_fab2_lib.baseboard_fab2(sch_1):page132_i6:a"
				( attribute "PN" "1"
					( Origin gPackager )
				)
				( objectStatus "C3M6.1" )
			)
			( pin "@baseboard_fab2_lib.baseboard_fab2(sch_1):page132_i6:b"
				( attribute "PN" "2"
					( Origin gPackager )
				)
				( objectStatus "C3M6.2" )
			)
			( pin "@baseboard_fab2_lib.baseboard_fab2(sch_1):page132_i7:a"
				( attribute "PN" "1"
					( Origin gPackager )
				)
				( objectStatus "C7C9.1" )
			)
			( pin "@baseboard_fab2_lib.baseboard_fab2(sch_1):page132_i7:b"
				( attribute "PN" "2"
					( Origin gPackager )
				)
				( objectStatus "C7C9.2" )
			)
			( pin "@baseboard_fab2_lib.baseboard_fab2(sch_1):page132_i8:a"
				( attribute "PN" "1"
					( Origin gPackager )
				)
				( objectStatus "C3N27.1" )
			)
			( pin "@baseboard_fab2_lib.baseboard_fab2(sch_1):page132_i8:b"
				( attribute "PN" "2"
					( Origin gPackager )
				)
				( objectStatus "C3N27.2" )
			)
			( pin "@baseboard_fab2_lib.baseboard_fab2(sch_1):page132_i9:a"
				( attribute "PN" "1"
					( Origin gPackager )
				)
				( objectStatus "C3N30.1" )
			)
			( pin "@baseboard_fab2_lib.baseboard_fab2(sch_1):page132_i9:b"
				( attribute "PN" "2"
					( Origin gPackager )
				)
				( objectStatus "C3N30.2" )
			)
			( pin "@baseboard_fab2_lib.baseboard_fab2(sch_1):page132_i11:a"
				( attribute "PN" "1"
					( Origin gPackager )
				)
				( objectStatus "C7A36.1" )
			)
			( pin "@baseboard_fab2_lib.baseboard_fab2(sch_1):page132_i11:b"
				( attribute "PN" "2"
					( Origin gPackager )
				)
				( objectStatus "C7A36.2" )
			)
			( pin "@baseboard_fab2_lib.baseboard_fab2(sch_1):page132_i12:a"
				( attribute "PN" "1"
					( Origin gPackager )
				)
				( objectStatus "C3N12.1" )
			)
			( pin "@baseboard_fab2_lib.baseboard_fab2(sch_1):page132_i12:b"
				( attribute "PN" "2"
					( Origin gPackager )
				)
				( objectStatus "C3N12.2" )
			)
			( pin "@baseboard_fab2_lib.baseboard_fab2(sch_1):page132_i13:a"
				( attribute "PN" "1"
					( Origin gPackager )
				)
				( objectStatus "C3N10.1" )
			)
			( pin "@baseboard_fab2_lib.baseboard_fab2(sch_1):page132_i13:b"
				( attribute "PN" "2"
					( Origin gPackager )
				)
				( objectStatus "C3N10.2" )
			)
			( pin "@baseboard_fab2_lib.baseboard_fab2(sch_1):page132_i16:a"
				( attribute "PN" "1"
					( Origin gPackager )
				)
				( objectStatus "C3N24.1" )
			)
			( pin "@baseboard_fab2_lib.baseboard_fab2(sch_1):page132_i16:b"
				( attribute "PN" "2"
					( Origin gPackager )
				)
				( objectStatus "C3N24.2" )
			)
			( pin "@baseboard_fab2_lib.baseboard_fab2(sch_1):page132_i17:a"
				( attribute "PN" "1"
					( Origin gPackager )
				)
				( objectStatus "C3N28.1" )
			)
			( pin "@baseboard_fab2_lib.baseboard_fab2(sch_1):page132_i17:b"
				( attribute "PN" "2"
					( Origin gPackager )
				)
				( objectStatus "C3N28.2" )
			)
			( pin "@baseboard_fab2_lib.baseboard_fab2(sch_1):page132_i19:a"
				( attribute "PN" "1"
					( Origin gPackager )
				)
				( objectStatus "C3N11.1" )
			)
			( pin "@baseboard_fab2_lib.baseboard_fab2(sch_1):page132_i19:b"
				( attribute "PN" "2"
					( Origin gPackager )
				)
				( objectStatus "C3N11.2" )
			)
			( pin "@baseboard_fab2_lib.baseboard_fab2(sch_1):page132_i20:a"
				( attribute "PN" "1"
					( Origin gPackager )
				)
				( objectStatus "C3N31.1" )
			)
			( pin "@baseboard_fab2_lib.baseboard_fab2(sch_1):page132_i20:b"
				( attribute "PN" "2"
					( Origin gPackager )
				)
				( objectStatus "C3N31.2" )
			)
			( pin "@baseboard_fab2_lib.baseboard_fab2(sch_1):page132_i23:a"
				( attribute "PN" "1"
					( Origin gPackager )
				)
				( objectStatus "C7A33.1" )
			)
			( pin "@baseboard_fab2_lib.baseboard_fab2(sch_1):page132_i23:b"
				( attribute "PN" "2"
					( Origin gPackager )
				)
				( objectStatus "C7A33.2" )
			)
			( pin "@baseboard_fab2_lib.baseboard_fab2(sch_1):page132_i24:a"
				( attribute "PN" "1"
					( Origin gPackager )
				)
				( objectStatus "C7B4.1" )
			)
			( pin "@baseboard_fab2_lib.baseboard_fab2(sch_1):page132_i24:b"
				( attribute "PN" "2"
					( Origin gPackager )
				)
				( objectStatus "C7B4.2" )
			)
			( pin "@baseboard_fab2_lib.baseboard_fab2(sch_1):page132_i26:a"
				( attribute "PN" "1"
					( Origin gPackager )
				)
				( objectStatus "C2N9.1" )
			)
			( pin "@baseboard_fab2_lib.baseboard_fab2(sch_1):page132_i26:b"
				( attribute "PN" "2"
					( Origin gPackager )
				)
				( objectStatus "C2N9.2" )
			)
			( pin "@baseboard_fab2_lib.baseboard_fab2(sch_1):page132_i27:a"
				( attribute "PN" "1"
					( Origin gPackager )
				)
				( objectStatus "C2N3.1" )
			)
			( pin "@baseboard_fab2_lib.baseboard_fab2(sch_1):page132_i27:b"
				( attribute "PN" "2"
					( Origin gPackager )
				)
				( objectStatus "C2N3.2" )
			)
			( pin "@baseboard_fab2_lib.baseboard_fab2(sch_1):page132_i28:a"
				( attribute "PN" "1"
					( Origin gPackager )
				)
				( objectStatus "C2N4.1" )
			)
			( pin "@baseboard_fab2_lib.baseboard_fab2(sch_1):page132_i28:b"
				( attribute "PN" "2"
					( Origin gPackager )
				)
				( objectStatus "C2N4.2" )
			)
			( pin "@baseboard_fab2_lib.baseboard_fab2(sch_1):page132_i29:a"
				( attribute "PN" "1"
					( Origin gPackager )
				)
				( objectStatus "C2N12.1" )
			)
			( pin "@baseboard_fab2_lib.baseboard_fab2(sch_1):page132_i29:b"
				( attribute "PN" "2"
					( Origin gPackager )
				)
				( objectStatus "C2N12.2" )
			)
			( pin "@baseboard_fab2_lib.baseboard_fab2(sch_1):page132_i30:a"
				( attribute "PN" "1"
					( Origin gPackager )
				)
				( objectStatus "C2N11.1" )
			)
			( pin "@baseboard_fab2_lib.baseboard_fab2(sch_1):page132_i30:b"
				( attribute "PN" "2"
					( Origin gPackager )
				)
				( objectStatus "C2N11.2" )
			)
			( pin "@baseboard_fab2_lib.baseboard_fab2(sch_1):page132_i31:a"
				( attribute "PN" "1"
					( Origin gPackager )
				)
				( objectStatus "C3N19.1" )
			)
			( pin "@baseboard_fab2_lib.baseboard_fab2(sch_1):page132_i31:b"
				( attribute "PN" "2"
					( Origin gPackager )
				)
				( objectStatus "C3N19.2" )
			)
			( pin "@baseboard_fab2_lib.baseboard_fab2(sch_1):page132_i32:a"
				( attribute "PN" "1"
					( Origin gPackager )
				)
				( objectStatus "C3N3.1" )
			)
			( pin "@baseboard_fab2_lib.baseboard_fab2(sch_1):page132_i32:b"
				( attribute "PN" "2"
					( Origin gPackager )
				)
				( objectStatus "C3N3.2" )
			)
			( pin "@baseboard_fab2_lib.baseboard_fab2(sch_1):page132_i34:a"
				( attribute "PN" "1"
					( Origin gPackager )
				)
				( objectStatus "C3N1.1" )
			)
			( pin "@baseboard_fab2_lib.baseboard_fab2(sch_1):page132_i34:b"
				( attribute "PN" "2"
					( Origin gPackager )
				)
				( objectStatus "C3N1.2" )
			)
			( pin "@baseboard_fab2_lib.baseboard_fab2(sch_1):page132_i35:a"
				( attribute "PN" "1"
					( Origin gPackager )
				)
				( objectStatus "C3N7.1" )
			)
			( pin "@baseboard_fab2_lib.baseboard_fab2(sch_1):page132_i35:b"
				( attribute "PN" "2"
					( Origin gPackager )
				)
				( objectStatus "C3N7.2" )
			)
			( pin "@baseboard_fab2_lib.baseboard_fab2(sch_1):page132_i36:a"
				( attribute "PN" "1"
					( Origin gPackager )
				)
				( objectStatus "C3N16.1" )
			)
			( pin "@baseboard_fab2_lib.baseboard_fab2(sch_1):page132_i36:b"
				( attribute "PN" "2"
					( Origin gPackager )
				)
				( objectStatus "C3N16.2" )
			)
			( pin "@baseboard_fab2_lib.baseboard_fab2(sch_1):page132_i38:a"
				( attribute "PN" "1"
					( Origin gPackager )
				)
				( objectStatus "C7A32.1" )
			)
			( pin "@baseboard_fab2_lib.baseboard_fab2(sch_1):page132_i38:b"
				( attribute "PN" "2"
					( Origin gPackager )
				)
				( objectStatus "C7A32.2" )
			)
			( pin "@baseboard_fab2_lib.baseboard_fab2(sch_1):page132_i40:a"
				( attribute "PN" "1"
					( Origin gPackager )
				)
				( objectStatus "C7A31.1" )
			)
			( pin "@baseboard_fab2_lib.baseboard_fab2(sch_1):page132_i40:b"
				( attribute "PN" "2"
					( Origin gPackager )
				)
				( objectStatus "C7A31.2" )
			)
			( pin "@baseboard_fab2_lib.baseboard_fab2(sch_1):page132_i42:a"
				( attribute "PN" "1"
					( Origin gPackager )
				)
				( objectStatus "C3N18.1" )
			)
			( pin "@baseboard_fab2_lib.baseboard_fab2(sch_1):page132_i42:b"
				( attribute "PN" "2"
					( Origin gPackager )
				)
				( objectStatus "C3N18.2" )
			)
			( pin "@baseboard_fab2_lib.baseboard_fab2(sch_1):page132_i43:a"
				( attribute "PN" "1"
					( Origin gPackager )
				)
				( objectStatus "C3N2.1" )
			)
			( pin "@baseboard_fab2_lib.baseboard_fab2(sch_1):page132_i43:b"
				( attribute "PN" "2"
					( Origin gPackager )
				)
				( objectStatus "C3N2.2" )
			)
			( pin "@baseboard_fab2_lib.baseboard_fab2(sch_1):page132_i44:a"
				( attribute "PN" "1"
					( Origin gPackager )
				)
				( objectStatus "C3N6.1" )
			)
			( pin "@baseboard_fab2_lib.baseboard_fab2(sch_1):page132_i44:b"
				( attribute "PN" "2"
					( Origin gPackager )
				)
				( objectStatus "C3N6.2" )
			)
			( pin "@baseboard_fab2_lib.baseboard_fab2(sch_1):page132_i45:a"
				( attribute "PN" "1"
					( Origin gPackager )
				)
				( objectStatus "C3N17.1" )
			)
			( pin "@baseboard_fab2_lib.baseboard_fab2(sch_1):page132_i45:b"
				( attribute "PN" "2"
					( Origin gPackager )
				)
				( objectStatus "C3N17.2" )
			)
			( pin "@baseboard_fab2_lib.baseboard_fab2(sch_1):page132_i46:a"
				( attribute "PN" "1"
					( Origin gPackager )
				)
				( objectStatus "C3N4.1" )
			)
			( pin "@baseboard_fab2_lib.baseboard_fab2(sch_1):page132_i46:b"
				( attribute "PN" "2"
					( Origin gPackager )
				)
				( objectStatus "C3N4.2" )
			)
			( pin "@baseboard_fab2_lib.baseboard_fab2(sch_1):page132_i48:a"
				( attribute "PN" "1"
					( Origin gPackager )
				)
				( objectStatus "C3N5.1" )
			)
			( pin "@baseboard_fab2_lib.baseboard_fab2(sch_1):page132_i48:b"
				( attribute "PN" "2"
					( Origin gPackager )
				)
				( objectStatus "C3N5.2" )
			)
			( pin "@baseboard_fab2_lib.baseboard_fab2(sch_1):page132_i49:a"
				( attribute "PN" "1"
					( Origin gPackager )
				)
				( objectStatus "C3N15.1" )
			)
			( pin "@baseboard_fab2_lib.baseboard_fab2(sch_1):page132_i49:b"
				( attribute "PN" "2"
					( Origin gPackager )
				)
				( objectStatus "C3N15.2" )
			)
			( pin "@baseboard_fab2_lib.baseboard_fab2(sch_1):page132_i51:a"
				( attribute "PN" "1"
					( Origin gPackager )
				)
				( objectStatus "C3N20.1" )
			)
			( pin "@baseboard_fab2_lib.baseboard_fab2(sch_1):page132_i51:b"
				( attribute "PN" "2"
					( Origin gPackager )
				)
				( objectStatus "C3N20.2" )
			)
			( pin "@baseboard_fab2_lib.baseboard_fab2(sch_1):page132_i52:a"
				( attribute "PN" "1"
					( Origin gPackager )
				)
				( objectStatus "C3L23.1" )
			)
			( pin "@baseboard_fab2_lib.baseboard_fab2(sch_1):page132_i52:b"
				( attribute "PN" "2"
					( Origin gPackager )
				)
				( objectStatus "C3L23.2" )
			)
			( pin "@baseboard_fab2_lib.baseboard_fab2(sch_1):page132_i54:a"
				( attribute "PN" "1"
					( Origin gPackager )
				)
				( objectStatus "C3L22.1" )
			)
			( pin "@baseboard_fab2_lib.baseboard_fab2(sch_1):page132_i54:b"
				( attribute "PN" "2"
					( Origin gPackager )
				)
				( objectStatus "C3L22.2" )
			)
			( pin "@baseboard_fab2_lib.baseboard_fab2(sch_1):page132_i56:a"
				( attribute "PN" "1"
					( Origin gPackager )
				)
				( objectStatus "C3L24.1" )
			)
			( pin "@baseboard_fab2_lib.baseboard_fab2(sch_1):page132_i56:b"
				( attribute "PN" "2"
					( Origin gPackager )
				)
				( objectStatus "C3L24.2" )
			)
			( pin "@baseboard_fab2_lib.baseboard_fab2(sch_1):page133_i120:a"
				( attribute "PN" "1"
					( Origin gPackager )
				)
				( objectStatus "R3N3.1" )
			)
			( pin "@baseboard_fab2_lib.baseboard_fab2(sch_1):page133_i120:b"
				( attribute "PN" "2"
					( Origin gPackager )
				)
				( objectStatus "R3N3.2" )
			)
			( pin "@baseboard_fab2_lib.baseboard_fab2(sch_1):page133_i122:a"
				( attribute "PN" "1"
					( Origin gPackager )
				)
				( objectStatus "R2N12.1" )
			)
			( pin "@baseboard_fab2_lib.baseboard_fab2(sch_1):page133_i122:b"
				( attribute "PN" "2"
					( Origin gPackager )
				)
				( objectStatus "R2N12.2" )
			)
			( pin "@baseboard_fab2_lib.baseboard_fab2(sch_1):page133_i200:a"
				( attribute "PN" "1"
					( Origin gPackager )
				)
				( objectStatus "R7D8.1" )
			)
			( pin "@baseboard_fab2_lib.baseboard_fab2(sch_1):page133_i200:b"
				( attribute "PN" "2"
					( Origin gPackager )
				)
				( objectStatus "R7D8.2" )
			)
			( pin "@baseboard_fab2_lib.baseboard_fab2(sch_1):page133_i202:a"
				( attribute "PN" "1"
					( Origin gPackager )
				)
				( objectStatus "R7D10.1" )
			)
			( pin "@baseboard_fab2_lib.baseboard_fab2(sch_1):page133_i202:b"
				( attribute "PN" "2"
					( Origin gPackager )
				)
				( objectStatus "R7D10.2" )
			)
			( pin "@baseboard_fab2_lib.baseboard_fab2(sch_1):page133_i237:a"
				( attribute "PN" "1"
					( Origin gPackager )
				)
				( objectStatus "R7D12.1" )
			)
			( pin "@baseboard_fab2_lib.baseboard_fab2(sch_1):page133_i237:b"
				( attribute "PN" "2"
					( Origin gPackager )
				)
				( objectStatus "R7D12.2" )
			)
			( pin "@baseboard_fab2_lib.baseboard_fab2(sch_1):page133_i243:a"
				( attribute "PN" "1"
					( Origin gPackager )
				)
				( objectStatus "R7D3.1" )
			)
			( pin "@baseboard_fab2_lib.baseboard_fab2(sch_1):page133_i243:b"
				( attribute "PN" "2"
					( Origin gPackager )
				)
				( objectStatus "R7D3.2" )
			)
			( pin "@baseboard_fab2_lib.baseboard_fab2(sch_1):page133_i245:a"
				( attribute "PN" "1"
					( Origin gPackager )
				)
				( objectStatus "R7D4.1" )
			)
			( pin "@baseboard_fab2_lib.baseboard_fab2(sch_1):page133_i245:b"
				( attribute "PN" "2"
					( Origin gPackager )
				)
				( objectStatus "R7D4.2" )
			)
			( pin "@baseboard_fab2_lib.baseboard_fab2(sch_1):page133_i247:a"
				( attribute "PN" "1"
					( Origin gPackager )
				)
				( objectStatus "R2N16.1" )
			)
			( pin "@baseboard_fab2_lib.baseboard_fab2(sch_1):page133_i247:b"
				( attribute "PN" "2"
					( Origin gPackager )
				)
				( objectStatus "R2N16.2" )
			)
			( pin "@baseboard_fab2_lib.baseboard_fab2(sch_1):page133_i258:a"
				( attribute "PN" "1"
					( Origin gPackager )
				)
				( objectStatus "R2R5.1" )
			)
			( pin "@baseboard_fab2_lib.baseboard_fab2(sch_1):page133_i258:b"
				( attribute "PN" "2"
					( Origin gPackager )
				)
				( objectStatus "R2R5.2" )
			)
			( pin "@baseboard_fab2_lib.baseboard_fab2(sch_1):page133_i267:a"
				( attribute "PN" "1"
					( Origin gPackager )
				)
				( objectStatus "R2N9.1" )
			)
			( pin "@baseboard_fab2_lib.baseboard_fab2(sch_1):page133_i267:b"
				( attribute "PN" "2"
					( Origin gPackager )
				)
				( objectStatus "R2N9.2" )
			)
			( pin "@baseboard_fab2_lib.baseboard_fab2(sch_1):page133_i280:a"
				( attribute "PN" "1"
					( Origin gPackager )
				)
				( objectStatus "R8B23.1" )
			)
			( pin "@baseboard_fab2_lib.baseboard_fab2(sch_1):page133_i280:b"
				( attribute "PN" "2"
					( Origin gPackager )
				)
				( objectStatus "R8B23.2" )
			)
			( pin "@baseboard_fab2_lib.baseboard_fab2(sch_1):page133_i282:a"
				( attribute "PN" "1"
					( Origin gPackager )
				)
				( objectStatus "R8B30.1" )
			)
			( pin "@baseboard_fab2_lib.baseboard_fab2(sch_1):page133_i282:b"
				( attribute "PN" "2"
					( Origin gPackager )
				)
				( objectStatus "R8B30.2" )
			)
			( pin "@baseboard_fab2_lib.baseboard_fab2(sch_1):page133_i284:a"
				( attribute "PN" "1"
					( Origin gPackager )
				)
				( objectStatus "R2M4.1" )
			)
			( pin "@baseboard_fab2_lib.baseboard_fab2(sch_1):page133_i284:b"
				( attribute "PN" "2"
					( Origin gPackager )
				)
				( objectStatus "R2M4.2" )
			)
			( pin "@baseboard_fab2_lib.baseboard_fab2(sch_1):page133_i286:a"
				( attribute "PN" "1"
					( Origin gPackager )
				)
				( objectStatus "R8C4.1" )
			)
			( pin "@baseboard_fab2_lib.baseboard_fab2(sch_1):page133_i286:b"
				( attribute "PN" "2"
					( Origin gPackager )
				)
				( objectStatus "R8C4.2" )
			)
			( pin "@baseboard_fab2_lib.baseboard_fab2(sch_1):page133_i295:a"
				( attribute "PN" "1"
					( Origin gPackager )
				)
				( objectStatus "R7B6.1" )
			)
			( pin "@baseboard_fab2_lib.baseboard_fab2(sch_1):page133_i295:b"
				( attribute "PN" "2"
					( Origin gPackager )
				)
				( objectStatus "R7B6.2" )
			)
			( pin "@baseboard_fab2_lib.baseboard_fab2(sch_1):page133_i296:a"
				( attribute "PN" "1"
					( Origin gPackager )
				)
				( objectStatus "R7C8.1" )
			)
			( pin "@baseboard_fab2_lib.baseboard_fab2(sch_1):page133_i296:b"
				( attribute "PN" "2"
					( Origin gPackager )
				)
				( objectStatus "R7C8.2" )
			)
			( pin "@baseboard_fab2_lib.baseboard_fab2(sch_1):page133_i297:a"
				( attribute "PN" "1"
					( Origin gPackager )
				)
				( objectStatus "R7C5.1" )
			)
			( pin "@baseboard_fab2_lib.baseboard_fab2(sch_1):page133_i297:b"
				( attribute "PN" "2"
					( Origin gPackager )
				)
				( objectStatus "R7C5.2" )
			)
			( pin "@baseboard_fab2_lib.baseboard_fab2(sch_1):page133_i301:a"
				( attribute "PN" "1"
					( Origin gPackager )
				)
				( objectStatus "R8D14.1" )
			)
			( pin "@baseboard_fab2_lib.baseboard_fab2(sch_1):page133_i301:b"
				( attribute "PN" "2"
					( Origin gPackager )
				)
				( objectStatus "R8D14.2" )
			)
			( pin "@baseboard_fab2_lib.baseboard_fab2(sch_1):page133_i303:a"
				( attribute "PN" "1"
					( Origin gPackager )
				)
				( objectStatus "R8C6.1" )
			)
			( pin "@baseboard_fab2_lib.baseboard_fab2(sch_1):page133_i303:b"
				( attribute "PN" "2"
					( Origin gPackager )
				)
				( objectStatus "R8C6.2" )
			)
			( pin "@baseboard_fab2_lib.baseboard_fab2(sch_1):page133_i304:a"
				( attribute "PN" "1"
					( Origin gPackager )
				)
				( objectStatus "R8C2.1" )
			)
			( pin "@baseboard_fab2_lib.baseboard_fab2(sch_1):page133_i304:b"
				( attribute "PN" "2"
					( Origin gPackager )
				)
				( objectStatus "R8C2.2" )
			)
			( pin "@baseboard_fab2_lib.baseboard_fab2(sch_1):page133_i306:a"
				( attribute "PN" "1"
					( Origin gPackager )
				)
				( objectStatus "R7D6.1" )
			)
			( pin "@baseboard_fab2_lib.baseboard_fab2(sch_1):page133_i306:b"
				( attribute "PN" "2"
					( Origin gPackager )
				)
				( objectStatus "R7D6.2" )
			)
			( pin "@baseboard_fab2_lib.baseboard_fab2(sch_1):page133_i307:a"
				( attribute "PN" "1"
					( Origin gPackager )
				)
				( objectStatus "R8B31.1" )
			)
			( pin "@baseboard_fab2_lib.baseboard_fab2(sch_1):page133_i307:b"
				( attribute "PN" "2"
					( Origin gPackager )
				)
				( objectStatus "R8B31.2" )
			)
			( pin "@baseboard_fab2_lib.baseboard_fab2(sch_1):page133_i309:a"
				( attribute "PN" "1"
					( Origin gPackager )
				)
				( objectStatus "R2N7.1" )
			)
			( pin "@baseboard_fab2_lib.baseboard_fab2(sch_1):page133_i309:b"
				( attribute "PN" "2"
					( Origin gPackager )
				)
				( objectStatus "R2N7.2" )
			)
			( pin "@baseboard_fab2_lib.baseboard_fab2(sch_1):page133_i322:a"
				( attribute "PN" "1"
					( Origin gPackager )
				)
				( objectStatus "R3P8.1" )
			)
			( pin "@baseboard_fab2_lib.baseboard_fab2(sch_1):page133_i322:b"
				( attribute "PN" "2"
					( Origin gPackager )
				)
				( objectStatus "R3P8.2" )
			)
			( pin "@baseboard_fab2_lib.baseboard_fab2(sch_1):page133_i326:a"
				( attribute "PN" "1"
					( Origin gPackager )
				)
				( objectStatus "R8C1.1" )
			)
			( pin "@baseboard_fab2_lib.baseboard_fab2(sch_1):page133_i326:b"
				( attribute "PN" "2"
					( Origin gPackager )
				)
				( objectStatus "R8C1.2" )
			)
			( pin "@baseboard_fab2_lib.baseboard_fab2(sch_1):page133_i327:a"
				( attribute "PN" "1"
					( Origin gPackager )
				)
				( objectStatus "R8C7.1" )
			)
			( pin "@baseboard_fab2_lib.baseboard_fab2(sch_1):page133_i327:b"
				( attribute "PN" "2"
					( Origin gPackager )
				)
				( objectStatus "R8C7.2" )
			)
			( pin "@baseboard_fab2_lib.baseboard_fab2(sch_1):page133_i331:a"
				( attribute "PN" "1"
					( Origin gPackager )
				)
				( objectStatus "R7D7.1" )
			)
			( pin "@baseboard_fab2_lib.baseboard_fab2(sch_1):page133_i331:b"
				( attribute "PN" "2"
					( Origin gPackager )
				)
				( objectStatus "R7D7.2" )
			)
			( pin "@baseboard_fab2_lib.baseboard_fab2(sch_1):page133_i332:a"
				( attribute "PN" "1"
					( Origin gPackager )
				)
				( objectStatus "R7D2.1" )
			)
			( pin "@baseboard_fab2_lib.baseboard_fab2(sch_1):page133_i332:b"
				( attribute "PN" "2"
					( Origin gPackager )
				)
				( objectStatus "R7D2.2" )
			)
			( pin "@baseboard_fab2_lib.baseboard_fab2(sch_1):page133_i333:a"
				( attribute "PN" "1"
					( Origin gPackager )
				)
				( objectStatus "R8C25.1" )
			)
			( pin "@baseboard_fab2_lib.baseboard_fab2(sch_1):page133_i333:b"
				( attribute "PN" "2"
					( Origin gPackager )
				)
				( objectStatus "R8C25.2" )
			)
			( pin "@baseboard_fab2_lib.baseboard_fab2(sch_1):page133_i341:a"
				( attribute "PN" "1"
					( Origin gPackager )
				)
				( objectStatus "R2N32.1" )
			)
			( pin "@baseboard_fab2_lib.baseboard_fab2(sch_1):page133_i341:b"
				( attribute "PN" "2"
					( Origin gPackager )
				)
				( objectStatus "R2N32.2" )
			)
			( pin "@baseboard_fab2_lib.baseboard_fab2(sch_1):page133_i349:a"
				( attribute "PN" "1"
					( Origin gPackager )
				)
				( objectStatus "R2M8.1" )
			)
			( pin "@baseboard_fab2_lib.baseboard_fab2(sch_1):page133_i349:b"
				( attribute "PN" "2"
					( Origin gPackager )
				)
				( objectStatus "R2M8.2" )
			)
			( pin "@baseboard_fab2_lib.baseboard_fab2(sch_1):page133_i352:a"
				( attribute "PN" "1"
					( Origin gPackager )
				)
				( objectStatus "R2N29.1" )
			)
			( pin "@baseboard_fab2_lib.baseboard_fab2(sch_1):page133_i352:b"
				( attribute "PN" "2"
					( Origin gPackager )
				)
				( objectStatus "R2N29.2" )
			)
			( pin "@baseboard_fab2_lib.baseboard_fab2(sch_1):page42_i220:a"
				( attribute "PN" "1"
					( Origin gPackager )
				)
				( objectStatus "C5P29.1" )
			)
			( pin "@baseboard_fab2_lib.baseboard_fab2(sch_1):page42_i220:b"
				( attribute "PN" "2"
					( Origin gPackager )
				)
				( objectStatus "C5P29.2" )
			)
			( pin "@baseboard_fab2_lib.baseboard_fab2(sch_1):page133_i356:a"
				( attribute "PN" "1"
					( Origin gPackager )
				)
				( objectStatus "R7D44.1" )
			)
			( pin "@baseboard_fab2_lib.baseboard_fab2(sch_1):page133_i356:b"
				( attribute "PN" "2"
					( Origin gPackager )
				)
				( objectStatus "R7D44.2" )
			)
			( pin "@baseboard_fab2_lib.baseboard_fab2(sch_1):page133_i360:a"
				( attribute "PN" "1"
					( Origin gPackager )
				)
				( objectStatus "R2P22.1" )
			)
			( pin "@baseboard_fab2_lib.baseboard_fab2(sch_1):page133_i360:b"
				( attribute "PN" "2"
					( Origin gPackager )
				)
				( objectStatus "R2P22.2" )
			)
			( pin "@baseboard_fab2_lib.baseboard_fab2(sch_1):page133_i362:a"
				( attribute "PN" "1"
					( Origin gPackager )
				)
				( objectStatus "R8D44.1" )
			)
			( pin "@baseboard_fab2_lib.baseboard_fab2(sch_1):page133_i362:b"
				( attribute "PN" "2"
					( Origin gPackager )
				)
				( objectStatus "R8D44.2" )
			)
			( pin "@baseboard_fab2_lib.baseboard_fab2(sch_1):page134_i3:a"
				( attribute "PN" "1"
					( Origin gPackager )
				)
				( objectStatus "R2P17.1" )
			)
			( pin "@baseboard_fab2_lib.baseboard_fab2(sch_1):page134_i3:b"
				( attribute "PN" "2"
					( Origin gPackager )
				)
				( objectStatus "R2P17.2" )
			)
			( pin "@baseboard_fab2_lib.baseboard_fab2(sch_1):page95_i123:drn"
				( attribute "PN" "3"
					( Origin gPackager )
				)
				( objectStatus "Q7E8.3" )
			)
			( pin "@baseboard_fab2_lib.baseboard_fab2(sch_1):page95_i123:gate"
				( attribute "PN" "1"
					( Origin gPackager )
				)
				( objectStatus "Q7E8.1" )
			)
			( pin "@baseboard_fab2_lib.baseboard_fab2(sch_1):page95_i123:src"
				( attribute "PN" "2"
					( Origin gPackager )
				)
				( objectStatus "Q7E8.2" )
			)
			( pin "@baseboard_fab2_lib.baseboard_fab2(sch_1):page134_i9:a"
				( attribute "PN" "1"
					( Origin gPackager )
				)
				( objectStatus "R7C21.1" )
			)
			( pin "@baseboard_fab2_lib.baseboard_fab2(sch_1):page134_i9:b"
				( attribute "PN" "2"
					( Origin gPackager )
				)
				( objectStatus "R7C21.2" )
			)
			( pin "@baseboard_fab2_lib.baseboard_fab2(sch_1):page95_i122:drn"
				( attribute "PN" "3"
					( Origin gPackager )
				)
				( objectStatus "Q7E4.3" )
			)
			( pin "@baseboard_fab2_lib.baseboard_fab2(sch_1):page95_i122:gate"
				( attribute "PN" "1"
					( Origin gPackager )
				)
				( objectStatus "Q7E4.1" )
			)
			( pin "@baseboard_fab2_lib.baseboard_fab2(sch_1):page95_i122:src"
				( attribute "PN" "2"
					( Origin gPackager )
				)
				( objectStatus "Q7E4.2" )
			)
			( pin "@baseboard_fab2_lib.baseboard_fab2(sch_1):page134_i11:a"
				( attribute "PN" "1"
					( Origin gPackager )
				)
				( objectStatus "R7D18.1" )
			)
			( pin "@baseboard_fab2_lib.baseboard_fab2(sch_1):page134_i11:b"
				( attribute "PN" "2"
					( Origin gPackager )
				)
				( objectStatus "R7D18.2" )
			)
			( pin "@baseboard_fab2_lib.baseboard_fab2(sch_1):page135_i107:a"
				( attribute "PN" "1"
					( Origin gPackager )
				)
				( objectStatus "R2P19.1" )
			)
			( pin "@baseboard_fab2_lib.baseboard_fab2(sch_1):page135_i107:b"
				( attribute "PN" "2"
					( Origin gPackager )
				)
				( objectStatus "R2P19.2" )
			)
			( pin "@baseboard_fab2_lib.baseboard_fab2(sch_1):page135_i112:a"
				( attribute "PN" "1"
					( Origin gPackager )
				)
				( objectStatus "R2N23.1" )
			)
			( pin "@baseboard_fab2_lib.baseboard_fab2(sch_1):page135_i112:b"
				( attribute "PN" "2"
					( Origin gPackager )
				)
				( objectStatus "R2N23.2" )
			)
			( pin "@baseboard_fab2_lib.baseboard_fab2(sch_1):page135_i113:a"
				( attribute "PN" "1"
					( Origin gPackager )
				)
				( objectStatus "R2N24.1" )
			)
			( pin "@baseboard_fab2_lib.baseboard_fab2(sch_1):page135_i113:b"
				( attribute "PN" "2"
					( Origin gPackager )
				)
				( objectStatus "R2N24.2" )
			)
			( pin "@baseboard_fab2_lib.baseboard_fab2(sch_1):page135_i117:a"
				( attribute "PN" "1"
					( Origin gPackager )
				)
				( objectStatus "R9A12.1" )
			)
			( pin "@baseboard_fab2_lib.baseboard_fab2(sch_1):page135_i117:b"
				( attribute "PN" "2"
					( Origin gPackager )
				)
				( objectStatus "R9A12.2" )
			)
			( pin "@baseboard_fab2_lib.baseboard_fab2(sch_1):page135_i118:a"
				( attribute "PN" "1"
					( Origin gPackager )
				)
				( objectStatus "R9A13.1" )
			)
			( pin "@baseboard_fab2_lib.baseboard_fab2(sch_1):page135_i118:b"
				( attribute "PN" "2"
					( Origin gPackager )
				)
				( objectStatus "R9A13.2" )
			)
			( pin "@baseboard_fab2_lib.baseboard_fab2(sch_1):page135_i120:a"
				( attribute "PN" "1"
					( Origin gPackager )
				)
				( objectStatus "R8D21.1" )
			)
			( pin "@baseboard_fab2_lib.baseboard_fab2(sch_1):page135_i120:b"
				( attribute "PN" "2"
					( Origin gPackager )
				)
				( objectStatus "R8D21.2" )
			)
			( pin "@baseboard_fab2_lib.baseboard_fab2(sch_1):page135_i121:a"
				( attribute "PN" "1"
					( Origin gPackager )
				)
				( objectStatus "R7D30.1" )
			)
			( pin "@baseboard_fab2_lib.baseboard_fab2(sch_1):page135_i121:b"
				( attribute "PN" "2"
					( Origin gPackager )
				)
				( objectStatus "R7D30.2" )
			)
			( pin "@baseboard_fab2_lib.baseboard_fab2(sch_1):page135_i124:io1"
				( attribute "PN" "1"
					( Origin gPackager )
				)
				( objectStatus "J8G2.1" )
			)
			( pin "@baseboard_fab2_lib.baseboard_fab2(sch_1):page135_i124:io2"
				( attribute "PN" "2"
					( Origin gPackager )
				)
				( objectStatus "J8G2.2" )
			)
			( pin "@baseboard_fab2_lib.baseboard_fab2(sch_1):page135_i124:io3"
				( attribute "PN" "3"
					( Origin gPackager )
				)
				( objectStatus "J8G2.3" )
			)
			( pin "@baseboard_fab2_lib.baseboard_fab2(sch_1):page135_i124:io4"
				( attribute "PN" "4"
					( Origin gPackager )
				)
				( objectStatus "J8G2.4" )
			)
			( pin "@baseboard_fab2_lib.baseboard_fab2(sch_1):page135_i124:io5"
				( attribute "PN" "5"
					( Origin gPackager )
				)
				( objectStatus "J8G2.5" )
			)
			( pin "@baseboard_fab2_lib.baseboard_fab2(sch_1):page135_i124:io6"
				( attribute "PN" "6"
					( Origin gPackager )
				)
				( objectStatus "J8G2.6" )
			)
			( pin "@baseboard_fab2_lib.baseboard_fab2(sch_1):page135_i124:io7"
				( attribute "PN" "7"
					( Origin gPackager )
				)
				( objectStatus "J8G2.7" )
			)
			( pin "@baseboard_fab2_lib.baseboard_fab2(sch_1):page135_i124:io8"
				( attribute "PN" "8"
					( Origin gPackager )
				)
				( objectStatus "J8G2.8" )
			)
			( pin "@baseboard_fab2_lib.baseboard_fab2(sch_1):page135_i124:io9"
				( attribute "PN" "9"
					( Origin gPackager )
				)
				( objectStatus "J8G2.9" )
			)
			( pin "@baseboard_fab2_lib.baseboard_fab2(sch_1):page135_i124:io10"
				( attribute "PN" "10"
					( Origin gPackager )
				)
				( objectStatus "J8G2.10" )
			)
			( pin "@baseboard_fab2_lib.baseboard_fab2(sch_1):page135_i124:io11"
				( attribute "PN" "11"
					( Origin gPackager )
				)
				( objectStatus "J8G2.11" )
			)
			( pin "@baseboard_fab2_lib.baseboard_fab2(sch_1):page135_i124:io12"
				( attribute "PN" "12"
					( Origin gPackager )
				)
				( objectStatus "J8G2.12" )
			)
			( pin "@baseboard_fab2_lib.baseboard_fab2(sch_1):page135_i129:a"
				( attribute "PN" "1"
					( Origin gPackager )
				)
				( objectStatus "R9A16.1" )
			)
			( pin "@baseboard_fab2_lib.baseboard_fab2(sch_1):page135_i129:b"
				( attribute "PN" "2"
					( Origin gPackager )
				)
				( objectStatus "R9A16.2" )
			)
			( pin "@baseboard_fab2_lib.baseboard_fab2(sch_1):page135_i131:io1"
				( attribute "PN" "1"
					( Origin gPackager )
				)
				( objectStatus "J9A1.1" )
			)
			( pin "@baseboard_fab2_lib.baseboard_fab2(sch_1):page135_i131:io2"
				( attribute "PN" "2"
					( Origin gPackager )
				)
				( objectStatus "J9A1.2" )
			)
			( pin "@baseboard_fab2_lib.baseboard_fab2(sch_1):page135_i131:io3"
				( attribute "PN" "3"
					( Origin gPackager )
				)
				( objectStatus "J9A1.3" )
			)
			( pin "@baseboard_fab2_lib.baseboard_fab2(sch_1):page135_i131:io4"
				( attribute "PN" "4"
					( Origin gPackager )
				)
				( objectStatus "J9A1.4" )
			)
			( pin "@baseboard_fab2_lib.baseboard_fab2(sch_1):page136_i101:a"
				( attribute "PN" "1"
					( Origin gPackager )
				)
				( objectStatus "R7G26.1" )
			)
			( pin "@baseboard_fab2_lib.baseboard_fab2(sch_1):page136_i101:b"
				( attribute "PN" "2"
					( Origin gPackager )
				)
				( objectStatus "R7G26.2" )
			)
			( pin "@baseboard_fab2_lib.baseboard_fab2(sch_1):page136_i102:a"
				( attribute "PN" "1"
					( Origin gPackager )
				)
				( objectStatus "R7G28.1" )
			)
			( pin "@baseboard_fab2_lib.baseboard_fab2(sch_1):page136_i102:b"
				( attribute "PN" "2"
					( Origin gPackager )
				)
				( objectStatus "R7G28.2" )
			)
			( pin "@baseboard_fab2_lib.baseboard_fab2(sch_1):page136_i126:a"
				( attribute "PN" "1"
					( Origin gPackager )
				)
				( objectStatus "R8E20.1" )
			)
			( pin "@baseboard_fab2_lib.baseboard_fab2(sch_1):page136_i126:b"
				( attribute "PN" "2"
					( Origin gPackager )
				)
				( objectStatus "R8E20.2" )
			)
			( pin "@baseboard_fab2_lib.baseboard_fab2(sch_1):page136_i128:a"
				( attribute "PN" "1"
					( Origin gPackager )
				)
				( objectStatus "C8E8.1" )
			)
			( pin "@baseboard_fab2_lib.baseboard_fab2(sch_1):page136_i128:b"
				( attribute "PN" "2"
					( Origin gPackager )
				)
				( objectStatus "C8E8.2" )
			)
			( pin "@baseboard_fab2_lib.baseboard_fab2(sch_1):page136_i130:a"
				( attribute "PN" "2"
					( Origin gPackager )
				)
				( objectStatus "U8E3.2" )
			)
			( pin "@baseboard_fab2_lib.baseboard_fab2(sch_1):page136_i130:oe"
				( attribute "PN" "1"
					( Origin gPackager )
				)
				( objectStatus "U8E3.1" )
			)
			( pin "@baseboard_fab2_lib.baseboard_fab2(sch_1):page136_i130:y"
				( attribute "PN" "4"
					( Origin gPackager )
				)
				( objectStatus "U8E3.4" )
			)
			( pin "@baseboard_fab2_lib.baseboard_fab2(sch_1):page136_i133:a"
				( attribute "PN" "1"
					( Origin gPackager )
				)
				( objectStatus "R8E14.1" )
			)
			( pin "@baseboard_fab2_lib.baseboard_fab2(sch_1):page136_i133:b"
				( attribute "PN" "2"
					( Origin gPackager )
				)
				( objectStatus "R8E14.2" )
			)
			( pin "@baseboard_fab2_lib.baseboard_fab2(sch_1):page136_i134:drn"
				( attribute "PN" "3"
					( Origin gPackager )
				)
				( objectStatus "Q8E1.3" )
			)
			( pin "@baseboard_fab2_lib.baseboard_fab2(sch_1):page136_i134:gate"
				( attribute "PN" "1"
					( Origin gPackager )
				)
				( objectStatus "Q8E1.1" )
			)
			( pin "@baseboard_fab2_lib.baseboard_fab2(sch_1):page136_i134:src"
				( attribute "PN" "2"
					( Origin gPackager )
				)
				( objectStatus "Q8E1.2" )
			)
			( pin "@baseboard_fab2_lib.baseboard_fab2(sch_1):page136_i139:a"
				( attribute "PN" "1"
					( Origin gPackager )
				)
				( objectStatus "R7G31.1" )
			)
			( pin "@baseboard_fab2_lib.baseboard_fab2(sch_1):page136_i139:b"
				( attribute "PN" "2"
					( Origin gPackager )
				)
				( objectStatus "R7G31.2" )
			)
			( pin "@baseboard_fab2_lib.baseboard_fab2(sch_1):page136_i140:a"
				( attribute "PN" "1"
					( Origin gPackager )
				)
				( objectStatus "R8E16.1" )
			)
			( pin "@baseboard_fab2_lib.baseboard_fab2(sch_1):page136_i140:b"
				( attribute "PN" "2"
					( Origin gPackager )
				)
				( objectStatus "R8E16.2" )
			)
			( pin "@baseboard_fab2_lib.baseboard_fab2(sch_1):page136_i147:a"
				( attribute "PN" "1"
					( Origin gPackager )
				)
				( objectStatus "R2N28.1" )
			)
			( pin "@baseboard_fab2_lib.baseboard_fab2(sch_1):page136_i147:b"
				( attribute "PN" "2"
					( Origin gPackager )
				)
				( objectStatus "R2N28.2" )
			)
			( pin "@baseboard_fab2_lib.baseboard_fab2(sch_1):page136_i148:a"
				( attribute "PN" "1"
					( Origin gPackager )
				)
				( objectStatus "R7G29.1" )
			)
			( pin "@baseboard_fab2_lib.baseboard_fab2(sch_1):page136_i148:b"
				( attribute "PN" "2"
					( Origin gPackager )
				)
				( objectStatus "R7G29.2" )
			)
			( pin "@baseboard_fab2_lib.baseboard_fab2(sch_1):page136_i155:a"
				( attribute "PN" "1"
					( Origin gPackager )
				)
				( objectStatus "R7G27.1" )
			)
			( pin "@baseboard_fab2_lib.baseboard_fab2(sch_1):page136_i155:b"
				( attribute "PN" "2"
					( Origin gPackager )
				)
				( objectStatus "R7G27.2" )
			)
			( pin "@baseboard_fab2_lib.baseboard_fab2(sch_1):page136_i156:a"
				( attribute "PN" "1"
					( Origin gPackager )
				)
				( objectStatus "R3T14.1" )
			)
			( pin "@baseboard_fab2_lib.baseboard_fab2(sch_1):page136_i156:b"
				( attribute "PN" "2"
					( Origin gPackager )
				)
				( objectStatus "R3T14.2" )
			)
			( pin "@baseboard_fab2_lib.baseboard_fab2(sch_1):page136_i174:io1"
				( attribute "PN" "1"
					( Origin gPackager )
				)
				( objectStatus "J7G3.1" )
			)
			( pin "@baseboard_fab2_lib.baseboard_fab2(sch_1):page136_i174:io2"
				( attribute "PN" "2"
					( Origin gPackager )
				)
				( objectStatus "J7G3.2" )
			)
			( pin "@baseboard_fab2_lib.baseboard_fab2(sch_1):page136_i174:io3"
				( attribute "PN" "3"
					( Origin gPackager )
				)
				( objectStatus "J7G3.3" )
			)
			( pin "@baseboard_fab2_lib.baseboard_fab2(sch_1):page136_i174:io4"
				( attribute "PN" "4"
					( Origin gPackager )
				)
				( objectStatus "J7G3.4" )
			)
			( pin "@baseboard_fab2_lib.baseboard_fab2(sch_1):page136_i174:io5"
				( attribute "PN" "5"
					( Origin gPackager )
				)
				( objectStatus "J7G3.5" )
			)
			( pin "@baseboard_fab2_lib.baseboard_fab2(sch_1):page136_i174:io6"
				( attribute "PN" "6"
					( Origin gPackager )
				)
				( objectStatus "J7G3.6" )
			)
			( pin "@baseboard_fab2_lib.baseboard_fab2(sch_1):page136_i174:io7"
				( attribute "PN" "7"
					( Origin gPackager )
				)
				( objectStatus "J7G3.7" )
			)
			( pin "@baseboard_fab2_lib.baseboard_fab2(sch_1):page136_i174:io8"
				( attribute "PN" "8"
					( Origin gPackager )
				)
				( objectStatus "J7G3.8" )
			)
			( pin "@baseboard_fab2_lib.baseboard_fab2(sch_1):page136_i174:io9"
				( attribute "PN" "9"
					( Origin gPackager )
				)
				( objectStatus "J7G3.9" )
			)
			( pin "@baseboard_fab2_lib.baseboard_fab2(sch_1):page136_i174:io10"
				( attribute "PN" "10"
					( Origin gPackager )
				)
				( objectStatus "J7G3.10" )
			)
			( pin "@baseboard_fab2_lib.baseboard_fab2(sch_1):page136_i174:io11"
				( attribute "PN" "11"
					( Origin gPackager )
				)
				( objectStatus "J7G3.11" )
			)
			( pin "@baseboard_fab2_lib.baseboard_fab2(sch_1):page136_i174:io12"
				( attribute "PN" "12"
					( Origin gPackager )
				)
				( objectStatus "J7G3.12" )
			)
			( pin "@baseboard_fab2_lib.baseboard_fab2(sch_1):page137_i11:a"
				( attribute "PN" "1"
					( Origin gPackager )
				)
				( objectStatus "R7C11.1" )
			)
			( pin "@baseboard_fab2_lib.baseboard_fab2(sch_1):page137_i11:b"
				( attribute "PN" "2"
					( Origin gPackager )
				)
				( objectStatus "R7C11.2" )
			)
			( pin "@baseboard_fab2_lib.baseboard_fab2(sch_1):page137_i13:a"
				( attribute "PN" "1"
					( Origin gPackager )
				)
				( objectStatus "R7C10.1" )
			)
			( pin "@baseboard_fab2_lib.baseboard_fab2(sch_1):page137_i13:b"
				( attribute "PN" "2"
					( Origin gPackager )
				)
				( objectStatus "R7C10.2" )
			)
			( pin "@baseboard_fab2_lib.baseboard_fab2(sch_1):page137_i14:a"
				( attribute "PN" "1"
					( Origin gPackager )
				)
				( objectStatus "C7C19.1" )
			)
			( pin "@baseboard_fab2_lib.baseboard_fab2(sch_1):page137_i14:b"
				( attribute "PN" "2"
					( Origin gPackager )
				)
				( objectStatus "C7C19.2" )
			)
			( pin "@baseboard_fab2_lib.baseboard_fab2(sch_1):page137_i15:a"
				( attribute "PN" "1"
					( Origin gPackager )
				)
				( objectStatus "R1U63.1" )
			)
			( pin "@baseboard_fab2_lib.baseboard_fab2(sch_1):page137_i15:b"
				( attribute "PN" "2"
					( Origin gPackager )
				)
				( objectStatus "R1U63.2" )
			)
			( pin "@baseboard_fab2_lib.baseboard_fab2(sch_1):page137_i19:a"
				( attribute "PN" "1"
					( Origin gPackager )
				)
				( objectStatus "R3N4.1" )
			)
			( pin "@baseboard_fab2_lib.baseboard_fab2(sch_1):page137_i19:b"
				( attribute "PN" "2"
					( Origin gPackager )
				)
				( objectStatus "R3N4.2" )
			)
			( pin "@baseboard_fab2_lib.baseboard_fab2(sch_1):page137_i20:a"
				( attribute "PN" "1"
					( Origin gPackager )
				)
				( objectStatus "C3N32.1" )
			)
			( pin "@baseboard_fab2_lib.baseboard_fab2(sch_1):page137_i20:b"
				( attribute "PN" "2"
					( Origin gPackager )
				)
				( objectStatus "C3N32.2" )
			)
			( pin "@baseboard_fab2_lib.baseboard_fab2(sch_1):page137_i67:a"
				( attribute "PN" "1"
					( Origin gPackager )
				)
				( objectStatus "R7C13.1" )
			)
			( pin "@baseboard_fab2_lib.baseboard_fab2(sch_1):page137_i67:b"
				( attribute "PN" "2"
					( Origin gPackager )
				)
				( objectStatus "R7C13.2" )
			)
			( pin "@baseboard_fab2_lib.baseboard_fab2(sch_1):page137_i69:a"
				( attribute "PN" "1"
					( Origin gPackager )
				)
				( objectStatus "R1U64.1" )
			)
			( pin "@baseboard_fab2_lib.baseboard_fab2(sch_1):page137_i69:b"
				( attribute "PN" "2"
					( Origin gPackager )
				)
				( objectStatus "R1U64.2" )
			)
			( pin "@baseboard_fab2_lib.baseboard_fab2(sch_1):page137_i128:io1"
				( attribute "PN" "1"
					( Origin gPackager )
				)
				( objectStatus "J9G1.1" )
			)
			( pin "@baseboard_fab2_lib.baseboard_fab2(sch_1):page137_i128:io2"
				( attribute "PN" "2"
					( Origin gPackager )
				)
				( objectStatus "J9G1.2" )
			)
			( pin "@baseboard_fab2_lib.baseboard_fab2(sch_1):page137_i128:io3"
				( attribute "PN" "3"
					( Origin gPackager )
				)
				( objectStatus "J9G1.3" )
			)
			( pin "@baseboard_fab2_lib.baseboard_fab2(sch_1):page137_i128:io4"
				( attribute "PN" "4"
					( Origin gPackager )
				)
				( objectStatus "J9G1.4" )
			)
			( pin "@baseboard_fab2_lib.baseboard_fab2(sch_1):page137_i128:io5"
				( attribute "PN" "5"
					( Origin gPackager )
				)
				( objectStatus "J9G1.5" )
			)
			( pin "@baseboard_fab2_lib.baseboard_fab2(sch_1):page137_i128:io6"
				( attribute "PN" "6"
					( Origin gPackager )
				)
				( objectStatus "J9G1.6" )
			)
			( pin "@baseboard_fab2_lib.baseboard_fab2(sch_1):page137_i128:io7"
				( attribute "PN" "7"
					( Origin gPackager )
				)
				( objectStatus "J9G1.7" )
			)
			( pin "@baseboard_fab2_lib.baseboard_fab2(sch_1):page137_i128:io8"
				( attribute "PN" "8"
					( Origin gPackager )
				)
				( objectStatus "J9G1.8" )
			)
			( pin "@baseboard_fab2_lib.baseboard_fab2(sch_1):page137_i128:io9"
				( attribute "PN" "9"
					( Origin gPackager )
				)
				( objectStatus "J9G1.9" )
			)
			( pin "@baseboard_fab2_lib.baseboard_fab2(sch_1):page137_i128:io10"
				( attribute "PN" "10"
					( Origin gPackager )
				)
				( objectStatus "J9G1.10" )
			)
			( pin "@baseboard_fab2_lib.baseboard_fab2(sch_1):page137_i128:io11"
				( attribute "PN" "11"
					( Origin gPackager )
				)
				( objectStatus "J9G1.11" )
			)
			( pin "@baseboard_fab2_lib.baseboard_fab2(sch_1):page137_i128:io12"
				( attribute "PN" "12"
					( Origin gPackager )
				)
				( objectStatus "J9G1.12" )
			)
			( pin "@baseboard_fab2_lib.baseboard_fab2(sch_1):page138_i83:a"
				( attribute "PN" "1"
					( Origin gPackager )
				)
				( objectStatus "R2T53.1" )
			)
			( pin "@baseboard_fab2_lib.baseboard_fab2(sch_1):page138_i83:b"
				( attribute "PN" "2"
					( Origin gPackager )
				)
				( objectStatus "R2T53.2" )
			)
			( pin "@baseboard_fab2_lib.baseboard_fab2(sch_1):page138_i84:a"
				( attribute "PN" "1"
					( Origin gPackager )
				)
				( objectStatus "R2T54.1" )
			)
			( pin "@baseboard_fab2_lib.baseboard_fab2(sch_1):page138_i84:b"
				( attribute "PN" "2"
					( Origin gPackager )
				)
				( objectStatus "R2T54.2" )
			)
			( pin "@baseboard_fab2_lib.baseboard_fab2(sch_1):page138_i87:a"
				( attribute "PN" "1"
					( Origin gPackager )
				)
				( objectStatus "R8D17.1" )
			)
			( pin "@baseboard_fab2_lib.baseboard_fab2(sch_1):page138_i87:b"
				( attribute "PN" "2"
					( Origin gPackager )
				)
				( objectStatus "R8D17.2" )
			)
			( pin "@baseboard_fab2_lib.baseboard_fab2(sch_1):page138_i88:a"
				( attribute "PN" "1"
					( Origin gPackager )
				)
				( objectStatus "R8D15.1" )
			)
			( pin "@baseboard_fab2_lib.baseboard_fab2(sch_1):page138_i88:b"
				( attribute "PN" "2"
					( Origin gPackager )
				)
				( objectStatus "R8D15.2" )
			)
			( pin "@baseboard_fab2_lib.baseboard_fab2(sch_1):page138_i89:a"
				( attribute "PN" "1"
					( Origin gPackager )
				)
				( objectStatus "R2N8.1" )
			)
			( pin "@baseboard_fab2_lib.baseboard_fab2(sch_1):page138_i89:b"
				( attribute "PN" "2"
					( Origin gPackager )
				)
				( objectStatus "R2N8.2" )
			)
			( pin "@baseboard_fab2_lib.baseboard_fab2(sch_1):page138_i90:a"
				( attribute "PN" "1"
					( Origin gPackager )
				)
				( objectStatus "R2N5.1" )
			)
			( pin "@baseboard_fab2_lib.baseboard_fab2(sch_1):page138_i90:b"
				( attribute "PN" "2"
					( Origin gPackager )
				)
				( objectStatus "R2N5.2" )
			)
			( pin "@baseboard_fab2_lib.baseboard_fab2(sch_1):page138_i97:a"
				( attribute "PN" "1"
					( Origin gPackager )
				)
				( objectStatus "R2U11.1" )
			)
			( pin "@baseboard_fab2_lib.baseboard_fab2(sch_1):page138_i97:b"
				( attribute "PN" "2"
					( Origin gPackager )
				)
				( objectStatus "R2U11.2" )
			)
			( pin "@baseboard_fab2_lib.baseboard_fab2(sch_1):page138_i98:a"
				( attribute "PN" "1"
					( Origin gPackager )
				)
				( objectStatus "R2U3.1" )
			)
			( pin "@baseboard_fab2_lib.baseboard_fab2(sch_1):page138_i98:b"
				( attribute "PN" "2"
					( Origin gPackager )
				)
				( objectStatus "R2U3.2" )
			)
			( pin "@baseboard_fab2_lib.baseboard_fab2(sch_1):page138_i158:a"
				( attribute "PN" "1"
					( Origin gPackager )
				)
				( objectStatus "R2U8.1" )
			)
			( pin "@baseboard_fab2_lib.baseboard_fab2(sch_1):page138_i158:b"
				( attribute "PN" "2"
					( Origin gPackager )
				)
				( objectStatus "R2U8.2" )
			)
			( pin "@baseboard_fab2_lib.baseboard_fab2(sch_1):page138_i159:a"
				( attribute "PN" "1"
					( Origin gPackager )
				)
				( objectStatus "R2U12.1" )
			)
			( pin "@baseboard_fab2_lib.baseboard_fab2(sch_1):page138_i159:b"
				( attribute "PN" "2"
					( Origin gPackager )
				)
				( objectStatus "R2U12.2" )
			)
			( pin "@baseboard_fab2_lib.baseboard_fab2(sch_1):page247_i105:a"
				( attribute "PN" "1"
					( Origin gPackager )
				)
				( objectStatus "C6W4.1" )
			)
			( pin "@baseboard_fab2_lib.baseboard_fab2(sch_1):page247_i105:b"
				( attribute "PN" "2"
					( Origin gPackager )
				)
				( objectStatus "C6W4.2" )
			)
			( pin "@baseboard_fab2_lib.baseboard_fab2(sch_1):page138_i163:a"
				( attribute "PN" "1"
					( Origin gPackager )
				)
				( objectStatus "R8D7.1" )
			)
			( pin "@baseboard_fab2_lib.baseboard_fab2(sch_1):page138_i163:b"
				( attribute "PN" "2"
					( Origin gPackager )
				)
				( objectStatus "R8D7.2" )
			)
			( pin "@baseboard_fab2_lib.baseboard_fab2(sch_1):page138_i164:a"
				( attribute "PN" "1"
					( Origin gPackager )
				)
				( objectStatus "R8D4.1" )
			)
			( pin "@baseboard_fab2_lib.baseboard_fab2(sch_1):page138_i164:b"
				( attribute "PN" "2"
					( Origin gPackager )
				)
				( objectStatus "R8D4.2" )
			)
			( pin "@baseboard_fab2_lib.baseboard_fab2(sch_1):page138_i165:a"
				( attribute "PN" "1"
					( Origin gPackager )
				)
				( objectStatus "R2U9.1" )
			)
			( pin "@baseboard_fab2_lib.baseboard_fab2(sch_1):page138_i165:b"
				( attribute "PN" "2"
					( Origin gPackager )
				)
				( objectStatus "R2U9.2" )
			)
			( pin "@baseboard_fab2_lib.baseboard_fab2(sch_1):page138_i166:a"
				( attribute "PN" "1"
					( Origin gPackager )
				)
				( objectStatus "R2U6.1" )
			)
			( pin "@baseboard_fab2_lib.baseboard_fab2(sch_1):page138_i166:b"
				( attribute "PN" "2"
					( Origin gPackager )
				)
				( objectStatus "R2U6.2" )
			)
			( pin "@baseboard_fab2_lib.baseboard_fab2(sch_1):page138_i167:a"
				( attribute "PN" "1"
					( Origin gPackager )
				)
				( objectStatus "R8C20.1" )
			)
			( pin "@baseboard_fab2_lib.baseboard_fab2(sch_1):page138_i167:b"
				( attribute "PN" "2"
					( Origin gPackager )
				)
				( objectStatus "R8C20.2" )
			)
			( pin "@baseboard_fab2_lib.baseboard_fab2(sch_1):page138_i168:a"
				( attribute "PN" "1"
					( Origin gPackager )
				)
				( objectStatus "R8C14.1" )
			)
			( pin "@baseboard_fab2_lib.baseboard_fab2(sch_1):page138_i168:b"
				( attribute "PN" "2"
					( Origin gPackager )
				)
				( objectStatus "R8C14.2" )
			)
			( pin "@baseboard_fab2_lib.baseboard_fab2(sch_1):page138_i169:a"
				( attribute "PN" "1"
					( Origin gPackager )
				)
				( objectStatus "R8C11.1" )
			)
			( pin "@baseboard_fab2_lib.baseboard_fab2(sch_1):page138_i169:b"
				( attribute "PN" "2"
					( Origin gPackager )
				)
				( objectStatus "R8C11.2" )
			)
			( pin "@baseboard_fab2_lib.baseboard_fab2(sch_1):page138_i170:a"
				( attribute "PN" "1"
					( Origin gPackager )
				)
				( objectStatus "R8C12.1" )
			)
			( pin "@baseboard_fab2_lib.baseboard_fab2(sch_1):page138_i170:b"
				( attribute "PN" "2"
					( Origin gPackager )
				)
				( objectStatus "R8C12.2" )
			)
			( pin "@baseboard_fab2_lib.baseboard_fab2(sch_1):page138_i171:a"
				( attribute "PN" "1"
					( Origin gPackager )
				)
				( objectStatus "R2N20.1" )
			)
			( pin "@baseboard_fab2_lib.baseboard_fab2(sch_1):page138_i171:b"
				( attribute "PN" "2"
					( Origin gPackager )
				)
				( objectStatus "R2N20.2" )
			)
			( pin "@baseboard_fab2_lib.baseboard_fab2(sch_1):page138_i175:a"
				( attribute "PN" "1"
					( Origin gPackager )
				)
				( objectStatus "R2N21.1" )
			)
			( pin "@baseboard_fab2_lib.baseboard_fab2(sch_1):page138_i175:b"
				( attribute "PN" "2"
					( Origin gPackager )
				)
				( objectStatus "R2N21.2" )
			)
			( pin "@baseboard_fab2_lib.baseboard_fab2(sch_1):page139_i72:cbot"
				( attribute "PN" "37"
					( Origin gPackager )
				)
				( objectStatus "EU9E1.37" )
			)
			( pin "@baseboard_fab2_lib.baseboard_fab2(sch_1):page139_i72:ctop"
				( attribute "PN" "40"
					( Origin gPackager )
				)
				( objectStatus "EU9E1.40" )
			)
			( pin "@baseboard_fab2_lib.baseboard_fab2(sch_1):page139_i72:dev_off_n"
				( attribute "PN" "28"
					( Origin gPackager )
				)
				( objectStatus "EU9E1.28" )
			)
			( pin "@baseboard_fab2_lib.baseboard_fab2(sch_1):page139_i72:gnd"
				( attribute "PN" "65"
					( Origin gPackager )
				)
				( objectStatus "EU9E1.65" )
			)
			( pin "@baseboard_fab2_lib.baseboard_fab2(sch_1):page139_i72:jtag_clk"
				( attribute "PN" "19"
					( Origin gPackager )
				)
				( objectStatus "EU9E1.19" )
			)
			( pin "@baseboard_fab2_lib.baseboard_fab2(sch_1):page139_i72:jtag_tdi"
				( attribute "PN" "29"
					( Origin gPackager )
				)
				( objectStatus "EU9E1.29" )
			)
			( pin "@baseboard_fab2_lib.baseboard_fab2(sch_1):page139_i72:jtag_tdo"
				( attribute "PN" "4"
					( Origin gPackager )
				)
				( objectStatus "EU9E1.4" )
			)
			( pin "@baseboard_fab2_lib.baseboard_fab2(sch_1):page139_i72:jtag_tms"
				( attribute "PN" "18"
					( Origin gPackager )
				)
				( objectStatus "EU9E1.18" )
			)
			( pin "@baseboard_fab2_lib.baseboard_fab2(sch_1):page139_i72:lan_pwr_good"
				( attribute "PN" "1"
					( Origin gPackager )
				)
				( objectStatus "EU9E1.1" )
			)
			( pin "@baseboard_fab2_lib.baseboard_fab2(sch_1):page139_i72:led0"
				( attribute "PN" "31"
					( Origin gPackager )
				)
				( objectStatus "EU9E1.31" )
			)
			( pin "@baseboard_fab2_lib.baseboard_fab2(sch_1):page139_i72:led1"
				( attribute "PN" "30"
					( Origin gPackager )
				)
				( objectStatus "EU9E1.30" )
			)
			( pin "@baseboard_fab2_lib.baseboard_fab2(sch_1):page139_i72:led2"
				( attribute "PN" "33"
					( Origin gPackager )
				)
				( objectStatus "EU9E1.33" )
			)
			( pin "@baseboard_fab2_lib.baseboard_fab2(sch_1):page139_i72:mdi_minus0_sfp_i2c_data"
				( attribute "PN" "57"
					( Origin gPackager )
				)
				( objectStatus "EU9E1.57" )
			)
			( pin "@baseboard_fab2_lib.baseboard_fab2(sch_1):page139_i72:mdi_minus1_srds_sig_det"
				( attribute "PN" "54"
					( Origin gPackager )
				)
				( objectStatus "EU9E1.54" )
			)
			( pin "@baseboard_fab2_lib.baseboard_fab2(sch_1):page139_i72:mdi_minus2_setn"
				( attribute "PN" "52"
					( Origin gPackager )
				)
				( objectStatus "EU9E1.52" )
			)
			( pin "@baseboard_fab2_lib.baseboard_fab2(sch_1):page139_i72:mdi_minus3_sern"
				( attribute "PN" "49"
					( Origin gPackager )
				)
				( objectStatus "EU9E1.49" )
			)
			( pin "@baseboard_fab2_lib.baseboard_fab2(sch_1):page139_i72:mdi_plus0_nc"
				( attribute "PN" "58"
					( Origin gPackager )
				)
				( objectStatus "EU9E1.58" )
			)
			( pin "@baseboard_fab2_lib.baseboard_fab2(sch_1):page139_i72:mdi_plus1_sfp_i2c_clk"
				( attribute "PN" "55"
					( Origin gPackager )
				)
				( objectStatus "EU9E1.55" )
			)
			( pin "@baseboard_fab2_lib.baseboard_fab2(sch_1):page139_i72:mdi_plus2_setp"
				( attribute "PN" "53"
					( Origin gPackager )
				)
				( objectStatus "EU9E1.53" )
			)
			( pin "@baseboard_fab2_lib.baseboard_fab2(sch_1):page139_i72:mdi_plus3_serp"
				( attribute "PN" "50"
					( Origin gPackager )
				)
				( objectStatus "EU9E1.50" )
			)
			( pin "@baseboard_fab2_lib.baseboard_fab2(sch_1):page139_i72:nc"
				( attribute "PN" "22"
					( Origin gPackager )
				)
				( objectStatus "EU9E1.22" )
			)
			( pin "@baseboard_fab2_lib.baseboard_fab2(sch_1):page139_i72:nc_si_arb_in"
				( attribute "PN" "43"
					( Origin gPackager )
				)
				( objectStatus "EU9E1.43" )
			)
			( pin "@baseboard_fab2_lib.baseboard_fab2(sch_1):page139_i72:nc_si_arb_out"
				( attribute "PN" "44"
					( Origin gPackager )
				)
				( objectStatus "EU9E1.44" )
			)
			( pin "@baseboard_fab2_lib.baseboard_fab2(sch_1):page139_i72:nc_si_clk_in"
				( attribute "PN" "2"
					( Origin gPackager )
				)
				( objectStatus "EU9E1.2" )
			)
			( pin "@baseboard_fab2_lib.baseboard_fab2(sch_1):page139_i72:nc_si_crs_dv"
				( attribute "PN" "3"
					( Origin gPackager )
				)
				( objectStatus "EU9E1.3" )
			)
			( pin "@baseboard_fab2_lib.baseboard_fab2(sch_1):page139_i72:nc_si_rxd0"
				( attribute "PN" "6"
					( Origin gPackager )
				)
				( objectStatus "EU9E1.6" )
			)
			( pin "@baseboard_fab2_lib.baseboard_fab2(sch_1):page139_i72:nc_si_rxd1"
				( attribute "PN" "5"
					( Origin gPackager )
				)
				( objectStatus "EU9E1.5" )
			)
			( pin "@baseboard_fab2_lib.baseboard_fab2(sch_1):page139_i72:nc_si_tx_en"
				( attribute "PN" "7"
					( Origin gPackager )
				)
				( objectStatus "EU9E1.7" )
			)
			( pin "@baseboard_fab2_lib.baseboard_fab2(sch_1):page139_i72:nc_si_txd0"
				( attribute "PN" "9"
					( Origin gPackager )
				)
				( objectStatus "EU9E1.9" )
			)
			( pin "@baseboard_fab2_lib.baseboard_fab2(sch_1):page139_i72:nc_si_txd1"
				( attribute "PN" "8"
					( Origin gPackager )
				)
				( objectStatus "EU9E1.8" )
			)
			( pin "@baseboard_fab2_lib.baseboard_fab2(sch_1):page139_i72:nvm_cs_n"
				( attribute "PN" "15"
					( Origin gPackager )
				)
				( objectStatus "EU9E1.15" )
			)
			( pin "@baseboard_fab2_lib.baseboard_fab2(sch_1):page139_i72:nvm_si"
				( attribute "PN" "12"
					( Origin gPackager )
				)
				( objectStatus "EU9E1.12" )
			)
			( pin "@baseboard_fab2_lib.baseboard_fab2(sch_1):page139_i72:nvm_sk"
				( attribute "PN" "13"
					( Origin gPackager )
				)
				( objectStatus "EU9E1.13" )
			)
			( pin "@baseboard_fab2_lib.baseboard_fab2(sch_1):page139_i72:nvm_so"
				( attribute "PN" "14"
					( Origin gPackager )
				)
				( objectStatus "EU9E1.14" )
			)
			( pin "@baseboard_fab2_lib.baseboard_fab2(sch_1):page139_i72:pe_rn"
				( attribute "PN" "23"
					( Origin gPackager )
				)
				( objectStatus "EU9E1.23" )
			)
			( pin "@baseboard_fab2_lib.baseboard_fab2(sch_1):page139_i72:pe_rp"
				( attribute "PN" "24"
					( Origin gPackager )
				)
				( objectStatus "EU9E1.24" )
			)
			( pin "@baseboard_fab2_lib.baseboard_fab2(sch_1):page139_i72:pe_rst_n"
				( attribute "PN" "17"
					( Origin gPackager )
				)
				( objectStatus "EU9E1.17" )
			)
			( pin "@baseboard_fab2_lib.baseboard_fab2(sch_1):page139_i72:pe_tn"
				( attribute "PN" "20"
					( Origin gPackager )
				)
				( objectStatus "EU9E1.20" )
			)
			( pin "@baseboard_fab2_lib.baseboard_fab2(sch_1):page139_i72:pe_tp"
				( attribute "PN" "21"
					( Origin gPackager )
				)
				( objectStatus "EU9E1.21" )
			)
			( pin "@baseboard_fab2_lib.baseboard_fab2(sch_1):page139_i72:pe_wake_n"
				( attribute "PN" "16"
					( Origin gPackager )
				)
				( objectStatus "EU9E1.16" )
			)
			( pin "@baseboard_fab2_lib.baseboard_fab2(sch_1):page139_i72:peclkn"
				( attribute "PN" "25"
					( Origin gPackager )
				)
				( objectStatus "EU9E1.25" )
			)
			( pin "@baseboard_fab2_lib.baseboard_fab2(sch_1):page139_i72:peclkp"
				( attribute "PN" "26"
					( Origin gPackager )
				)
				( objectStatus "EU9E1.26" )
			)
			( pin "@baseboard_fab2_lib.baseboard_fab2(sch_1):page139_i72:rset"
				( attribute "PN" "48"
					( Origin gPackager )
				)
				( objectStatus "EU9E1.48" )
			)
			( pin "@baseboard_fab2_lib.baseboard_fab2(sch_1):page139_i72:sdp0"
				( attribute "PN" "63"
					( Origin gPackager )
				)
				( objectStatus "EU9E1.63" )
			)
			( pin "@baseboard_fab2_lib.baseboard_fab2(sch_1):page139_i72:sdp1_pcie_dis_sdp1"
				( attribute "PN" "61"
					( Origin gPackager )
				)
				( objectStatus "EU9E1.61" )
			)
			( pin "@baseboard_fab2_lib.baseboard_fab2(sch_1):page139_i72:sdp2"
				( attribute "PN" "62"
					( Origin gPackager )
				)
				( objectStatus "EU9E1.62" )
			)
			( pin "@baseboard_fab2_lib.baseboard_fab2(sch_1):page139_i72:sdp3"
				( attribute "PN" "60"
					( Origin gPackager )
				)
				( objectStatus "EU9E1.60" )
			)
			( pin "@baseboard_fab2_lib.baseboard_fab2(sch_1):page139_i72:smb_alrt_n"
				( attribute "PN" "35"
					( Origin gPackager )
				)
				( objectStatus "EU9E1.35" )
			)
			( pin "@baseboard_fab2_lib.baseboard_fab2(sch_1):page139_i72:smb_clk"
				( attribute "PN" "34"
					( Origin gPackager )
				)
				( objectStatus "EU9E1.34" )
			)
			( pin "@baseboard_fab2_lib.baseboard_fab2(sch_1):page139_i72:smb_data"
				( attribute "PN" "36"
					( Origin gPackager )
				)
				( objectStatus "EU9E1.36" )
			)
			( pin "@baseboard_fab2_lib.baseboard_fab2(sch_1):page139_i72:vdd0p9(0)"
				( attribute "PN" "59"
					( Origin gPackager )
				)
				( objectStatus "EU9E1.59" )
			)
			( pin "@baseboard_fab2_lib.baseboard_fab2(sch_1):page139_i72:vdd0p9(1)"
				( attribute "PN" "32"
					( Origin gPackager )
				)
				( objectStatus "EU9E1.32" )
			)
			( pin "@baseboard_fab2_lib.baseboard_fab2(sch_1):page139_i72:vdd0p9(2)"
				( attribute "PN" "11"
					( Origin gPackager )
				)
				( objectStatus "EU9E1.11" )
			)
			( pin "@baseboard_fab2_lib.baseboard_fab2(sch_1):page139_i72:vdd0p9(3)"
				( attribute "PN" "42"
					( Origin gPackager )
				)
				( objectStatus "EU9E1.42" )
			)
			( pin "@baseboard_fab2_lib.baseboard_fab2(sch_1):page139_i72:vdd0p9_out"
				( attribute "PN" "38"
					( Origin gPackager )
				)
				( objectStatus "EU9E1.38" )
			)
			( pin "@baseboard_fab2_lib.baseboard_fab2(sch_1):page139_i72:vdd1p5(0)"
				( attribute "PN" "56"
					( Origin gPackager )
				)
				( objectStatus "EU9E1.56" )
			)
			( pin "@baseboard_fab2_lib.baseboard_fab2(sch_1):page139_i72:vdd1p5(1)"
				( attribute "PN" "47"
					( Origin gPackager )
				)
				( objectStatus "EU9E1.47" )
			)
			( pin "@baseboard_fab2_lib.baseboard_fab2(sch_1):page139_i72:vdd1p5_out"
				( attribute "PN" "39"
					( Origin gPackager )
				)
				( objectStatus "EU9E1.39" )
			)
			( pin "@baseboard_fab2_lib.baseboard_fab2(sch_1):page139_i72:vdd3p3(0)"
				( attribute "PN" "64"
					( Origin gPackager )
				)
				( objectStatus "EU9E1.64" )
			)
			( pin "@baseboard_fab2_lib.baseboard_fab2(sch_1):page139_i72:vdd3p3(1)"
				( attribute "PN" "51"
					( Origin gPackager )
				)
				( objectStatus "EU9E1.51" )
			)
			( pin "@baseboard_fab2_lib.baseboard_fab2(sch_1):page139_i72:vdd3p3(2)"
				( attribute "PN" "41"
					( Origin gPackager )
				)
				( objectStatus "EU9E1.41" )
			)
			( pin "@baseboard_fab2_lib.baseboard_fab2(sch_1):page139_i72:vdd3p3(3)"
				( attribute "PN" "27"
					( Origin gPackager )
				)
				( objectStatus "EU9E1.27" )
			)
			( pin "@baseboard_fab2_lib.baseboard_fab2(sch_1):page139_i72:vdd3p3(4)"
				( attribute "PN" "10"
					( Origin gPackager )
				)
				( objectStatus "EU9E1.10" )
			)
			( pin "@baseboard_fab2_lib.baseboard_fab2(sch_1):page139_i72:xtal1"
				( attribute "PN" "46"
					( Origin gPackager )
				)
				( objectStatus "EU9E1.46" )
			)
			( pin "@baseboard_fab2_lib.baseboard_fab2(sch_1):page139_i72:xtal2"
				( attribute "PN" "45"
					( Origin gPackager )
				)
				( objectStatus "EU9E1.45" )
			)
			( pin "@baseboard_fab2_lib.baseboard_fab2(sch_1):page139_i76:a"
				( attribute "PN" "1"
					( Origin gPackager )
				)
				( objectStatus "C9E7.1" )
			)
			( pin "@baseboard_fab2_lib.baseboard_fab2(sch_1):page139_i76:b"
				( attribute "PN" "2"
					( Origin gPackager )
				)
				( objectStatus "C9E7.2" )
			)
			( pin "@baseboard_fab2_lib.baseboard_fab2(sch_1):page139_i87:a"
				( attribute "PN" "1"
					( Origin gPackager )
				)
				( objectStatus "C9E5.1" )
			)
			( pin "@baseboard_fab2_lib.baseboard_fab2(sch_1):page139_i87:b"
				( attribute "PN" "2"
					( Origin gPackager )
				)
				( objectStatus "C9E5.2" )
			)
			( pin "@baseboard_fab2_lib.baseboard_fab2(sch_1):page139_i88:a"
				( attribute "PN" "1"
					( Origin gPackager )
				)
				( objectStatus "C9E4.1" )
			)
			( pin "@baseboard_fab2_lib.baseboard_fab2(sch_1):page139_i88:b"
				( attribute "PN" "2"
					( Origin gPackager )
				)
				( objectStatus "C9E4.2" )
			)
			( pin "@baseboard_fab2_lib.baseboard_fab2(sch_1):page139_i89:a"
				( attribute "PN" "1"
					( Origin gPackager )
				)
				( objectStatus "C2M23.1" )
			)
			( pin "@baseboard_fab2_lib.baseboard_fab2(sch_1):page139_i89:b"
				( attribute "PN" "2"
					( Origin gPackager )
				)
				( objectStatus "C2M23.2" )
			)
			( pin "@baseboard_fab2_lib.baseboard_fab2(sch_1):page139_i90:a"
				( attribute "PN" "1"
					( Origin gPackager )
				)
				( objectStatus "C2M24.1" )
			)
			( pin "@baseboard_fab2_lib.baseboard_fab2(sch_1):page139_i90:b"
				( attribute "PN" "2"
					( Origin gPackager )
				)
				( objectStatus "C2M24.2" )
			)
			( pin "@baseboard_fab2_lib.baseboard_fab2(sch_1):page139_i109:a"
				( attribute "PN" "1"
					( Origin gPackager )
				)
				( objectStatus "Y9E1.1" )
			)
			( pin "@baseboard_fab2_lib.baseboard_fab2(sch_1):page139_i109:b"
				( attribute "PN" "3"
					( Origin gPackager )
				)
				( objectStatus "Y9E1.3" )
			)
			( pin "@baseboard_fab2_lib.baseboard_fab2(sch_1):page139_i110:a"
				( attribute "PN" "1"
					( Origin gPackager )
				)
				( objectStatus "R9E20.1" )
			)
			( pin "@baseboard_fab2_lib.baseboard_fab2(sch_1):page139_i110:b"
				( attribute "PN" "2"
					( Origin gPackager )
				)
				( objectStatus "R9E20.2" )
			)
			( pin "@baseboard_fab2_lib.baseboard_fab2(sch_1):page185_i217:a"
				( attribute "PN" "1"
					( Origin gPackager )
				)
				( objectStatus "C32W5.1" )
			)
			( pin "@baseboard_fab2_lib.baseboard_fab2(sch_1):page185_i217:b"
				( attribute "PN" "2"
					( Origin gPackager )
				)
				( objectStatus "C32W5.2" )
			)
			( pin "@baseboard_fab2_lib.baseboard_fab2(sch_1):page139_i128:a"
				( attribute "PN" "1"
					( Origin gPackager )
				)
				( objectStatus "R9E9.1" )
			)
			( pin "@baseboard_fab2_lib.baseboard_fab2(sch_1):page139_i128:b"
				( attribute "PN" "2"
					( Origin gPackager )
				)
				( objectStatus "R9E9.2" )
			)
			( pin "@baseboard_fab2_lib.baseboard_fab2(sch_1):page139_i129:a"
				( attribute "PN" "1"
					( Origin gPackager )
				)
				( objectStatus "R9E5.1" )
			)
			( pin "@baseboard_fab2_lib.baseboard_fab2(sch_1):page139_i129:b"
				( attribute "PN" "2"
					( Origin gPackager )
				)
				( objectStatus "R9E5.2" )
			)
			( pin "@baseboard_fab2_lib.baseboard_fab2(sch_1):page139_i130:a"
				( attribute "PN" "1"
					( Origin gPackager )
				)
				( objectStatus "R9E8.1" )
			)
			( pin "@baseboard_fab2_lib.baseboard_fab2(sch_1):page139_i130:b"
				( attribute "PN" "2"
					( Origin gPackager )
				)
				( objectStatus "R9E8.2" )
			)
			( pin "@baseboard_fab2_lib.baseboard_fab2(sch_1):page139_i134:a"
				( attribute "PN" "1"
					( Origin gPackager )
				)
				( objectStatus "C1T4.1" )
			)
			( pin "@baseboard_fab2_lib.baseboard_fab2(sch_1):page139_i134:b"
				( attribute "PN" "2"
					( Origin gPackager )
				)
				( objectStatus "C1T4.2" )
			)
			( pin "@baseboard_fab2_lib.baseboard_fab2(sch_1):page139_i135:a"
				( attribute "PN" "1"
					( Origin gPackager )
				)
				( objectStatus "C1R30.1" )
			)
			( pin "@baseboard_fab2_lib.baseboard_fab2(sch_1):page139_i135:b"
				( attribute "PN" "2"
					( Origin gPackager )
				)
				( objectStatus "C1R30.2" )
			)
			( pin "@baseboard_fab2_lib.baseboard_fab2(sch_1):page139_i136:a"
				( attribute "PN" "1"
					( Origin gPackager )
				)
				( objectStatus "C1R22.1" )
			)
			( pin "@baseboard_fab2_lib.baseboard_fab2(sch_1):page139_i136:b"
				( attribute "PN" "2"
					( Origin gPackager )
				)
				( objectStatus "C1R22.2" )
			)
			( pin "@baseboard_fab2_lib.baseboard_fab2(sch_1):page139_i142:a"
				( attribute "PN" "1"
					( Origin gPackager )
				)
				( objectStatus "C1R13.1" )
			)
			( pin "@baseboard_fab2_lib.baseboard_fab2(sch_1):page139_i142:b"
				( attribute "PN" "2"
					( Origin gPackager )
				)
				( objectStatus "C1R13.2" )
			)
			( pin "@baseboard_fab2_lib.baseboard_fab2(sch_1):page139_i143:a"
				( attribute "PN" "1"
					( Origin gPackager )
				)
				( objectStatus "C1R20.1" )
			)
			( pin "@baseboard_fab2_lib.baseboard_fab2(sch_1):page139_i143:b"
				( attribute "PN" "2"
					( Origin gPackager )
				)
				( objectStatus "C1R20.2" )
			)
			( pin "@baseboard_fab2_lib.baseboard_fab2(sch_1):page139_i144:a"
				( attribute "PN" "1"
					( Origin gPackager )
				)
				( objectStatus "C1T3.1" )
			)
			( pin "@baseboard_fab2_lib.baseboard_fab2(sch_1):page139_i144:b"
				( attribute "PN" "2"
					( Origin gPackager )
				)
				( objectStatus "C1T3.2" )
			)
			( pin "@baseboard_fab2_lib.baseboard_fab2(sch_1):page139_i145:a"
				( attribute "PN" "1"
					( Origin gPackager )
				)
				( objectStatus "C1R14.1" )
			)
			( pin "@baseboard_fab2_lib.baseboard_fab2(sch_1):page139_i145:b"
				( attribute "PN" "2"
					( Origin gPackager )
				)
				( objectStatus "C1R14.2" )
			)
			( pin "@baseboard_fab2_lib.baseboard_fab2(sch_1):page139_i146:a"
				( attribute "PN" "1"
					( Origin gPackager )
				)
				( objectStatus "C1R21.1" )
			)
			( pin "@baseboard_fab2_lib.baseboard_fab2(sch_1):page139_i146:b"
				( attribute "PN" "2"
					( Origin gPackager )
				)
				( objectStatus "C1R21.2" )
			)
			( pin "@baseboard_fab2_lib.baseboard_fab2(sch_1):page139_i149:a"
				( attribute "PN" "1"
					( Origin gPackager )
				)
				( objectStatus "C1R26.1" )
			)
			( pin "@baseboard_fab2_lib.baseboard_fab2(sch_1):page139_i149:b"
				( attribute "PN" "2"
					( Origin gPackager )
				)
				( objectStatus "C1R26.2" )
			)
			( pin "@baseboard_fab2_lib.baseboard_fab2(sch_1):page139_i150:a"
				( attribute "PN" "1"
					( Origin gPackager )
				)
				( objectStatus "C1R29.1" )
			)
			( pin "@baseboard_fab2_lib.baseboard_fab2(sch_1):page139_i150:b"
				( attribute "PN" "2"
					( Origin gPackager )
				)
				( objectStatus "C1R29.2" )
			)
			( pin "@baseboard_fab2_lib.baseboard_fab2(sch_1):page139_i151:a"
				( attribute "PN" "1"
					( Origin gPackager )
				)
				( objectStatus "C1R19.1" )
			)
			( pin "@baseboard_fab2_lib.baseboard_fab2(sch_1):page139_i151:b"
				( attribute "PN" "2"
					( Origin gPackager )
				)
				( objectStatus "C1R19.2" )
			)
			( pin "@baseboard_fab2_lib.baseboard_fab2(sch_1):page139_i152:a"
				( attribute "PN" "1"
					( Origin gPackager )
				)
				( objectStatus "C1R31.1" )
			)
			( pin "@baseboard_fab2_lib.baseboard_fab2(sch_1):page139_i152:b"
				( attribute "PN" "2"
					( Origin gPackager )
				)
				( objectStatus "C1R31.2" )
			)
			( pin "@baseboard_fab2_lib.baseboard_fab2(sch_1):page139_i153:a"
				( attribute "PN" "1"
					( Origin gPackager )
				)
				( objectStatus "C1R17.1" )
			)
			( pin "@baseboard_fab2_lib.baseboard_fab2(sch_1):page139_i153:b"
				( attribute "PN" "2"
					( Origin gPackager )
				)
				( objectStatus "C1R17.2" )
			)
			( pin "@baseboard_fab2_lib.baseboard_fab2(sch_1):page139_i157:a"
				( attribute "PN" "1"
					( Origin gPackager )
				)
				( objectStatus "C1R18.1" )
			)
			( pin "@baseboard_fab2_lib.baseboard_fab2(sch_1):page139_i157:b"
				( attribute "PN" "2"
					( Origin gPackager )
				)
				( objectStatus "C1R18.2" )
			)
			( pin "@baseboard_fab2_lib.baseboard_fab2(sch_1):page139_i158:a"
				( attribute "PN" "1"
					( Origin gPackager )
				)
				( objectStatus "C1T5.1" )
			)
			( pin "@baseboard_fab2_lib.baseboard_fab2(sch_1):page139_i158:b"
				( attribute "PN" "2"
					( Origin gPackager )
				)
				( objectStatus "C1T5.2" )
			)
			( pin "@baseboard_fab2_lib.baseboard_fab2(sch_1):page139_i159:a"
				( attribute "PN" "1"
					( Origin gPackager )
				)
				( objectStatus "C1R24.1" )
			)
			( pin "@baseboard_fab2_lib.baseboard_fab2(sch_1):page139_i159:b"
				( attribute "PN" "2"
					( Origin gPackager )
				)
				( objectStatus "C1R24.2" )
			)
			( pin "@baseboard_fab2_lib.baseboard_fab2(sch_1):page139_i160:a"
				( attribute "PN" "1"
					( Origin gPackager )
				)
				( objectStatus "C1R15.1" )
			)
			( pin "@baseboard_fab2_lib.baseboard_fab2(sch_1):page139_i160:b"
				( attribute "PN" "2"
					( Origin gPackager )
				)
				( objectStatus "C1R15.2" )
			)
			( pin "@baseboard_fab2_lib.baseboard_fab2(sch_1):page139_i161:a"
				( attribute "PN" "1"
					( Origin gPackager )
				)
				( objectStatus "C1R16.1" )
			)
			( pin "@baseboard_fab2_lib.baseboard_fab2(sch_1):page139_i161:b"
				( attribute "PN" "2"
					( Origin gPackager )
				)
				( objectStatus "C1R16.2" )
			)
			( pin "@baseboard_fab2_lib.baseboard_fab2(sch_1):page139_i163:a"
				( attribute "PN" "1"
					( Origin gPackager )
				)
				( objectStatus "C9E1.1" )
			)
			( pin "@baseboard_fab2_lib.baseboard_fab2(sch_1):page139_i163:b"
				( attribute "PN" "2"
					( Origin gPackager )
				)
				( objectStatus "C9E1.2" )
			)
			( pin "@baseboard_fab2_lib.baseboard_fab2(sch_1):page139_i173:a"
				( attribute "PN" "1"
					( Origin gPackager )
				)
				( objectStatus "R9F5.1" )
			)
			( pin "@baseboard_fab2_lib.baseboard_fab2(sch_1):page139_i173:b"
				( attribute "PN" "2"
					( Origin gPackager )
				)
				( objectStatus "R9F5.2" )
			)
			( pin "@baseboard_fab2_lib.baseboard_fab2(sch_1):page139_i174:a"
				( attribute "PN" "1"
					( Origin gPackager )
				)
				( objectStatus "R9E23.1" )
			)
			( pin "@baseboard_fab2_lib.baseboard_fab2(sch_1):page139_i174:b"
				( attribute "PN" "2"
					( Origin gPackager )
				)
				( objectStatus "R9E23.2" )
			)
			( pin "@baseboard_fab2_lib.baseboard_fab2(sch_1):page139_i177:a"
				( attribute "PN" "1"
					( Origin gPackager )
				)
				( objectStatus "R9E2.1" )
			)
			( pin "@baseboard_fab2_lib.baseboard_fab2(sch_1):page139_i177:b"
				( attribute "PN" "2"
					( Origin gPackager )
				)
				( objectStatus "R9E2.2" )
			)
			( pin "@baseboard_fab2_lib.baseboard_fab2(sch_1):page139_i178:a"
				( attribute "PN" "1"
					( Origin gPackager )
				)
				( objectStatus "R9E3.1" )
			)
			( pin "@baseboard_fab2_lib.baseboard_fab2(sch_1):page139_i178:b"
				( attribute "PN" "2"
					( Origin gPackager )
				)
				( objectStatus "R9E3.2" )
			)
			( pin "@baseboard_fab2_lib.baseboard_fab2(sch_1):page139_i179:a"
				( attribute "PN" "1"
					( Origin gPackager )
				)
				( objectStatus "R9E1.1" )
			)
			( pin "@baseboard_fab2_lib.baseboard_fab2(sch_1):page139_i179:b"
				( attribute "PN" "2"
					( Origin gPackager )
				)
				( objectStatus "R9E1.2" )
			)
			( pin "@baseboard_fab2_lib.baseboard_fab2(sch_1):page139_i181:a"
				( attribute "PN" "1"
					( Origin gPackager )
				)
				( objectStatus "R9E22.1" )
			)
			( pin "@baseboard_fab2_lib.baseboard_fab2(sch_1):page139_i181:b"
				( attribute "PN" "2"
					( Origin gPackager )
				)
				( objectStatus "R9E22.2" )
			)
			( pin "@baseboard_fab2_lib.baseboard_fab2(sch_1):page139_i193:a"
				( attribute "PN" "1"
					( Origin gPackager )
				)
				( objectStatus "R9E7.1" )
			)
			( pin "@baseboard_fab2_lib.baseboard_fab2(sch_1):page139_i193:b"
				( attribute "PN" "2"
					( Origin gPackager )
				)
				( objectStatus "R9E7.2" )
			)
			( pin "@baseboard_fab2_lib.baseboard_fab2(sch_1):page139_i195:a"
				( attribute "PN" "1"
					( Origin gPackager )
				)
				( objectStatus "R1R1.1" )
			)
			( pin "@baseboard_fab2_lib.baseboard_fab2(sch_1):page139_i195:b"
				( attribute "PN" "2"
					( Origin gPackager )
				)
				( objectStatus "R1R1.2" )
			)
			( pin "@baseboard_fab2_lib.baseboard_fab2(sch_1):page139_i200:a"
				( attribute "PN" "1"
					( Origin gPackager )
				)
				( objectStatus "R9E4.1" )
			)
			( pin "@baseboard_fab2_lib.baseboard_fab2(sch_1):page139_i200:b"
				( attribute "PN" "2"
					( Origin gPackager )
				)
				( objectStatus "R9E4.2" )
			)
			( pin "@baseboard_fab2_lib.baseboard_fab2(sch_1):page139_i201:a"
				( attribute "PN" "1"
					( Origin gPackager )
				)
				( objectStatus "R9E18.1" )
			)
			( pin "@baseboard_fab2_lib.baseboard_fab2(sch_1):page139_i201:b"
				( attribute "PN" "2"
					( Origin gPackager )
				)
				( objectStatus "R9E18.2" )
			)
			( pin "@baseboard_fab2_lib.baseboard_fab2(sch_1):page139_i212:a"
				( attribute "PN" "1"
					( Origin gPackager )
				)
				( objectStatus "R9E13.1" )
			)
			( pin "@baseboard_fab2_lib.baseboard_fab2(sch_1):page139_i212:b"
				( attribute "PN" "2"
					( Origin gPackager )
				)
				( objectStatus "R9E13.2" )
			)
			( pin "@baseboard_fab2_lib.baseboard_fab2(sch_1):page139_i213:a"
				( attribute "PN" "1"
					( Origin gPackager )
				)
				( objectStatus "R1R12.1" )
			)
			( pin "@baseboard_fab2_lib.baseboard_fab2(sch_1):page139_i213:b"
				( attribute "PN" "2"
					( Origin gPackager )
				)
				( objectStatus "R1R12.2" )
			)
			( pin "@baseboard_fab2_lib.baseboard_fab2(sch_1):page139_i214:a"
				( attribute "PN" "1"
					( Origin gPackager )
				)
				( objectStatus "R1T1.1" )
			)
			( pin "@baseboard_fab2_lib.baseboard_fab2(sch_1):page139_i214:b"
				( attribute "PN" "2"
					( Origin gPackager )
				)
				( objectStatus "R1T1.2" )
			)
			( pin "@baseboard_fab2_lib.baseboard_fab2(sch_1):page139_i225:a"
				( attribute "PN" "1"
					( Origin gPackager )
				)
				( objectStatus "R9F1.1" )
			)
			( pin "@baseboard_fab2_lib.baseboard_fab2(sch_1):page139_i225:b"
				( attribute "PN" "2"
					( Origin gPackager )
				)
				( objectStatus "R9F1.2" )
			)
			( pin "@baseboard_fab2_lib.baseboard_fab2(sch_1):page139_i228:a"
				( attribute "PN" "1"
					( Origin gPackager )
				)
				( objectStatus "R9E19.1" )
			)
			( pin "@baseboard_fab2_lib.baseboard_fab2(sch_1):page139_i228:b"
				( attribute "PN" "2"
					( Origin gPackager )
				)
				( objectStatus "R9E19.2" )
			)
			( pin "@baseboard_fab2_lib.baseboard_fab2(sch_1):page139_i229:a"
				( attribute "PN" "1"
					( Origin gPackager )
				)
				( objectStatus "R9E17.1" )
			)
			( pin "@baseboard_fab2_lib.baseboard_fab2(sch_1):page139_i229:b"
				( attribute "PN" "2"
					( Origin gPackager )
				)
				( objectStatus "R9E17.2" )
			)
			( pin "@baseboard_fab2_lib.baseboard_fab2(sch_1):page139_i235:a"
				( attribute "PN" "1"
					( Origin gPackager )
				)
				( objectStatus "R9E16.1" )
			)
			( pin "@baseboard_fab2_lib.baseboard_fab2(sch_1):page139_i235:b"
				( attribute "PN" "2"
					( Origin gPackager )
				)
				( objectStatus "R9E16.2" )
			)
			( pin "@baseboard_fab2_lib.baseboard_fab2(sch_1):page139_i237:a"
				( attribute "PN" "1"
					( Origin gPackager )
				)
				( objectStatus "R1R15.1" )
			)
			( pin "@baseboard_fab2_lib.baseboard_fab2(sch_1):page139_i237:b"
				( attribute "PN" "2"
					( Origin gPackager )
				)
				( objectStatus "R1R15.2" )
			)
			( pin "@baseboard_fab2_lib.baseboard_fab2(sch_1):page139_i238:a"
				( attribute "PN" "1"
					( Origin gPackager )
				)
				( objectStatus "R1T32.1" )
			)
			( pin "@baseboard_fab2_lib.baseboard_fab2(sch_1):page139_i238:b"
				( attribute "PN" "2"
					( Origin gPackager )
				)
				( objectStatus "R1T32.2" )
			)
			( pin "@baseboard_fab2_lib.baseboard_fab2(sch_1):page139_i239:a"
				( attribute "PN" "1"
					( Origin gPackager )
				)
				( objectStatus "R1T34.1" )
			)
			( pin "@baseboard_fab2_lib.baseboard_fab2(sch_1):page139_i239:b"
				( attribute "PN" "2"
					( Origin gPackager )
				)
				( objectStatus "R1T34.2" )
			)
			( pin "@baseboard_fab2_lib.baseboard_fab2(sch_1):page139_i240:a"
				( attribute "PN" "1"
					( Origin gPackager )
				)
				( objectStatus "R1T33.1" )
			)
			( pin "@baseboard_fab2_lib.baseboard_fab2(sch_1):page139_i240:b"
				( attribute "PN" "2"
					( Origin gPackager )
				)
				( objectStatus "R1T33.2" )
			)
			( pin "@baseboard_fab2_lib.baseboard_fab2(sch_1):page139_i241:a"
				( attribute "PN" "1"
					( Origin gPackager )
				)
				( objectStatus "C9E12.1" )
			)
			( pin "@baseboard_fab2_lib.baseboard_fab2(sch_1):page139_i241:b"
				( attribute "PN" "2"
					( Origin gPackager )
				)
				( objectStatus "C9E12.2" )
			)
			( pin "@baseboard_fab2_lib.baseboard_fab2(sch_1):page140_i1:c"
				( attribute "PN" "6"
					( Origin gPackager )
				)
				( objectStatus "U9E1.6" )
			)
			( pin "@baseboard_fab2_lib.baseboard_fab2(sch_1):page140_i1:dq0"
				( attribute "PN" "5"
					( Origin gPackager )
				)
				( objectStatus "U9E1.5" )
			)
			( pin "@baseboard_fab2_lib.baseboard_fab2(sch_1):page140_i1:dq1"
				( attribute "PN" "2"
					( Origin gPackager )
				)
				( objectStatus "U9E1.2" )
			)
			( pin "@baseboard_fab2_lib.baseboard_fab2(sch_1):page140_i1:reset_n"
				( attribute "PN" "7"
					( Origin gPackager )
				)
				( objectStatus "U9E1.7" )
			)
			( pin "@baseboard_fab2_lib.baseboard_fab2(sch_1):page140_i1:s_n"
				( attribute "PN" "1"
					( Origin gPackager )
				)
				( objectStatus "U9E1.1" )
			)
			( pin "@baseboard_fab2_lib.baseboard_fab2(sch_1):page140_i1:vcc"
				( attribute "PN" "8"
					( Origin gPackager )
				)
				( objectStatus "U9E1.8" )
			)
			( pin "@baseboard_fab2_lib.baseboard_fab2(sch_1):page140_i1:vss"
				( attribute "PN" "4"
					( Origin gPackager )
				)
				( objectStatus "U9E1.4" )
			)
			( pin "@baseboard_fab2_lib.baseboard_fab2(sch_1):page140_i1:w_n"
				( attribute "PN" "3"
					( Origin gPackager )
				)
				( objectStatus "U9E1.3" )
			)
			( pin "@baseboard_fab2_lib.baseboard_fab2(sch_1):page140_i3:a"
				( attribute "PN" "1"
					( Origin gPackager )
				)
				( objectStatus "C1R25.1" )
			)
			( pin "@baseboard_fab2_lib.baseboard_fab2(sch_1):page140_i3:b"
				( attribute "PN" "2"
					( Origin gPackager )
				)
				( objectStatus "C1R25.2" )
			)
			( pin "@baseboard_fab2_lib.baseboard_fab2(sch_1):page140_i10:a"
				( attribute "PN" "1"
					( Origin gPackager )
				)
				( objectStatus "R1R9.1" )
			)
			( pin "@baseboard_fab2_lib.baseboard_fab2(sch_1):page140_i10:b"
				( attribute "PN" "2"
					( Origin gPackager )
				)
				( objectStatus "R1R9.2" )
			)
			( pin "@baseboard_fab2_lib.baseboard_fab2(sch_1):page140_i11:a"
				( attribute "PN" "1"
					( Origin gPackager )
				)
				( objectStatus "R1R3.1" )
			)
			( pin "@baseboard_fab2_lib.baseboard_fab2(sch_1):page140_i11:b"
				( attribute "PN" "2"
					( Origin gPackager )
				)
				( objectStatus "R1R3.2" )
			)
			( pin "@baseboard_fab2_lib.baseboard_fab2(sch_1):page140_i12:a"
				( attribute "PN" "1"
					( Origin gPackager )
				)
				( objectStatus "R1R7.1" )
			)
			( pin "@baseboard_fab2_lib.baseboard_fab2(sch_1):page140_i12:b"
				( attribute "PN" "2"
					( Origin gPackager )
				)
				( objectStatus "R1R7.2" )
			)
			( pin "@baseboard_fab2_lib.baseboard_fab2(sch_1):page140_i14:a"
				( attribute "PN" "1"
					( Origin gPackager )
				)
				( objectStatus "R1R6.1" )
			)
			( pin "@baseboard_fab2_lib.baseboard_fab2(sch_1):page140_i14:b"
				( attribute "PN" "2"
					( Origin gPackager )
				)
				( objectStatus "R1R6.2" )
			)
			( pin "@baseboard_fab2_lib.baseboard_fab2(sch_1):page140_i17:a"
				( attribute "PN" "1"
					( Origin gPackager )
				)
				( objectStatus "R9E6.1" )
			)
			( pin "@baseboard_fab2_lib.baseboard_fab2(sch_1):page140_i17:b"
				( attribute "PN" "2"
					( Origin gPackager )
				)
				( objectStatus "R9E6.2" )
			)
			( pin "@baseboard_fab2_lib.baseboard_fab2(sch_1):page141_i46:a"
				( attribute "PN" "1"
					( Origin gPackager )
				)
				( objectStatus "C9G4.1" )
			)
			( pin "@baseboard_fab2_lib.baseboard_fab2(sch_1):page141_i46:b"
				( attribute "PN" "2"
					( Origin gPackager )
				)
				( objectStatus "C9G4.2" )
			)
			( pin "@baseboard_fab2_lib.baseboard_fab2(sch_1):page141_i47:a"
				( attribute "PN" "1"
					( Origin gPackager )
				)
				( objectStatus "C9G6.1" )
			)
			( pin "@baseboard_fab2_lib.baseboard_fab2(sch_1):page141_i47:b"
				( attribute "PN" "2"
					( Origin gPackager )
				)
				( objectStatus "C9G6.2" )
			)
			( pin "@baseboard_fab2_lib.baseboard_fab2(sch_1):page141_i48:a"
				( attribute "PN" "1"
					( Origin gPackager )
				)
				( objectStatus "C9G5.1" )
			)
			( pin "@baseboard_fab2_lib.baseboard_fab2(sch_1):page141_i48:b"
				( attribute "PN" "2"
					( Origin gPackager )
				)
				( objectStatus "C9G5.2" )
			)
			( pin "@baseboard_fab2_lib.baseboard_fab2(sch_1):page141_i75:a"
				( attribute "PN" "1"
					( Origin gPackager )
				)
				( objectStatus "R9G9.1" )
			)
			( pin "@baseboard_fab2_lib.baseboard_fab2(sch_1):page141_i75:b"
				( attribute "PN" "2"
					( Origin gPackager )
				)
				( objectStatus "R9G9.2" )
			)
			( pin "@baseboard_fab2_lib.baseboard_fab2(sch_1):page141_i76:a"
				( attribute "PN" "1"
					( Origin gPackager )
				)
				( objectStatus "R9G11.1" )
			)
			( pin "@baseboard_fab2_lib.baseboard_fab2(sch_1):page141_i76:b"
				( attribute "PN" "2"
					( Origin gPackager )
				)
				( objectStatus "R9G11.2" )
			)
			( pin "@baseboard_fab2_lib.baseboard_fab2(sch_1):page141_i77:a"
				( attribute "PN" "1"
					( Origin gPackager )
				)
				( objectStatus "R9G18.1" )
			)
			( pin "@baseboard_fab2_lib.baseboard_fab2(sch_1):page141_i77:b"
				( attribute "PN" "2"
					( Origin gPackager )
				)
				( objectStatus "R9G18.2" )
			)
			( pin "@baseboard_fab2_lib.baseboard_fab2(sch_1):page141_i78:a"
				( attribute "PN" "1"
					( Origin gPackager )
				)
				( objectStatus "R9G17.1" )
			)
			( pin "@baseboard_fab2_lib.baseboard_fab2(sch_1):page141_i78:b"
				( attribute "PN" "2"
					( Origin gPackager )
				)
				( objectStatus "R9G17.2" )
			)
			( pin "@baseboard_fab2_lib.baseboard_fab2(sch_1):page141_i79:a"
				( attribute "PN" "1"
					( Origin gPackager )
				)
				( objectStatus "R9G19.1" )
			)
			( pin "@baseboard_fab2_lib.baseboard_fab2(sch_1):page141_i79:b"
				( attribute "PN" "2"
					( Origin gPackager )
				)
				( objectStatus "R9G19.2" )
			)
			( pin "@baseboard_fab2_lib.baseboard_fab2(sch_1):page141_i80:a"
				( attribute "PN" "1"
					( Origin gPackager )
				)
				( objectStatus "R9G20.1" )
			)
			( pin "@baseboard_fab2_lib.baseboard_fab2(sch_1):page141_i80:b"
				( attribute "PN" "2"
					( Origin gPackager )
				)
				( objectStatus "R9G20.2" )
			)
			( pin "@baseboard_fab2_lib.baseboard_fab2(sch_1):page141_i81:a"
				( attribute "PN" "1"
					( Origin gPackager )
				)
				( objectStatus "R9G24.1" )
			)
			( pin "@baseboard_fab2_lib.baseboard_fab2(sch_1):page141_i81:b"
				( attribute "PN" "2"
					( Origin gPackager )
				)
				( objectStatus "R9G24.2" )
			)
			( pin "@baseboard_fab2_lib.baseboard_fab2(sch_1):page141_i82:a"
				( attribute "PN" "1"
					( Origin gPackager )
				)
				( objectStatus "R9G22.1" )
			)
			( pin "@baseboard_fab2_lib.baseboard_fab2(sch_1):page141_i82:b"
				( attribute "PN" "2"
					( Origin gPackager )
				)
				( objectStatus "R9G22.2" )
			)
			( pin "@baseboard_fab2_lib.baseboard_fab2(sch_1):page141_i99:a"
				( attribute "PN" "1"
					( Origin gPackager )
				)
				( objectStatus "C9G9.1" )
			)
			( pin "@baseboard_fab2_lib.baseboard_fab2(sch_1):page141_i99:b"
				( attribute "PN" "2"
					( Origin gPackager )
				)
				( objectStatus "C9G9.2" )
			)
			( pin "@baseboard_fab2_lib.baseboard_fab2(sch_1):page141_i100:a"
				( attribute "PN" "1"
					( Origin gPackager )
				)
				( objectStatus "C9G12.1" )
			)
			( pin "@baseboard_fab2_lib.baseboard_fab2(sch_1):page141_i100:b"
				( attribute "PN" "2"
					( Origin gPackager )
				)
				( objectStatus "C9G12.2" )
			)
			( pin "@baseboard_fab2_lib.baseboard_fab2(sch_1):page141_i101:a"
				( attribute "PN" "1"
					( Origin gPackager )
				)
				( objectStatus "C9G16.1" )
			)
			( pin "@baseboard_fab2_lib.baseboard_fab2(sch_1):page141_i101:b"
				( attribute "PN" "2"
					( Origin gPackager )
				)
				( objectStatus "C9G16.2" )
			)
			( pin "@baseboard_fab2_lib.baseboard_fab2(sch_1):page141_i102:a"
				( attribute "PN" "1"
					( Origin gPackager )
				)
				( objectStatus "C9G13.1" )
			)
			( pin "@baseboard_fab2_lib.baseboard_fab2(sch_1):page141_i102:b"
				( attribute "PN" "2"
					( Origin gPackager )
				)
				( objectStatus "C9G13.2" )
			)
			( pin "@baseboard_fab2_lib.baseboard_fab2(sch_1):page114_i193:a"
				( attribute "PN" "1"
					( Origin gPackager )
				)
				( objectStatus "C3W1.1" )
			)
			( pin "@baseboard_fab2_lib.baseboard_fab2(sch_1):page114_i193:b"
				( attribute "PN" "2"
					( Origin gPackager )
				)
				( objectStatus "C3W1.2" )
			)
			( pin "@baseboard_fab2_lib.baseboard_fab2(sch_1):page142_i1:a"
				( attribute "PN" "2"
					( Origin gPackager )
				)
				( objectStatus "U8E4.2" )
			)
			( pin "@baseboard_fab2_lib.baseboard_fab2(sch_1):page142_i1:oe"
				( attribute "PN" "1"
					( Origin gPackager )
				)
				( objectStatus "U8E4.1" )
			)
			( pin "@baseboard_fab2_lib.baseboard_fab2(sch_1):page142_i1:y"
				( attribute "PN" "4"
					( Origin gPackager )
				)
				( objectStatus "U8E4.4" )
			)
			( pin "@baseboard_fab2_lib.baseboard_fab2(sch_1):page142_i2:a"
				( attribute "PN" "1"
					( Origin gPackager )
				)
				( objectStatus "R8E17.1" )
			)
			( pin "@baseboard_fab2_lib.baseboard_fab2(sch_1):page142_i2:b"
				( attribute "PN" "2"
					( Origin gPackager )
				)
				( objectStatus "R8E17.2" )
			)
			( pin "@baseboard_fab2_lib.baseboard_fab2(sch_1):page142_i3:a"
				( attribute "PN" "1"
					( Origin gPackager )
				)
				( objectStatus "R8E23.1" )
			)
			( pin "@baseboard_fab2_lib.baseboard_fab2(sch_1):page142_i3:b"
				( attribute "PN" "2"
					( Origin gPackager )
				)
				( objectStatus "R8E23.2" )
			)
			( pin "@baseboard_fab2_lib.baseboard_fab2(sch_1):page142_i18:a"
				( attribute "PN" "1"
					( Origin gPackager )
				)
				( objectStatus "R8E29.1" )
			)
			( pin "@baseboard_fab2_lib.baseboard_fab2(sch_1):page142_i18:b"
				( attribute "PN" "2"
					( Origin gPackager )
				)
				( objectStatus "R8E29.2" )
			)
			( pin "@baseboard_fab2_lib.baseboard_fab2(sch_1):page142_i20:a"
				( attribute "PN" "1"
					( Origin gPackager )
				)
				( objectStatus "C8E5.1" )
			)
			( pin "@baseboard_fab2_lib.baseboard_fab2(sch_1):page142_i20:b"
				( attribute "PN" "2"
					( Origin gPackager )
				)
				( objectStatus "C8E5.2" )
			)
			( pin "@baseboard_fab2_lib.baseboard_fab2(sch_1):page92_i111:\1\"
				( attribute "PN" "1"
					( Origin gPackager )
				)
				( objectStatus "R7D33.1" )
			)
			( pin "@baseboard_fab2_lib.baseboard_fab2(sch_1):page92_i111:\2\"
				( attribute "PN" "2"
					( Origin gPackager )
				)
				( objectStatus "R7D33.2" )
			)
			( pin "@baseboard_fab2_lib.baseboard_fab2(sch_1):page92_i110:\1\"
				( attribute "PN" "1"
					( Origin gPackager )
				)
				( objectStatus "R3P45.1" )
			)
			( pin "@baseboard_fab2_lib.baseboard_fab2(sch_1):page92_i110:\2\"
				( attribute "PN" "2"
					( Origin gPackager )
				)
				( objectStatus "R3P45.2" )
			)
			( pin "@baseboard_fab2_lib.baseboard_fab2(sch_1):page142_i30:a"
				( attribute "PN" "1"
					( Origin gPackager )
				)
				( objectStatus "R8E26.1" )
			)
			( pin "@baseboard_fab2_lib.baseboard_fab2(sch_1):page142_i30:b"
				( attribute "PN" "2"
					( Origin gPackager )
				)
				( objectStatus "R8E26.2" )
			)
			( pin "@baseboard_fab2_lib.baseboard_fab2(sch_1):page142_i31:a"
				( attribute "PN" "1"
					( Origin gPackager )
				)
				( objectStatus "R8E28.1" )
			)
			( pin "@baseboard_fab2_lib.baseboard_fab2(sch_1):page142_i31:b"
				( attribute "PN" "2"
					( Origin gPackager )
				)
				( objectStatus "R8E28.2" )
			)
			( pin "@baseboard_fab2_lib.baseboard_fab2(sch_1):page142_i32:a"
				( attribute "PN" "1"
					( Origin gPackager )
				)
				( objectStatus "R8E27.1" )
			)
			( pin "@baseboard_fab2_lib.baseboard_fab2(sch_1):page142_i32:b"
				( attribute "PN" "2"
					( Origin gPackager )
				)
				( objectStatus "R8E27.2" )
			)
			( pin "@baseboard_fab2_lib.baseboard_fab2(sch_1):page142_i33:a"
				( attribute "PN" "1"
					( Origin gPackager )
				)
				( objectStatus "R8E21.1" )
			)
			( pin "@baseboard_fab2_lib.baseboard_fab2(sch_1):page142_i33:b"
				( attribute "PN" "2"
					( Origin gPackager )
				)
				( objectStatus "R8E21.2" )
			)
			( pin "@baseboard_fab2_lib.baseboard_fab2(sch_1):page145_i117:clkin"
				( attribute "PN" "W18"
					( Origin gPackager )
				)
				( objectStatus "U25W4.W18" )
			)
			( pin "@baseboard_fab2_lib.baseboard_fab2(sch_1):page145_i117:gpioa0_mac1link"
				( attribute "PN" "B14"
					( Origin gPackager )
				)
				( objectStatus "U25W4.B14" )
			)
			( pin "@baseboard_fab2_lib.baseboard_fab2(sch_1):page145_i117:gpioa1_mac2link"
				( attribute "PN" "D14"
					( Origin gPackager )
				)
				( objectStatus "U25W4.D14" )
			)
			( pin "@baseboard_fab2_lib.baseboard_fab2(sch_1):page145_i117:\gpioa2_timer3_spi1cs1#\"
				( attribute "PN" "D13"
					( Origin gPackager )
				)
				( objectStatus "U25W4.D13" )
			)
			( pin "@baseboard_fab2_lib.baseboard_fab2(sch_1):page145_i117:gpioa3_timer4"
				( attribute "PN" "E13"
					( Origin gPackager )
				)
				( objectStatus "U25W4.E13" )
			)
			( pin "@baseboard_fab2_lib.baseboard_fab2(sch_1):page145_i117:gpioc0_sd1clk_scl10"
				( attribute "PN" "C12"
					( Origin gPackager )
				)
				( objectStatus "U25W4.C12" )
			)
			( pin "@baseboard_fab2_lib.baseboard_fab2(sch_1):page145_i117:gpioc1_sd1cmd_sda10"
				( attribute "PN" "A12"
					( Origin gPackager )
				)
				( objectStatus "U25W4.A12" )
			)
			( pin "@baseboard_fab2_lib.baseboard_fab2(sch_1):page145_i117:gpioc2_sd1dat0_scl11"
				( attribute "PN" "B12"
					( Origin gPackager )
				)
				( objectStatus "U25W4.B12" )
			)
			( pin "@baseboard_fab2_lib.baseboard_fab2(sch_1):page145_i117:gpioc3_sd1dat1_sda11"
				( attribute "PN" "D9"
					( Origin gPackager )
				)
				( objectStatus "U25W4.D9" )
			)
			( pin "@baseboard_fab2_lib.baseboard_fab2(sch_1):page145_i117:gpioc4_sd1dat2_scl12"
				( attribute "PN" "D10"
					( Origin gPackager )
				)
				( objectStatus "U25W4.D10" )
			)
			( pin "@baseboard_fab2_lib.baseboard_fab2(sch_1):page145_i117:gpioc5_sd1dat3_sda12"
				( attribute "PN" "E12"
					( Origin gPackager )
				)
				( objectStatus "U25W4.E12" )
			)
			( pin "@baseboard_fab2_lib.baseboard_fab2(sch_1):page145_i117:\gpioc6_sd1cd#_scl13\"
				( attribute "PN" "C11"
					( Origin gPackager )
				)
				( objectStatus "U25W4.C11" )
			)
			( pin "@baseboard_fab2_lib.baseboard_fab2(sch_1):page145_i117:\gpioc7_sd1wp#_sda13\"
				( attribute "PN" "B11"
					( Origin gPackager )
				)
				( objectStatus "U25W4.B11" )
			)
			( pin "@baseboard_fab2_lib.baseboard_fab2(sch_1):page145_i117:gpiod0_sd2clk"
				( attribute "PN" "F19"
					( Origin gPackager )
				)
				( objectStatus "U25W4.F19" )
			)
			( pin "@baseboard_fab2_lib.baseboard_fab2(sch_1):page145_i117:gpiod1_sd2cmd"
				( attribute "PN" "E21"
					( Origin gPackager )
				)
				( objectStatus "U25W4.E21" )
			)
			( pin "@baseboard_fab2_lib.baseboard_fab2(sch_1):page145_i117:gpiod2_sd2dat0"
				( attribute "PN" "F20"
					( Origin gPackager )
				)
				( objectStatus "U25W4.F20" )
			)
			( pin "@baseboard_fab2_lib.baseboard_fab2(sch_1):page145_i117:gpiod3_sd2dat1"
				( attribute "PN" "D20"
					( Origin gPackager )
				)
				( objectStatus "U25W4.D20" )
			)
			( pin "@baseboard_fab2_lib.baseboard_fab2(sch_1):page145_i117:gpiod4_sd2dat2"
				( attribute "PN" "D21"
					( Origin gPackager )
				)
				( objectStatus "U25W4.D21" )
			)
			( pin "@baseboard_fab2_lib.baseboard_fab2(sch_1):page145_i117:gpiod5_sd2dat3"
				( attribute "PN" "E20"
					( Origin gPackager )
				)
				( objectStatus "U25W4.E20" )
			)
			( pin "@baseboard_fab2_lib.baseboard_fab2(sch_1):page145_i117:\gpiod6_sd2cd#\"
				( attribute "PN" "G18"
					( Origin gPackager )
				)
				( objectStatus "U25W4.G18" )
			)
			( pin "@baseboard_fab2_lib.baseboard_fab2(sch_1):page145_i117:\gpiod7_sd2wp#\"
				( attribute "PN" "C21"
					( Origin gPackager )
				)
				( objectStatus "U25W4.C21" )
			)
			( pin "@baseboard_fab2_lib.baseboard_fab2(sch_1):page145_i117:gpioe0_ncts3"
				( attribute "PN" "B20"
					( Origin gPackager )
				)
				( objectStatus "U25W4.B20" )
			)
			( pin "@baseboard_fab2_lib.baseboard_fab2(sch_1):page145_i117:gpioe1_ndcd3"
				( attribute "PN" "C20"
					( Origin gPackager )
				)
				( objectStatus "U25W4.C20" )
			)
			( pin "@baseboard_fab2_lib.baseboard_fab2(sch_1):page145_i117:gpioe2_ndsr3"
				( attribute "PN" "F18"
					( Origin gPackager )
				)
				( objectStatus "U25W4.F18" )
			)
			( pin "@baseboard_fab2_lib.baseboard_fab2(sch_1):page145_i117:gpioe3_nri3"
				( attribute "PN" "F17"
					( Origin gPackager )
				)
				( objectStatus "U25W4.F17" )
			)
			( pin "@baseboard_fab2_lib.baseboard_fab2(sch_1):page145_i117:gpioe4_ndtr3"
				( attribute "PN" "E18"
					( Origin gPackager )
				)
				( objectStatus "U25W4.E18" )
			)
			( pin "@baseboard_fab2_lib.baseboard_fab2(sch_1):page145_i117:gpioe5_nrts3"
				( attribute "PN" "D19"
					( Origin gPackager )
				)
				( objectStatus "U25W4.D19" )
			)
			( pin "@baseboard_fab2_lib.baseboard_fab2(sch_1):page145_i117:gpioe6_txd3"
				( attribute "PN" "A20"
					( Origin gPackager )
				)
				( objectStatus "U25W4.A20" )
			)
			( pin "@baseboard_fab2_lib.baseboard_fab2(sch_1):page145_i117:gpioe7_rxd3"
				( attribute "PN" "B19"
					( Origin gPackager )
				)
				( objectStatus "U25W4.B19" )
			)
			( pin "@baseboard_fab2_lib.baseboard_fab2(sch_1):page145_i117:gpiof0_ncts4_lhad0"
				( attribute "PN" "J19"
					( Origin gPackager )
				)
				( objectStatus "U25W4.J19" )
			)
			( pin "@baseboard_fab2_lib.baseboard_fab2(sch_1):page145_i117:gpiof1_ndcd4_lhad1"
				( attribute "PN" "J18"
					( Origin gPackager )
				)
				( objectStatus "U25W4.J18" )
			)
			( pin "@baseboard_fab2_lib.baseboard_fab2(sch_1):page145_i117:gpiof2_ndsr4_lhad2"
				( attribute "PN" "B22"
					( Origin gPackager )
				)
				( objectStatus "U25W4.B22" )
			)
			( pin "@baseboard_fab2_lib.baseboard_fab2(sch_1):page145_i117:gpiof3_nri4_lhad3"
				( attribute "PN" "B21"
					( Origin gPackager )
				)
				( objectStatus "U25W4.B21" )
			)
			( pin "@baseboard_fab2_lib.baseboard_fab2(sch_1):page145_i117:gpiof4_ndtr4_lhclk"
				( attribute "PN" "A21"
					( Origin gPackager )
				)
				( objectStatus "U25W4.A21" )
			)
			( pin "@baseboard_fab2_lib.baseboard_fab2(sch_1):page145_i117:\gpiof5_nrts4_lhframe#\"
				( attribute "PN" "H19"
					( Origin gPackager )
				)
				( objectStatus "U25W4.H19" )
			)
			( pin "@baseboard_fab2_lib.baseboard_fab2(sch_1):page145_i117:\gpiof6_txd4_lhsirq#\"
				( attribute "PN" "G17"
					( Origin gPackager )
				)
				( objectStatus "U25W4.G17" )
			)
			( pin "@baseboard_fab2_lib.baseboard_fab2(sch_1):page145_i117:\gpiof7_rxd4_lhrst#\"
				( attribute "PN" "H18"
					( Origin gPackager )
				)
				( objectStatus "U25W4.H18" )
			)
			( pin "@baseboard_fab2_lib.baseboard_fab2(sch_1):page145_i117:gpiog4_sgps2ck_salt1"
				( attribute "PN" "E17"
					( Origin gPackager )
				)
				( objectStatus "U25W4.E17" )
			)
			( pin "@baseboard_fab2_lib.baseboard_fab2(sch_1):page145_i117:gpiog5_sgps2ld_salt2"
				( attribute "PN" "D16"
					( Origin gPackager )
				)
				( objectStatus "U25W4.D16" )
			)
			( pin "@baseboard_fab2_lib.baseboard_fab2(sch_1):page145_i117:gpiog6_sgps2i0_salt3"
				( attribute "PN" "D15"
					( Origin gPackager )
				)
				( objectStatus "U25W4.D15" )
			)
			( pin "@baseboard_fab2_lib.baseboard_fab2(sch_1):page145_i117:gpiog7_sgps2i1_salt4"
				( attribute "PN" "E14"
					( Origin gPackager )
				)
				( objectStatus "U25W4.E14" )
			)
			( pin "@baseboard_fab2_lib.baseboard_fab2(sch_1):page145_i117:gpiol0_ncts1"
				( attribute "PN" "T2"
					( Origin gPackager )
				)
				( objectStatus "U25W4.T2" )
			)
			( pin "@baseboard_fab2_lib.baseboard_fab2(sch_1):page145_i117:gpiol1_ndcd1_vpide"
				( attribute "PN" "T1"
					( Origin gPackager )
				)
				( objectStatus "U25W4.T1" )
			)
			( pin "@baseboard_fab2_lib.baseboard_fab2(sch_1):page145_i117:gpiol2_ndsr1"
				( attribute "PN" "U1"
					( Origin gPackager )
				)
				( objectStatus "U25W4.U1" )
			)
			( pin "@baseboard_fab2_lib.baseboard_fab2(sch_1):page145_i117:gpiol3_nri1_vpihs"
				( attribute "PN" "U2"
					( Origin gPackager )
				)
				( objectStatus "U25W4.U2" )
			)
			( pin "@baseboard_fab2_lib.baseboard_fab2(sch_1):page145_i117:gpiol4_ndtr1_vpivs"
				( attribute "PN" "P4"
					( Origin gPackager )
				)
				( objectStatus "U25W4.P4" )
			)
			( pin "@baseboard_fab2_lib.baseboard_fab2(sch_1):page145_i117:gpiol5_nrts1_vpiclk"
				( attribute "PN" "P3"
					( Origin gPackager )
				)
				( objectStatus "U25W4.P3" )
			)
			( pin "@baseboard_fab2_lib.baseboard_fab2(sch_1):page145_i117:gpiol6_txd1"
				( attribute "PN" "V1"
					( Origin gPackager )
				)
				( objectStatus "U25W4.V1" )
			)
			( pin "@baseboard_fab2_lib.baseboard_fab2(sch_1):page145_i117:gpiol7_rxd1"
				( attribute "PN" "W1"
					( Origin gPackager )
				)
				( objectStatus "U25W4.W1" )
			)
			( pin "@baseboard_fab2_lib.baseboard_fab2(sch_1):page145_i117:gpiom0_ncts2_vpib2"
				( attribute "PN" "Y1"
					( Origin gPackager )
				)
				( objectStatus "U25W4.Y1" )
			)
			( pin "@baseboard_fab2_lib.baseboard_fab2(sch_1):page145_i117:gpiom1_ndcd2_vpib3"
				( attribute "PN" "AB2"
					( Origin gPackager )
				)
				( objectStatus "U25W4.AB2" )
			)
			( pin "@baseboard_fab2_lib.baseboard_fab2(sch_1):page145_i117:gpiom2_ndsr2_vpib4"
				( attribute "PN" "AA1"
					( Origin gPackager )
				)
				( objectStatus "U25W4.AA1" )
			)
			( pin "@baseboard_fab2_lib.baseboard_fab2(sch_1):page145_i117:gpiom3_nri2_vpib5"
				( attribute "PN" "Y2"
					( Origin gPackager )
				)
				( objectStatus "U25W4.Y2" )
			)
			( pin "@baseboard_fab2_lib.baseboard_fab2(sch_1):page145_i117:gpiom4_ndtr2_vpib6"
				( attribute "PN" "AA2"
					( Origin gPackager )
				)
				( objectStatus "U25W4.AA2" )
			)
			( pin "@baseboard_fab2_lib.baseboard_fab2(sch_1):page145_i117:gpiom5_nrts2_vpib7"
				( attribute "PN" "P5"
					( Origin gPackager )
				)
				( objectStatus "U25W4.P5" )
			)
			( pin "@baseboard_fab2_lib.baseboard_fab2(sch_1):page145_i117:gpiom6_txd2_vpib8"
				( attribute "PN" "R5"
					( Origin gPackager )
				)
				( objectStatus "U25W4.R5" )
			)
			( pin "@baseboard_fab2_lib.baseboard_fab2(sch_1):page145_i117:gpiom7_rxd2_vpib9"
				( attribute "PN" "T5"
					( Origin gPackager )
				)
				( objectStatus "U25W4.T5" )
			)
			( pin "@baseboard_fab2_lib.baseboard_fab2(sch_1):page145_i117:\gpioy3_sioonctrl#\"
				( attribute "PN" "P21"
					( Origin gPackager )
				)
				( objectStatus "U25W4.P21" )
			)
			( pin "@baseboard_fab2_lib.baseboard_fab2(sch_1):page145_i117:peci"
				( attribute "PN" "AB18"
					( Origin gPackager )
				)
				( objectStatus "U25W4.AB18" )
			)
			( pin "@baseboard_fab2_lib.baseboard_fab2(sch_1):page145_i117:perefclkn"
				( attribute "PN" "K22"
					( Origin gPackager )
				)
				( objectStatus "U25W4.K22" )
			)
			( pin "@baseboard_fab2_lib.baseboard_fab2(sch_1):page145_i117:perefclkp"
				( attribute "PN" "K21"
					( Origin gPackager )
				)
				( objectStatus "U25W4.K21" )
			)
			( pin "@baseboard_fab2_lib.baseboard_fab2(sch_1):page145_i117:perext"
				( attribute "PN" "K20"
					( Origin gPackager )
				)
				( objectStatus "U25W4.K20" )
			)
			( pin "@baseboard_fab2_lib.baseboard_fab2(sch_1):page145_i117:\perst#\"
				( attribute "PN" "L20"
					( Origin gPackager )
				)
				( objectStatus "U25W4.L20" )
			)
			( pin "@baseboard_fab2_lib.baseboard_fab2(sch_1):page145_i117:perxn"
				( attribute "PN" "M22"
					( Origin gPackager )
				)
				( objectStatus "U25W4.M22" )
			)
			( pin "@baseboard_fab2_lib.baseboard_fab2(sch_1):page145_i117:perxp"
				( attribute "PN" "M21"
					( Origin gPackager )
				)
				( objectStatus "U25W4.M21" )
			)
			( pin "@baseboard_fab2_lib.baseboard_fab2(sch_1):page145_i117:petxn"
				( attribute "PN" "L22"
					( Origin gPackager )
				)
				( objectStatus "U25W4.L22" )
			)
			( pin "@baseboard_fab2_lib.baseboard_fab2(sch_1):page145_i117:petxp"
				( attribute "PN" "L21"
					( Origin gPackager )
				)
				( objectStatus "U25W4.L21" )
			)
			( pin "@baseboard_fab2_lib.baseboard_fab2(sch_1):page145_i117:rxd5"
				( attribute "PN" "K2"
					( Origin gPackager )
				)
				( objectStatus "U25W4.K2" )
			)
			( pin "@baseboard_fab2_lib.baseboard_fab2(sch_1):page145_i117:\srst#\"
				( attribute "PN" "U18"
					( Origin gPackager )
				)
				( objectStatus "U25W4.U18" )
			)
			( pin "@baseboard_fab2_lib.baseboard_fab2(sch_1):page145_i117:txd5"
				( attribute "PN" "K1"
					( Origin gPackager )
				)
				( objectStatus "U25W4.K1" )
			)
			( pin "@baseboard_fab2_lib.baseboard_fab2(sch_1):page151_i141:a"
				( attribute "PN" "1"
					( Origin gPackager )
				)
				( objectStatus "C25W4.1" )
			)
			( pin "@baseboard_fab2_lib.baseboard_fab2(sch_1):page151_i141:b"
				( attribute "PN" "2"
					( Origin gPackager )
				)
				( objectStatus "C25W4.2" )
			)
			( pin "@baseboard_fab2_lib.baseboard_fab2(sch_1):page151_i140:a"
				( attribute "PN" "1"
					( Origin gPackager )
				)
				( objectStatus "C25W3.1" )
			)
			( pin "@baseboard_fab2_lib.baseboard_fab2(sch_1):page151_i140:b"
				( attribute "PN" "2"
					( Origin gPackager )
				)
				( objectStatus "C25W3.2" )
			)
			( pin "@baseboard_fab2_lib.baseboard_fab2(sch_1):page151_i139:a"
				( attribute "PN" "1"
					( Origin gPackager )
				)
				( objectStatus "C25W2.1" )
			)
			( pin "@baseboard_fab2_lib.baseboard_fab2(sch_1):page151_i139:b"
				( attribute "PN" "2"
					( Origin gPackager )
				)
				( objectStatus "C25W2.2" )
			)
			( pin "@baseboard_fab2_lib.baseboard_fab2(sch_1):page143_i58:a"
				( attribute "PN" "1"
					( Origin gPackager )
				)
				( objectStatus "R1T27.1" )
			)
			( pin "@baseboard_fab2_lib.baseboard_fab2(sch_1):page143_i58:b"
				( attribute "PN" "2"
					( Origin gPackager )
				)
				( objectStatus "R1T27.2" )
			)
			( pin "@baseboard_fab2_lib.baseboard_fab2(sch_1):page151_i142:a"
				( attribute "PN" "1"
					( Origin gPackager )
				)
				( objectStatus "C25W5.1" )
			)
			( pin "@baseboard_fab2_lib.baseboard_fab2(sch_1):page151_i142:b"
				( attribute "PN" "2"
					( Origin gPackager )
				)
				( objectStatus "C25W5.2" )
			)
			( pin "@baseboard_fab2_lib.baseboard_fab2(sch_1):page151_i143:a"
				( attribute "PN" "1"
					( Origin gPackager )
				)
				( objectStatus "C25W6.1" )
			)
			( pin "@baseboard_fab2_lib.baseboard_fab2(sch_1):page151_i143:b"
				( attribute "PN" "2"
					( Origin gPackager )
				)
				( objectStatus "C25W6.2" )
			)
			( pin "@baseboard_fab2_lib.baseboard_fab2(sch_1):page151_i227:\1\"
				( attribute "PN" "1"
					( Origin gPackager )
				)
				( objectStatus "R25W32.1" )
			)
			( pin "@baseboard_fab2_lib.baseboard_fab2(sch_1):page151_i227:\2\"
				( attribute "PN" "2"
					( Origin gPackager )
				)
				( objectStatus "R25W32.2" )
			)
			( pin "@baseboard_fab2_lib.baseboard_fab2(sch_1):page151_i226:\1\"
				( attribute "PN" "1"
					( Origin gPackager )
				)
				( objectStatus "R25W31.1" )
			)
			( pin "@baseboard_fab2_lib.baseboard_fab2(sch_1):page151_i226:\2\"
				( attribute "PN" "2"
					( Origin gPackager )
				)
				( objectStatus "R25W31.2" )
			)
			( pin "@baseboard_fab2_lib.baseboard_fab2(sch_1):page139_i249:a"
				( attribute "PN" "1"
					( Origin gPackager )
				)
				( objectStatus "C9E9.1" )
			)
			( pin "@baseboard_fab2_lib.baseboard_fab2(sch_1):page139_i249:b"
				( attribute "PN" "2"
					( Origin gPackager )
				)
				( objectStatus "C9E9.2" )
			)
			( pin "@baseboard_fab2_lib.baseboard_fab2(sch_1):page251_i10:a"
				( attribute "PN" "2"
					( Origin gPackager )
				)
				( objectStatus "CR10W2.2" )
			)
			( pin "@baseboard_fab2_lib.baseboard_fab2(sch_1):page251_i10:c"
				( attribute "PN" "1"
					( Origin gPackager )
				)
				( objectStatus "CR10W2.1" )
			)
			( pin "@baseboard_fab2_lib.baseboard_fab2(sch_1):page168_i43:drn"
				( attribute "PN" "3"
					( Origin gPackager )
				)
				( objectStatus "Q6W4.3" )
			)
			( pin "@baseboard_fab2_lib.baseboard_fab2(sch_1):page168_i43:gate"
				( attribute "PN" "1"
					( Origin gPackager )
				)
				( objectStatus "Q6W4.1" )
			)
			( pin "@baseboard_fab2_lib.baseboard_fab2(sch_1):page168_i43:src"
				( attribute "PN" "2"
					( Origin gPackager )
				)
				( objectStatus "Q6W4.2" )
			)
			( pin "@baseboard_fab2_lib.baseboard_fab2(sch_1):page145_i22:a"
				( attribute "PN" "1"
					( Origin gPackager )
				)
				( objectStatus "R9F20.1" )
			)
			( pin "@baseboard_fab2_lib.baseboard_fab2(sch_1):page145_i22:b"
				( attribute "PN" "2"
					( Origin gPackager )
				)
				( objectStatus "R9F20.2" )
			)
			( pin "@baseboard_fab2_lib.baseboard_fab2(sch_1):page145_i136:a"
				( attribute "PN" "1"
					( Origin gPackager )
				)
				( objectStatus "R2T41.1" )
			)
			( pin "@baseboard_fab2_lib.baseboard_fab2(sch_1):page145_i136:b"
				( attribute "PN" "2"
					( Origin gPackager )
				)
				( objectStatus "R2T41.2" )
			)
			( pin "@baseboard_fab2_lib.baseboard_fab2(sch_1):page151_i175:a"
				( attribute "PN" "1"
					( Origin gPackager )
				)
				( objectStatus "R8B25.1" )
			)
			( pin "@baseboard_fab2_lib.baseboard_fab2(sch_1):page151_i175:b"
				( attribute "PN" "2"
					( Origin gPackager )
				)
				( objectStatus "R8B25.2" )
			)
			( pin "@baseboard_fab2_lib.baseboard_fab2(sch_1):page152_i1:a0"
				( attribute "PN" "13"
					( Origin gPackager )
				)
				( objectStatus "U9G1.13" )
			)
			( pin "@baseboard_fab2_lib.baseboard_fab2(sch_1):page152_i1:a1"
				( attribute "PN" "12"
					( Origin gPackager )
				)
				( objectStatus "U9G1.12" )
			)
			( pin "@baseboard_fab2_lib.baseboard_fab2(sch_1):page152_i1:a2"
				( attribute "PN" "10"
					( Origin gPackager )
				)
				( objectStatus "U9G1.10" )
			)
			( pin "@baseboard_fab2_lib.baseboard_fab2(sch_1):page152_i1:a3"
				( attribute "PN" "9"
					( Origin gPackager )
				)
				( objectStatus "U9G1.9" )
			)
			( pin "@baseboard_fab2_lib.baseboard_fab2(sch_1):page152_i1:b0"
				( attribute "PN" "2"
					( Origin gPackager )
				)
				( objectStatus "U9G1.2" )
			)
			( pin "@baseboard_fab2_lib.baseboard_fab2(sch_1):page152_i1:b1"
				( attribute "PN" "3"
					( Origin gPackager )
				)
				( objectStatus "U9G1.3" )
			)
			( pin "@baseboard_fab2_lib.baseboard_fab2(sch_1):page152_i1:b2"
				( attribute "PN" "5"
					( Origin gPackager )
				)
				( objectStatus "U9G1.5" )
			)
			( pin "@baseboard_fab2_lib.baseboard_fab2(sch_1):page152_i1:b3"
				( attribute "PN" "6"
					( Origin gPackager )
				)
				( objectStatus "U9G1.6" )
			)
			( pin "@baseboard_fab2_lib.baseboard_fab2(sch_1):page152_i1:dir"
				( attribute "PN" "1"
					( Origin gPackager )
				)
				( objectStatus "U9G1.1" )
			)
			( pin "@baseboard_fab2_lib.baseboard_fab2(sch_1):page152_i1:gnd(0)"
				( attribute "PN" "7"
					( Origin gPackager )
				)
				( objectStatus "U9G1.7" )
			)
			( pin "@baseboard_fab2_lib.baseboard_fab2(sch_1):page152_i1:gnd(1)"
				( attribute "PN" "8"
					( Origin gPackager )
				)
				( objectStatus "U9G1.8" )
			)
			( pin "@baseboard_fab2_lib.baseboard_fab2(sch_1):page152_i1:gnd(2)"
				( attribute "PN" "11"
					( Origin gPackager )
				)
				( objectStatus "U9G1.11" )
			)
			( pin "@baseboard_fab2_lib.baseboard_fab2(sch_1):page152_i1:vcc"
				( attribute "PN" "14"
					( Origin gPackager )
				)
				( objectStatus "U9G1.14" )
			)
			( pin "@baseboard_fab2_lib.baseboard_fab2(sch_1):page152_i1:vref"
				( attribute "PN" "4"
					( Origin gPackager )
				)
				( objectStatus "U9G1.4" )
			)
			( pin "@baseboard_fab2_lib.baseboard_fab2(sch_1):page152_i2:a"
				( attribute "PN" "1"
					( Origin gPackager )
				)
				( objectStatus "R1U30.1" )
			)
			( pin "@baseboard_fab2_lib.baseboard_fab2(sch_1):page152_i2:b"
				( attribute "PN" "2"
					( Origin gPackager )
				)
				( objectStatus "R1U30.2" )
			)
			( pin "@baseboard_fab2_lib.baseboard_fab2(sch_1):page152_i6:a"
				( attribute "PN" "1"
					( Origin gPackager )
				)
				( objectStatus "R1U46.1" )
			)
			( pin "@baseboard_fab2_lib.baseboard_fab2(sch_1):page152_i6:b"
				( attribute "PN" "2"
					( Origin gPackager )
				)
				( objectStatus "R1U46.2" )
			)
			( pin "@baseboard_fab2_lib.baseboard_fab2(sch_1):page152_i14:a"
				( attribute "PN" "1"
					( Origin gPackager )
				)
				( objectStatus "R9G31.1" )
			)
			( pin "@baseboard_fab2_lib.baseboard_fab2(sch_1):page152_i14:b"
				( attribute "PN" "2"
					( Origin gPackager )
				)
				( objectStatus "R9G31.2" )
			)
			( pin "@baseboard_fab2_lib.baseboard_fab2(sch_1):page152_i15:a"
				( attribute "PN" "1"
					( Origin gPackager )
				)
				( objectStatus "R1U36.1" )
			)
			( pin "@baseboard_fab2_lib.baseboard_fab2(sch_1):page152_i15:b"
				( attribute "PN" "2"
					( Origin gPackager )
				)
				( objectStatus "R1U36.2" )
			)
			( pin "@baseboard_fab2_lib.baseboard_fab2(sch_1):page152_i16:a"
				( attribute "PN" "1"
					( Origin gPackager )
				)
				( objectStatus "R1U34.1" )
			)
			( pin "@baseboard_fab2_lib.baseboard_fab2(sch_1):page152_i16:b"
				( attribute "PN" "2"
					( Origin gPackager )
				)
				( objectStatus "R1U34.2" )
			)
			( pin "@baseboard_fab2_lib.baseboard_fab2(sch_1):page152_i18:a"
				( attribute "PN" "1"
					( Origin gPackager )
				)
				( objectStatus "C1U19.1" )
			)
			( pin "@baseboard_fab2_lib.baseboard_fab2(sch_1):page152_i18:b"
				( attribute "PN" "2"
					( Origin gPackager )
				)
				( objectStatus "C1U19.2" )
			)
			( pin "@baseboard_fab2_lib.baseboard_fab2(sch_1):page152_i26:a"
				( attribute "PN" "1"
					( Origin gPackager )
				)
				( objectStatus "R1U37.1" )
			)
			( pin "@baseboard_fab2_lib.baseboard_fab2(sch_1):page152_i26:b"
				( attribute "PN" "2"
					( Origin gPackager )
				)
				( objectStatus "R1U37.2" )
			)
			( pin "@baseboard_fab2_lib.baseboard_fab2(sch_1):page152_i27:a"
				( attribute "PN" "1"
					( Origin gPackager )
				)
				( objectStatus "C1U22.1" )
			)
			( pin "@baseboard_fab2_lib.baseboard_fab2(sch_1):page152_i27:b"
				( attribute "PN" "2"
					( Origin gPackager )
				)
				( objectStatus "C1U22.2" )
			)
			( pin "@baseboard_fab2_lib.baseboard_fab2(sch_1):page152_i45:a"
				( attribute "PN" "1"
					( Origin gPackager )
				)
				( objectStatus "R9G34.1" )
			)
			( pin "@baseboard_fab2_lib.baseboard_fab2(sch_1):page152_i45:b"
				( attribute "PN" "2"
					( Origin gPackager )
				)
				( objectStatus "R9G34.2" )
			)
			( pin "@baseboard_fab2_lib.baseboard_fab2(sch_1):page152_i47:a"
				( attribute "PN" "1"
					( Origin gPackager )
				)
				( objectStatus "R9G27.1" )
			)
			( pin "@baseboard_fab2_lib.baseboard_fab2(sch_1):page152_i47:b"
				( attribute "PN" "2"
					( Origin gPackager )
				)
				( objectStatus "R9G27.2" )
			)
			( pin "@baseboard_fab2_lib.baseboard_fab2(sch_1):page152_i49:a"
				( attribute "PN" "1"
					( Origin gPackager )
				)
				( objectStatus "R1U58.1" )
			)
			( pin "@baseboard_fab2_lib.baseboard_fab2(sch_1):page152_i49:b"
				( attribute "PN" "2"
					( Origin gPackager )
				)
				( objectStatus "R1U58.2" )
			)
			( pin "@baseboard_fab2_lib.baseboard_fab2(sch_1):page152_i50:a"
				( attribute "PN" "1"
					( Origin gPackager )
				)
				( objectStatus "R1U56.1" )
			)
			( pin "@baseboard_fab2_lib.baseboard_fab2(sch_1):page152_i50:b"
				( attribute "PN" "2"
					( Origin gPackager )
				)
				( objectStatus "R1U56.2" )
			)
			( pin "@baseboard_fab2_lib.baseboard_fab2(sch_1):page152_i51:a"
				( attribute "PN" "1"
					( Origin gPackager )
				)
				( objectStatus "R2U51.1" )
			)
			( pin "@baseboard_fab2_lib.baseboard_fab2(sch_1):page152_i51:b"
				( attribute "PN" "2"
					( Origin gPackager )
				)
				( objectStatus "R2U51.2" )
			)
			( pin "@baseboard_fab2_lib.baseboard_fab2(sch_1):page152_i53:a"
				( attribute "PN" "1"
					( Origin gPackager )
				)
				( objectStatus "R2U40.1" )
			)
			( pin "@baseboard_fab2_lib.baseboard_fab2(sch_1):page152_i53:b"
				( attribute "PN" "2"
					( Origin gPackager )
				)
				( objectStatus "R2U40.2" )
			)
			( pin "@baseboard_fab2_lib.baseboard_fab2(sch_1):page152_i54:a"
				( attribute "PN" "1"
					( Origin gPackager )
				)
				( objectStatus "R2U41.1" )
			)
			( pin "@baseboard_fab2_lib.baseboard_fab2(sch_1):page152_i54:b"
				( attribute "PN" "2"
					( Origin gPackager )
				)
				( objectStatus "R2U41.2" )
			)
			( pin "@baseboard_fab2_lib.baseboard_fab2(sch_1):page152_i56:a"
				( attribute "PN" "1"
					( Origin gPackager )
				)
				( objectStatus "R1U41.1" )
			)
			( pin "@baseboard_fab2_lib.baseboard_fab2(sch_1):page152_i56:b"
				( attribute "PN" "2"
					( Origin gPackager )
				)
				( objectStatus "R1U41.2" )
			)
			( pin "@baseboard_fab2_lib.baseboard_fab2(sch_1):page152_i57:a"
				( attribute "PN" "1"
					( Origin gPackager )
				)
				( objectStatus "R1U35.1" )
			)
			( pin "@baseboard_fab2_lib.baseboard_fab2(sch_1):page152_i57:b"
				( attribute "PN" "2"
					( Origin gPackager )
				)
				( objectStatus "R1U35.2" )
			)
			( pin "@baseboard_fab2_lib.baseboard_fab2(sch_1):page152_i58:a"
				( attribute "PN" "1"
					( Origin gPackager )
				)
				( objectStatus "R4P17.1" )
			)
			( pin "@baseboard_fab2_lib.baseboard_fab2(sch_1):page152_i58:b"
				( attribute "PN" "2"
					( Origin gPackager )
				)
				( objectStatus "R4P17.2" )
			)
			( pin "@baseboard_fab2_lib.baseboard_fab2(sch_1):page152_i59:a"
				( attribute "PN" "1"
					( Origin gPackager )
				)
				( objectStatus "R4P20.1" )
			)
			( pin "@baseboard_fab2_lib.baseboard_fab2(sch_1):page152_i59:b"
				( attribute "PN" "2"
					( Origin gPackager )
				)
				( objectStatus "R4P20.2" )
			)
			( pin "@baseboard_fab2_lib.baseboard_fab2(sch_1):page152_i61:a"
				( attribute "PN" "1"
					( Origin gPackager )
				)
				( objectStatus "R7P5.1" )
			)
			( pin "@baseboard_fab2_lib.baseboard_fab2(sch_1):page152_i61:b"
				( attribute "PN" "2"
					( Origin gPackager )
				)
				( objectStatus "R7P5.2" )
			)
			( pin "@baseboard_fab2_lib.baseboard_fab2(sch_1):page152_i62:a"
				( attribute "PN" "1"
					( Origin gPackager )
				)
				( objectStatus "R7P21.1" )
			)
			( pin "@baseboard_fab2_lib.baseboard_fab2(sch_1):page152_i62:b"
				( attribute "PN" "2"
					( Origin gPackager )
				)
				( objectStatus "R7P21.2" )
			)
			( pin "@baseboard_fab2_lib.baseboard_fab2(sch_1):page152_i64:a"
				( attribute "PN" "1"
					( Origin gPackager )
				)
				( objectStatus "R1U53.1" )
			)
			( pin "@baseboard_fab2_lib.baseboard_fab2(sch_1):page152_i64:b"
				( attribute "PN" "2"
					( Origin gPackager )
				)
				( objectStatus "R1U53.2" )
			)
			( pin "@baseboard_fab2_lib.baseboard_fab2(sch_1):page152_i65:a"
				( attribute "PN" "1"
					( Origin gPackager )
				)
				( objectStatus "R1U60.1" )
			)
			( pin "@baseboard_fab2_lib.baseboard_fab2(sch_1):page152_i65:b"
				( attribute "PN" "2"
					( Origin gPackager )
				)
				( objectStatus "R1U60.2" )
			)
			( pin "@baseboard_fab2_lib.baseboard_fab2(sch_1):page152_i66:a"
				( attribute "PN" "1"
					( Origin gPackager )
				)
				( objectStatus "R2U49.1" )
			)
			( pin "@baseboard_fab2_lib.baseboard_fab2(sch_1):page152_i66:b"
				( attribute "PN" "2"
					( Origin gPackager )
				)
				( objectStatus "R2U49.2" )
			)
			( pin "@baseboard_fab2_lib.baseboard_fab2(sch_1):page152_i67:a"
				( attribute "PN" "1"
					( Origin gPackager )
				)
				( objectStatus "R1U55.1" )
			)
			( pin "@baseboard_fab2_lib.baseboard_fab2(sch_1):page152_i67:b"
				( attribute "PN" "2"
					( Origin gPackager )
				)
				( objectStatus "R1U55.2" )
			)
			( pin "@baseboard_fab2_lib.baseboard_fab2(sch_1):page152_i68:a"
				( attribute "PN" "1"
					( Origin gPackager )
				)
				( objectStatus "R1U62.1" )
			)
			( pin "@baseboard_fab2_lib.baseboard_fab2(sch_1):page152_i68:b"
				( attribute "PN" "2"
					( Origin gPackager )
				)
				( objectStatus "R1U62.2" )
			)
			( pin "@baseboard_fab2_lib.baseboard_fab2(sch_1):page152_i69:a"
				( attribute "PN" "1"
					( Origin gPackager )
				)
				( objectStatus "R1U57.1" )
			)
			( pin "@baseboard_fab2_lib.baseboard_fab2(sch_1):page152_i69:b"
				( attribute "PN" "2"
					( Origin gPackager )
				)
				( objectStatus "R1U57.2" )
			)
			( pin "@baseboard_fab2_lib.baseboard_fab2(sch_1):page152_i70:a"
				( attribute "PN" "1"
					( Origin gPackager )
				)
				( objectStatus "R1U61.1" )
			)
			( pin "@baseboard_fab2_lib.baseboard_fab2(sch_1):page152_i70:b"
				( attribute "PN" "2"
					( Origin gPackager )
				)
				( objectStatus "R1U61.2" )
			)
			( pin "@baseboard_fab2_lib.baseboard_fab2(sch_1):page152_i71:a"
				( attribute "PN" "1"
					( Origin gPackager )
				)
				( objectStatus "R9G28.1" )
			)
			( pin "@baseboard_fab2_lib.baseboard_fab2(sch_1):page152_i71:b"
				( attribute "PN" "2"
					( Origin gPackager )
				)
				( objectStatus "R9G28.2" )
			)
			( pin "@baseboard_fab2_lib.baseboard_fab2(sch_1):page152_i72:a"
				( attribute "PN" "1"
					( Origin gPackager )
				)
				( objectStatus "R9G32.1" )
			)
			( pin "@baseboard_fab2_lib.baseboard_fab2(sch_1):page152_i72:b"
				( attribute "PN" "2"
					( Origin gPackager )
				)
				( objectStatus "R9G32.2" )
			)
			( pin "@baseboard_fab2_lib.baseboard_fab2(sch_1):page152_i73:a"
				( attribute "PN" "1"
					( Origin gPackager )
				)
				( objectStatus "R9G33.1" )
			)
			( pin "@baseboard_fab2_lib.baseboard_fab2(sch_1):page152_i73:b"
				( attribute "PN" "2"
					( Origin gPackager )
				)
				( objectStatus "R9G33.2" )
			)
			( pin "@baseboard_fab2_lib.baseboard_fab2(sch_1):page152_i74:a"
				( attribute "PN" "1"
					( Origin gPackager )
				)
				( objectStatus "R1U59.1" )
			)
			( pin "@baseboard_fab2_lib.baseboard_fab2(sch_1):page152_i74:b"
				( attribute "PN" "2"
					( Origin gPackager )
				)
				( objectStatus "R1U59.2" )
			)
			( pin "@baseboard_fab2_lib.baseboard_fab2(sch_1):page152_i79:a"
				( attribute "PN" "1"
					( Origin gPackager )
				)
				( objectStatus "R2U47.1" )
			)
			( pin "@baseboard_fab2_lib.baseboard_fab2(sch_1):page152_i79:b"
				( attribute "PN" "2"
					( Origin gPackager )
				)
				( objectStatus "R2U47.2" )
			)
			( pin "@baseboard_fab2_lib.baseboard_fab2(sch_1):page152_i92:a"
				( attribute "PN" "1"
					( Origin gPackager )
				)
				( objectStatus "R9G29.1" )
			)
			( pin "@baseboard_fab2_lib.baseboard_fab2(sch_1):page152_i92:b"
				( attribute "PN" "2"
					( Origin gPackager )
				)
				( objectStatus "R9G29.2" )
			)
			( pin "@baseboard_fab2_lib.baseboard_fab2(sch_1):page152_i93:a"
				( attribute "PN" "1"
					( Origin gPackager )
				)
				( objectStatus "R1U54.1" )
			)
			( pin "@baseboard_fab2_lib.baseboard_fab2(sch_1):page152_i93:b"
				( attribute "PN" "2"
					( Origin gPackager )
				)
				( objectStatus "R1U54.2" )
			)
			( pin "@baseboard_fab2_lib.baseboard_fab2(sch_1):page152_i94:a"
				( attribute "PN" "1"
					( Origin gPackager )
				)
				( objectStatus "R2U46.1" )
			)
			( pin "@baseboard_fab2_lib.baseboard_fab2(sch_1):page152_i94:b"
				( attribute "PN" "2"
					( Origin gPackager )
				)
				( objectStatus "R2U46.2" )
			)
			( pin "@baseboard_fab2_lib.baseboard_fab2(sch_1):page152_i95:a"
				( attribute "PN" "1"
					( Origin gPackager )
				)
				( objectStatus "R3N30.1" )
			)
			( pin "@baseboard_fab2_lib.baseboard_fab2(sch_1):page152_i95:b"
				( attribute "PN" "2"
					( Origin gPackager )
				)
				( objectStatus "R3N30.2" )
			)
			( pin "@baseboard_fab2_lib.baseboard_fab2(sch_1):page152_i98:a"
				( attribute "PN" "1"
					( Origin gPackager )
				)
				( objectStatus "R9G30.1" )
			)
			( pin "@baseboard_fab2_lib.baseboard_fab2(sch_1):page152_i98:b"
				( attribute "PN" "2"
					( Origin gPackager )
				)
				( objectStatus "R9G30.2" )
			)
			( pin "@baseboard_fab2_lib.baseboard_fab2(sch_1):page152_i100:a"
				( attribute "PN" "1"
					( Origin gPackager )
				)
				( objectStatus "R3P63.1" )
			)
			( pin "@baseboard_fab2_lib.baseboard_fab2(sch_1):page152_i100:b"
				( attribute "PN" "2"
					( Origin gPackager )
				)
				( objectStatus "R3P63.2" )
			)
			( pin "@baseboard_fab2_lib.baseboard_fab2(sch_1):page152_i102:a"
				( attribute "PN" "1"
					( Origin gPackager )
				)
				( objectStatus "R2U45.1" )
			)
			( pin "@baseboard_fab2_lib.baseboard_fab2(sch_1):page152_i102:b"
				( attribute "PN" "2"
					( Origin gPackager )
				)
				( objectStatus "R2U45.2" )
			)
			( pin "@baseboard_fab2_lib.baseboard_fab2(sch_1):page153_i90:a"
				( attribute "PN" "1"
					( Origin gPackager )
				)
				( objectStatus "R7F6.1" )
			)
			( pin "@baseboard_fab2_lib.baseboard_fab2(sch_1):page153_i90:b"
				( attribute "PN" "2"
					( Origin gPackager )
				)
				( objectStatus "R7F6.2" )
			)
			( pin "@baseboard_fab2_lib.baseboard_fab2(sch_1):page153_i94:a"
				( attribute "PN" "1"
					( Origin gPackager )
				)
				( objectStatus "R7F5.1" )
			)
			( pin "@baseboard_fab2_lib.baseboard_fab2(sch_1):page153_i94:b"
				( attribute "PN" "2"
					( Origin gPackager )
				)
				( objectStatus "R7F5.2" )
			)
			( pin "@baseboard_fab2_lib.baseboard_fab2(sch_1):page153_i98:a"
				( attribute "PN" "1"
					( Origin gPackager )
				)
				( objectStatus "R7F4.1" )
			)
			( pin "@baseboard_fab2_lib.baseboard_fab2(sch_1):page153_i98:b"
				( attribute "PN" "2"
					( Origin gPackager )
				)
				( objectStatus "R7F4.2" )
			)
			( pin "@baseboard_fab2_lib.baseboard_fab2(sch_1):page153_i108:a"
				( attribute "PN" "1"
					( Origin gPackager )
				)
				( objectStatus "R7F37.1" )
			)
			( pin "@baseboard_fab2_lib.baseboard_fab2(sch_1):page153_i108:b"
				( attribute "PN" "2"
					( Origin gPackager )
				)
				( objectStatus "R7F37.2" )
			)
			( pin "@baseboard_fab2_lib.baseboard_fab2(sch_1):page153_i109:a"
				( attribute "PN" "1"
					( Origin gPackager )
				)
				( objectStatus "R7F3.1" )
			)
			( pin "@baseboard_fab2_lib.baseboard_fab2(sch_1):page153_i109:b"
				( attribute "PN" "2"
					( Origin gPackager )
				)
				( objectStatus "R7F3.2" )
			)
			( pin "@baseboard_fab2_lib.baseboard_fab2(sch_1):page153_i130:a"
				( attribute "PN" "1"
					( Origin gPackager )
				)
				( objectStatus "C7F2.1" )
			)
			( pin "@baseboard_fab2_lib.baseboard_fab2(sch_1):page153_i130:b"
				( attribute "PN" "2"
					( Origin gPackager )
				)
				( objectStatus "C7F2.2" )
			)
			( pin "@baseboard_fab2_lib.baseboard_fab2(sch_1):page153_i131:a"
				( attribute "PN" "1"
					( Origin gPackager )
				)
				( objectStatus "C7F1.1" )
			)
			( pin "@baseboard_fab2_lib.baseboard_fab2(sch_1):page153_i131:b"
				( attribute "PN" "2"
					( Origin gPackager )
				)
				( objectStatus "C7F1.2" )
			)
			( pin "@baseboard_fab2_lib.baseboard_fab2(sch_1):page153_i136:a"
				( attribute "PN" "1"
					( Origin gPackager )
				)
				( objectStatus "C3T5.1" )
			)
			( pin "@baseboard_fab2_lib.baseboard_fab2(sch_1):page153_i136:b"
				( attribute "PN" "2"
					( Origin gPackager )
				)
				( objectStatus "C3T5.2" )
			)
			( pin "@baseboard_fab2_lib.baseboard_fab2(sch_1):page153_i138:a"
				( attribute "PN" "1"
					( Origin gPackager )
				)
				( objectStatus "C3T4.1" )
			)
			( pin "@baseboard_fab2_lib.baseboard_fab2(sch_1):page153_i138:b"
				( attribute "PN" "2"
					( Origin gPackager )
				)
				( objectStatus "C3T4.2" )
			)
			( pin "@baseboard_fab2_lib.baseboard_fab2(sch_1):page153_i140:a"
				( attribute "PN" "1"
					( Origin gPackager )
				)
				( objectStatus "R7F32.1" )
			)
			( pin "@baseboard_fab2_lib.baseboard_fab2(sch_1):page153_i140:b"
				( attribute "PN" "2"
					( Origin gPackager )
				)
				( objectStatus "R7F32.2" )
			)
			( pin "@baseboard_fab2_lib.baseboard_fab2(sch_1):page153_i146:clk"
				( attribute "PN" "16"
					( Origin gPackager )
				)
				( objectStatus "U7F1.16" )
			)
			( pin "@baseboard_fab2_lib.baseboard_fab2(sch_1):page153_i146:cs_n"
				( attribute "PN" "7"
					( Origin gPackager )
				)
				( objectStatus "U7F1.7" )
			)
			( pin "@baseboard_fab2_lib.baseboard_fab2(sch_1):page153_i146:di_io(0)"
				( attribute "PN" "15"
					( Origin gPackager )
				)
				( objectStatus "U7F1.15" )
			)
			( pin "@baseboard_fab2_lib.baseboard_fab2(sch_1):page153_i146:do_io(1)"
				( attribute "PN" "8"
					( Origin gPackager )
				)
				( objectStatus "U7F1.8" )
			)
			( pin "@baseboard_fab2_lib.baseboard_fab2(sch_1):page153_i146:gnd"
				( attribute "PN" "10"
					( Origin gPackager )
				)
				( objectStatus "U7F1.10" )
			)
			( pin "@baseboard_fab2_lib.baseboard_fab2(sch_1):page153_i146:hold_n_io(3)"
				( attribute "PN" "1"
					( Origin gPackager )
				)
				( objectStatus "U7F1.1" )
			)
			( pin "@baseboard_fab2_lib.baseboard_fab2(sch_1):page153_i146:nc(0)"
				( attribute "PN" "14"
					( Origin gPackager )
				)
				( objectStatus "U7F1.14" )
			)
			( pin "@baseboard_fab2_lib.baseboard_fab2(sch_1):page153_i146:nc(1)"
				( attribute "PN" "13"
					( Origin gPackager )
				)
				( objectStatus "U7F1.13" )
			)
			( pin "@baseboard_fab2_lib.baseboard_fab2(sch_1):page153_i146:nc(2)"
				( attribute "PN" "12"
					( Origin gPackager )
				)
				( objectStatus "U7F1.12" )
			)
			( pin "@baseboard_fab2_lib.baseboard_fab2(sch_1):page153_i146:nc(3)"
				( attribute "PN" "11"
					( Origin gPackager )
				)
				( objectStatus "U7F1.11" )
			)
			( pin "@baseboard_fab2_lib.baseboard_fab2(sch_1):page153_i146:nc(4)"
				( attribute "PN" "6"
					( Origin gPackager )
				)
				( objectStatus "U7F1.6" )
			)
			( pin "@baseboard_fab2_lib.baseboard_fab2(sch_1):page153_i146:nc(5)"
				( attribute "PN" "5"
					( Origin gPackager )
				)
				( objectStatus "U7F1.5" )
			)
			( pin "@baseboard_fab2_lib.baseboard_fab2(sch_1):page153_i146:nc(6)"
				( attribute "PN" "4"
					( Origin gPackager )
				)
				( objectStatus "U7F1.4" )
			)
			( pin "@baseboard_fab2_lib.baseboard_fab2(sch_1):page153_i146:reset_n"
				( attribute "PN" "3"
					( Origin gPackager )
				)
				( objectStatus "U7F1.3" )
			)
			( pin "@baseboard_fab2_lib.baseboard_fab2(sch_1):page153_i146:vcc"
				( attribute "PN" "2"
					( Origin gPackager )
				)
				( objectStatus "U7F1.2" )
			)
			( pin "@baseboard_fab2_lib.baseboard_fab2(sch_1):page153_i146:wp_n_io(2)"
				( attribute "PN" "9"
					( Origin gPackager )
				)
				( objectStatus "U7F1.9" )
			)
			( pin "@baseboard_fab2_lib.baseboard_fab2(sch_1):page153_i150:a"
				( attribute "PN" "1"
					( Origin gPackager )
				)
				( objectStatus "R3T3.1" )
			)
			( pin "@baseboard_fab2_lib.baseboard_fab2(sch_1):page153_i150:b"
				( attribute "PN" "2"
					( Origin gPackager )
				)
				( objectStatus "R3T3.2" )
			)
			( pin "@baseboard_fab2_lib.baseboard_fab2(sch_1):page153_i152:a"
				( attribute "PN" "1"
					( Origin gPackager )
				)
				( objectStatus "R3T5.1" )
			)
			( pin "@baseboard_fab2_lib.baseboard_fab2(sch_1):page153_i152:b"
				( attribute "PN" "2"
					( Origin gPackager )
				)
				( objectStatus "R3T5.2" )
			)
			( pin "@baseboard_fab2_lib.baseboard_fab2(sch_1):page153_i155:a"
				( attribute "PN" "1"
					( Origin gPackager )
				)
				( objectStatus "R3T2.1" )
			)
			( pin "@baseboard_fab2_lib.baseboard_fab2(sch_1):page153_i155:b"
				( attribute "PN" "2"
					( Origin gPackager )
				)
				( objectStatus "R3T2.2" )
			)
			( pin "@baseboard_fab2_lib.baseboard_fab2(sch_1):page153_i156:a"
				( attribute "PN" "1"
					( Origin gPackager )
				)
				( objectStatus "R3U1.1" )
			)
			( pin "@baseboard_fab2_lib.baseboard_fab2(sch_1):page153_i156:b"
				( attribute "PN" "2"
					( Origin gPackager )
				)
				( objectStatus "R3U1.2" )
			)
			( pin "@baseboard_fab2_lib.baseboard_fab2(sch_1):page153_i157:a"
				( attribute "PN" "1"
					( Origin gPackager )
				)
				( objectStatus "R3T1.1" )
			)
			( pin "@baseboard_fab2_lib.baseboard_fab2(sch_1):page153_i157:b"
				( attribute "PN" "2"
					( Origin gPackager )
				)
				( objectStatus "R3T1.2" )
			)
			( pin "@baseboard_fab2_lib.baseboard_fab2(sch_1):page153_i166:a"
				( attribute "PN" "1"
					( Origin gPackager )
				)
				( objectStatus "R8F8.1" )
			)
			( pin "@baseboard_fab2_lib.baseboard_fab2(sch_1):page153_i166:b"
				( attribute "PN" "2"
					( Origin gPackager )
				)
				( objectStatus "R8F8.2" )
			)
			( pin "@baseboard_fab2_lib.baseboard_fab2(sch_1):page153_i167:a"
				( attribute "PN" "1"
					( Origin gPackager )
				)
				( objectStatus "R8F7.1" )
			)
			( pin "@baseboard_fab2_lib.baseboard_fab2(sch_1):page153_i167:b"
				( attribute "PN" "2"
					( Origin gPackager )
				)
				( objectStatus "R8F7.2" )
			)
			( pin "@baseboard_fab2_lib.baseboard_fab2(sch_1):page153_i168:a"
				( attribute "PN" "1"
					( Origin gPackager )
				)
				( objectStatus "R7F28.1" )
			)
			( pin "@baseboard_fab2_lib.baseboard_fab2(sch_1):page153_i168:b"
				( attribute "PN" "2"
					( Origin gPackager )
				)
				( objectStatus "R7F28.2" )
			)
			( pin "@baseboard_fab2_lib.baseboard_fab2(sch_1):page153_i170:a"
				( attribute "PN" "1"
					( Origin gPackager )
				)
				( objectStatus "R7F30.1" )
			)
			( pin "@baseboard_fab2_lib.baseboard_fab2(sch_1):page153_i170:b"
				( attribute "PN" "2"
					( Origin gPackager )
				)
				( objectStatus "R7F30.2" )
			)
			( pin "@baseboard_fab2_lib.baseboard_fab2(sch_1):page153_i174:a"
				( attribute "PN" "1"
					( Origin gPackager )
				)
				( objectStatus "R3T4.1" )
			)
			( pin "@baseboard_fab2_lib.baseboard_fab2(sch_1):page153_i174:b"
				( attribute "PN" "2"
					( Origin gPackager )
				)
				( objectStatus "R3T4.2" )
			)
			( pin "@baseboard_fab2_lib.baseboard_fab2(sch_1):page153_i178:a"
				( attribute "PN" "1"
					( Origin gPackager )
				)
				( objectStatus "R3T12.1" )
			)
			( pin "@baseboard_fab2_lib.baseboard_fab2(sch_1):page153_i178:b"
				( attribute "PN" "2"
					( Origin gPackager )
				)
				( objectStatus "R3T12.2" )
			)
			( pin "@baseboard_fab2_lib.baseboard_fab2(sch_1):page153_i179:a"
				( attribute "PN" "1"
					( Origin gPackager )
				)
				( objectStatus "R3T9.1" )
			)
			( pin "@baseboard_fab2_lib.baseboard_fab2(sch_1):page153_i179:b"
				( attribute "PN" "2"
					( Origin gPackager )
				)
				( objectStatus "R3T9.2" )
			)
			( pin "@baseboard_fab2_lib.baseboard_fab2(sch_1):page153_i181:a"
				( attribute "PN" "1"
					( Origin gPackager )
				)
				( objectStatus "R7F29.1" )
			)
			( pin "@baseboard_fab2_lib.baseboard_fab2(sch_1):page153_i181:b"
				( attribute "PN" "2"
					( Origin gPackager )
				)
				( objectStatus "R7F29.2" )
			)
			( pin "@baseboard_fab2_lib.baseboard_fab2(sch_1):page153_i184:a"
				( attribute "PN" "1"
					( Origin gPackager )
				)
				( objectStatus "R3T10.1" )
			)
			( pin "@baseboard_fab2_lib.baseboard_fab2(sch_1):page153_i184:b"
				( attribute "PN" "2"
					( Origin gPackager )
				)
				( objectStatus "R3T10.2" )
			)
			( pin "@baseboard_fab2_lib.baseboard_fab2(sch_1):page154_i14:a"
				( attribute "PN" "1"
					( Origin gPackager )
				)
				( objectStatus "C8E18.1" )
			)
			( pin "@baseboard_fab2_lib.baseboard_fab2(sch_1):page154_i14:b"
				( attribute "PN" "2"
					( Origin gPackager )
				)
				( objectStatus "C8E18.2" )
			)
			( pin "@baseboard_fab2_lib.baseboard_fab2(sch_1):page154_i62:a"
				( attribute "PN" "1"
					( Origin gPackager )
				)
				( objectStatus "R2T9.1" )
			)
			( pin "@baseboard_fab2_lib.baseboard_fab2(sch_1):page154_i62:b"
				( attribute "PN" "2"
					( Origin gPackager )
				)
				( objectStatus "R2T9.2" )
			)
			( pin "@baseboard_fab2_lib.baseboard_fab2(sch_1):page154_i74:en"
				( attribute "PN" "15"
					( Origin gPackager )
				)
				( objectStatus "U8F1.15" )
			)
			( pin "@baseboard_fab2_lib.baseboard_fab2(sch_1):page154_i74:gnd"
				( attribute "PN" "8"
					( Origin gPackager )
				)
				( objectStatus "U8F1.8" )
			)
			( pin "@baseboard_fab2_lib.baseboard_fab2(sch_1):page154_i74:ia0"
				( attribute "PN" "2"
					( Origin gPackager )
				)
				( objectStatus "U8F1.2" )
			)
			( pin "@baseboard_fab2_lib.baseboard_fab2(sch_1):page154_i74:ia1"
				( attribute "PN" "3"
					( Origin gPackager )
				)
				( objectStatus "U8F1.3" )
			)
			( pin "@baseboard_fab2_lib.baseboard_fab2(sch_1):page154_i74:ib0"
				( attribute "PN" "5"
					( Origin gPackager )
				)
				( objectStatus "U8F1.5" )
			)
			( pin "@baseboard_fab2_lib.baseboard_fab2(sch_1):page154_i74:ib1"
				( attribute "PN" "6"
					( Origin gPackager )
				)
				( objectStatus "U8F1.6" )
			)
			( pin "@baseboard_fab2_lib.baseboard_fab2(sch_1):page154_i74:ic0"
				( attribute "PN" "11"
					( Origin gPackager )
				)
				( objectStatus "U8F1.11" )
			)
			( pin "@baseboard_fab2_lib.baseboard_fab2(sch_1):page154_i74:ic1"
				( attribute "PN" "10"
					( Origin gPackager )
				)
				( objectStatus "U8F1.10" )
			)
			( pin "@baseboard_fab2_lib.baseboard_fab2(sch_1):page154_i74:id0"
				( attribute "PN" "14"
					( Origin gPackager )
				)
				( objectStatus "U8F1.14" )
			)
			( pin "@baseboard_fab2_lib.baseboard_fab2(sch_1):page154_i74:id1"
				( attribute "PN" "13"
					( Origin gPackager )
				)
				( objectStatus "U8F1.13" )
			)
			( pin "@baseboard_fab2_lib.baseboard_fab2(sch_1):page154_i74:s"
				( attribute "PN" "1"
					( Origin gPackager )
				)
				( objectStatus "U8F1.1" )
			)
			( pin "@baseboard_fab2_lib.baseboard_fab2(sch_1):page154_i74:vcc"
				( attribute "PN" "16"
					( Origin gPackager )
				)
				( objectStatus "U8F1.16" )
			)
			( pin "@baseboard_fab2_lib.baseboard_fab2(sch_1):page154_i74:ya"
				( attribute "PN" "4"
					( Origin gPackager )
				)
				( objectStatus "U8F1.4" )
			)
			( pin "@baseboard_fab2_lib.baseboard_fab2(sch_1):page154_i74:yb"
				( attribute "PN" "7"
					( Origin gPackager )
				)
				( objectStatus "U8F1.7" )
			)
			( pin "@baseboard_fab2_lib.baseboard_fab2(sch_1):page154_i74:yc"
				( attribute "PN" "9"
					( Origin gPackager )
				)
				( objectStatus "U8F1.9" )
			)
			( pin "@baseboard_fab2_lib.baseboard_fab2(sch_1):page154_i74:yd"
				( attribute "PN" "12"
					( Origin gPackager )
				)
				( objectStatus "U8F1.12" )
			)
			( pin "@baseboard_fab2_lib.baseboard_fab2(sch_1):page154_i75:en"
				( attribute "PN" "15"
					( Origin gPackager )
				)
				( objectStatus "U2T1.15" )
			)
			( pin "@baseboard_fab2_lib.baseboard_fab2(sch_1):page154_i75:gnd"
				( attribute "PN" "8"
					( Origin gPackager )
				)
				( objectStatus "U2T1.8" )
			)
			( pin "@baseboard_fab2_lib.baseboard_fab2(sch_1):page154_i75:ia0"
				( attribute "PN" "2"
					( Origin gPackager )
				)
				( objectStatus "U2T1.2" )
			)
			( pin "@baseboard_fab2_lib.baseboard_fab2(sch_1):page154_i75:ia1"
				( attribute "PN" "3"
					( Origin gPackager )
				)
				( objectStatus "U2T1.3" )
			)
			( pin "@baseboard_fab2_lib.baseboard_fab2(sch_1):page154_i75:ib0"
				( attribute "PN" "5"
					( Origin gPackager )
				)
				( objectStatus "U2T1.5" )
			)
			( pin "@baseboard_fab2_lib.baseboard_fab2(sch_1):page154_i75:ib1"
				( attribute "PN" "6"
					( Origin gPackager )
				)
				( objectStatus "U2T1.6" )
			)
			( pin "@baseboard_fab2_lib.baseboard_fab2(sch_1):page154_i75:ic0"
				( attribute "PN" "11"
					( Origin gPackager )
				)
				( objectStatus "U2T1.11" )
			)
			( pin "@baseboard_fab2_lib.baseboard_fab2(sch_1):page154_i75:ic1"
				( attribute "PN" "10"
					( Origin gPackager )
				)
				( objectStatus "U2T1.10" )
			)
			( pin "@baseboard_fab2_lib.baseboard_fab2(sch_1):page154_i75:id0"
				( attribute "PN" "14"
					( Origin gPackager )
				)
				( objectStatus "U2T1.14" )
			)
			( pin "@baseboard_fab2_lib.baseboard_fab2(sch_1):page154_i75:id1"
				( attribute "PN" "13"
					( Origin gPackager )
				)
				( objectStatus "U2T1.13" )
			)
			( pin "@baseboard_fab2_lib.baseboard_fab2(sch_1):page154_i75:s"
				( attribute "PN" "1"
					( Origin gPackager )
				)
				( objectStatus "U2T1.1" )
			)
			( pin "@baseboard_fab2_lib.baseboard_fab2(sch_1):page154_i75:vcc"
				( attribute "PN" "16"
					( Origin gPackager )
				)
				( objectStatus "U2T1.16" )
			)
			( pin "@baseboard_fab2_lib.baseboard_fab2(sch_1):page154_i75:ya"
				( attribute "PN" "4"
					( Origin gPackager )
				)
				( objectStatus "U2T1.4" )
			)
			( pin "@baseboard_fab2_lib.baseboard_fab2(sch_1):page154_i75:yb"
				( attribute "PN" "7"
					( Origin gPackager )
				)
				( objectStatus "U2T1.7" )
			)
			( pin "@baseboard_fab2_lib.baseboard_fab2(sch_1):page154_i75:yc"
				( attribute "PN" "9"
					( Origin gPackager )
				)
				( objectStatus "U2T1.9" )
			)
			( pin "@baseboard_fab2_lib.baseboard_fab2(sch_1):page154_i75:yd"
				( attribute "PN" "12"
					( Origin gPackager )
				)
				( objectStatus "U2T1.12" )
			)
			( pin "@baseboard_fab2_lib.baseboard_fab2(sch_1):page154_i92:a"
				( attribute "PN" "1"
					( Origin gPackager )
				)
				( objectStatus "R2T2.1" )
			)
			( pin "@baseboard_fab2_lib.baseboard_fab2(sch_1):page154_i92:b"
				( attribute "PN" "2"
					( Origin gPackager )
				)
				( objectStatus "R2T2.2" )
			)
			( pin "@baseboard_fab2_lib.baseboard_fab2(sch_1):page154_i93:a"
				( attribute "PN" "1"
					( Origin gPackager )
				)
				( objectStatus "R2R12.1" )
			)
			( pin "@baseboard_fab2_lib.baseboard_fab2(sch_1):page154_i93:b"
				( attribute "PN" "2"
					( Origin gPackager )
				)
				( objectStatus "R2R12.2" )
			)
			( pin "@baseboard_fab2_lib.baseboard_fab2(sch_1):page154_i94:a"
				( attribute "PN" "1"
					( Origin gPackager )
				)
				( objectStatus "C2T1.1" )
			)
			( pin "@baseboard_fab2_lib.baseboard_fab2(sch_1):page154_i94:b"
				( attribute "PN" "2"
					( Origin gPackager )
				)
				( objectStatus "C2T1.2" )
			)
			( pin "@baseboard_fab2_lib.baseboard_fab2(sch_1):page154_i99:a"
				( attribute "PN" "1"
					( Origin gPackager )
				)
				( objectStatus "U2T3.1" )
			)
			( pin "@baseboard_fab2_lib.baseboard_fab2(sch_1):page154_i99:b"
				( attribute "PN" "2"
					( Origin gPackager )
				)
				( objectStatus "U2T3.2" )
			)
			( pin "@baseboard_fab2_lib.baseboard_fab2(sch_1):page154_i99:y"
				( attribute "PN" "4"
					( Origin gPackager )
				)
				( objectStatus "U2T3.4" )
			)
			( pin "@baseboard_fab2_lib.baseboard_fab2(sch_1):page154_i100:a"
				( attribute "PN" "1"
					( Origin gPackager )
				)
				( objectStatus "U2T2.1" )
			)
			( pin "@baseboard_fab2_lib.baseboard_fab2(sch_1):page154_i100:b"
				( attribute "PN" "2"
					( Origin gPackager )
				)
				( objectStatus "U2T2.2" )
			)
			( pin "@baseboard_fab2_lib.baseboard_fab2(sch_1):page154_i100:y"
				( attribute "PN" "4"
					( Origin gPackager )
				)
				( objectStatus "U2T2.4" )
			)
			( pin "@baseboard_fab2_lib.baseboard_fab2(sch_1):page154_i101:a"
				( attribute "PN" "1"
					( Origin gPackager )
				)
				( objectStatus "R2T13.1" )
			)
			( pin "@baseboard_fab2_lib.baseboard_fab2(sch_1):page154_i101:b"
				( attribute "PN" "2"
					( Origin gPackager )
				)
				( objectStatus "R2T13.2" )
			)
			( pin "@baseboard_fab2_lib.baseboard_fab2(sch_1):page154_i105:a"
				( attribute "PN" "1"
					( Origin gPackager )
				)
				( objectStatus "R2T11.1" )
			)
			( pin "@baseboard_fab2_lib.baseboard_fab2(sch_1):page154_i105:b"
				( attribute "PN" "2"
					( Origin gPackager )
				)
				( objectStatus "R2T11.2" )
			)
			( pin "@baseboard_fab2_lib.baseboard_fab2(sch_1):page154_i106:a"
				( attribute "PN" "1"
					( Origin gPackager )
				)
				( objectStatus "R2T8.1" )
			)
			( pin "@baseboard_fab2_lib.baseboard_fab2(sch_1):page154_i106:b"
				( attribute "PN" "2"
					( Origin gPackager )
				)
				( objectStatus "R2T8.2" )
			)
			( pin "@baseboard_fab2_lib.baseboard_fab2(sch_1):page154_i119:a"
				( attribute "PN" "1"
					( Origin gPackager )
				)
				( objectStatus "R8F6.1" )
			)
			( pin "@baseboard_fab2_lib.baseboard_fab2(sch_1):page154_i119:b"
				( attribute "PN" "2"
					( Origin gPackager )
				)
				( objectStatus "R8F6.2" )
			)
			( pin "@baseboard_fab2_lib.baseboard_fab2(sch_1):page154_i126:drn"
				( attribute "PN" "3"
					( Origin gPackager )
				)
				( objectStatus "Q8F1.3" )
			)
			( pin "@baseboard_fab2_lib.baseboard_fab2(sch_1):page154_i126:gate"
				( attribute "PN" "1"
					( Origin gPackager )
				)
				( objectStatus "Q8F1.1" )
			)
			( pin "@baseboard_fab2_lib.baseboard_fab2(sch_1):page154_i126:src"
				( attribute "PN" "2"
					( Origin gPackager )
				)
				( objectStatus "Q8F1.2" )
			)
			( pin "@baseboard_fab2_lib.baseboard_fab2(sch_1):page154_i127:a"
				( attribute "PN" "1"
					( Origin gPackager )
				)
				( objectStatus "R2T6.1" )
			)
			( pin "@baseboard_fab2_lib.baseboard_fab2(sch_1):page154_i127:b"
				( attribute "PN" "2"
					( Origin gPackager )
				)
				( objectStatus "R2T6.2" )
			)
			( pin "@baseboard_fab2_lib.baseboard_fab2(sch_1):page154_i128:a"
				( attribute "PN" "1"
					( Origin gPackager )
				)
				( objectStatus "R1U6.1" )
			)
			( pin "@baseboard_fab2_lib.baseboard_fab2(sch_1):page154_i128:b"
				( attribute "PN" "2"
					( Origin gPackager )
				)
				( objectStatus "R1U6.2" )
			)
			( pin "@baseboard_fab2_lib.baseboard_fab2(sch_1):page154_i132:a"
				( attribute "PN" "1"
					( Origin gPackager )
				)
				( objectStatus "C2T12.1" )
			)
			( pin "@baseboard_fab2_lib.baseboard_fab2(sch_1):page154_i132:b"
				( attribute "PN" "2"
					( Origin gPackager )
				)
				( objectStatus "C2T12.2" )
			)
			( pin "@baseboard_fab2_lib.baseboard_fab2(sch_1):page154_i135:a"
				( attribute "PN" "1"
					( Origin gPackager )
				)
				( objectStatus "C2T8.1" )
			)
			( pin "@baseboard_fab2_lib.baseboard_fab2(sch_1):page154_i135:b"
				( attribute "PN" "2"
					( Origin gPackager )
				)
				( objectStatus "C2T8.2" )
			)
			( pin "@baseboard_fab2_lib.baseboard_fab2(sch_1):page155_i53:a"
				( attribute "PN" "1"
					( Origin gPackager )
				)
				( objectStatus "R9A8.1" )
			)
			( pin "@baseboard_fab2_lib.baseboard_fab2(sch_1):page155_i53:b"
				( attribute "PN" "2"
					( Origin gPackager )
				)
				( objectStatus "R9A8.2" )
			)
			( pin "@baseboard_fab2_lib.baseboard_fab2(sch_1):page155_i65:a"
				( attribute "PN" "1"
					( Origin gPackager )
				)
				( objectStatus "R1L32.1" )
			)
			( pin "@baseboard_fab2_lib.baseboard_fab2(sch_1):page155_i65:b"
				( attribute "PN" "2"
					( Origin gPackager )
				)
				( objectStatus "R1L32.2" )
			)
			( pin "@baseboard_fab2_lib.baseboard_fab2(sch_1):page155_i66:a"
				( attribute "PN" "1"
					( Origin gPackager )
				)
				( objectStatus "R1L30.1" )
			)
			( pin "@baseboard_fab2_lib.baseboard_fab2(sch_1):page155_i66:b"
				( attribute "PN" "2"
					( Origin gPackager )
				)
				( objectStatus "R1L30.2" )
			)
			( pin "@baseboard_fab2_lib.baseboard_fab2(sch_1):page155_i67:a"
				( attribute "PN" "1"
					( Origin gPackager )
				)
				( objectStatus "R1L25.1" )
			)
			( pin "@baseboard_fab2_lib.baseboard_fab2(sch_1):page155_i67:b"
				( attribute "PN" "2"
					( Origin gPackager )
				)
				( objectStatus "R1L25.2" )
			)
			( pin "@baseboard_fab2_lib.baseboard_fab2(sch_1):page155_i68:a"
				( attribute "PN" "1"
					( Origin gPackager )
				)
				( objectStatus "R1L24.1" )
			)
			( pin "@baseboard_fab2_lib.baseboard_fab2(sch_1):page155_i68:b"
				( attribute "PN" "2"
					( Origin gPackager )
				)
				( objectStatus "R1L24.2" )
			)
			( pin "@baseboard_fab2_lib.baseboard_fab2(sch_1):page155_i73:a"
				( attribute "PN" "1"
					( Origin gPackager )
				)
				( objectStatus "R1L20.1" )
			)
			( pin "@baseboard_fab2_lib.baseboard_fab2(sch_1):page155_i73:b"
				( attribute "PN" "2"
					( Origin gPackager )
				)
				( objectStatus "R1L20.2" )
			)
			( pin "@baseboard_fab2_lib.baseboard_fab2(sch_1):page155_i74:a"
				( attribute "PN" "1"
					( Origin gPackager )
				)
				( objectStatus "R1L18.1" )
			)
			( pin "@baseboard_fab2_lib.baseboard_fab2(sch_1):page155_i74:b"
				( attribute "PN" "2"
					( Origin gPackager )
				)
				( objectStatus "R1L18.2" )
			)
			( pin "@baseboard_fab2_lib.baseboard_fab2(sch_1):page155_i75:a"
				( attribute "PN" "1"
					( Origin gPackager )
				)
				( objectStatus "R1L14.1" )
			)
			( pin "@baseboard_fab2_lib.baseboard_fab2(sch_1):page155_i75:b"
				( attribute "PN" "2"
					( Origin gPackager )
				)
				( objectStatus "R1L14.2" )
			)
			( pin "@baseboard_fab2_lib.baseboard_fab2(sch_1):page155_i76:a"
				( attribute "PN" "1"
					( Origin gPackager )
				)
				( objectStatus "R1L11.1" )
			)
			( pin "@baseboard_fab2_lib.baseboard_fab2(sch_1):page155_i76:b"
				( attribute "PN" "2"
					( Origin gPackager )
				)
				( objectStatus "R1L11.2" )
			)
			( pin "@baseboard_fab2_lib.baseboard_fab2(sch_1):page155_i80:a"
				( attribute "PN" "1"
					( Origin gPackager )
				)
				( objectStatus "R9A7.1" )
			)
			( pin "@baseboard_fab2_lib.baseboard_fab2(sch_1):page155_i80:b"
				( attribute "PN" "2"
					( Origin gPackager )
				)
				( objectStatus "R9A7.2" )
			)
			( pin "@baseboard_fab2_lib.baseboard_fab2(sch_1):page155_i127:a"
				( attribute "PN" "1"
					( Origin gPackager )
				)
				( objectStatus "C9A1.1" )
			)
			( pin "@baseboard_fab2_lib.baseboard_fab2(sch_1):page155_i127:b"
				( attribute "PN" "2"
					( Origin gPackager )
				)
				( objectStatus "C9A1.2" )
			)
			( pin "@baseboard_fab2_lib.baseboard_fab2(sch_1):page155_i129:a(0)"
				( attribute "PN" "1"
					( Origin gPackager )
				)
				( objectStatus "F1L1.1" )
			)
			( pin "@baseboard_fab2_lib.baseboard_fab2(sch_1):page155_i129:b(0)"
				( attribute "PN" "2"
					( Origin gPackager )
				)
				( objectStatus "F1L1.2" )
			)
			( pin "@baseboard_fab2_lib.baseboard_fab2(sch_1):page155_i130:a"
				( attribute "PN" "1"
					( Origin gPackager )
				)
				( objectStatus "R1L9.1" )
			)
			( pin "@baseboard_fab2_lib.baseboard_fab2(sch_1):page155_i130:b"
				( attribute "PN" "2"
					( Origin gPackager )
				)
				( objectStatus "R1L9.2" )
			)
			( pin "@baseboard_fab2_lib.baseboard_fab2(sch_1):page155_i171:io1"
				( attribute "PN" "1"
					( Origin gPackager )
				)
				( objectStatus "J9A2.1" )
			)
			( pin "@baseboard_fab2_lib.baseboard_fab2(sch_1):page155_i171:io2"
				( attribute "PN" "2"
					( Origin gPackager )
				)
				( objectStatus "J9A2.2" )
			)
			( pin "@baseboard_fab2_lib.baseboard_fab2(sch_1):page155_i171:io3"
				( attribute "PN" "3"
					( Origin gPackager )
				)
				( objectStatus "J9A2.3" )
			)
			( pin "@baseboard_fab2_lib.baseboard_fab2(sch_1):page155_i171:io4"
				( attribute "PN" "4"
					( Origin gPackager )
				)
				( objectStatus "J9A2.4" )
			)
			( pin "@baseboard_fab2_lib.baseboard_fab2(sch_1):page155_i171:io5"
				( attribute "PN" "5"
					( Origin gPackager )
				)
				( objectStatus "J9A2.5" )
			)
			( pin "@baseboard_fab2_lib.baseboard_fab2(sch_1):page155_i171:io6"
				( attribute "PN" "6"
					( Origin gPackager )
				)
				( objectStatus "J9A2.6" )
			)
			( pin "@baseboard_fab2_lib.baseboard_fab2(sch_1):page155_i171:io7"
				( attribute "PN" "7"
					( Origin gPackager )
				)
				( objectStatus "J9A2.7" )
			)
			( pin "@baseboard_fab2_lib.baseboard_fab2(sch_1):page155_i171:io8"
				( attribute "PN" "8"
					( Origin gPackager )
				)
				( objectStatus "J9A2.8" )
			)
			( pin "@baseboard_fab2_lib.baseboard_fab2(sch_1):page155_i171:io9"
				( attribute "PN" "9"
					( Origin gPackager )
				)
				( objectStatus "J9A2.9" )
			)
			( pin "@baseboard_fab2_lib.baseboard_fab2(sch_1):page155_i171:io10"
				( attribute "PN" "10"
					( Origin gPackager )
				)
				( objectStatus "J9A2.10" )
			)
			( pin "@baseboard_fab2_lib.baseboard_fab2(sch_1):page155_i171:io11"
				( attribute "PN" "11"
					( Origin gPackager )
				)
				( objectStatus "J9A2.11" )
			)
			( pin "@baseboard_fab2_lib.baseboard_fab2(sch_1):page155_i171:io12"
				( attribute "PN" "12"
					( Origin gPackager )
				)
				( objectStatus "J9A2.12" )
			)
			( pin "@baseboard_fab2_lib.baseboard_fab2(sch_1):page155_i171:io13"
				( attribute "PN" "13"
					( Origin gPackager )
				)
				( objectStatus "J9A2.13" )
			)
			( pin "@baseboard_fab2_lib.baseboard_fab2(sch_1):page155_i171:io14"
				( attribute "PN" "14"
					( Origin gPackager )
				)
				( objectStatus "J9A2.14" )
			)
			( pin "@baseboard_fab2_lib.baseboard_fab2(sch_1):page155_i178:a"
				( attribute "PN" "2"
					( Origin gPackager )
				)
				( objectStatus "U9A1.2" )
			)
			( pin "@baseboard_fab2_lib.baseboard_fab2(sch_1):page155_i178:y"
				( attribute "PN" "4"
					( Origin gPackager )
				)
				( objectStatus "U9A1.4" )
			)
			( pin "@baseboard_fab2_lib.baseboard_fab2(sch_1):page155_i184:a"
				( attribute "PN" "1"
					( Origin gPackager )
				)
				( objectStatus "C1T56.1" )
			)
			( pin "@baseboard_fab2_lib.baseboard_fab2(sch_1):page155_i184:b"
				( attribute "PN" "2"
					( Origin gPackager )
				)
				( objectStatus "C1T56.2" )
			)
			( pin "@baseboard_fab2_lib.baseboard_fab2(sch_1):page155_i186:a"
				( attribute "PN" "1"
					( Origin gPackager )
				)
				( objectStatus "R1L2.1" )
			)
			( pin "@baseboard_fab2_lib.baseboard_fab2(sch_1):page155_i186:b"
				( attribute "PN" "2"
					( Origin gPackager )
				)
				( objectStatus "R1L2.2" )
			)
			( pin "@baseboard_fab2_lib.baseboard_fab2(sch_1):page155_i187:drain(0)"
				( attribute "PN" "3"
					( Origin gPackager )
				)
				( objectStatus "Q1L2.3" )
			)
			( pin "@baseboard_fab2_lib.baseboard_fab2(sch_1):page155_i187:gate(0)"
				( attribute "PN" "5"
					( Origin gPackager )
				)
				( objectStatus "Q1L2.5" )
			)
			( pin "@baseboard_fab2_lib.baseboard_fab2(sch_1):page155_i187:source(0)"
				( attribute "PN" "4"
					( Origin gPackager )
				)
				( objectStatus "Q1L2.4" )
			)
			( pin "@baseboard_fab2_lib.baseboard_fab2(sch_1):page155_i188:drain(0)"
				( attribute "PN" "6"
					( Origin gPackager )
				)
				( objectStatus "Q1L2.6" )
			)
			( pin "@baseboard_fab2_lib.baseboard_fab2(sch_1):page155_i188:gate(0)"
				( attribute "PN" "2"
					( Origin gPackager )
				)
				( objectStatus "Q1L2.2" )
			)
			( pin "@baseboard_fab2_lib.baseboard_fab2(sch_1):page155_i188:source(0)"
				( attribute "PN" "1"
					( Origin gPackager )
				)
				( objectStatus "Q1L2.1" )
			)
			( pin "@baseboard_fab2_lib.baseboard_fab2(sch_1):page156_i206:a"
				( attribute "PN" "1"
					( Origin gPackager )
				)
				( objectStatus "R2T34.1" )
			)
			( pin "@baseboard_fab2_lib.baseboard_fab2(sch_1):page156_i206:b"
				( attribute "PN" "2"
					( Origin gPackager )
				)
				( objectStatus "R2T34.2" )
			)
			( pin "@baseboard_fab2_lib.baseboard_fab2(sch_1):page156_i207:a"
				( attribute "PN" "1"
					( Origin gPackager )
				)
				( objectStatus "R2T35.1" )
			)
			( pin "@baseboard_fab2_lib.baseboard_fab2(sch_1):page156_i207:b"
				( attribute "PN" "2"
					( Origin gPackager )
				)
				( objectStatus "R2T35.2" )
			)
			( pin "@baseboard_fab2_lib.baseboard_fab2(sch_1):page156_i210:a"
				( attribute "PN" "1"
					( Origin gPackager )
				)
				( objectStatus "R2T22.1" )
			)
			( pin "@baseboard_fab2_lib.baseboard_fab2(sch_1):page156_i210:b"
				( attribute "PN" "2"
					( Origin gPackager )
				)
				( objectStatus "R2T22.2" )
			)
			( pin "@baseboard_fab2_lib.baseboard_fab2(sch_1):page156_i211:a"
				( attribute "PN" "1"
					( Origin gPackager )
				)
				( objectStatus "R8F26.1" )
			)
			( pin "@baseboard_fab2_lib.baseboard_fab2(sch_1):page156_i211:b"
				( attribute "PN" "2"
					( Origin gPackager )
				)
				( objectStatus "R8F26.2" )
			)
			( pin "@baseboard_fab2_lib.baseboard_fab2(sch_1):page156_i214:a"
				( attribute "PN" "1"
					( Origin gPackager )
				)
				( objectStatus "R8E24.1" )
			)
			( pin "@baseboard_fab2_lib.baseboard_fab2(sch_1):page156_i214:b"
				( attribute "PN" "2"
					( Origin gPackager )
				)
				( objectStatus "R8E24.2" )
			)
			( pin "@baseboard_fab2_lib.baseboard_fab2(sch_1):page156_i215:a"
				( attribute "PN" "1"
					( Origin gPackager )
				)
				( objectStatus "R8E22.1" )
			)
			( pin "@baseboard_fab2_lib.baseboard_fab2(sch_1):page156_i215:b"
				( attribute "PN" "2"
					( Origin gPackager )
				)
				( objectStatus "R8E22.2" )
			)
			( pin "@baseboard_fab2_lib.baseboard_fab2(sch_1):page156_i265:a"
				( attribute "PN" "1"
					( Origin gPackager )
				)
				( objectStatus "R2U2.1" )
			)
			( pin "@baseboard_fab2_lib.baseboard_fab2(sch_1):page156_i265:b"
				( attribute "PN" "2"
					( Origin gPackager )
				)
				( objectStatus "R2U2.2" )
			)
			( pin "@baseboard_fab2_lib.baseboard_fab2(sch_1):page156_i267:a"
				( attribute "PN" "1"
					( Origin gPackager )
				)
				( objectStatus "R8G2.1" )
			)
			( pin "@baseboard_fab2_lib.baseboard_fab2(sch_1):page156_i267:b"
				( attribute "PN" "2"
					( Origin gPackager )
				)
				( objectStatus "R8G2.2" )
			)
			( pin "@baseboard_fab2_lib.baseboard_fab2(sch_1):page156_i273:a"
				( attribute "PN" "1"
					( Origin gPackager )
				)
				( objectStatus "C2T35.1" )
			)
			( pin "@baseboard_fab2_lib.baseboard_fab2(sch_1):page156_i273:b"
				( attribute "PN" "2"
					( Origin gPackager )
				)
				( objectStatus "C2T35.2" )
			)
			( pin "@baseboard_fab2_lib.baseboard_fab2(sch_1):page156_i275:a"
				( attribute "PN" "1"
					( Origin gPackager )
				)
				( objectStatus "C8F16.1" )
			)
			( pin "@baseboard_fab2_lib.baseboard_fab2(sch_1):page156_i275:b"
				( attribute "PN" "2"
					( Origin gPackager )
				)
				( objectStatus "C8F16.2" )
			)
			( pin "@baseboard_fab2_lib.baseboard_fab2(sch_1):page156_i279:a"
				( attribute "PN" "1"
					( Origin gPackager )
				)
				( objectStatus "R8E11.1" )
			)
			( pin "@baseboard_fab2_lib.baseboard_fab2(sch_1):page156_i279:b"
				( attribute "PN" "2"
					( Origin gPackager )
				)
				( objectStatus "R8E11.2" )
			)
			( pin "@baseboard_fab2_lib.baseboard_fab2(sch_1):page156_i281:io1"
				( attribute "PN" "1"
					( Origin gPackager )
				)
				( objectStatus "J9B2.1" )
			)
			( pin "@baseboard_fab2_lib.baseboard_fab2(sch_1):page156_i281:io2"
				( attribute "PN" "2"
					( Origin gPackager )
				)
				( objectStatus "J9B2.2" )
			)
			( pin "@baseboard_fab2_lib.baseboard_fab2(sch_1):page156_i281:io3"
				( attribute "PN" "3"
					( Origin gPackager )
				)
				( objectStatus "J9B2.3" )
			)
			( pin "@baseboard_fab2_lib.baseboard_fab2(sch_1):page156_i285:io1"
				( attribute "PN" "1"
					( Origin gPackager )
				)
				( objectStatus "J8C1.1" )
			)
			( pin "@baseboard_fab2_lib.baseboard_fab2(sch_1):page156_i285:io2"
				( attribute "PN" "2"
					( Origin gPackager )
				)
				( objectStatus "J8C1.2" )
			)
			( pin "@baseboard_fab2_lib.baseboard_fab2(sch_1):page156_i285:io3"
				( attribute "PN" "3"
					( Origin gPackager )
				)
				( objectStatus "J8C1.3" )
			)
			( pin "@baseboard_fab2_lib.baseboard_fab2(sch_1):page156_i288:a"
				( attribute "PN" "1"
					( Origin gPackager )
				)
				( objectStatus "R2T18.1" )
			)
			( pin "@baseboard_fab2_lib.baseboard_fab2(sch_1):page156_i288:b"
				( attribute "PN" "2"
					( Origin gPackager )
				)
				( objectStatus "R2T18.2" )
			)
			( pin "@baseboard_fab2_lib.baseboard_fab2(sch_1):page156_i289:a"
				( attribute "PN" "1"
					( Origin gPackager )
				)
				( objectStatus "R2T28.1" )
			)
			( pin "@baseboard_fab2_lib.baseboard_fab2(sch_1):page156_i289:b"
				( attribute "PN" "2"
					( Origin gPackager )
				)
				( objectStatus "R2T28.2" )
			)
			( pin "@baseboard_fab2_lib.baseboard_fab2(sch_1):page156_i299:a"
				( attribute "PN" "1"
					( Origin gPackager )
				)
				( objectStatus "R6D16.1" )
			)
			( pin "@baseboard_fab2_lib.baseboard_fab2(sch_1):page156_i299:b"
				( attribute "PN" "2"
					( Origin gPackager )
				)
				( objectStatus "R6D16.2" )
			)
			( pin "@baseboard_fab2_lib.baseboard_fab2(sch_1):page156_i300:a"
				( attribute "PN" "1"
					( Origin gPackager )
				)
				( objectStatus "R3D31.1" )
			)
			( pin "@baseboard_fab2_lib.baseboard_fab2(sch_1):page156_i300:b"
				( attribute "PN" "2"
					( Origin gPackager )
				)
				( objectStatus "R3D31.2" )
			)
			( pin "@baseboard_fab2_lib.baseboard_fab2(sch_1):page156_i302:a"
				( attribute "PN" "1"
					( Origin gPackager )
				)
				( objectStatus "R6N14.1" )
			)
			( pin "@baseboard_fab2_lib.baseboard_fab2(sch_1):page156_i302:b"
				( attribute "PN" "2"
					( Origin gPackager )
				)
				( objectStatus "R6N14.2" )
			)
			( pin "@baseboard_fab2_lib.baseboard_fab2(sch_1):page156_i303:a"
				( attribute "PN" "1"
					( Origin gPackager )
				)
				( objectStatus "R6N13.1" )
			)
			( pin "@baseboard_fab2_lib.baseboard_fab2(sch_1):page156_i303:b"
				( attribute "PN" "2"
					( Origin gPackager )
				)
				( objectStatus "R6N13.2" )
			)
			( pin "@baseboard_fab2_lib.baseboard_fab2(sch_1):page156_i304:a"
				( attribute "PN" "1"
					( Origin gPackager )
				)
				( objectStatus "R6N15.1" )
			)
			( pin "@baseboard_fab2_lib.baseboard_fab2(sch_1):page156_i304:b"
				( attribute "PN" "2"
					( Origin gPackager )
				)
				( objectStatus "R6N15.2" )
			)
			( pin "@baseboard_fab2_lib.baseboard_fab2(sch_1):page156_i312:a"
				( attribute "PN" "1"
					( Origin gPackager )
				)
				( objectStatus "R1C32.1" )
			)
			( pin "@baseboard_fab2_lib.baseboard_fab2(sch_1):page156_i312:b"
				( attribute "PN" "2"
					( Origin gPackager )
				)
				( objectStatus "R1C32.2" )
			)
			( pin "@baseboard_fab2_lib.baseboard_fab2(sch_1):page156_i313:a"
				( attribute "PN" "1"
					( Origin gPackager )
				)
				( objectStatus "R1C33.1" )
			)
			( pin "@baseboard_fab2_lib.baseboard_fab2(sch_1):page156_i313:b"
				( attribute "PN" "2"
					( Origin gPackager )
				)
				( objectStatus "R1C33.2" )
			)
			( pin "@baseboard_fab2_lib.baseboard_fab2(sch_1):page156_i320:a"
				( attribute "PN" "1"
					( Origin gPackager )
				)
				( objectStatus "R1C34.1" )
			)
			( pin "@baseboard_fab2_lib.baseboard_fab2(sch_1):page156_i320:b"
				( attribute "PN" "2"
					( Origin gPackager )
				)
				( objectStatus "R1C34.2" )
			)
			( pin "@baseboard_fab2_lib.baseboard_fab2(sch_1):page156_i321:a"
				( attribute "PN" "1"
					( Origin gPackager )
				)
				( objectStatus "R9M21.1" )
			)
			( pin "@baseboard_fab2_lib.baseboard_fab2(sch_1):page156_i321:b"
				( attribute "PN" "2"
					( Origin gPackager )
				)
				( objectStatus "R9M21.2" )
			)
			( pin "@baseboard_fab2_lib.baseboard_fab2(sch_1):page156_i322:a"
				( attribute "PN" "1"
					( Origin gPackager )
				)
				( objectStatus "R4A8.1" )
			)
			( pin "@baseboard_fab2_lib.baseboard_fab2(sch_1):page156_i322:b"
				( attribute "PN" "2"
					( Origin gPackager )
				)
				( objectStatus "R4A8.2" )
			)
			( pin "@baseboard_fab2_lib.baseboard_fab2(sch_1):page156_i323:a"
				( attribute "PN" "1"
					( Origin gPackager )
				)
				( objectStatus "R9M20.1" )
			)
			( pin "@baseboard_fab2_lib.baseboard_fab2(sch_1):page156_i323:b"
				( attribute "PN" "2"
					( Origin gPackager )
				)
				( objectStatus "R9M20.2" )
			)
			( pin "@baseboard_fab2_lib.baseboard_fab2(sch_1):page156_i324:a"
				( attribute "PN" "1"
					( Origin gPackager )
				)
				( objectStatus "R4A9.1" )
			)
			( pin "@baseboard_fab2_lib.baseboard_fab2(sch_1):page156_i324:b"
				( attribute "PN" "2"
					( Origin gPackager )
				)
				( objectStatus "R4A9.2" )
			)
			( pin "@baseboard_fab2_lib.baseboard_fab2(sch_1):page156_i331:a"
				( attribute "PN" "1"
					( Origin gPackager )
				)
				( objectStatus "R3P54.1" )
			)
			( pin "@baseboard_fab2_lib.baseboard_fab2(sch_1):page156_i331:b"
				( attribute "PN" "2"
					( Origin gPackager )
				)
				( objectStatus "R3P54.2" )
			)
			( pin "@baseboard_fab2_lib.baseboard_fab2(sch_1):page156_i333:a"
				( attribute "PN" "1"
					( Origin gPackager )
				)
				( objectStatus "R3P56.1" )
			)
			( pin "@baseboard_fab2_lib.baseboard_fab2(sch_1):page156_i333:b"
				( attribute "PN" "2"
					( Origin gPackager )
				)
				( objectStatus "R3P56.2" )
			)
			( pin "@baseboard_fab2_lib.baseboard_fab2(sch_1):page156_i336:a"
				( attribute "PN" "1"
					( Origin gPackager )
				)
				( objectStatus "R1C35.1" )
			)
			( pin "@baseboard_fab2_lib.baseboard_fab2(sch_1):page156_i336:b"
				( attribute "PN" "2"
					( Origin gPackager )
				)
				( objectStatus "R1C35.2" )
			)
			( pin "@baseboard_fab2_lib.baseboard_fab2(sch_1):page156_i337:a"
				( attribute "PN" "1"
					( Origin gPackager )
				)
				( objectStatus "R1C36.1" )
			)
			( pin "@baseboard_fab2_lib.baseboard_fab2(sch_1):page156_i337:b"
				( attribute "PN" "2"
					( Origin gPackager )
				)
				( objectStatus "R1C36.2" )
			)
			( pin "@baseboard_fab2_lib.baseboard_fab2(sch_1):page157_i97:a"
				( attribute "PN" "1"
					( Origin gPackager )
				)
				( objectStatus "R2N27.1" )
			)
			( pin "@baseboard_fab2_lib.baseboard_fab2(sch_1):page157_i97:b"
				( attribute "PN" "2"
					( Origin gPackager )
				)
				( objectStatus "R2N27.2" )
			)
			( pin "@baseboard_fab2_lib.baseboard_fab2(sch_1):page157_i296:a"
				( attribute "PN" "1"
					( Origin gPackager )
				)
				( objectStatus "R8F23.1" )
			)
			( pin "@baseboard_fab2_lib.baseboard_fab2(sch_1):page157_i296:b"
				( attribute "PN" "2"
					( Origin gPackager )
				)
				( objectStatus "R8F23.2" )
			)
			( pin "@baseboard_fab2_lib.baseboard_fab2(sch_1):page157_i298:a"
				( attribute "PN" "1"
					( Origin gPackager )
				)
				( objectStatus "R2T29.1" )
			)
			( pin "@baseboard_fab2_lib.baseboard_fab2(sch_1):page157_i298:b"
				( attribute "PN" "2"
					( Origin gPackager )
				)
				( objectStatus "R2T29.2" )
			)
			( pin "@baseboard_fab2_lib.baseboard_fab2(sch_1):page157_i302:a"
				( attribute "PN" "1"
					( Origin gPackager )
				)
				( objectStatus "R2N25.1" )
			)
			( pin "@baseboard_fab2_lib.baseboard_fab2(sch_1):page157_i302:b"
				( attribute "PN" "2"
					( Origin gPackager )
				)
				( objectStatus "R2N25.2" )
			)
			( pin "@baseboard_fab2_lib.baseboard_fab2(sch_1):page157_i316:a"
				( attribute "PN" "1"
					( Origin gPackager )
				)
				( objectStatus "R8F24.1" )
			)
			( pin "@baseboard_fab2_lib.baseboard_fab2(sch_1):page157_i316:b"
				( attribute "PN" "2"
					( Origin gPackager )
				)
				( objectStatus "R8F24.2" )
			)
			( pin "@baseboard_fab2_lib.baseboard_fab2(sch_1):page157_i326:a"
				( attribute "PN" "1"
					( Origin gPackager )
				)
				( objectStatus "R2T5.1" )
			)
			( pin "@baseboard_fab2_lib.baseboard_fab2(sch_1):page157_i326:b"
				( attribute "PN" "2"
					( Origin gPackager )
				)
				( objectStatus "R2T5.2" )
			)
			( pin "@baseboard_fab2_lib.baseboard_fab2(sch_1):page157_i327:a"
				( attribute "PN" "1"
					( Origin gPackager )
				)
				( objectStatus "R2T7.1" )
			)
			( pin "@baseboard_fab2_lib.baseboard_fab2(sch_1):page157_i327:b"
				( attribute "PN" "2"
					( Origin gPackager )
				)
				( objectStatus "R2T7.2" )
			)
			( pin "@baseboard_fab2_lib.baseboard_fab2(sch_1):page157_i330:b"
				( attribute "PN" "1"
					( Origin gPackager )
				)
				( objectStatus "Q2T1.1" )
			)
			( pin "@baseboard_fab2_lib.baseboard_fab2(sch_1):page157_i330:c"
				( attribute "PN" "3"
					( Origin gPackager )
				)
				( objectStatus "Q2T1.3" )
			)
			( pin "@baseboard_fab2_lib.baseboard_fab2(sch_1):page157_i330:e"
				( attribute "PN" "2"
					( Origin gPackager )
				)
				( objectStatus "Q2T1.2" )
			)
			( pin "@baseboard_fab2_lib.baseboard_fab2(sch_1):page157_i335:a"
				( attribute "PN" "1"
					( Origin gPackager )
				)
				( objectStatus "R8D25.1" )
			)
			( pin "@baseboard_fab2_lib.baseboard_fab2(sch_1):page157_i335:b"
				( attribute "PN" "2"
					( Origin gPackager )
				)
				( objectStatus "R8D25.2" )
			)
			( pin "@baseboard_fab2_lib.baseboard_fab2(sch_1):page157_i340:drn"
				( attribute "PN" "3"
					( Origin gPackager )
				)
				( objectStatus "Q2T2.3" )
			)
			( pin "@baseboard_fab2_lib.baseboard_fab2(sch_1):page157_i340:gate"
				( attribute "PN" "1"
					( Origin gPackager )
				)
				( objectStatus "Q2T2.1" )
			)
			( pin "@baseboard_fab2_lib.baseboard_fab2(sch_1):page157_i340:src"
				( attribute "PN" "2"
					( Origin gPackager )
				)
				( objectStatus "Q2T2.2" )
			)
			( pin "@baseboard_fab2_lib.baseboard_fab2(sch_1):page157_i342:a"
				( attribute "PN" "1"
					( Origin gPackager )
				)
				( objectStatus "R3N12.1" )
			)
			( pin "@baseboard_fab2_lib.baseboard_fab2(sch_1):page157_i342:b"
				( attribute "PN" "2"
					( Origin gPackager )
				)
				( objectStatus "R3N12.2" )
			)
			( pin "@baseboard_fab2_lib.baseboard_fab2(sch_1):page157_i344:a"
				( attribute "PN" "1"
					( Origin gPackager )
				)
				( objectStatus "R3N11.1" )
			)
			( pin "@baseboard_fab2_lib.baseboard_fab2(sch_1):page157_i344:b"
				( attribute "PN" "2"
					( Origin gPackager )
				)
				( objectStatus "R3N11.2" )
			)
			( pin "@baseboard_fab2_lib.baseboard_fab2(sch_1):page157_i346:a"
				( attribute "PN" "1"
					( Origin gPackager )
				)
				( objectStatus "R2M2.1" )
			)
			( pin "@baseboard_fab2_lib.baseboard_fab2(sch_1):page157_i346:b"
				( attribute "PN" "2"
					( Origin gPackager )
				)
				( objectStatus "R2M2.2" )
			)
			( pin "@baseboard_fab2_lib.baseboard_fab2(sch_1):page157_i348:a"
				( attribute "PN" "1"
					( Origin gPackager )
				)
				( objectStatus "R2M5.1" )
			)
			( pin "@baseboard_fab2_lib.baseboard_fab2(sch_1):page157_i348:b"
				( attribute "PN" "2"
					( Origin gPackager )
				)
				( objectStatus "R2M5.2" )
			)
			( pin "@baseboard_fab2_lib.baseboard_fab2(sch_1):page157_i351:a"
				( attribute "PN" "1"
					( Origin gPackager )
				)
				( objectStatus "S8E1.1" )
			)
			( pin "@baseboard_fab2_lib.baseboard_fab2(sch_1):page157_i351:b"
				( attribute "PN" "2"
					( Origin gPackager )
				)
				( objectStatus "S8E1.2" )
			)
			( pin "@baseboard_fab2_lib.baseboard_fab2(sch_1):page157_i352:a"
				( attribute "PN" "1"
					( Origin gPackager )
				)
				( objectStatus "R2R9.1" )
			)
			( pin "@baseboard_fab2_lib.baseboard_fab2(sch_1):page157_i352:b"
				( attribute "PN" "2"
					( Origin gPackager )
				)
				( objectStatus "R2R9.2" )
			)
			( pin "@baseboard_fab2_lib.baseboard_fab2(sch_1):page157_i353:a"
				( attribute "PN" "1"
					( Origin gPackager )
				)
				( objectStatus "C2R12.1" )
			)
			( pin "@baseboard_fab2_lib.baseboard_fab2(sch_1):page157_i353:b"
				( attribute "PN" "2"
					( Origin gPackager )
				)
				( objectStatus "C2R12.2" )
			)
			( pin "@baseboard_fab2_lib.baseboard_fab2(sch_1):page175_i93:\1a\"
				( attribute "PN" "1"
					( Origin gPackager )
				)
				( objectStatus "U9A3.1" )
			)
			( pin "@baseboard_fab2_lib.baseboard_fab2(sch_1):page175_i93:\1y\"
				( attribute "PN" "6"
					( Origin gPackager )
				)
				( objectStatus "U9A3.6" )
			)
			( pin "@baseboard_fab2_lib.baseboard_fab2(sch_1):page175_i93:\2a\"
				( attribute "PN" "3"
					( Origin gPackager )
				)
				( objectStatus "U9A3.3" )
			)
			( pin "@baseboard_fab2_lib.baseboard_fab2(sch_1):page175_i93:\2y\"
				( attribute "PN" "4"
					( Origin gPackager )
				)
				( objectStatus "U9A3.4" )
			)
			( pin "@baseboard_fab2_lib.baseboard_fab2(sch_1):page175_i93:gnd"
				( attribute "PN" "2"
					( Origin gPackager )
				)
				( objectStatus "U9A3.2" )
			)
			( pin "@baseboard_fab2_lib.baseboard_fab2(sch_1):page175_i93:vcc"
				( attribute "PN" "5"
					( Origin gPackager )
				)
				( objectStatus "U9A3.5" )
			)
			( pin "@baseboard_fab2_lib.baseboard_fab2(sch_1):page157_i361:a"
				( attribute "PN" "1"
					( Origin gPackager )
				)
				( objectStatus "R8E19.1" )
			)
			( pin "@baseboard_fab2_lib.baseboard_fab2(sch_1):page157_i361:b"
				( attribute "PN" "2"
					( Origin gPackager )
				)
				( objectStatus "R8E19.2" )
			)
			( pin "@baseboard_fab2_lib.baseboard_fab2(sch_1):page157_i367:a"
				( attribute "PN" "1"
					( Origin gPackager )
				)
				( objectStatus "R2U4.1" )
			)
			( pin "@baseboard_fab2_lib.baseboard_fab2(sch_1):page157_i367:b"
				( attribute "PN" "2"
					( Origin gPackager )
				)
				( objectStatus "R2U4.2" )
			)
			( pin "@baseboard_fab2_lib.baseboard_fab2(sch_1):page157_i368:a"
				( attribute "PN" "1"
					( Origin gPackager )
				)
				( objectStatus "R4R1.1" )
			)
			( pin "@baseboard_fab2_lib.baseboard_fab2(sch_1):page157_i368:b"
				( attribute "PN" "2"
					( Origin gPackager )
				)
				( objectStatus "R4R1.2" )
			)
			( pin "@baseboard_fab2_lib.baseboard_fab2(sch_1):page157_i370:a"
				( attribute "PN" "1"
					( Origin gPackager )
				)
				( objectStatus "C2T3.1" )
			)
			( pin "@baseboard_fab2_lib.baseboard_fab2(sch_1):page157_i370:b"
				( attribute "PN" "2"
					( Origin gPackager )
				)
				( objectStatus "C2T3.2" )
			)
			( pin "@baseboard_fab2_lib.baseboard_fab2(sch_1):page157_i374:a"
				( attribute "PN" "2"
					( Origin gPackager )
				)
				( objectStatus "U8D2.2" )
			)
			( pin "@baseboard_fab2_lib.baseboard_fab2(sch_1):page157_i374:y"
				( attribute "PN" "4"
					( Origin gPackager )
				)
				( objectStatus "U8D2.4" )
			)
			( pin "@baseboard_fab2_lib.baseboard_fab2(sch_1):page157_i376:a"
				( attribute "PN" "1"
					( Origin gPackager )
				)
				( objectStatus "C8D1.1" )
			)
			( pin "@baseboard_fab2_lib.baseboard_fab2(sch_1):page157_i376:b"
				( attribute "PN" "2"
					( Origin gPackager )
				)
				( objectStatus "C8D1.2" )
			)
			( pin "@baseboard_fab2_lib.baseboard_fab2(sch_1):page157_i382:a"
				( attribute "PN" "1"
					( Origin gPackager )
				)
				( objectStatus "R1L7.1" )
			)
			( pin "@baseboard_fab2_lib.baseboard_fab2(sch_1):page157_i382:b"
				( attribute "PN" "2"
					( Origin gPackager )
				)
				( objectStatus "R1L7.2" )
			)
			( pin "@baseboard_fab2_lib.baseboard_fab2(sch_1):page157_i385:a"
				( attribute "PN" "1"
					( Origin gPackager )
				)
				( objectStatus "R8E32.1" )
			)
			( pin "@baseboard_fab2_lib.baseboard_fab2(sch_1):page157_i385:b"
				( attribute "PN" "2"
					( Origin gPackager )
				)
				( objectStatus "R8E32.2" )
			)
			( pin "@baseboard_fab2_lib.baseboard_fab2(sch_1):page157_i386:a"
				( attribute "PN" "1"
					( Origin gPackager )
				)
				( objectStatus "R8D22.1" )
			)
			( pin "@baseboard_fab2_lib.baseboard_fab2(sch_1):page157_i386:b"
				( attribute "PN" "2"
					( Origin gPackager )
				)
				( objectStatus "R8D22.2" )
			)
			( pin "@baseboard_fab2_lib.baseboard_fab2(sch_1):page157_i388:a"
				( attribute "PN" "1"
					( Origin gPackager )
				)
				( objectStatus "R8D36.1" )
			)
			( pin "@baseboard_fab2_lib.baseboard_fab2(sch_1):page157_i388:b"
				( attribute "PN" "2"
					( Origin gPackager )
				)
				( objectStatus "R8D36.2" )
			)
			( pin "@baseboard_fab2_lib.baseboard_fab2(sch_1):page158_i70:a"
				( attribute "PN" "1"
					( Origin gPackager )
				)
				( objectStatus "C1T10.1" )
			)
			( pin "@baseboard_fab2_lib.baseboard_fab2(sch_1):page158_i70:b"
				( attribute "PN" "2"
					( Origin gPackager )
				)
				( objectStatus "C1T10.2" )
			)
			( pin "@baseboard_fab2_lib.baseboard_fab2(sch_1):page158_i74:a"
				( attribute "PN" "7"
					( Origin gPackager )
				)
				( objectStatus "U9F2.7" )
			)
			( pin "@baseboard_fab2_lib.baseboard_fab2(sch_1):page158_i74:b0"
				( attribute "PN" "1"
					( Origin gPackager )
				)
				( objectStatus "U9F2.1" )
			)
			( pin "@baseboard_fab2_lib.baseboard_fab2(sch_1):page158_i74:b1"
				( attribute "PN" "2"
					( Origin gPackager )
				)
				( objectStatus "U9F2.2" )
			)
			( pin "@baseboard_fab2_lib.baseboard_fab2(sch_1):page158_i74:b2"
				( attribute "PN" "3"
					( Origin gPackager )
				)
				( objectStatus "U9F2.3" )
			)
			( pin "@baseboard_fab2_lib.baseboard_fab2(sch_1):page158_i74:gnd"
				( attribute "PN" "4"
					( Origin gPackager )
				)
				( objectStatus "U9F2.4" )
			)
			( pin "@baseboard_fab2_lib.baseboard_fab2(sch_1):page158_i74:s1"
				( attribute "PN" "6"
					( Origin gPackager )
				)
				( objectStatus "U9F2.6" )
			)
			( pin "@baseboard_fab2_lib.baseboard_fab2(sch_1):page158_i74:s2"
				( attribute "PN" "5"
					( Origin gPackager )
				)
				( objectStatus "U9F2.5" )
			)
			( pin "@baseboard_fab2_lib.baseboard_fab2(sch_1):page158_i74:vcc"
				( attribute "PN" "8"
					( Origin gPackager )
				)
				( objectStatus "U9F2.8" )
			)
			( pin "@baseboard_fab2_lib.baseboard_fab2(sch_1):page158_i75:a"
				( attribute "PN" "7"
					( Origin gPackager )
				)
				( objectStatus "U9F1.7" )
			)
			( pin "@baseboard_fab2_lib.baseboard_fab2(sch_1):page158_i75:b0"
				( attribute "PN" "1"
					( Origin gPackager )
				)
				( objectStatus "U9F1.1" )
			)
			( pin "@baseboard_fab2_lib.baseboard_fab2(sch_1):page158_i75:b1"
				( attribute "PN" "2"
					( Origin gPackager )
				)
				( objectStatus "U9F1.2" )
			)
			( pin "@baseboard_fab2_lib.baseboard_fab2(sch_1):page158_i75:b2"
				( attribute "PN" "3"
					( Origin gPackager )
				)
				( objectStatus "U9F1.3" )
			)
			( pin "@baseboard_fab2_lib.baseboard_fab2(sch_1):page158_i75:gnd"
				( attribute "PN" "4"
					( Origin gPackager )
				)
				( objectStatus "U9F1.4" )
			)
			( pin "@baseboard_fab2_lib.baseboard_fab2(sch_1):page158_i75:s1"
				( attribute "PN" "6"
					( Origin gPackager )
				)
				( objectStatus "U9F1.6" )
			)
			( pin "@baseboard_fab2_lib.baseboard_fab2(sch_1):page158_i75:s2"
				( attribute "PN" "5"
					( Origin gPackager )
				)
				( objectStatus "U9F1.5" )
			)
			( pin "@baseboard_fab2_lib.baseboard_fab2(sch_1):page158_i75:vcc"
				( attribute "PN" "8"
					( Origin gPackager )
				)
				( objectStatus "U9F1.8" )
			)
			( pin "@baseboard_fab2_lib.baseboard_fab2(sch_1):page158_i86:a"
				( attribute "PN" "1"
					( Origin gPackager )
				)
				( objectStatus "R9F25.1" )
			)
			( pin "@baseboard_fab2_lib.baseboard_fab2(sch_1):page158_i86:b"
				( attribute "PN" "2"
					( Origin gPackager )
				)
				( objectStatus "R9F25.2" )
			)
			( pin "@baseboard_fab2_lib.baseboard_fab2(sch_1):page158_i91:a"
				( attribute "PN" "1"
					( Origin gPackager )
				)
				( objectStatus "R9F27.1" )
			)
			( pin "@baseboard_fab2_lib.baseboard_fab2(sch_1):page158_i91:b"
				( attribute "PN" "2"
					( Origin gPackager )
				)
				( objectStatus "R9F27.2" )
			)
			( pin "@baseboard_fab2_lib.baseboard_fab2(sch_1):page158_i97:a"
				( attribute "PN" "1"
					( Origin gPackager )
				)
				( objectStatus "C1T11.1" )
			)
			( pin "@baseboard_fab2_lib.baseboard_fab2(sch_1):page158_i97:b"
				( attribute "PN" "2"
					( Origin gPackager )
				)
				( objectStatus "C1T11.2" )
			)
			( pin "@baseboard_fab2_lib.baseboard_fab2(sch_1):page158_i99:a"
				( attribute "PN" "1"
					( Origin gPackager )
				)
				( objectStatus "R9F26.1" )
			)
			( pin "@baseboard_fab2_lib.baseboard_fab2(sch_1):page158_i99:b"
				( attribute "PN" "2"
					( Origin gPackager )
				)
				( objectStatus "R9F26.2" )
			)
			( pin "@baseboard_fab2_lib.baseboard_fab2(sch_1):page158_i100:a"
				( attribute "PN" "1"
					( Origin gPackager )
				)
				( objectStatus "R9F24.1" )
			)
			( pin "@baseboard_fab2_lib.baseboard_fab2(sch_1):page158_i100:b"
				( attribute "PN" "2"
					( Origin gPackager )
				)
				( objectStatus "R9F24.2" )
			)
			( pin "@baseboard_fab2_lib.baseboard_fab2(sch_1):page158_i130:a"
				( attribute "PN" "1"
					( Origin gPackager )
				)
				( objectStatus "DS9A4.1" )
			)
			( pin "@baseboard_fab2_lib.baseboard_fab2(sch_1):page158_i130:c"
				( attribute "PN" "2"
					( Origin gPackager )
				)
				( objectStatus "DS9A4.2" )
			)
			( pin "@baseboard_fab2_lib.baseboard_fab2(sch_1):page158_i131:a"
				( attribute "PN" "1"
					( Origin gPackager )
				)
				( objectStatus "R1L43.1" )
			)
			( pin "@baseboard_fab2_lib.baseboard_fab2(sch_1):page158_i131:b"
				( attribute "PN" "2"
					( Origin gPackager )
				)
				( objectStatus "R1L43.2" )
			)
			( pin "@baseboard_fab2_lib.baseboard_fab2(sch_1):page158_i134:a"
				( attribute "PN" "1"
					( Origin gPackager )
				)
				( objectStatus "DS9A7.1" )
			)
			( pin "@baseboard_fab2_lib.baseboard_fab2(sch_1):page158_i134:c"
				( attribute "PN" "2"
					( Origin gPackager )
				)
				( objectStatus "DS9A7.2" )
			)
			( pin "@baseboard_fab2_lib.baseboard_fab2(sch_1):page158_i136:a"
				( attribute "PN" "1"
					( Origin gPackager )
				)
				( objectStatus "R1L44.1" )
			)
			( pin "@baseboard_fab2_lib.baseboard_fab2(sch_1):page158_i136:b"
				( attribute "PN" "2"
					( Origin gPackager )
				)
				( objectStatus "R1L44.2" )
			)
			( pin "@baseboard_fab2_lib.baseboard_fab2(sch_1):page239_i98:\1\"
				( attribute "PN" "1"
					( Origin gPackager )
				)
				( objectStatus "R9F31.1" )
			)
			( pin "@baseboard_fab2_lib.baseboard_fab2(sch_1):page239_i98:\2\"
				( attribute "PN" "2"
					( Origin gPackager )
				)
				( objectStatus "R9F31.2" )
			)
			( pin "@baseboard_fab2_lib.baseboard_fab2(sch_1):page159_i210:a"
				( attribute "PN" "1"
					( Origin gPackager )
				)
				( objectStatus "R8G3.1" )
			)
			( pin "@baseboard_fab2_lib.baseboard_fab2(sch_1):page159_i210:b"
				( attribute "PN" "2"
					( Origin gPackager )
				)
				( objectStatus "R8G3.2" )
			)
			( pin "@baseboard_fab2_lib.baseboard_fab2(sch_1):page159_i212:a"
				( attribute "PN" "1"
					( Origin gPackager )
				)
				( objectStatus "R8G6.1" )
			)
			( pin "@baseboard_fab2_lib.baseboard_fab2(sch_1):page159_i212:b"
				( attribute "PN" "2"
					( Origin gPackager )
				)
				( objectStatus "R8G6.2" )
			)
			( pin "@baseboard_fab2_lib.baseboard_fab2(sch_1):page159_i214:a"
				( attribute "PN" "1"
					( Origin gPackager )
				)
				( objectStatus "R2U5.1" )
			)
			( pin "@baseboard_fab2_lib.baseboard_fab2(sch_1):page159_i214:b"
				( attribute "PN" "2"
					( Origin gPackager )
				)
				( objectStatus "R2U5.2" )
			)
			( pin "@baseboard_fab2_lib.baseboard_fab2(sch_1):page159_i216:a"
				( attribute "PN" "1"
					( Origin gPackager )
				)
				( objectStatus "R2U13.1" )
			)
			( pin "@baseboard_fab2_lib.baseboard_fab2(sch_1):page159_i216:b"
				( attribute "PN" "2"
					( Origin gPackager )
				)
				( objectStatus "R2U13.2" )
			)
			( pin "@baseboard_fab2_lib.baseboard_fab2(sch_1):page159_i218:a"
				( attribute "PN" "1"
					( Origin gPackager )
				)
				( objectStatus "R2U1.1" )
			)
			( pin "@baseboard_fab2_lib.baseboard_fab2(sch_1):page159_i218:b"
				( attribute "PN" "2"
					( Origin gPackager )
				)
				( objectStatus "R2U1.2" )
			)
			( pin "@baseboard_fab2_lib.baseboard_fab2(sch_1):page159_i219:a"
				( attribute "PN" "1"
					( Origin gPackager )
				)
				( objectStatus "R2T49.1" )
			)
			( pin "@baseboard_fab2_lib.baseboard_fab2(sch_1):page159_i219:b"
				( attribute "PN" "2"
					( Origin gPackager )
				)
				( objectStatus "R2T49.2" )
			)
			( pin "@baseboard_fab2_lib.baseboard_fab2(sch_1):page159_i220:a"
				( attribute "PN" "1"
					( Origin gPackager )
				)
				( objectStatus "R2U7.1" )
			)
			( pin "@baseboard_fab2_lib.baseboard_fab2(sch_1):page159_i220:b"
				( attribute "PN" "2"
					( Origin gPackager )
				)
				( objectStatus "R2U7.2" )
			)
			( pin "@baseboard_fab2_lib.baseboard_fab2(sch_1):page159_i221:a"
				( attribute "PN" "1"
					( Origin gPackager )
				)
				( objectStatus "R2U10.1" )
			)
			( pin "@baseboard_fab2_lib.baseboard_fab2(sch_1):page159_i221:b"
				( attribute "PN" "2"
					( Origin gPackager )
				)
				( objectStatus "R2U10.2" )
			)
			( pin "@baseboard_fab2_lib.baseboard_fab2(sch_1):page159_i222:a"
				( attribute "PN" "1"
					( Origin gPackager )
				)
				( objectStatus "R1U11.1" )
			)
			( pin "@baseboard_fab2_lib.baseboard_fab2(sch_1):page159_i222:b"
				( attribute "PN" "2"
					( Origin gPackager )
				)
				( objectStatus "R1U11.2" )
			)
			( pin "@baseboard_fab2_lib.baseboard_fab2(sch_1):page159_i223:a"
				( attribute "PN" "1"
					( Origin gPackager )
				)
				( objectStatus "R1U8.1" )
			)
			( pin "@baseboard_fab2_lib.baseboard_fab2(sch_1):page159_i223:b"
				( attribute "PN" "2"
					( Origin gPackager )
				)
				( objectStatus "R1U8.2" )
			)
			( pin "@baseboard_fab2_lib.baseboard_fab2(sch_1):page159_i224:a"
				( attribute "PN" "1"
					( Origin gPackager )
				)
				( objectStatus "R9G12.1" )
			)
			( pin "@baseboard_fab2_lib.baseboard_fab2(sch_1):page159_i224:b"
				( attribute "PN" "2"
					( Origin gPackager )
				)
				( objectStatus "R9G12.2" )
			)
			( pin "@baseboard_fab2_lib.baseboard_fab2(sch_1):page159_i225:a"
				( attribute "PN" "1"
					( Origin gPackager )
				)
				( objectStatus "R1U20.1" )
			)
			( pin "@baseboard_fab2_lib.baseboard_fab2(sch_1):page159_i225:b"
				( attribute "PN" "2"
					( Origin gPackager )
				)
				( objectStatus "R1U20.2" )
			)
			( pin "@baseboard_fab2_lib.baseboard_fab2(sch_1):page159_i226:a"
				( attribute "PN" "1"
					( Origin gPackager )
				)
				( objectStatus "R1U19.1" )
			)
			( pin "@baseboard_fab2_lib.baseboard_fab2(sch_1):page159_i226:b"
				( attribute "PN" "2"
					( Origin gPackager )
				)
				( objectStatus "R1U19.2" )
			)
			( pin "@baseboard_fab2_lib.baseboard_fab2(sch_1):page159_i227:a"
				( attribute "PN" "1"
					( Origin gPackager )
				)
				( objectStatus "R9G13.1" )
			)
			( pin "@baseboard_fab2_lib.baseboard_fab2(sch_1):page159_i227:b"
				( attribute "PN" "2"
					( Origin gPackager )
				)
				( objectStatus "R9G13.2" )
			)
			( pin "@baseboard_fab2_lib.baseboard_fab2(sch_1):page159_i228:a"
				( attribute "PN" "1"
					( Origin gPackager )
				)
				( objectStatus "R8G5.1" )
			)
			( pin "@baseboard_fab2_lib.baseboard_fab2(sch_1):page159_i228:b"
				( attribute "PN" "2"
					( Origin gPackager )
				)
				( objectStatus "R8G5.2" )
			)
			( pin "@baseboard_fab2_lib.baseboard_fab2(sch_1):page159_i229:a"
				( attribute "PN" "1"
					( Origin gPackager )
				)
				( objectStatus "R8G4.1" )
			)
			( pin "@baseboard_fab2_lib.baseboard_fab2(sch_1):page159_i229:b"
				( attribute "PN" "2"
					( Origin gPackager )
				)
				( objectStatus "R8G4.2" )
			)
			( pin "@baseboard_fab2_lib.baseboard_fab2(sch_1):page159_i230:a"
				( attribute "PN" "1"
					( Origin gPackager )
				)
				( objectStatus "R2U34.1" )
			)
			( pin "@baseboard_fab2_lib.baseboard_fab2(sch_1):page159_i230:b"
				( attribute "PN" "2"
					( Origin gPackager )
				)
				( objectStatus "R2U34.2" )
			)
			( pin "@baseboard_fab2_lib.baseboard_fab2(sch_1):page159_i231:a"
				( attribute "PN" "1"
					( Origin gPackager )
				)
				( objectStatus "R2U33.1" )
			)
			( pin "@baseboard_fab2_lib.baseboard_fab2(sch_1):page159_i231:b"
				( attribute "PN" "2"
					( Origin gPackager )
				)
				( objectStatus "R2U33.2" )
			)
			( pin "@baseboard_fab2_lib.baseboard_fab2(sch_1):page159_i232:a"
				( attribute "PN" "1"
					( Origin gPackager )
				)
				( objectStatus "R1U9.1" )
			)
			( pin "@baseboard_fab2_lib.baseboard_fab2(sch_1):page159_i232:b"
				( attribute "PN" "2"
					( Origin gPackager )
				)
				( objectStatus "R1U9.2" )
			)
			( pin "@baseboard_fab2_lib.baseboard_fab2(sch_1):page159_i233:a"
				( attribute "PN" "1"
					( Origin gPackager )
				)
				( objectStatus "R1U10.1" )
			)
			( pin "@baseboard_fab2_lib.baseboard_fab2(sch_1):page159_i233:b"
				( attribute "PN" "2"
					( Origin gPackager )
				)
				( objectStatus "R1U10.2" )
			)
			( pin "@baseboard_fab2_lib.baseboard_fab2(sch_1):page160_i4:a"
				( attribute "PN" "1"
					( Origin gPackager )
				)
				( objectStatus "R1T8.1" )
			)
			( pin "@baseboard_fab2_lib.baseboard_fab2(sch_1):page160_i4:b"
				( attribute "PN" "2"
					( Origin gPackager )
				)
				( objectStatus "R1T8.2" )
			)
			( pin "@baseboard_fab2_lib.baseboard_fab2(sch_1):page160_i46:a"
				( attribute "PN" "1"
					( Origin gPackager )
				)
				( objectStatus "R1T3.1" )
			)
			( pin "@baseboard_fab2_lib.baseboard_fab2(sch_1):page160_i46:b"
				( attribute "PN" "2"
					( Origin gPackager )
				)
				( objectStatus "R1T3.2" )
			)
			( pin "@baseboard_fab2_lib.baseboard_fab2(sch_1):page160_i49:a"
				( attribute "PN" "1"
					( Origin gPackager )
				)
				( objectStatus "R1T2.1" )
			)
			( pin "@baseboard_fab2_lib.baseboard_fab2(sch_1):page160_i49:b"
				( attribute "PN" "2"
					( Origin gPackager )
				)
				( objectStatus "R1T2.2" )
			)
			( pin "@baseboard_fab2_lib.baseboard_fab2(sch_1):page160_i50:a"
				( attribute "PN" "1"
					( Origin gPackager )
				)
				( objectStatus "R1T7.1" )
			)
			( pin "@baseboard_fab2_lib.baseboard_fab2(sch_1):page160_i50:b"
				( attribute "PN" "2"
					( Origin gPackager )
				)
				( objectStatus "R1T7.2" )
			)
			( pin "@baseboard_fab2_lib.baseboard_fab2(sch_1):page160_i51:a"
				( attribute "PN" "1"
					( Origin gPackager )
				)
				( objectStatus "R9F23.1" )
			)
			( pin "@baseboard_fab2_lib.baseboard_fab2(sch_1):page160_i51:b"
				( attribute "PN" "2"
					( Origin gPackager )
				)
				( objectStatus "R9F23.2" )
			)
			( pin "@baseboard_fab2_lib.baseboard_fab2(sch_1):page160_i52:a"
				( attribute "PN" "1"
					( Origin gPackager )
				)
				( objectStatus "R9F22.1" )
			)
			( pin "@baseboard_fab2_lib.baseboard_fab2(sch_1):page160_i52:b"
				( attribute "PN" "2"
					( Origin gPackager )
				)
				( objectStatus "R9F22.2" )
			)
			( pin "@baseboard_fab2_lib.baseboard_fab2(sch_1):page161_i140:\1\"
				( attribute "PN" "1"
					( Origin gPackager )
				)
				( objectStatus "J10W1.1" )
			)
			( pin "@baseboard_fab2_lib.baseboard_fab2(sch_1):page161_i140:\2\"
				( attribute "PN" "2"
					( Origin gPackager )
				)
				( objectStatus "J10W1.2" )
			)
			( pin "@baseboard_fab2_lib.baseboard_fab2(sch_1):page161_i140:\3\"
				( attribute "PN" "3"
					( Origin gPackager )
				)
				( objectStatus "J10W1.3" )
			)
			( pin "@baseboard_fab2_lib.baseboard_fab2(sch_1):page161_i140:\4\"
				( attribute "PN" "4"
					( Origin gPackager )
				)
				( objectStatus "J10W1.4" )
			)
			( pin "@baseboard_fab2_lib.baseboard_fab2(sch_1):page161_i140:np1"
				( attribute "PN" "NP1"
					( Origin gPackager )
				)
				( objectStatus "J10W1.NP1" )
			)
			( pin "@baseboard_fab2_lib.baseboard_fab2(sch_1):page161_i3:a"
				( attribute "PN" "1"
					( Origin gPackager )
				)
				( objectStatus "C1E21.1" )
			)
			( pin "@baseboard_fab2_lib.baseboard_fab2(sch_1):page161_i3:b"
				( attribute "PN" "2"
					( Origin gPackager )
				)
				( objectStatus "C1E21.2" )
			)
			( pin "@baseboard_fab2_lib.baseboard_fab2(sch_1):page161_i4:a"
				( attribute "PN" "1"
					( Origin gPackager )
				)
				( objectStatus "C1E20.1" )
			)
			( pin "@baseboard_fab2_lib.baseboard_fab2(sch_1):page161_i4:b"
				( attribute "PN" "2"
					( Origin gPackager )
				)
				( objectStatus "C1E20.2" )
			)
			( pin "@baseboard_fab2_lib.baseboard_fab2(sch_1):page161_i26:a"
				( attribute "PN" "1"
					( Origin gPackager )
				)
				( objectStatus "C9M5.1" )
			)
			( pin "@baseboard_fab2_lib.baseboard_fab2(sch_1):page161_i26:b"
				( attribute "PN" "2"
					( Origin gPackager )
				)
				( objectStatus "C9M5.2" )
			)
			( pin "@baseboard_fab2_lib.baseboard_fab2(sch_1):page161_i27:a"
				( attribute "PN" "1"
					( Origin gPackager )
				)
				( objectStatus "C9M4.1" )
			)
			( pin "@baseboard_fab2_lib.baseboard_fab2(sch_1):page161_i27:b"
				( attribute "PN" "2"
					( Origin gPackager )
				)
				( objectStatus "C9M4.2" )
			)
			( pin "@baseboard_fab2_lib.baseboard_fab2(sch_1):page161_i42:a"
				( attribute "PN" "2"
					( Origin gPackager )
				)
				( objectStatus "CR1F1.2" )
			)
			( pin "@baseboard_fab2_lib.baseboard_fab2(sch_1):page161_i42:c"
				( attribute "PN" "1"
					( Origin gPackager )
				)
				( objectStatus "CR1F1.1" )
			)
			( pin "@baseboard_fab2_lib.baseboard_fab2(sch_1):page161_i43:a"
				( attribute "PN" "1"
					( Origin gPackager )
				)
				( objectStatus "R1F2.1" )
			)
			( pin "@baseboard_fab2_lib.baseboard_fab2(sch_1):page161_i43:b"
				( attribute "PN" "2"
					( Origin gPackager )
				)
				( objectStatus "R1F2.2" )
			)
			( pin "@baseboard_fab2_lib.baseboard_fab2(sch_1):page161_i45:a"
				( attribute "PN" "1"
					( Origin gPackager )
				)
				( objectStatus "R1F1.1" )
			)
			( pin "@baseboard_fab2_lib.baseboard_fab2(sch_1):page161_i45:b"
				( attribute "PN" "2"
					( Origin gPackager )
				)
				( objectStatus "R1F1.2" )
			)
			( pin "@baseboard_fab2_lib.baseboard_fab2(sch_1):page161_i46:a"
				( attribute "PN" "1"
					( Origin gPackager )
				)
				( objectStatus "C1F9.1" )
			)
			( pin "@baseboard_fab2_lib.baseboard_fab2(sch_1):page161_i46:b"
				( attribute "PN" "2"
					( Origin gPackager )
				)
				( objectStatus "C1F9.2" )
			)
			( pin "@baseboard_fab2_lib.baseboard_fab2(sch_1):page161_i50:a"
				( attribute "PN" "2"
					( Origin gPackager )
				)
				( objectStatus "CR1E1.2" )
			)
			( pin "@baseboard_fab2_lib.baseboard_fab2(sch_1):page161_i50:c"
				( attribute "PN" "1"
					( Origin gPackager )
				)
				( objectStatus "CR1E1.1" )
			)
			( pin "@baseboard_fab2_lib.baseboard_fab2(sch_1):page161_i51:a"
				( attribute "PN" "1"
					( Origin gPackager )
				)
				( objectStatus "R1E12.1" )
			)
			( pin "@baseboard_fab2_lib.baseboard_fab2(sch_1):page161_i51:b"
				( attribute "PN" "2"
					( Origin gPackager )
				)
				( objectStatus "R1E12.2" )
			)
			( pin "@baseboard_fab2_lib.baseboard_fab2(sch_1):page161_i62:a"
				( attribute "PN" "2"
					( Origin gPackager )
				)
				( objectStatus "CR1B2.2" )
			)
			( pin "@baseboard_fab2_lib.baseboard_fab2(sch_1):page161_i62:c"
				( attribute "PN" "1"
					( Origin gPackager )
				)
				( objectStatus "CR1B2.1" )
			)
			( pin "@baseboard_fab2_lib.baseboard_fab2(sch_1):page161_i64:a"
				( attribute "PN" "2"
					( Origin gPackager )
				)
				( objectStatus "CR1B1.2" )
			)
			( pin "@baseboard_fab2_lib.baseboard_fab2(sch_1):page161_i64:c"
				( attribute "PN" "1"
					( Origin gPackager )
				)
				( objectStatus "CR1B1.1" )
			)
			( pin "@baseboard_fab2_lib.baseboard_fab2(sch_1):page161_i65:a"
				( attribute "PN" "1"
					( Origin gPackager )
				)
				( objectStatus "R7F33.1" )
			)
			( pin "@baseboard_fab2_lib.baseboard_fab2(sch_1):page161_i65:b"
				( attribute "PN" "2"
					( Origin gPackager )
				)
				( objectStatus "R7F33.2" )
			)
			( pin "@baseboard_fab2_lib.baseboard_fab2(sch_1):page161_i67:a"
				( attribute "PN" "1"
					( Origin gPackager )
				)
				( objectStatus "R1B22.1" )
			)
			( pin "@baseboard_fab2_lib.baseboard_fab2(sch_1):page161_i67:b"
				( attribute "PN" "2"
					( Origin gPackager )
				)
				( objectStatus "R1B22.2" )
			)
			( pin "@baseboard_fab2_lib.baseboard_fab2(sch_1):page161_i68:a"
				( attribute "PN" "1"
					( Origin gPackager )
				)
				( objectStatus "C1B15.1" )
			)
			( pin "@baseboard_fab2_lib.baseboard_fab2(sch_1):page161_i68:b"
				( attribute "PN" "2"
					( Origin gPackager )
				)
				( objectStatus "C1B15.2" )
			)
			( pin "@baseboard_fab2_lib.baseboard_fab2(sch_1):page161_i70:a"
				( attribute "PN" "1"
					( Origin gPackager )
				)
				( objectStatus "R1B21.1" )
			)
			( pin "@baseboard_fab2_lib.baseboard_fab2(sch_1):page161_i70:b"
				( attribute "PN" "2"
					( Origin gPackager )
				)
				( objectStatus "R1B21.2" )
			)
			( pin "@baseboard_fab2_lib.baseboard_fab2(sch_1):page161_i88:a"
				( attribute "PN" "2"
					( Origin gPackager )
				)
				( objectStatus "U8G2.2" )
			)
			( pin "@baseboard_fab2_lib.baseboard_fab2(sch_1):page161_i88:y"
				( attribute "PN" "4"
					( Origin gPackager )
				)
				( objectStatus "U8G2.4" )
			)
			( pin "@baseboard_fab2_lib.baseboard_fab2(sch_1):page161_i90:a"
				( attribute "PN" "1"
					( Origin gPackager )
				)
				( objectStatus "C2U27.1" )
			)
			( pin "@baseboard_fab2_lib.baseboard_fab2(sch_1):page161_i90:b"
				( attribute "PN" "2"
					( Origin gPackager )
				)
				( objectStatus "C2U27.2" )
			)
			( pin "@baseboard_fab2_lib.baseboard_fab2(sch_1):page161_i92:a"
				( attribute "PN" "2"
					( Origin gPackager )
				)
				( objectStatus "U8G3.2" )
			)
			( pin "@baseboard_fab2_lib.baseboard_fab2(sch_1):page161_i92:y"
				( attribute "PN" "4"
					( Origin gPackager )
				)
				( objectStatus "U8G3.4" )
			)
			( pin "@baseboard_fab2_lib.baseboard_fab2(sch_1):page161_i93:a"
				( attribute "PN" "1"
					( Origin gPackager )
				)
				( objectStatus "C2U28.1" )
			)
			( pin "@baseboard_fab2_lib.baseboard_fab2(sch_1):page161_i93:b"
				( attribute "PN" "2"
					( Origin gPackager )
				)
				( objectStatus "C2U28.2" )
			)
			( pin "@baseboard_fab2_lib.baseboard_fab2(sch_1):page161_i99:a"
				( attribute "PN" "1"
					( Origin gPackager )
				)
				( objectStatus "R2U42.1" )
			)
			( pin "@baseboard_fab2_lib.baseboard_fab2(sch_1):page161_i99:b"
				( attribute "PN" "2"
					( Origin gPackager )
				)
				( objectStatus "R2U42.2" )
			)
			( pin "@baseboard_fab2_lib.baseboard_fab2(sch_1):page161_i102:a"
				( attribute "PN" "1"
					( Origin gPackager )
				)
				( objectStatus "R2U44.1" )
			)
			( pin "@baseboard_fab2_lib.baseboard_fab2(sch_1):page161_i102:b"
				( attribute "PN" "2"
					( Origin gPackager )
				)
				( objectStatus "R2U44.2" )
			)
			( pin "@baseboard_fab2_lib.baseboard_fab2(sch_1):page161_i113:a"
				( attribute "PN" "1"
					( Origin gPackager )
				)
				( objectStatus "C1E22.1" )
			)
			( pin "@baseboard_fab2_lib.baseboard_fab2(sch_1):page161_i113:b"
				( attribute "PN" "2"
					( Origin gPackager )
				)
				( objectStatus "C1E22.2" )
			)
			( pin "@baseboard_fab2_lib.baseboard_fab2(sch_1):page161_i120:a"
				( attribute "PN" "1"
					( Origin gPackager )
				)
				( objectStatus "R1E11.1" )
			)
			( pin "@baseboard_fab2_lib.baseboard_fab2(sch_1):page161_i120:b"
				( attribute "PN" "2"
					( Origin gPackager )
				)
				( objectStatus "R1E11.2" )
			)
			( pin "@baseboard_fab2_lib.baseboard_fab2(sch_1):page161_i121:a(0)"
				( attribute "PN" "1"
					( Origin gPackager )
				)
				( objectStatus "U1E2.1" )
			)
			( pin "@baseboard_fab2_lib.baseboard_fab2(sch_1):page161_i121:b(0)"
				( attribute "PN" "2"
					( Origin gPackager )
				)
				( objectStatus "U1E2.2" )
			)
			( pin "@baseboard_fab2_lib.baseboard_fab2(sch_1):page161_i121:y(0)"
				( attribute "PN" "4"
					( Origin gPackager )
				)
				( objectStatus "U1E2.4" )
			)
			( pin "@baseboard_fab2_lib.baseboard_fab2(sch_1):page162_i8:a"
				( attribute "PN" "1"
					( Origin gPackager )
				)
				( objectStatus "R8F16.1" )
			)
			( pin "@baseboard_fab2_lib.baseboard_fab2(sch_1):page162_i8:b"
				( attribute "PN" "2"
					( Origin gPackager )
				)
				( objectStatus "R8F16.2" )
			)
			( pin "@baseboard_fab2_lib.baseboard_fab2(sch_1):page162_i9:a"
				( attribute "PN" "1"
					( Origin gPackager )
				)
				( objectStatus "R8F14.1" )
			)
			( pin "@baseboard_fab2_lib.baseboard_fab2(sch_1):page162_i9:b"
				( attribute "PN" "2"
					( Origin gPackager )
				)
				( objectStatus "R8F14.2" )
			)
			( pin "@baseboard_fab2_lib.baseboard_fab2(sch_1):page162_i13:a"
				( attribute "PN" "1"
					( Origin gPackager )
				)
				( objectStatus "R8F12.1" )
			)
			( pin "@baseboard_fab2_lib.baseboard_fab2(sch_1):page162_i13:b"
				( attribute "PN" "2"
					( Origin gPackager )
				)
				( objectStatus "R8F12.2" )
			)
			( pin "@baseboard_fab2_lib.baseboard_fab2(sch_1):page162_i22:a"
				( attribute "PN" "1"
					( Origin gPackager )
				)
				( objectStatus "R8F34.1" )
			)
			( pin "@baseboard_fab2_lib.baseboard_fab2(sch_1):page162_i22:b"
				( attribute "PN" "2"
					( Origin gPackager )
				)
				( objectStatus "R8F34.2" )
			)
			( pin "@baseboard_fab2_lib.baseboard_fab2(sch_1):page246_i20:a"
				( attribute "PN" "1"
					( Origin gPackager )
				)
				( objectStatus "RN8F2.1" )
			)
			( pin "@baseboard_fab2_lib.baseboard_fab2(sch_1):page246_i20:b"
				( attribute "PN" "2"
					( Origin gPackager )
				)
				( objectStatus "RN8F2.2" )
			)
			( pin "@baseboard_fab2_lib.baseboard_fab2(sch_1):page162_i24:a"
				( attribute "PN" "1"
					( Origin gPackager )
				)
				( objectStatus "R8F35.1" )
			)
			( pin "@baseboard_fab2_lib.baseboard_fab2(sch_1):page162_i24:b"
				( attribute "PN" "2"
					( Origin gPackager )
				)
				( objectStatus "R8F35.2" )
			)
			( pin "@baseboard_fab2_lib.baseboard_fab2(sch_1):page162_i28:a"
				( attribute "PN" "1"
					( Origin gPackager )
				)
				( objectStatus "C8F5.1" )
			)
			( pin "@baseboard_fab2_lib.baseboard_fab2(sch_1):page162_i28:b"
				( attribute "PN" "2"
					( Origin gPackager )
				)
				( objectStatus "C8F5.2" )
			)
			( pin "@baseboard_fab2_lib.baseboard_fab2(sch_1):page162_i30:a"
				( attribute "PN" "1"
					( Origin gPackager )
				)
				( objectStatus "C8F4.1" )
			)
			( pin "@baseboard_fab2_lib.baseboard_fab2(sch_1):page162_i30:b"
				( attribute "PN" "2"
					( Origin gPackager )
				)
				( objectStatus "C8F4.2" )
			)
			( pin "@baseboard_fab2_lib.baseboard_fab2(sch_1):page162_i32:clk"
				( attribute "PN" "16"
					( Origin gPackager )
				)
				( objectStatus "U8F2.16" )
			)
			( pin "@baseboard_fab2_lib.baseboard_fab2(sch_1):page162_i32:cs_n"
				( attribute "PN" "7"
					( Origin gPackager )
				)
				( objectStatus "U8F2.7" )
			)
			( pin "@baseboard_fab2_lib.baseboard_fab2(sch_1):page162_i32:di_io(0)"
				( attribute "PN" "15"
					( Origin gPackager )
				)
				( objectStatus "U8F2.15" )
			)
			( pin "@baseboard_fab2_lib.baseboard_fab2(sch_1):page162_i32:do_io(1)"
				( attribute "PN" "8"
					( Origin gPackager )
				)
				( objectStatus "U8F2.8" )
			)
			( pin "@baseboard_fab2_lib.baseboard_fab2(sch_1):page162_i32:gnd"
				( attribute "PN" "10"
					( Origin gPackager )
				)
				( objectStatus "U8F2.10" )
			)
			( pin "@baseboard_fab2_lib.baseboard_fab2(sch_1):page162_i32:hold_n_io(3)"
				( attribute "PN" "1"
					( Origin gPackager )
				)
				( objectStatus "U8F2.1" )
			)
			( pin "@baseboard_fab2_lib.baseboard_fab2(sch_1):page162_i32:nc(0)"
				( attribute "PN" "4"
					( Origin gPackager )
				)
				( objectStatus "U8F2.4" )
			)
			( pin "@baseboard_fab2_lib.baseboard_fab2(sch_1):page162_i32:nc(1)"
				( attribute "PN" "5"
					( Origin gPackager )
				)
				( objectStatus "U8F2.5" )
			)
			( pin "@baseboard_fab2_lib.baseboard_fab2(sch_1):page162_i32:nc(2)"
				( attribute "PN" "6"
					( Origin gPackager )
				)
				( objectStatus "U8F2.6" )
			)
			( pin "@baseboard_fab2_lib.baseboard_fab2(sch_1):page162_i32:nc(3)"
				( attribute "PN" "11"
					( Origin gPackager )
				)
				( objectStatus "U8F2.11" )
			)
			( pin "@baseboard_fab2_lib.baseboard_fab2(sch_1):page162_i32:nc(4)"
				( attribute "PN" "12"
					( Origin gPackager )
				)
				( objectStatus "U8F2.12" )
			)
			( pin "@baseboard_fab2_lib.baseboard_fab2(sch_1):page162_i32:nc(5)"
				( attribute "PN" "13"
					( Origin gPackager )
				)
				( objectStatus "U8F2.13" )
			)
			( pin "@baseboard_fab2_lib.baseboard_fab2(sch_1):page162_i32:nc(6)"
				( attribute "PN" "14"
					( Origin gPackager )
				)
				( objectStatus "U8F2.14" )
			)
			( pin "@baseboard_fab2_lib.baseboard_fab2(sch_1):page162_i32:reset_n"
				( attribute "PN" "3"
					( Origin gPackager )
				)
				( objectStatus "U8F2.3" )
			)
			( pin "@baseboard_fab2_lib.baseboard_fab2(sch_1):page162_i32:vcc"
				( attribute "PN" "2"
					( Origin gPackager )
				)
				( objectStatus "U8F2.2" )
			)
			( pin "@baseboard_fab2_lib.baseboard_fab2(sch_1):page162_i32:wp_n_io(2)"
				( attribute "PN" "9"
					( Origin gPackager )
				)
				( objectStatus "U8F2.9" )
			)
			( pin "@baseboard_fab2_lib.baseboard_fab2(sch_1):page163_i2:a"
				( attribute "PN" "1"
					( Origin gPackager )
				)
				( objectStatus "R6N8.1" )
			)
			( pin "@baseboard_fab2_lib.baseboard_fab2(sch_1):page163_i2:b"
				( attribute "PN" "2"
					( Origin gPackager )
				)
				( objectStatus "R6N8.2" )
			)
			( pin "@baseboard_fab2_lib.baseboard_fab2(sch_1):page163_i3:a"
				( attribute "PN" "1"
					( Origin gPackager )
				)
				( objectStatus "R6N9.1" )
			)
			( pin "@baseboard_fab2_lib.baseboard_fab2(sch_1):page163_i3:b"
				( attribute "PN" "2"
					( Origin gPackager )
				)
				( objectStatus "R6N9.2" )
			)
			( pin "@baseboard_fab2_lib.baseboard_fab2(sch_1):page163_i6:a"
				( attribute "PN" "1"
					( Origin gPackager )
				)
				( objectStatus "R9M18.1" )
			)
			( pin "@baseboard_fab2_lib.baseboard_fab2(sch_1):page163_i6:b"
				( attribute "PN" "2"
					( Origin gPackager )
				)
				( objectStatus "R9M18.2" )
			)
			( pin "@baseboard_fab2_lib.baseboard_fab2(sch_1):page163_i7:a"
				( attribute "PN" "1"
					( Origin gPackager )
				)
				( objectStatus "R9M19.1" )
			)
			( pin "@baseboard_fab2_lib.baseboard_fab2(sch_1):page163_i7:b"
				( attribute "PN" "2"
					( Origin gPackager )
				)
				( objectStatus "R9M19.2" )
			)
			( pin "@baseboard_fab2_lib.baseboard_fab2(sch_1):page163_i10:a"
				( attribute "PN" "1"
					( Origin gPackager )
				)
				( objectStatus "C9M8.1" )
			)
			( pin "@baseboard_fab2_lib.baseboard_fab2(sch_1):page163_i10:b"
				( attribute "PN" "2"
					( Origin gPackager )
				)
				( objectStatus "C9M8.2" )
			)
			( pin "@baseboard_fab2_lib.baseboard_fab2(sch_1):page163_i12:a"
				( attribute "PN" "1"
					( Origin gPackager )
				)
				( objectStatus "C9M7.1" )
			)
			( pin "@baseboard_fab2_lib.baseboard_fab2(sch_1):page163_i12:b"
				( attribute "PN" "2"
					( Origin gPackager )
				)
				( objectStatus "C9M7.2" )
			)
			( pin "@baseboard_fab2_lib.baseboard_fab2(sch_1):page163_i15:a"
				( attribute "PN" "1"
					( Origin gPackager )
				)
				( objectStatus "R9M17.1" )
			)
			( pin "@baseboard_fab2_lib.baseboard_fab2(sch_1):page163_i15:b"
				( attribute "PN" "2"
					( Origin gPackager )
				)
				( objectStatus "R9M17.2" )
			)
			( pin "@baseboard_fab2_lib.baseboard_fab2(sch_1):page163_i16:a"
				( attribute "PN" "1"
					( Origin gPackager )
				)
				( objectStatus "R9M16.1" )
			)
			( pin "@baseboard_fab2_lib.baseboard_fab2(sch_1):page163_i16:b"
				( attribute "PN" "2"
					( Origin gPackager )
				)
				( objectStatus "R9M16.2" )
			)
			( pin "@baseboard_fab2_lib.baseboard_fab2(sch_1):page163_i20:a"
				( attribute "PN" "1"
					( Origin gPackager )
				)
				( objectStatus "R9M14.1" )
			)
			( pin "@baseboard_fab2_lib.baseboard_fab2(sch_1):page163_i20:b"
				( attribute "PN" "2"
					( Origin gPackager )
				)
				( objectStatus "R9M14.2" )
			)
			( pin "@baseboard_fab2_lib.baseboard_fab2(sch_1):page163_i21:a"
				( attribute "PN" "1"
					( Origin gPackager )
				)
				( objectStatus "R9M13.1" )
			)
			( pin "@baseboard_fab2_lib.baseboard_fab2(sch_1):page163_i21:b"
				( attribute "PN" "2"
					( Origin gPackager )
				)
				( objectStatus "R9M13.2" )
			)
			( pin "@baseboard_fab2_lib.baseboard_fab2(sch_1):page246_i19:\1\"
				( attribute "PN" "1"
					( Origin gPackager )
				)
				( objectStatus "RN8F6.1" )
			)
			( pin "@baseboard_fab2_lib.baseboard_fab2(sch_1):page246_i19:\2\"
				( attribute "PN" "2"
					( Origin gPackager )
				)
				( objectStatus "RN8F6.2" )
			)
			( pin "@baseboard_fab2_lib.baseboard_fab2(sch_1):page164_i47:a"
				( attribute "PN" "1"
					( Origin gPackager )
				)
				( objectStatus "R1U24.1" )
			)
			( pin "@baseboard_fab2_lib.baseboard_fab2(sch_1):page164_i47:b"
				( attribute "PN" "2"
					( Origin gPackager )
				)
				( objectStatus "R1U24.2" )
			)
			( pin "@baseboard_fab2_lib.baseboard_fab2(sch_1):page164_i7:a"
				( attribute "PN" "1"
					( Origin gPackager )
				)
				( objectStatus "R1T11.1" )
			)
			( pin "@baseboard_fab2_lib.baseboard_fab2(sch_1):page164_i7:b"
				( attribute "PN" "2"
					( Origin gPackager )
				)
				( objectStatus "R1T11.2" )
			)
			( pin "@baseboard_fab2_lib.baseboard_fab2(sch_1):page164_i11:a"
				( attribute "PN" "1"
					( Origin gPackager )
				)
				( objectStatus "R1T5.1" )
			)
			( pin "@baseboard_fab2_lib.baseboard_fab2(sch_1):page164_i11:b"
				( attribute "PN" "2"
					( Origin gPackager )
				)
				( objectStatus "R1T5.2" )
			)
			( pin "@baseboard_fab2_lib.baseboard_fab2(sch_1):page164_i46:a"
				( attribute "PN" "1"
					( Origin gPackager )
				)
				( objectStatus "R2N17.1" )
			)
			( pin "@baseboard_fab2_lib.baseboard_fab2(sch_1):page164_i46:b"
				( attribute "PN" "2"
					( Origin gPackager )
				)
				( objectStatus "R2N17.2" )
			)
			( pin "@baseboard_fab2_lib.baseboard_fab2(sch_1):page164_i21:a"
				( attribute "PN" "1"
					( Origin gPackager )
				)
				( objectStatus "R1U17.1" )
			)
			( pin "@baseboard_fab2_lib.baseboard_fab2(sch_1):page164_i21:b"
				( attribute "PN" "2"
					( Origin gPackager )
				)
				( objectStatus "R1U17.2" )
			)
			( pin "@baseboard_fab2_lib.baseboard_fab2(sch_1):page164_i32:a"
				( attribute "PN" "1"
					( Origin gPackager )
				)
				( objectStatus "R2N18.1" )
			)
			( pin "@baseboard_fab2_lib.baseboard_fab2(sch_1):page164_i32:b"
				( attribute "PN" "2"
					( Origin gPackager )
				)
				( objectStatus "R2N18.2" )
			)
			( pin "@baseboard_fab2_lib.baseboard_fab2(sch_1):page166_i46:a"
				( attribute "PN" "1"
					( Origin gPackager )
				)
				( objectStatus "R7W3.1" )
			)
			( pin "@baseboard_fab2_lib.baseboard_fab2(sch_1):page166_i46:b"
				( attribute "PN" "2"
					( Origin gPackager )
				)
				( objectStatus "R7W3.2" )
			)
			( pin "@baseboard_fab2_lib.baseboard_fab2(sch_1):page166_i42:a"
				( attribute "PN" "1"
					( Origin gPackager )
				)
				( objectStatus "R7W2.1" )
			)
			( pin "@baseboard_fab2_lib.baseboard_fab2(sch_1):page166_i42:b"
				( attribute "PN" "2"
					( Origin gPackager )
				)
				( objectStatus "R7W2.2" )
			)
			( pin "@baseboard_fab2_lib.baseboard_fab2(sch_1):page166_i28:a"
				( attribute "PN" "1"
					( Origin gPackager )
				)
				( objectStatus "R7C17.1" )
			)
			( pin "@baseboard_fab2_lib.baseboard_fab2(sch_1):page166_i28:b"
				( attribute "PN" "2"
					( Origin gPackager )
				)
				( objectStatus "R7C17.2" )
			)
			( pin "@baseboard_fab2_lib.baseboard_fab2(sch_1):page166_i32:a"
				( attribute "PN" "1"
					( Origin gPackager )
				)
				( objectStatus "R7D15.1" )
			)
			( pin "@baseboard_fab2_lib.baseboard_fab2(sch_1):page166_i32:b"
				( attribute "PN" "2"
					( Origin gPackager )
				)
				( objectStatus "R7D15.2" )
			)
			( pin "@baseboard_fab2_lib.baseboard_fab2(sch_1):page167_i1:a(0)"
				( attribute "PN" "4"
					( Origin gPackager )
				)
				( objectStatus "U9B4.4" )
			)
			( pin "@baseboard_fab2_lib.baseboard_fab2(sch_1):page167_i1:a(1)"
				( attribute "PN" "3"
					( Origin gPackager )
				)
				( objectStatus "U9B4.3" )
			)
			( pin "@baseboard_fab2_lib.baseboard_fab2(sch_1):page167_i1:dxn"
				( attribute "PN" "2"
					( Origin gPackager )
				)
				( objectStatus "U9B4.2" )
			)
			( pin "@baseboard_fab2_lib.baseboard_fab2(sch_1):page167_i1:dxp"
				( attribute "PN" "1"
					( Origin gPackager )
				)
				( objectStatus "U9B4.1" )
			)
			( pin "@baseboard_fab2_lib.baseboard_fab2(sch_1):page167_i1:gnd"
				( attribute "PN" "5"
					( Origin gPackager )
				)
				( objectStatus "U9B4.5" )
			)
			( pin "@baseboard_fab2_lib.baseboard_fab2(sch_1):page167_i1:scl"
				( attribute "PN" "7"
					( Origin gPackager )
				)
				( objectStatus "U9B4.7" )
			)
			( pin "@baseboard_fab2_lib.baseboard_fab2(sch_1):page167_i1:sda"
				( attribute "PN" "6"
					( Origin gPackager )
				)
				( objectStatus "U9B4.6" )
			)
			( pin "@baseboard_fab2_lib.baseboard_fab2(sch_1):page167_i1:vp"
				( attribute "PN" "8"
					( Origin gPackager )
				)
				( objectStatus "U9B4.8" )
			)
			( pin "@baseboard_fab2_lib.baseboard_fab2(sch_1):page167_i5:a"
				( attribute "PN" "1"
					( Origin gPackager )
				)
				( objectStatus "R9B5.1" )
			)
			( pin "@baseboard_fab2_lib.baseboard_fab2(sch_1):page167_i5:b"
				( attribute "PN" "2"
					( Origin gPackager )
				)
				( objectStatus "R9B5.2" )
			)
			( pin "@baseboard_fab2_lib.baseboard_fab2(sch_1):page167_i6:a"
				( attribute "PN" "1"
					( Origin gPackager )
				)
				( objectStatus "R9B4.1" )
			)
			( pin "@baseboard_fab2_lib.baseboard_fab2(sch_1):page167_i6:b"
				( attribute "PN" "2"
					( Origin gPackager )
				)
				( objectStatus "R9B4.2" )
			)
			( pin "@baseboard_fab2_lib.baseboard_fab2(sch_1):page167_i7:a"
				( attribute "PN" "1"
					( Origin gPackager )
				)
				( objectStatus "C1M4.1" )
			)
			( pin "@baseboard_fab2_lib.baseboard_fab2(sch_1):page167_i7:b"
				( attribute "PN" "2"
					( Origin gPackager )
				)
				( objectStatus "C1M4.2" )
			)
			( pin "@baseboard_fab2_lib.baseboard_fab2(sch_1):page167_i8:a"
				( attribute "PN" "1"
					( Origin gPackager )
				)
				( objectStatus "R1M9.1" )
			)
			( pin "@baseboard_fab2_lib.baseboard_fab2(sch_1):page167_i8:b"
				( attribute "PN" "2"
					( Origin gPackager )
				)
				( objectStatus "R1M9.2" )
			)
			( pin "@baseboard_fab2_lib.baseboard_fab2(sch_1):page167_i10:a"
				( attribute "PN" "1"
					( Origin gPackager )
				)
				( objectStatus "R9B8.1" )
			)
			( pin "@baseboard_fab2_lib.baseboard_fab2(sch_1):page167_i10:b"
				( attribute "PN" "2"
					( Origin gPackager )
				)
				( objectStatus "R9B8.2" )
			)
			( pin "@baseboard_fab2_lib.baseboard_fab2(sch_1):page167_i24:a"
				( attribute "PN" "1"
					( Origin gPackager )
				)
				( objectStatus "C1E19.1" )
			)
			( pin "@baseboard_fab2_lib.baseboard_fab2(sch_1):page167_i24:b"
				( attribute "PN" "2"
					( Origin gPackager )
				)
				( objectStatus "C1E19.2" )
			)
			( pin "@baseboard_fab2_lib.baseboard_fab2(sch_1):page167_i25:a"
				( attribute "PN" "1"
					( Origin gPackager )
				)
				( objectStatus "R9R5.1" )
			)
			( pin "@baseboard_fab2_lib.baseboard_fab2(sch_1):page167_i25:b"
				( attribute "PN" "2"
					( Origin gPackager )
				)
				( objectStatus "R9R5.2" )
			)
			( pin "@baseboard_fab2_lib.baseboard_fab2(sch_1):page167_i26:a"
				( attribute "PN" "1"
					( Origin gPackager )
				)
				( objectStatus "R9R6.1" )
			)
			( pin "@baseboard_fab2_lib.baseboard_fab2(sch_1):page167_i26:b"
				( attribute "PN" "2"
					( Origin gPackager )
				)
				( objectStatus "R9R6.2" )
			)
			( pin "@baseboard_fab2_lib.baseboard_fab2(sch_1):page167_i30:a(0)"
				( attribute "PN" "4"
					( Origin gPackager )
				)
				( objectStatus "U1E1.4" )
			)
			( pin "@baseboard_fab2_lib.baseboard_fab2(sch_1):page167_i30:a(1)"
				( attribute "PN" "3"
					( Origin gPackager )
				)
				( objectStatus "U1E1.3" )
			)
			( pin "@baseboard_fab2_lib.baseboard_fab2(sch_1):page167_i30:dxn"
				( attribute "PN" "2"
					( Origin gPackager )
				)
				( objectStatus "U1E1.2" )
			)
			( pin "@baseboard_fab2_lib.baseboard_fab2(sch_1):page167_i30:dxp"
				( attribute "PN" "1"
					( Origin gPackager )
				)
				( objectStatus "U1E1.1" )
			)
			( pin "@baseboard_fab2_lib.baseboard_fab2(sch_1):page167_i30:gnd"
				( attribute "PN" "5"
					( Origin gPackager )
				)
				( objectStatus "U1E1.5" )
			)
			( pin "@baseboard_fab2_lib.baseboard_fab2(sch_1):page167_i30:scl"
				( attribute "PN" "7"
					( Origin gPackager )
				)
				( objectStatus "U1E1.7" )
			)
			( pin "@baseboard_fab2_lib.baseboard_fab2(sch_1):page167_i30:sda"
				( attribute "PN" "6"
					( Origin gPackager )
				)
				( objectStatus "U1E1.6" )
			)
			( pin "@baseboard_fab2_lib.baseboard_fab2(sch_1):page167_i30:vp"
				( attribute "PN" "8"
					( Origin gPackager )
				)
				( objectStatus "U1E1.8" )
			)
			( pin "@baseboard_fab2_lib.baseboard_fab2(sch_1):page167_i34:a"
				( attribute "PN" "1"
					( Origin gPackager )
				)
				( objectStatus "R1E9.1" )
			)
			( pin "@baseboard_fab2_lib.baseboard_fab2(sch_1):page167_i34:b"
				( attribute "PN" "2"
					( Origin gPackager )
				)
				( objectStatus "R1E9.2" )
			)
			( pin "@baseboard_fab2_lib.baseboard_fab2(sch_1):page167_i35:a"
				( attribute "PN" "1"
					( Origin gPackager )
				)
				( objectStatus "R9B6.1" )
			)
			( pin "@baseboard_fab2_lib.baseboard_fab2(sch_1):page167_i35:b"
				( attribute "PN" "2"
					( Origin gPackager )
				)
				( objectStatus "R9B6.2" )
			)
			( pin "@baseboard_fab2_lib.baseboard_fab2(sch_1):page167_i38:a"
				( attribute "PN" "1"
					( Origin gPackager )
				)
				( objectStatus "R1E10.1" )
			)
			( pin "@baseboard_fab2_lib.baseboard_fab2(sch_1):page167_i38:b"
				( attribute "PN" "2"
					( Origin gPackager )
				)
				( objectStatus "R1E10.2" )
			)
			( pin "@baseboard_fab2_lib.baseboard_fab2(sch_1):page167_i39:a"
				( attribute "PN" "1"
					( Origin gPackager )
				)
				( objectStatus "C9B7.1" )
			)
			( pin "@baseboard_fab2_lib.baseboard_fab2(sch_1):page167_i39:b"
				( attribute "PN" "2"
					( Origin gPackager )
				)
				( objectStatus "C9B7.2" )
			)
			( pin "@baseboard_fab2_lib.baseboard_fab2(sch_1):page167_i41:a"
				( attribute "PN" "1"
					( Origin gPackager )
				)
				( objectStatus "C9R14.1" )
			)
			( pin "@baseboard_fab2_lib.baseboard_fab2(sch_1):page167_i41:b"
				( attribute "PN" "2"
					( Origin gPackager )
				)
				( objectStatus "C9R14.2" )
			)
			( pin "@baseboard_fab2_lib.baseboard_fab2(sch_1):page167_i42:a"
				( attribute "PN" "1"
					( Origin gPackager )
				)
				( objectStatus "C9R13.1" )
			)
			( pin "@baseboard_fab2_lib.baseboard_fab2(sch_1):page167_i42:b"
				( attribute "PN" "2"
					( Origin gPackager )
				)
				( objectStatus "C9R13.2" )
			)
			( pin "@baseboard_fab2_lib.baseboard_fab2(sch_1):page167_i49:a0"
				( attribute "PN" "1"
					( Origin gPackager )
				)
				( objectStatus "U8D4.1" )
			)
			( pin "@baseboard_fab2_lib.baseboard_fab2(sch_1):page167_i49:a1"
				( attribute "PN" "2"
					( Origin gPackager )
				)
				( objectStatus "U8D4.2" )
			)
			( pin "@baseboard_fab2_lib.baseboard_fab2(sch_1):page167_i49:a2"
				( attribute "PN" "3"
					( Origin gPackager )
				)
				( objectStatus "U8D4.3" )
			)
			( pin "@baseboard_fab2_lib.baseboard_fab2(sch_1):page167_i49:scl"
				( attribute "PN" "6"
					( Origin gPackager )
				)
				( objectStatus "U8D4.6" )
			)
			( pin "@baseboard_fab2_lib.baseboard_fab2(sch_1):page167_i49:sda"
				( attribute "PN" "5"
					( Origin gPackager )
				)
				( objectStatus "U8D4.5" )
			)
			( pin "@baseboard_fab2_lib.baseboard_fab2(sch_1):page167_i49:wp"
				( attribute "PN" "7"
					( Origin gPackager )
				)
				( objectStatus "U8D4.7" )
			)
			( pin "@baseboard_fab2_lib.baseboard_fab2(sch_1):page167_i50:a"
				( attribute "PN" "1"
					( Origin gPackager )
				)
				( objectStatus "R8D27.1" )
			)
			( pin "@baseboard_fab2_lib.baseboard_fab2(sch_1):page167_i50:b"
				( attribute "PN" "2"
					( Origin gPackager )
				)
				( objectStatus "R8D27.2" )
			)
			( pin "@baseboard_fab2_lib.baseboard_fab2(sch_1):page167_i58:a"
				( attribute "PN" "1"
					( Origin gPackager )
				)
				( objectStatus "R9G15.1" )
			)
			( pin "@baseboard_fab2_lib.baseboard_fab2(sch_1):page167_i58:b"
				( attribute "PN" "2"
					( Origin gPackager )
				)
				( objectStatus "R9G15.2" )
			)
			( pin "@baseboard_fab2_lib.baseboard_fab2(sch_1):page167_i70:a"
				( attribute "PN" "1"
					( Origin gPackager )
				)
				( objectStatus "R8D28.1" )
			)
			( pin "@baseboard_fab2_lib.baseboard_fab2(sch_1):page167_i70:b"
				( attribute "PN" "2"
					( Origin gPackager )
				)
				( objectStatus "R8D28.2" )
			)
			( pin "@baseboard_fab2_lib.baseboard_fab2(sch_1):page167_i74:a"
				( attribute "PN" "1"
					( Origin gPackager )
				)
				( objectStatus "R1M8.1" )
			)
			( pin "@baseboard_fab2_lib.baseboard_fab2(sch_1):page167_i74:b"
				( attribute "PN" "2"
					( Origin gPackager )
				)
				( objectStatus "R1M8.2" )
			)
			( pin "@baseboard_fab2_lib.baseboard_fab2(sch_1):page167_i75:a"
				( attribute "PN" "1"
					( Origin gPackager )
				)
				( objectStatus "R9R7.1" )
			)
			( pin "@baseboard_fab2_lib.baseboard_fab2(sch_1):page167_i75:b"
				( attribute "PN" "2"
					( Origin gPackager )
				)
				( objectStatus "R9R7.2" )
			)
			( pin "@baseboard_fab2_lib.baseboard_fab2(sch_1):page167_i76:a"
				( attribute "PN" "1"
					( Origin gPackager )
				)
				( objectStatus "R9R8.1" )
			)
			( pin "@baseboard_fab2_lib.baseboard_fab2(sch_1):page167_i76:b"
				( attribute "PN" "2"
					( Origin gPackager )
				)
				( objectStatus "R9R8.2" )
			)
			( pin "@baseboard_fab2_lib.baseboard_fab2(sch_1):page167_i77:a"
				( attribute "PN" "1"
					( Origin gPackager )
				)
				( objectStatus "R9G14.1" )
			)
			( pin "@baseboard_fab2_lib.baseboard_fab2(sch_1):page167_i77:b"
				( attribute "PN" "2"
					( Origin gPackager )
				)
				( objectStatus "R9G14.2" )
			)
			( pin "@baseboard_fab2_lib.baseboard_fab2(sch_1):page167_i80:a"
				( attribute "PN" "1"
					( Origin gPackager )
				)
				( objectStatus "R2U38.1" )
			)
			( pin "@baseboard_fab2_lib.baseboard_fab2(sch_1):page167_i80:b"
				( attribute "PN" "2"
					( Origin gPackager )
				)
				( objectStatus "R2U38.2" )
			)
			( pin "@baseboard_fab2_lib.baseboard_fab2(sch_1):page167_i83:a"
				( attribute "PN" "1"
					( Origin gPackager )
				)
				( objectStatus "R2U39.1" )
			)
			( pin "@baseboard_fab2_lib.baseboard_fab2(sch_1):page167_i83:b"
				( attribute "PN" "2"
					( Origin gPackager )
				)
				( objectStatus "R2U39.2" )
			)
			( pin "@baseboard_fab2_lib.baseboard_fab2(sch_1):page167_i84:a"
				( attribute "PN" "1"
					( Origin gPackager )
				)
				( objectStatus "R8D24.1" )
			)
			( pin "@baseboard_fab2_lib.baseboard_fab2(sch_1):page167_i84:b"
				( attribute "PN" "2"
					( Origin gPackager )
				)
				( objectStatus "R8D24.2" )
			)
			( pin "@baseboard_fab2_lib.baseboard_fab2(sch_1):page167_i85:a"
				( attribute "PN" "1"
					( Origin gPackager )
				)
				( objectStatus "R8D23.1" )
			)
			( pin "@baseboard_fab2_lib.baseboard_fab2(sch_1):page167_i85:b"
				( attribute "PN" "2"
					( Origin gPackager )
				)
				( objectStatus "R8D23.2" )
			)
			( pin "@baseboard_fab2_lib.baseboard_fab2(sch_1):page168_i2:a"
				( attribute "PN" "2"
					( Origin gPackager )
				)
				( objectStatus "CR1L1.2" )
			)
			( pin "@baseboard_fab2_lib.baseboard_fab2(sch_1):page168_i2:c"
				( attribute "PN" "1"
					( Origin gPackager )
				)
				( objectStatus "CR1L1.1" )
			)
			( pin "@baseboard_fab2_lib.baseboard_fab2(sch_1):page168_i3:a"
				( attribute "PN" "2"
					( Origin gPackager )
				)
				( objectStatus "CR1L2.2" )
			)
			( pin "@baseboard_fab2_lib.baseboard_fab2(sch_1):page168_i3:c"
				( attribute "PN" "1"
					( Origin gPackager )
				)
				( objectStatus "CR1L2.1" )
			)
			( pin "@baseboard_fab2_lib.baseboard_fab2(sch_1):page168_i4:a"
				( attribute "PN" "2"
					( Origin gPackager )
				)
				( objectStatus "CR1L3.2" )
			)
			( pin "@baseboard_fab2_lib.baseboard_fab2(sch_1):page168_i4:c"
				( attribute "PN" "1"
					( Origin gPackager )
				)
				( objectStatus "CR1L3.1" )
			)
			( pin "@baseboard_fab2_lib.baseboard_fab2(sch_1):page168_i5:a"
				( attribute "PN" "2"
					( Origin gPackager )
				)
				( objectStatus "CR1L4.2" )
			)
			( pin "@baseboard_fab2_lib.baseboard_fab2(sch_1):page168_i5:c"
				( attribute "PN" "1"
					( Origin gPackager )
				)
				( objectStatus "CR1L4.1" )
			)
			( pin "@baseboard_fab2_lib.baseboard_fab2(sch_1):page168_i6:a"
				( attribute "PN" "1"
					( Origin gPackager )
				)
				( objectStatus "R1L6.1" )
			)
			( pin "@baseboard_fab2_lib.baseboard_fab2(sch_1):page168_i6:b"
				( attribute "PN" "2"
					( Origin gPackager )
				)
				( objectStatus "R1L6.2" )
			)
			( pin "@baseboard_fab2_lib.baseboard_fab2(sch_1):page168_i8:b"
				( attribute "PN" "1"
					( Origin gPackager )
				)
				( objectStatus "Q1L3.1" )
			)
			( pin "@baseboard_fab2_lib.baseboard_fab2(sch_1):page168_i8:c"
				( attribute "PN" "3"
					( Origin gPackager )
				)
				( objectStatus "Q1L3.3" )
			)
			( pin "@baseboard_fab2_lib.baseboard_fab2(sch_1):page168_i8:e"
				( attribute "PN" "2"
					( Origin gPackager )
				)
				( objectStatus "Q1L3.2" )
			)
			( pin "@baseboard_fab2_lib.baseboard_fab2(sch_1):page168_i11:a"
				( attribute "PN" "1"
					( Origin gPackager )
				)
				( objectStatus "R1L36.1" )
			)
			( pin "@baseboard_fab2_lib.baseboard_fab2(sch_1):page168_i11:b"
				( attribute "PN" "2"
					( Origin gPackager )
				)
				( objectStatus "R1L36.2" )
			)
			( pin "@baseboard_fab2_lib.baseboard_fab2(sch_1):page168_i18:drain(0)"
				( attribute "PN" "3"
					( Origin gPackager )
				)
				( objectStatus "Q1L4.3" )
			)
			( pin "@baseboard_fab2_lib.baseboard_fab2(sch_1):page168_i18:gate(0)"
				( attribute "PN" "5"
					( Origin gPackager )
				)
				( objectStatus "Q1L4.5" )
			)
			( pin "@baseboard_fab2_lib.baseboard_fab2(sch_1):page168_i18:source(0)"
				( attribute "PN" "4"
					( Origin gPackager )
				)
				( objectStatus "Q1L4.4" )
			)
			( pin "@baseboard_fab2_lib.baseboard_fab2(sch_1):page168_i19:drain(0)"
				( attribute "PN" "6"
					( Origin gPackager )
				)
				( objectStatus "Q1L4.6" )
			)
			( pin "@baseboard_fab2_lib.baseboard_fab2(sch_1):page168_i19:gate(0)"
				( attribute "PN" "2"
					( Origin gPackager )
				)
				( objectStatus "Q1L4.2" )
			)
			( pin "@baseboard_fab2_lib.baseboard_fab2(sch_1):page168_i19:source(0)"
				( attribute "PN" "1"
					( Origin gPackager )
				)
				( objectStatus "Q1L4.1" )
			)
			( pin "@baseboard_fab2_lib.baseboard_fab2(sch_1):page168_i22:a"
				( attribute "PN" "1"
					( Origin gPackager )
				)
				( objectStatus "R1L38.1" )
			)
			( pin "@baseboard_fab2_lib.baseboard_fab2(sch_1):page168_i22:b"
				( attribute "PN" "2"
					( Origin gPackager )
				)
				( objectStatus "R1L38.2" )
			)
			( pin "@baseboard_fab2_lib.baseboard_fab2(sch_1):page169_i56:a"
				( attribute "PN" "1"
					( Origin gPackager )
				)
				( objectStatus "C1U21.1" )
			)
			( pin "@baseboard_fab2_lib.baseboard_fab2(sch_1):page169_i56:b"
				( attribute "PN" "2"
					( Origin gPackager )
				)
				( objectStatus "C1U21.2" )
			)
			( pin "@baseboard_fab2_lib.baseboard_fab2(sch_1):page169_i57:a"
				( attribute "PN" "1"
					( Origin gPackager )
				)
				( objectStatus "FB1U3.1" )
			)
			( pin "@baseboard_fab2_lib.baseboard_fab2(sch_1):page169_i57:b"
				( attribute "PN" "2"
					( Origin gPackager )
				)
				( objectStatus "FB1U3.2" )
			)
			( pin "@baseboard_fab2_lib.baseboard_fab2(sch_1):page169_i68:a"
				( attribute "PN" "1"
					( Origin gPackager )
				)
				( objectStatus "C9G21.1" )
			)
			( pin "@baseboard_fab2_lib.baseboard_fab2(sch_1):page169_i68:b"
				( attribute "PN" "2"
					( Origin gPackager )
				)
				( objectStatus "C9G21.2" )
			)
			( pin "@baseboard_fab2_lib.baseboard_fab2(sch_1):page169_i80:a"
				( attribute "PN" "1"
					( Origin gPackager )
				)
				( objectStatus "C9G17.1" )
			)
			( pin "@baseboard_fab2_lib.baseboard_fab2(sch_1):page169_i80:b"
				( attribute "PN" "2"
					( Origin gPackager )
				)
				( objectStatus "C9G17.2" )
			)
			( pin "@baseboard_fab2_lib.baseboard_fab2(sch_1):page169_i82:a"
				( attribute "PN" "1"
					( Origin gPackager )
				)
				( objectStatus "R1U32.1" )
			)
			( pin "@baseboard_fab2_lib.baseboard_fab2(sch_1):page169_i82:b"
				( attribute "PN" "2"
					( Origin gPackager )
				)
				( objectStatus "R1U32.2" )
			)
			( pin "@baseboard_fab2_lib.baseboard_fab2(sch_1):page169_i86:a"
				( attribute "PN" "1"
					( Origin gPackager )
				)
				( objectStatus "C9G20.1" )
			)
			( pin "@baseboard_fab2_lib.baseboard_fab2(sch_1):page169_i86:b"
				( attribute "PN" "2"
					( Origin gPackager )
				)
				( objectStatus "C9G20.2" )
			)
			( pin "@baseboard_fab2_lib.baseboard_fab2(sch_1):page169_i88:a"
				( attribute "PN" "1"
					( Origin gPackager )
				)
				( objectStatus "R1U39.1" )
			)
			( pin "@baseboard_fab2_lib.baseboard_fab2(sch_1):page169_i88:b"
				( attribute "PN" "2"
					( Origin gPackager )
				)
				( objectStatus "R1U39.2" )
			)
			( pin "@baseboard_fab2_lib.baseboard_fab2(sch_1):page169_i106:a"
				( attribute "PN" "1"
					( Origin gPackager )
				)
				( objectStatus "R9G26.1" )
			)
			( pin "@baseboard_fab2_lib.baseboard_fab2(sch_1):page169_i106:b"
				( attribute "PN" "2"
					( Origin gPackager )
				)
				( objectStatus "R9G26.2" )
			)
			( pin "@baseboard_fab2_lib.baseboard_fab2(sch_1):page169_i108:a"
				( attribute "PN" "1"
					( Origin gPackager )
				)
				( objectStatus "C9G22.1" )
			)
			( pin "@baseboard_fab2_lib.baseboard_fab2(sch_1):page169_i108:b"
				( attribute "PN" "2"
					( Origin gPackager )
				)
				( objectStatus "C9G22.2" )
			)
			( pin "@baseboard_fab2_lib.baseboard_fab2(sch_1):page169_i170:\1\"
				( attribute "PN" "1"
					( Origin gPackager )
				)
				( objectStatus "R1U44.1" )
			)
			( pin "@baseboard_fab2_lib.baseboard_fab2(sch_1):page169_i170:\2\"
				( attribute "PN" "2"
					( Origin gPackager )
				)
				( objectStatus "R1U44.2" )
			)
			( pin "@baseboard_fab2_lib.baseboard_fab2(sch_1):page169_i115:a"
				( attribute "PN" "1"
					( Origin gPackager )
				)
				( objectStatus "R1U47.1" )
			)
			( pin "@baseboard_fab2_lib.baseboard_fab2(sch_1):page169_i115:b"
				( attribute "PN" "2"
					( Origin gPackager )
				)
				( objectStatus "R1U47.2" )
			)
			( pin "@baseboard_fab2_lib.baseboard_fab2(sch_1):page169_i126:a"
				( attribute "PN" "1"
					( Origin gPackager )
				)
				( objectStatus "R1U50.1" )
			)
			( pin "@baseboard_fab2_lib.baseboard_fab2(sch_1):page169_i126:b"
				( attribute "PN" "2"
					( Origin gPackager )
				)
				( objectStatus "R1U50.2" )
			)
			( pin "@baseboard_fab2_lib.baseboard_fab2(sch_1):page169_i139:a"
				( attribute "PN" "1"
					( Origin gPackager )
				)
				( objectStatus "C9G15.1" )
			)
			( pin "@baseboard_fab2_lib.baseboard_fab2(sch_1):page169_i139:b"
				( attribute "PN" "2"
					( Origin gPackager )
				)
				( objectStatus "C9G15.2" )
			)
			( pin "@baseboard_fab2_lib.baseboard_fab2(sch_1):page169_i141:a"
				( attribute "PN" "1"
					( Origin gPackager )
				)
				( objectStatus "R1U29.1" )
			)
			( pin "@baseboard_fab2_lib.baseboard_fab2(sch_1):page169_i141:b"
				( attribute "PN" "2"
					( Origin gPackager )
				)
				( objectStatus "R1U29.2" )
			)
			( pin "@baseboard_fab2_lib.baseboard_fab2(sch_1):page169_i146:a"
				( attribute "PN" "1"
					( Origin gPackager )
				)
				( objectStatus "C9G14.1" )
			)
			( pin "@baseboard_fab2_lib.baseboard_fab2(sch_1):page169_i146:b"
				( attribute "PN" "2"
					( Origin gPackager )
				)
				( objectStatus "C9G14.2" )
			)
			( pin "@baseboard_fab2_lib.baseboard_fab2(sch_1):page169_i148:a"
				( attribute "PN" "1"
					( Origin gPackager )
				)
				( objectStatus "R1U26.1" )
			)
			( pin "@baseboard_fab2_lib.baseboard_fab2(sch_1):page169_i148:b"
				( attribute "PN" "2"
					( Origin gPackager )
				)
				( objectStatus "R1U26.2" )
			)
			( pin "@baseboard_fab2_lib.baseboard_fab2(sch_1):page169_i169:\1\"
				( attribute "PN" "1"
					( Origin gPackager )
				)
				( objectStatus "R1U28.1" )
			)
			( pin "@baseboard_fab2_lib.baseboard_fab2(sch_1):page169_i169:\2\"
				( attribute "PN" "2"
					( Origin gPackager )
				)
				( objectStatus "R1U28.2" )
			)
			( pin "@baseboard_fab2_lib.baseboard_fab2(sch_1):page169_i153:a"
				( attribute "PN" "1"
					( Origin gPackager )
				)
				( objectStatus "C9G18.1" )
			)
			( pin "@baseboard_fab2_lib.baseboard_fab2(sch_1):page169_i153:b"
				( attribute "PN" "2"
					( Origin gPackager )
				)
				( objectStatus "C9G18.2" )
			)
			( pin "@baseboard_fab2_lib.baseboard_fab2(sch_1):page169_i155:a"
				( attribute "PN" "1"
					( Origin gPackager )
				)
				( objectStatus "FB1U4.1" )
			)
			( pin "@baseboard_fab2_lib.baseboard_fab2(sch_1):page169_i155:b"
				( attribute "PN" "2"
					( Origin gPackager )
				)
				( objectStatus "FB1U4.2" )
			)
			( pin "@baseboard_fab2_lib.baseboard_fab2(sch_1):page169_i157:drain(0)"
				( attribute "PN" "3"
					( Origin gPackager )
				)
				( objectStatus "Q9G1.3" )
			)
			( pin "@baseboard_fab2_lib.baseboard_fab2(sch_1):page169_i157:gate(0)"
				( attribute "PN" "5"
					( Origin gPackager )
				)
				( objectStatus "Q9G1.5" )
			)
			( pin "@baseboard_fab2_lib.baseboard_fab2(sch_1):page169_i157:source(0)"
				( attribute "PN" "4"
					( Origin gPackager )
				)
				( objectStatus "Q9G1.4" )
			)
			( pin "@baseboard_fab2_lib.baseboard_fab2(sch_1):page169_i162:drain(0)"
				( attribute "PN" "6"
					( Origin gPackager )
				)
				( objectStatus "Q9G1.6" )
			)
			( pin "@baseboard_fab2_lib.baseboard_fab2(sch_1):page169_i162:gate(0)"
				( attribute "PN" "2"
					( Origin gPackager )
				)
				( objectStatus "Q9G1.2" )
			)
			( pin "@baseboard_fab2_lib.baseboard_fab2(sch_1):page169_i162:source(0)"
				( attribute "PN" "1"
					( Origin gPackager )
				)
				( objectStatus "Q9G1.1" )
			)
			( pin "@baseboard_fab2_lib.baseboard_fab2(sch_1):page169_i163:a"
				( attribute "PN" "1"
					( Origin gPackager )
				)
				( objectStatus "R1U49.1" )
			)
			( pin "@baseboard_fab2_lib.baseboard_fab2(sch_1):page169_i163:b"
				( attribute "PN" "2"
					( Origin gPackager )
				)
				( objectStatus "R1U49.2" )
			)
			( pin "@baseboard_fab2_lib.baseboard_fab2(sch_1):page169_i164:a"
				( attribute "PN" "1"
					( Origin gPackager )
				)
				( objectStatus "R9G35.1" )
			)
			( pin "@baseboard_fab2_lib.baseboard_fab2(sch_1):page169_i164:b"
				( attribute "PN" "2"
					( Origin gPackager )
				)
				( objectStatus "R9G35.2" )
			)
			( pin "@baseboard_fab2_lib.baseboard_fab2(sch_1):page170_i2:a"
				( attribute "PN" "1"
					( Origin gPackager )
				)
				( objectStatus "R2P3.1" )
			)
			( pin "@baseboard_fab2_lib.baseboard_fab2(sch_1):page170_i2:b"
				( attribute "PN" "2"
					( Origin gPackager )
				)
				( objectStatus "R2P3.2" )
			)
			( pin "@baseboard_fab2_lib.baseboard_fab2(sch_1):page170_i4:a"
				( attribute "PN" "2"
					( Origin gPackager )
				)
				( objectStatus "U8D3.2" )
			)
			( pin "@baseboard_fab2_lib.baseboard_fab2(sch_1):page170_i4:y"
				( attribute "PN" "4"
					( Origin gPackager )
				)
				( objectStatus "U8D3.4" )
			)
			( pin "@baseboard_fab2_lib.baseboard_fab2(sch_1):page170_i8:a"
				( attribute "PN" "1"
					( Origin gPackager )
				)
				( objectStatus "C2P1.1" )
			)
			( pin "@baseboard_fab2_lib.baseboard_fab2(sch_1):page170_i8:b"
				( attribute "PN" "2"
					( Origin gPackager )
				)
				( objectStatus "C2P1.2" )
			)
			( pin "@baseboard_fab2_lib.baseboard_fab2(sch_1):page170_i10:a(0)"
				( attribute "PN" "1"
					( Origin gPackager )
				)
				( objectStatus "U8E1.1" )
			)
			( pin "@baseboard_fab2_lib.baseboard_fab2(sch_1):page170_i10:b(0)"
				( attribute "PN" "2"
					( Origin gPackager )
				)
				( objectStatus "U8E1.2" )
			)
			( pin "@baseboard_fab2_lib.baseboard_fab2(sch_1):page170_i10:y(0)"
				( attribute "PN" "3"
					( Origin gPackager )
				)
				( objectStatus "U8E1.3" )
			)
			( pin "@baseboard_fab2_lib.baseboard_fab2(sch_1):page170_i11:a(0)"
				( attribute "PN" "4"
					( Origin gPackager )
				)
				( objectStatus "U8E1.4" )
			)
			( pin "@baseboard_fab2_lib.baseboard_fab2(sch_1):page170_i11:b(0)"
				( attribute "PN" "5"
					( Origin gPackager )
				)
				( objectStatus "U8E1.5" )
			)
			( pin "@baseboard_fab2_lib.baseboard_fab2(sch_1):page170_i11:y(0)"
				( attribute "PN" "6"
					( Origin gPackager )
				)
				( objectStatus "U8E1.6" )
			)
			( pin "@baseboard_fab2_lib.baseboard_fab2(sch_1):page170_i12:a(0)"
				( attribute "PN" "12"
					( Origin gPackager )
				)
				( objectStatus "U8E1.12" )
			)
			( pin "@baseboard_fab2_lib.baseboard_fab2(sch_1):page170_i12:b(0)"
				( attribute "PN" "13"
					( Origin gPackager )
				)
				( objectStatus "U8E1.13" )
			)
			( pin "@baseboard_fab2_lib.baseboard_fab2(sch_1):page170_i12:y(0)"
				( attribute "PN" "11"
					( Origin gPackager )
				)
				( objectStatus "U8E1.11" )
			)
			( pin "@baseboard_fab2_lib.baseboard_fab2(sch_1):page170_i20:a"
				( attribute "PN" "2"
					( Origin gPackager )
				)
				( objectStatus "U1R2.2" )
			)
			( pin "@baseboard_fab2_lib.baseboard_fab2(sch_1):page170_i20:oe"
				( attribute "PN" "1"
					( Origin gPackager )
				)
				( objectStatus "U1R2.1" )
			)
			( pin "@baseboard_fab2_lib.baseboard_fab2(sch_1):page170_i20:y"
				( attribute "PN" "4"
					( Origin gPackager )
				)
				( objectStatus "U1R2.4" )
			)
			( pin "@baseboard_fab2_lib.baseboard_fab2(sch_1):page170_i30:a"
				( attribute "PN" "1"
					( Origin gPackager )
				)
				( objectStatus "C1R27.1" )
			)
			( pin "@baseboard_fab2_lib.baseboard_fab2(sch_1):page170_i30:b"
				( attribute "PN" "2"
					( Origin gPackager )
				)
				( objectStatus "C1R27.2" )
			)
			( pin "@baseboard_fab2_lib.baseboard_fab2(sch_1):page170_i33:a"
				( attribute "PN" "1"
					( Origin gPackager )
				)
				( objectStatus "C8D2.1" )
			)
			( pin "@baseboard_fab2_lib.baseboard_fab2(sch_1):page170_i33:b"
				( attribute "PN" "2"
					( Origin gPackager )
				)
				( objectStatus "C8D2.2" )
			)
			( pin "@baseboard_fab2_lib.baseboard_fab2(sch_1):page170_i38:a"
				( attribute "PN" "2"
					( Origin gPackager )
				)
				( objectStatus "U8D5.2" )
			)
			( pin "@baseboard_fab2_lib.baseboard_fab2(sch_1):page170_i38:oe"
				( attribute "PN" "1"
					( Origin gPackager )
				)
				( objectStatus "U8D5.1" )
			)
			( pin "@baseboard_fab2_lib.baseboard_fab2(sch_1):page170_i38:y"
				( attribute "PN" "4"
					( Origin gPackager )
				)
				( objectStatus "U8D5.4" )
			)
			( pin "@baseboard_fab2_lib.baseboard_fab2(sch_1):page170_i40:a"
				( attribute "PN" "1"
					( Origin gPackager )
				)
				( objectStatus "C8E2.1" )
			)
			( pin "@baseboard_fab2_lib.baseboard_fab2(sch_1):page170_i40:b"
				( attribute "PN" "2"
					( Origin gPackager )
				)
				( objectStatus "C8E2.2" )
			)
			( pin "@baseboard_fab2_lib.baseboard_fab2(sch_1):page170_i42:a"
				( attribute "PN" "1"
					( Origin gPackager )
				)
				( objectStatus "C8D3.1" )
			)
			( pin "@baseboard_fab2_lib.baseboard_fab2(sch_1):page170_i42:b"
				( attribute "PN" "2"
					( Origin gPackager )
				)
				( objectStatus "C8D3.2" )
			)
			( pin "@baseboard_fab2_lib.baseboard_fab2(sch_1):page170_i46:a"
				( attribute "PN" "2"
					( Origin gPackager )
				)
				( objectStatus "U1R1.2" )
			)
			( pin "@baseboard_fab2_lib.baseboard_fab2(sch_1):page170_i46:y"
				( attribute "PN" "4"
					( Origin gPackager )
				)
				( objectStatus "U1R1.4" )
			)
			( pin "@baseboard_fab2_lib.baseboard_fab2(sch_1):page170_i49:a"
				( attribute "PN" "1"
					( Origin gPackager )
				)
				( objectStatus "C1R28.1" )
			)
			( pin "@baseboard_fab2_lib.baseboard_fab2(sch_1):page170_i49:b"
				( attribute "PN" "2"
					( Origin gPackager )
				)
				( objectStatus "C1R28.2" )
			)
			( pin "@baseboard_fab2_lib.baseboard_fab2(sch_1):page170_i51:a"
				( attribute "PN" "1"
					( Origin gPackager )
				)
				( objectStatus "R1R8.1" )
			)
			( pin "@baseboard_fab2_lib.baseboard_fab2(sch_1):page170_i51:b"
				( attribute "PN" "2"
					( Origin gPackager )
				)
				( objectStatus "R1R8.2" )
			)
			( pin "@baseboard_fab2_lib.baseboard_fab2(sch_1):page170_i54:a"
				( attribute "PN" "1"
					( Origin gPackager )
				)
				( objectStatus "R2T3.1" )
			)
			( pin "@baseboard_fab2_lib.baseboard_fab2(sch_1):page170_i54:b"
				( attribute "PN" "2"
					( Origin gPackager )
				)
				( objectStatus "R2T3.2" )
			)
			( pin "@baseboard_fab2_lib.baseboard_fab2(sch_1):page170_i56:a"
				( attribute "PN" "1"
					( Origin gPackager )
				)
				( objectStatus "R2P5.1" )
			)
			( pin "@baseboard_fab2_lib.baseboard_fab2(sch_1):page170_i56:b"
				( attribute "PN" "2"
					( Origin gPackager )
				)
				( objectStatus "R2P5.2" )
			)
			( pin "@baseboard_fab2_lib.baseboard_fab2(sch_1):page170_i58:drn"
				( attribute "PN" "3"
					( Origin gPackager )
				)
				( objectStatus "Q2P1.3" )
			)
			( pin "@baseboard_fab2_lib.baseboard_fab2(sch_1):page170_i58:gate"
				( attribute "PN" "1"
					( Origin gPackager )
				)
				( objectStatus "Q2P1.1" )
			)
			( pin "@baseboard_fab2_lib.baseboard_fab2(sch_1):page170_i58:src"
				( attribute "PN" "2"
					( Origin gPackager )
				)
				( objectStatus "Q2P1.2" )
			)
			( pin "@baseboard_fab2_lib.baseboard_fab2(sch_1):page170_i61:a"
				( attribute "PN" "1"
					( Origin gPackager )
				)
				( objectStatus "R2P13.1" )
			)
			( pin "@baseboard_fab2_lib.baseboard_fab2(sch_1):page170_i61:b"
				( attribute "PN" "2"
					( Origin gPackager )
				)
				( objectStatus "R2P13.2" )
			)
			( pin "@baseboard_fab2_lib.baseboard_fab2(sch_1):page170_i63:a"
				( attribute "PN" "1"
					( Origin gPackager )
				)
				( objectStatus "R2P11.1" )
			)
			( pin "@baseboard_fab2_lib.baseboard_fab2(sch_1):page170_i63:b"
				( attribute "PN" "2"
					( Origin gPackager )
				)
				( objectStatus "R2P11.2" )
			)
			( pin "@baseboard_fab2_lib.baseboard_fab2(sch_1):page170_i65:a"
				( attribute "PN" "1"
					( Origin gPackager )
				)
				( objectStatus "R9F3.1" )
			)
			( pin "@baseboard_fab2_lib.baseboard_fab2(sch_1):page170_i65:b"
				( attribute "PN" "2"
					( Origin gPackager )
				)
				( objectStatus "R9F3.2" )
			)
			( pin "@baseboard_fab2_lib.baseboard_fab2(sch_1):page170_i67:drn"
				( attribute "PN" "3"
					( Origin gPackager )
				)
				( objectStatus "Q8F2.3" )
			)
			( pin "@baseboard_fab2_lib.baseboard_fab2(sch_1):page170_i67:gate"
				( attribute "PN" "1"
					( Origin gPackager )
				)
				( objectStatus "Q8F2.1" )
			)
			( pin "@baseboard_fab2_lib.baseboard_fab2(sch_1):page170_i67:src"
				( attribute "PN" "2"
					( Origin gPackager )
				)
				( objectStatus "Q8F2.2" )
			)
			( pin "@baseboard_fab2_lib.baseboard_fab2(sch_1):page170_i71:a"
				( attribute "PN" "1"
					( Origin gPackager )
				)
				( objectStatus "R8D26.1" )
			)
			( pin "@baseboard_fab2_lib.baseboard_fab2(sch_1):page170_i71:b"
				( attribute "PN" "2"
					( Origin gPackager )
				)
				( objectStatus "R8D26.2" )
			)
			( pin "@baseboard_fab2_lib.baseboard_fab2(sch_1):page170_i73:a"
				( attribute "PN" "1"
					( Origin gPackager )
				)
				( objectStatus "R1R5.1" )
			)
			( pin "@baseboard_fab2_lib.baseboard_fab2(sch_1):page170_i73:b"
				( attribute "PN" "2"
					( Origin gPackager )
				)
				( objectStatus "R1R5.2" )
			)
			( pin "@baseboard_fab2_lib.baseboard_fab2(sch_1):page170_i74:a"
				( attribute "PN" "1"
					( Origin gPackager )
				)
				( objectStatus "R2P4.1" )
			)
			( pin "@baseboard_fab2_lib.baseboard_fab2(sch_1):page170_i74:b"
				( attribute "PN" "2"
					( Origin gPackager )
				)
				( objectStatus "R2P4.2" )
			)
			( pin "@baseboard_fab2_lib.baseboard_fab2(sch_1):page172_i5:a"
				( attribute "PN" "1"
					( Origin gPackager )
				)
				( objectStatus "C2L49.1" )
			)
			( pin "@baseboard_fab2_lib.baseboard_fab2(sch_1):page172_i5:b"
				( attribute "PN" "2"
					( Origin gPackager )
				)
				( objectStatus "C2L49.2" )
			)
			( pin "@baseboard_fab2_lib.baseboard_fab2(sch_1):page172_i6:a"
				( attribute "PN" "1"
					( Origin gPackager )
				)
				( objectStatus "C2L52.1" )
			)
			( pin "@baseboard_fab2_lib.baseboard_fab2(sch_1):page172_i6:b"
				( attribute "PN" "2"
					( Origin gPackager )
				)
				( objectStatus "C2L52.2" )
			)
			( pin "@baseboard_fab2_lib.baseboard_fab2(sch_1):page172_i7:a"
				( attribute "PN" "1"
					( Origin gPackager )
				)
				( objectStatus "C2L50.1" )
			)
			( pin "@baseboard_fab2_lib.baseboard_fab2(sch_1):page172_i7:b"
				( attribute "PN" "2"
					( Origin gPackager )
				)
				( objectStatus "C2L50.2" )
			)
			( pin "@baseboard_fab2_lib.baseboard_fab2(sch_1):page172_i8:a"
				( attribute "PN" "1"
					( Origin gPackager )
				)
				( objectStatus "C2L51.1" )
			)
			( pin "@baseboard_fab2_lib.baseboard_fab2(sch_1):page172_i8:b"
				( attribute "PN" "2"
					( Origin gPackager )
				)
				( objectStatus "C2L51.2" )
			)
			( pin "@baseboard_fab2_lib.baseboard_fab2(sch_1):page172_i36:a"
				( attribute "PN" "1"
					( Origin gPackager )
				)
				( objectStatus "C9B2.1" )
			)
			( pin "@baseboard_fab2_lib.baseboard_fab2(sch_1):page172_i36:b"
				( attribute "PN" "2"
					( Origin gPackager )
				)
				( objectStatus "C9B2.2" )
			)
			( pin "@baseboard_fab2_lib.baseboard_fab2(sch_1):page172_i39:a"
				( attribute "PN" "1"
					( Origin gPackager )
				)
				( objectStatus "C9B1.1" )
			)
			( pin "@baseboard_fab2_lib.baseboard_fab2(sch_1):page172_i39:b"
				( attribute "PN" "2"
					( Origin gPackager )
				)
				( objectStatus "C9B1.2" )
			)
			( pin "@baseboard_fab2_lib.baseboard_fab2(sch_1):page150_i191:a"
				( attribute "PN" "1"
					( Origin gPackager )
				)
				( objectStatus "R25W108.1" )
			)
			( pin "@baseboard_fab2_lib.baseboard_fab2(sch_1):page150_i191:b"
				( attribute "PN" "2"
					( Origin gPackager )
				)
				( objectStatus "R25W108.2" )
			)
			( pin "@baseboard_fab2_lib.baseboard_fab2(sch_1):page150_i189:a"
				( attribute "PN" "1"
					( Origin gPackager )
				)
				( objectStatus "R25W116.1" )
			)
			( pin "@baseboard_fab2_lib.baseboard_fab2(sch_1):page150_i189:b"
				( attribute "PN" "2"
					( Origin gPackager )
				)
				( objectStatus "R25W116.2" )
			)
			( pin "@baseboard_fab2_lib.baseboard_fab2(sch_1):page173_i163:gnd(0)"
				( attribute "PN" "2D9"
					( Origin gPackager )
				)
				( objectStatus "J8A1.2D9" )
			)
			( pin "@baseboard_fab2_lib.baseboard_fab2(sch_1):page173_i163:gnd(1)"
				( attribute "PN" "2D6"
					( Origin gPackager )
				)
				( objectStatus "J8A1.2D6" )
			)
			( pin "@baseboard_fab2_lib.baseboard_fab2(sch_1):page173_i163:gnd(2)"
				( attribute "PN" "2D3"
					( Origin gPackager )
				)
				( objectStatus "J8A1.2D3" )
			)
			( pin "@baseboard_fab2_lib.baseboard_fab2(sch_1):page173_i163:gnd(3)"
				( attribute "PN" "2C9"
					( Origin gPackager )
				)
				( objectStatus "J8A1.2C9" )
			)
			( pin "@baseboard_fab2_lib.baseboard_fab2(sch_1):page173_i163:gnd(4)"
				( attribute "PN" "2C6"
					( Origin gPackager )
				)
				( objectStatus "J8A1.2C6" )
			)
			( pin "@baseboard_fab2_lib.baseboard_fab2(sch_1):page173_i163:gnd(5)"
				( attribute "PN" "2C3"
					( Origin gPackager )
				)
				( objectStatus "J8A1.2C3" )
			)
			( pin "@baseboard_fab2_lib.baseboard_fab2(sch_1):page173_i163:gnd(6)"
				( attribute "PN" "2B9"
					( Origin gPackager )
				)
				( objectStatus "J8A1.2B9" )
			)
			( pin "@baseboard_fab2_lib.baseboard_fab2(sch_1):page173_i163:gnd(7)"
				( attribute "PN" "2B6"
					( Origin gPackager )
				)
				( objectStatus "J8A1.2B6" )
			)
			( pin "@baseboard_fab2_lib.baseboard_fab2(sch_1):page173_i163:gnd(8)"
				( attribute "PN" "2B3"
					( Origin gPackager )
				)
				( objectStatus "J8A1.2B3" )
			)
			( pin "@baseboard_fab2_lib.baseboard_fab2(sch_1):page173_i163:gnd(9)"
				( attribute "PN" "2A9"
					( Origin gPackager )
				)
				( objectStatus "J8A1.2A9" )
			)
			( pin "@baseboard_fab2_lib.baseboard_fab2(sch_1):page173_i163:gnd(10)"
				( attribute "PN" "2A6"
					( Origin gPackager )
				)
				( objectStatus "J8A1.2A6" )
			)
			( pin "@baseboard_fab2_lib.baseboard_fab2(sch_1):page173_i163:gnd(11)"
				( attribute "PN" "2A3"
					( Origin gPackager )
				)
				( objectStatus "J8A1.2A3" )
			)
			( pin "@baseboard_fab2_lib.baseboard_fab2(sch_1):page173_i163:gnd(12)"
				( attribute "PN" "1D9"
					( Origin gPackager )
				)
				( objectStatus "J8A1.1D9" )
			)
			( pin "@baseboard_fab2_lib.baseboard_fab2(sch_1):page173_i163:gnd(13)"
				( attribute "PN" "1D6"
					( Origin gPackager )
				)
				( objectStatus "J8A1.1D6" )
			)
			( pin "@baseboard_fab2_lib.baseboard_fab2(sch_1):page173_i163:gnd(14)"
				( attribute "PN" "1D3"
					( Origin gPackager )
				)
				( objectStatus "J8A1.1D3" )
			)
			( pin "@baseboard_fab2_lib.baseboard_fab2(sch_1):page173_i163:gnd(15)"
				( attribute "PN" "1C9"
					( Origin gPackager )
				)
				( objectStatus "J8A1.1C9" )
			)
			( pin "@baseboard_fab2_lib.baseboard_fab2(sch_1):page173_i163:gnd(16)"
				( attribute "PN" "1C6"
					( Origin gPackager )
				)
				( objectStatus "J8A1.1C6" )
			)
			( pin "@baseboard_fab2_lib.baseboard_fab2(sch_1):page173_i163:gnd(17)"
				( attribute "PN" "1C3"
					( Origin gPackager )
				)
				( objectStatus "J8A1.1C3" )
			)
			( pin "@baseboard_fab2_lib.baseboard_fab2(sch_1):page173_i163:gnd(18)"
				( attribute "PN" "1B9"
					( Origin gPackager )
				)
				( objectStatus "J8A1.1B9" )
			)
			( pin "@baseboard_fab2_lib.baseboard_fab2(sch_1):page173_i163:gnd(19)"
				( attribute "PN" "1B6"
					( Origin gPackager )
				)
				( objectStatus "J8A1.1B6" )
			)
			( pin "@baseboard_fab2_lib.baseboard_fab2(sch_1):page173_i163:gnd(20)"
				( attribute "PN" "1B3"
					( Origin gPackager )
				)
				( objectStatus "J8A1.1B3" )
			)
			( pin "@baseboard_fab2_lib.baseboard_fab2(sch_1):page173_i163:gnd(21)"
				( attribute "PN" "1A9"
					( Origin gPackager )
				)
				( objectStatus "J8A1.1A9" )
			)
			( pin "@baseboard_fab2_lib.baseboard_fab2(sch_1):page173_i163:gnd(22)"
				( attribute "PN" "1A6"
					( Origin gPackager )
				)
				( objectStatus "J8A1.1A6" )
			)
			( pin "@baseboard_fab2_lib.baseboard_fab2(sch_1):page173_i163:gnd(23)"
				( attribute "PN" "1A3"
					( Origin gPackager )
				)
				( objectStatus "J8A1.1A3" )
			)
			( pin "@baseboard_fab2_lib.baseboard_fab2(sch_1):page173_i163:rxa0_dn"
				( attribute "PN" "1B5"
					( Origin gPackager )
				)
				( objectStatus "J8A1.1B5" )
			)
			( pin "@baseboard_fab2_lib.baseboard_fab2(sch_1):page173_i163:rxa0_dp"
				( attribute "PN" "1B4"
					( Origin gPackager )
				)
				( objectStatus "J8A1.1B4" )
			)
			( pin "@baseboard_fab2_lib.baseboard_fab2(sch_1):page173_i163:rxa1_dn"
				( attribute "PN" "1A5"
					( Origin gPackager )
				)
				( objectStatus "J8A1.1A5" )
			)
			( pin "@baseboard_fab2_lib.baseboard_fab2(sch_1):page173_i163:rxa1_dp"
				( attribute "PN" "1A4"
					( Origin gPackager )
				)
				( objectStatus "J8A1.1A4" )
			)
			( pin "@baseboard_fab2_lib.baseboard_fab2(sch_1):page173_i163:rxa2_dn"
				( attribute "PN" "1B8"
					( Origin gPackager )
				)
				( objectStatus "J8A1.1B8" )
			)
			( pin "@baseboard_fab2_lib.baseboard_fab2(sch_1):page173_i163:rxa2_dp"
				( attribute "PN" "1B7"
					( Origin gPackager )
				)
				( objectStatus "J8A1.1B7" )
			)
			( pin "@baseboard_fab2_lib.baseboard_fab2(sch_1):page173_i163:rxa3_dn"
				( attribute "PN" "1A8"
					( Origin gPackager )
				)
				( objectStatus "J8A1.1A8" )
			)
			( pin "@baseboard_fab2_lib.baseboard_fab2(sch_1):page173_i163:rxa3_dp"
				( attribute "PN" "1A7"
					( Origin gPackager )
				)
				( objectStatus "J8A1.1A7" )
			)
			( pin "@baseboard_fab2_lib.baseboard_fab2(sch_1):page173_i163:rxb0_dn"
				( attribute "PN" "2B5"
					( Origin gPackager )
				)
				( objectStatus "J8A1.2B5" )
			)
			( pin "@baseboard_fab2_lib.baseboard_fab2(sch_1):page173_i163:rxb0_dp"
				( attribute "PN" "2B4"
					( Origin gPackager )
				)
				( objectStatus "J8A1.2B4" )
			)
			( pin "@baseboard_fab2_lib.baseboard_fab2(sch_1):page173_i163:rxb1_dn"
				( attribute "PN" "2A5"
					( Origin gPackager )
				)
				( objectStatus "J8A1.2A5" )
			)
			( pin "@baseboard_fab2_lib.baseboard_fab2(sch_1):page173_i163:rxb1_dp"
				( attribute "PN" "2A4"
					( Origin gPackager )
				)
				( objectStatus "J8A1.2A4" )
			)
			( pin "@baseboard_fab2_lib.baseboard_fab2(sch_1):page173_i163:rxb2_dn"
				( attribute "PN" "2B8"
					( Origin gPackager )
				)
				( objectStatus "J8A1.2B8" )
			)
			( pin "@baseboard_fab2_lib.baseboard_fab2(sch_1):page173_i163:rxb2_dp"
				( attribute "PN" "2B7"
					( Origin gPackager )
				)
				( objectStatus "J8A1.2B7" )
			)
			( pin "@baseboard_fab2_lib.baseboard_fab2(sch_1):page173_i163:rxb3_dn"
				( attribute "PN" "2A8"
					( Origin gPackager )
				)
				( objectStatus "J8A1.2A8" )
			)
			( pin "@baseboard_fab2_lib.baseboard_fab2(sch_1):page173_i163:rxb3_dp"
				( attribute "PN" "2A7"
					( Origin gPackager )
				)
				( objectStatus "J8A1.2A7" )
			)
			( pin "@baseboard_fab2_lib.baseboard_fab2(sch_1):page173_i163:sidebanda_0"
				( attribute "PN" "1A2"
					( Origin gPackager )
				)
				( objectStatus "J8A1.1A2" )
			)
			( pin "@baseboard_fab2_lib.baseboard_fab2(sch_1):page173_i163:sidebanda_1"
				( attribute "PN" "1B2"
					( Origin gPackager )
				)
				( objectStatus "J8A1.1B2" )
			)
			( pin "@baseboard_fab2_lib.baseboard_fab2(sch_1):page173_i163:sidebanda_2"
				( attribute "PN" "1C2"
					( Origin gPackager )
				)
				( objectStatus "J8A1.1C2" )
			)
			( pin "@baseboard_fab2_lib.baseboard_fab2(sch_1):page173_i163:sidebanda_3"
				( attribute "PN" "1B1"
					( Origin gPackager )
				)
				( objectStatus "J8A1.1B1" )
			)
			( pin "@baseboard_fab2_lib.baseboard_fab2(sch_1):page173_i163:sidebanda_4"
				( attribute "PN" "1C1"
					( Origin gPackager )
				)
				( objectStatus "J8A1.1C1" )
			)
			( pin "@baseboard_fab2_lib.baseboard_fab2(sch_1):page173_i163:sidebanda_5"
				( attribute "PN" "1D1"
					( Origin gPackager )
				)
				( objectStatus "J8A1.1D1" )
			)
			( pin "@baseboard_fab2_lib.baseboard_fab2(sch_1):page173_i163:sidebanda_6"
				( attribute "PN" "1D2"
					( Origin gPackager )
				)
				( objectStatus "J8A1.1D2" )
			)
			( pin "@baseboard_fab2_lib.baseboard_fab2(sch_1):page173_i163:sidebanda_7"
				( attribute "PN" "1A1"
					( Origin gPackager )
				)
				( objectStatus "J8A1.1A1" )
			)
			( pin "@baseboard_fab2_lib.baseboard_fab2(sch_1):page173_i163:sidebandb_0"
				( attribute "PN" "2A2"
					( Origin gPackager )
				)
				( objectStatus "J8A1.2A2" )
			)
			( pin "@baseboard_fab2_lib.baseboard_fab2(sch_1):page173_i163:sidebandb_1"
				( attribute "PN" "2B2"
					( Origin gPackager )
				)
				( objectStatus "J8A1.2B2" )
			)
			( pin "@baseboard_fab2_lib.baseboard_fab2(sch_1):page173_i163:sidebandb_2"
				( attribute "PN" "2C2"
					( Origin gPackager )
				)
				( objectStatus "J8A1.2C2" )
			)
			( pin "@baseboard_fab2_lib.baseboard_fab2(sch_1):page173_i163:sidebandb_3"
				( attribute "PN" "2B1"
					( Origin gPackager )
				)
				( objectStatus "J8A1.2B1" )
			)
			( pin "@baseboard_fab2_lib.baseboard_fab2(sch_1):page173_i163:sidebandb_4"
				( attribute "PN" "2C1"
					( Origin gPackager )
				)
				( objectStatus "J8A1.2C1" )
			)
			( pin "@baseboard_fab2_lib.baseboard_fab2(sch_1):page173_i163:sidebandb_5"
				( attribute "PN" "2D1"
					( Origin gPackager )
				)
				( objectStatus "J8A1.2D1" )
			)
			( pin "@baseboard_fab2_lib.baseboard_fab2(sch_1):page173_i163:sidebandb_6"
				( attribute "PN" "2D2"
					( Origin gPackager )
				)
				( objectStatus "J8A1.2D2" )
			)
			( pin "@baseboard_fab2_lib.baseboard_fab2(sch_1):page173_i163:sidebandb_7"
				( attribute "PN" "2A1"
					( Origin gPackager )
				)
				( objectStatus "J8A1.2A1" )
			)
			( pin "@baseboard_fab2_lib.baseboard_fab2(sch_1):page173_i163:txa0_dn"
				( attribute "PN" "1D5"
					( Origin gPackager )
				)
				( objectStatus "J8A1.1D5" )
			)
			( pin "@baseboard_fab2_lib.baseboard_fab2(sch_1):page173_i163:txa0_dp"
				( attribute "PN" "1D4"
					( Origin gPackager )
				)
				( objectStatus "J8A1.1D4" )
			)
			( pin "@baseboard_fab2_lib.baseboard_fab2(sch_1):page173_i163:txa1_dn"
				( attribute "PN" "1C5"
					( Origin gPackager )
				)
				( objectStatus "J8A1.1C5" )
			)
			( pin "@baseboard_fab2_lib.baseboard_fab2(sch_1):page173_i163:txa1_dp"
				( attribute "PN" "1C4"
					( Origin gPackager )
				)
				( objectStatus "J8A1.1C4" )
			)
			( pin "@baseboard_fab2_lib.baseboard_fab2(sch_1):page173_i163:txa2_dn"
				( attribute "PN" "1D8"
					( Origin gPackager )
				)
				( objectStatus "J8A1.1D8" )
			)
			( pin "@baseboard_fab2_lib.baseboard_fab2(sch_1):page173_i163:txa2_dp"
				( attribute "PN" "1D7"
					( Origin gPackager )
				)
				( objectStatus "J8A1.1D7" )
			)
			( pin "@baseboard_fab2_lib.baseboard_fab2(sch_1):page173_i163:txa3_dn"
				( attribute "PN" "1C8"
					( Origin gPackager )
				)
				( objectStatus "J8A1.1C8" )
			)
			( pin "@baseboard_fab2_lib.baseboard_fab2(sch_1):page173_i163:txa3_dp"
				( attribute "PN" "1C7"
					( Origin gPackager )
				)
				( objectStatus "J8A1.1C7" )
			)
			( pin "@baseboard_fab2_lib.baseboard_fab2(sch_1):page173_i163:txb0_dn"
				( attribute "PN" "2D5"
					( Origin gPackager )
				)
				( objectStatus "J8A1.2D5" )
			)
			( pin "@baseboard_fab2_lib.baseboard_fab2(sch_1):page173_i163:txb0_dp"
				( attribute "PN" "2D4"
					( Origin gPackager )
				)
				( objectStatus "J8A1.2D4" )
			)
			( pin "@baseboard_fab2_lib.baseboard_fab2(sch_1):page173_i163:txb1_dn"
				( attribute "PN" "2C5"
					( Origin gPackager )
				)
				( objectStatus "J8A1.2C5" )
			)
			( pin "@baseboard_fab2_lib.baseboard_fab2(sch_1):page173_i163:txb1_dp"
				( attribute "PN" "2C4"
					( Origin gPackager )
				)
				( objectStatus "J8A1.2C4" )
			)
			( pin "@baseboard_fab2_lib.baseboard_fab2(sch_1):page173_i163:txb2_dn"
				( attribute "PN" "2D8"
					( Origin gPackager )
				)
				( objectStatus "J8A1.2D8" )
			)
			( pin "@baseboard_fab2_lib.baseboard_fab2(sch_1):page173_i163:txb2_dp"
				( attribute "PN" "2D7"
					( Origin gPackager )
				)
				( objectStatus "J8A1.2D7" )
			)
			( pin "@baseboard_fab2_lib.baseboard_fab2(sch_1):page173_i163:txb3_dn"
				( attribute "PN" "2C8"
					( Origin gPackager )
				)
				( objectStatus "J8A1.2C8" )
			)
			( pin "@baseboard_fab2_lib.baseboard_fab2(sch_1):page173_i163:txb3_dp"
				( attribute "PN" "2C7"
					( Origin gPackager )
				)
				( objectStatus "J8A1.2C7" )
			)
			( pin "@baseboard_fab2_lib.baseboard_fab2(sch_1):page173_i165:a"
				( attribute "PN" "1"
					( Origin gPackager )
				)
				( objectStatus "C2L13.1" )
			)
			( pin "@baseboard_fab2_lib.baseboard_fab2(sch_1):page173_i165:b"
				( attribute "PN" "2"
					( Origin gPackager )
				)
				( objectStatus "C2L13.2" )
			)
			( pin "@baseboard_fab2_lib.baseboard_fab2(sch_1):page173_i166:a"
				( attribute "PN" "1"
					( Origin gPackager )
				)
				( objectStatus "C2L6.1" )
			)
			( pin "@baseboard_fab2_lib.baseboard_fab2(sch_1):page173_i166:b"
				( attribute "PN" "2"
					( Origin gPackager )
				)
				( objectStatus "C2L6.2" )
			)
			( pin "@baseboard_fab2_lib.baseboard_fab2(sch_1):page173_i172:a"
				( attribute "PN" "1"
					( Origin gPackager )
				)
				( objectStatus "C2L19.1" )
			)
			( pin "@baseboard_fab2_lib.baseboard_fab2(sch_1):page173_i172:b"
				( attribute "PN" "2"
					( Origin gPackager )
				)
				( objectStatus "C2L19.2" )
			)
			( pin "@baseboard_fab2_lib.baseboard_fab2(sch_1):page173_i173:a"
				( attribute "PN" "1"
					( Origin gPackager )
				)
				( objectStatus "C2L10.1" )
			)
			( pin "@baseboard_fab2_lib.baseboard_fab2(sch_1):page173_i173:b"
				( attribute "PN" "2"
					( Origin gPackager )
				)
				( objectStatus "C2L10.2" )
			)
			( pin "@baseboard_fab2_lib.baseboard_fab2(sch_1):page173_i174:a"
				( attribute "PN" "1"
					( Origin gPackager )
				)
				( objectStatus "C2L17.1" )
			)
			( pin "@baseboard_fab2_lib.baseboard_fab2(sch_1):page173_i174:b"
				( attribute "PN" "2"
					( Origin gPackager )
				)
				( objectStatus "C2L17.2" )
			)
			( pin "@baseboard_fab2_lib.baseboard_fab2(sch_1):page173_i191:a"
				( attribute "PN" "1"
					( Origin gPackager )
				)
				( objectStatus "C2L15.1" )
			)
			( pin "@baseboard_fab2_lib.baseboard_fab2(sch_1):page173_i191:b"
				( attribute "PN" "2"
					( Origin gPackager )
				)
				( objectStatus "C2L15.2" )
			)
			( pin "@baseboard_fab2_lib.baseboard_fab2(sch_1):page173_i192:a"
				( attribute "PN" "1"
					( Origin gPackager )
				)
				( objectStatus "C2L4.1" )
			)
			( pin "@baseboard_fab2_lib.baseboard_fab2(sch_1):page173_i192:b"
				( attribute "PN" "2"
					( Origin gPackager )
				)
				( objectStatus "C2L4.2" )
			)
			( pin "@baseboard_fab2_lib.baseboard_fab2(sch_1):page173_i194:a"
				( attribute "PN" "1"
					( Origin gPackager )
				)
				( objectStatus "C2L3.1" )
			)
			( pin "@baseboard_fab2_lib.baseboard_fab2(sch_1):page173_i194:b"
				( attribute "PN" "2"
					( Origin gPackager )
				)
				( objectStatus "C2L3.2" )
			)
			( pin "@baseboard_fab2_lib.baseboard_fab2(sch_1):page173_i195:a"
				( attribute "PN" "1"
					( Origin gPackager )
				)
				( objectStatus "C2L20.1" )
			)
			( pin "@baseboard_fab2_lib.baseboard_fab2(sch_1):page173_i195:b"
				( attribute "PN" "2"
					( Origin gPackager )
				)
				( objectStatus "C2L20.2" )
			)
			( pin "@baseboard_fab2_lib.baseboard_fab2(sch_1):page173_i196:a"
				( attribute "PN" "1"
					( Origin gPackager )
				)
				( objectStatus "C2L12.1" )
			)
			( pin "@baseboard_fab2_lib.baseboard_fab2(sch_1):page173_i196:b"
				( attribute "PN" "2"
					( Origin gPackager )
				)
				( objectStatus "C2L12.2" )
			)
			( pin "@baseboard_fab2_lib.baseboard_fab2(sch_1):page173_i197:a"
				( attribute "PN" "1"
					( Origin gPackager )
				)
				( objectStatus "C2L18.1" )
			)
			( pin "@baseboard_fab2_lib.baseboard_fab2(sch_1):page173_i197:b"
				( attribute "PN" "2"
					( Origin gPackager )
				)
				( objectStatus "C2L18.2" )
			)
			( pin "@baseboard_fab2_lib.baseboard_fab2(sch_1):page173_i205:a"
				( attribute "PN" "1"
					( Origin gPackager )
				)
				( objectStatus "C2L16.1" )
			)
			( pin "@baseboard_fab2_lib.baseboard_fab2(sch_1):page173_i205:b"
				( attribute "PN" "2"
					( Origin gPackager )
				)
				( objectStatus "C2L16.2" )
			)
			( pin "@baseboard_fab2_lib.baseboard_fab2(sch_1):page173_i206:a"
				( attribute "PN" "1"
					( Origin gPackager )
				)
				( objectStatus "C2L7.1" )
			)
			( pin "@baseboard_fab2_lib.baseboard_fab2(sch_1):page173_i206:b"
				( attribute "PN" "2"
					( Origin gPackager )
				)
				( objectStatus "C2L7.2" )
			)
			( pin "@baseboard_fab2_lib.baseboard_fab2(sch_1):page173_i207:a"
				( attribute "PN" "1"
					( Origin gPackager )
				)
				( objectStatus "C2L9.1" )
			)
			( pin "@baseboard_fab2_lib.baseboard_fab2(sch_1):page173_i207:b"
				( attribute "PN" "2"
					( Origin gPackager )
				)
				( objectStatus "C2L9.2" )
			)
			( pin "@baseboard_fab2_lib.baseboard_fab2(sch_1):page173_i208:a"
				( attribute "PN" "1"
					( Origin gPackager )
				)
				( objectStatus "C2L14.1" )
			)
			( pin "@baseboard_fab2_lib.baseboard_fab2(sch_1):page173_i208:b"
				( attribute "PN" "2"
					( Origin gPackager )
				)
				( objectStatus "C2L14.2" )
			)
			( pin "@baseboard_fab2_lib.baseboard_fab2(sch_1):page173_i209:a"
				( attribute "PN" "1"
					( Origin gPackager )
				)
				( objectStatus "C2L5.1" )
			)
			( pin "@baseboard_fab2_lib.baseboard_fab2(sch_1):page173_i209:b"
				( attribute "PN" "2"
					( Origin gPackager )
				)
				( objectStatus "C2L5.2" )
			)
			( pin "@baseboard_fab2_lib.baseboard_fab2(sch_1):page173_i220:a"
				( attribute "PN" "1"
					( Origin gPackager )
				)
				( objectStatus "C2L40.1" )
			)
			( pin "@baseboard_fab2_lib.baseboard_fab2(sch_1):page173_i220:b"
				( attribute "PN" "2"
					( Origin gPackager )
				)
				( objectStatus "C2L40.2" )
			)
			( pin "@baseboard_fab2_lib.baseboard_fab2(sch_1):page173_i221:a"
				( attribute "PN" "1"
					( Origin gPackager )
				)
				( objectStatus "C2L39.1" )
			)
			( pin "@baseboard_fab2_lib.baseboard_fab2(sch_1):page173_i221:b"
				( attribute "PN" "2"
					( Origin gPackager )
				)
				( objectStatus "C2L39.2" )
			)
			( pin "@baseboard_fab2_lib.baseboard_fab2(sch_1):page173_i222:a"
				( attribute "PN" "1"
					( Origin gPackager )
				)
				( objectStatus "C2L43.1" )
			)
			( pin "@baseboard_fab2_lib.baseboard_fab2(sch_1):page173_i222:b"
				( attribute "PN" "2"
					( Origin gPackager )
				)
				( objectStatus "C2L43.2" )
			)
			( pin "@baseboard_fab2_lib.baseboard_fab2(sch_1):page173_i228:a"
				( attribute "PN" "1"
					( Origin gPackager )
				)
				( objectStatus "C2L44.1" )
			)
			( pin "@baseboard_fab2_lib.baseboard_fab2(sch_1):page173_i228:b"
				( attribute "PN" "2"
					( Origin gPackager )
				)
				( objectStatus "C2L44.2" )
			)
			( pin "@baseboard_fab2_lib.baseboard_fab2(sch_1):page173_i233:a"
				( attribute "PN" "1"
					( Origin gPackager )
				)
				( objectStatus "C2L42.1" )
			)
			( pin "@baseboard_fab2_lib.baseboard_fab2(sch_1):page173_i233:b"
				( attribute "PN" "2"
					( Origin gPackager )
				)
				( objectStatus "C2L42.2" )
			)
			( pin "@baseboard_fab2_lib.baseboard_fab2(sch_1):page173_i234:a"
				( attribute "PN" "1"
					( Origin gPackager )
				)
				( objectStatus "C2L22.1" )
			)
			( pin "@baseboard_fab2_lib.baseboard_fab2(sch_1):page173_i234:b"
				( attribute "PN" "2"
					( Origin gPackager )
				)
				( objectStatus "C2L22.2" )
			)
			( pin "@baseboard_fab2_lib.baseboard_fab2(sch_1):page173_i238:a"
				( attribute "PN" "1"
					( Origin gPackager )
				)
				( objectStatus "C2L37.1" )
			)
			( pin "@baseboard_fab2_lib.baseboard_fab2(sch_1):page173_i238:b"
				( attribute "PN" "2"
					( Origin gPackager )
				)
				( objectStatus "C2L37.2" )
			)
			( pin "@baseboard_fab2_lib.baseboard_fab2(sch_1):page173_i239:a"
				( attribute "PN" "1"
					( Origin gPackager )
				)
				( objectStatus "C2L47.1" )
			)
			( pin "@baseboard_fab2_lib.baseboard_fab2(sch_1):page173_i239:b"
				( attribute "PN" "2"
					( Origin gPackager )
				)
				( objectStatus "C2L47.2" )
			)
			( pin "@baseboard_fab2_lib.baseboard_fab2(sch_1):page173_i240:a"
				( attribute "PN" "1"
					( Origin gPackager )
				)
				( objectStatus "C2L27.1" )
			)
			( pin "@baseboard_fab2_lib.baseboard_fab2(sch_1):page173_i240:b"
				( attribute "PN" "2"
					( Origin gPackager )
				)
				( objectStatus "C2L27.2" )
			)
			( pin "@baseboard_fab2_lib.baseboard_fab2(sch_1):page173_i241:a"
				( attribute "PN" "1"
					( Origin gPackager )
				)
				( objectStatus "C2L23.1" )
			)
			( pin "@baseboard_fab2_lib.baseboard_fab2(sch_1):page173_i241:b"
				( attribute "PN" "2"
					( Origin gPackager )
				)
				( objectStatus "C2L23.2" )
			)
			( pin "@baseboard_fab2_lib.baseboard_fab2(sch_1):page173_i242:a"
				( attribute "PN" "1"
					( Origin gPackager )
				)
				( objectStatus "C2L41.1" )
			)
			( pin "@baseboard_fab2_lib.baseboard_fab2(sch_1):page173_i242:b"
				( attribute "PN" "2"
					( Origin gPackager )
				)
				( objectStatus "C2L41.2" )
			)
			( pin "@baseboard_fab2_lib.baseboard_fab2(sch_1):page173_i255:a"
				( attribute "PN" "1"
					( Origin gPackager )
				)
				( objectStatus "C2L26.1" )
			)
			( pin "@baseboard_fab2_lib.baseboard_fab2(sch_1):page173_i255:b"
				( attribute "PN" "2"
					( Origin gPackager )
				)
				( objectStatus "C2L26.2" )
			)
			( pin "@baseboard_fab2_lib.baseboard_fab2(sch_1):page173_i256:a"
				( attribute "PN" "1"
					( Origin gPackager )
				)
				( objectStatus "C2L38.1" )
			)
			( pin "@baseboard_fab2_lib.baseboard_fab2(sch_1):page173_i256:b"
				( attribute "PN" "2"
					( Origin gPackager )
				)
				( objectStatus "C2L38.2" )
			)
			( pin "@baseboard_fab2_lib.baseboard_fab2(sch_1):page173_i257:a"
				( attribute "PN" "1"
					( Origin gPackager )
				)
				( objectStatus "C2L48.1" )
			)
			( pin "@baseboard_fab2_lib.baseboard_fab2(sch_1):page173_i257:b"
				( attribute "PN" "2"
					( Origin gPackager )
				)
				( objectStatus "C2L48.2" )
			)
			( pin "@baseboard_fab2_lib.baseboard_fab2(sch_1):page173_i258:a"
				( attribute "PN" "1"
					( Origin gPackager )
				)
				( objectStatus "C2L24.1" )
			)
			( pin "@baseboard_fab2_lib.baseboard_fab2(sch_1):page173_i258:b"
				( attribute "PN" "2"
					( Origin gPackager )
				)
				( objectStatus "C2L24.2" )
			)
			( pin "@baseboard_fab2_lib.baseboard_fab2(sch_1):page173_i259:a"
				( attribute "PN" "1"
					( Origin gPackager )
				)
				( objectStatus "C2L21.1" )
			)
			( pin "@baseboard_fab2_lib.baseboard_fab2(sch_1):page173_i259:b"
				( attribute "PN" "2"
					( Origin gPackager )
				)
				( objectStatus "C2L21.2" )
			)
			( pin "@baseboard_fab2_lib.baseboard_fab2(sch_1):page173_i261:a"
				( attribute "PN" "1"
					( Origin gPackager )
				)
				( objectStatus "R2L23.1" )
			)
			( pin "@baseboard_fab2_lib.baseboard_fab2(sch_1):page173_i261:b"
				( attribute "PN" "2"
					( Origin gPackager )
				)
				( objectStatus "R2L23.2" )
			)
			( pin "@baseboard_fab2_lib.baseboard_fab2(sch_1):page173_i263:a"
				( attribute "PN" "1"
					( Origin gPackager )
				)
				( objectStatus "R2L21.1" )
			)
			( pin "@baseboard_fab2_lib.baseboard_fab2(sch_1):page173_i263:b"
				( attribute "PN" "2"
					( Origin gPackager )
				)
				( objectStatus "R2L21.2" )
			)
			( pin "@baseboard_fab2_lib.baseboard_fab2(sch_1):page173_i264:a"
				( attribute "PN" "1"
					( Origin gPackager )
				)
				( objectStatus "R2L22.1" )
			)
			( pin "@baseboard_fab2_lib.baseboard_fab2(sch_1):page173_i264:b"
				( attribute "PN" "2"
					( Origin gPackager )
				)
				( objectStatus "R2L22.2" )
			)
			( pin "@baseboard_fab2_lib.baseboard_fab2(sch_1):page173_i266:a"
				( attribute "PN" "1"
					( Origin gPackager )
				)
				( objectStatus "R2L18.1" )
			)
			( pin "@baseboard_fab2_lib.baseboard_fab2(sch_1):page173_i266:b"
				( attribute "PN" "2"
					( Origin gPackager )
				)
				( objectStatus "R2L18.2" )
			)
			( pin "@baseboard_fab2_lib.baseboard_fab2(sch_1):page164_i87:a"
				( attribute "PN" "1"
					( Origin gPackager )
				)
				( objectStatus "R6W41.1" )
			)
			( pin "@baseboard_fab2_lib.baseboard_fab2(sch_1):page164_i87:b"
				( attribute "PN" "2"
					( Origin gPackager )
				)
				( objectStatus "R6W41.2" )
			)
			( pin "@baseboard_fab2_lib.baseboard_fab2(sch_1):page149_i129:a"
				( attribute "PN" "1"
					( Origin gPackager )
				)
				( objectStatus "C25W29.1" )
			)
			( pin "@baseboard_fab2_lib.baseboard_fab2(sch_1):page149_i129:b"
				( attribute "PN" "2"
					( Origin gPackager )
				)
				( objectStatus "C25W29.2" )
			)
			( pin "@baseboard_fab2_lib.baseboard_fab2(sch_1):page164_i78:a"
				( attribute "PN" "1"
					( Origin gPackager )
				)
				( objectStatus "R6W44.1" )
			)
			( pin "@baseboard_fab2_lib.baseboard_fab2(sch_1):page164_i78:b"
				( attribute "PN" "2"
					( Origin gPackager )
				)
				( objectStatus "R6W44.2" )
			)
			( pin "@baseboard_fab2_lib.baseboard_fab2(sch_1):page164_i76:a"
				( attribute "PN" "1"
					( Origin gPackager )
				)
				( objectStatus "R6W47.1" )
			)
			( pin "@baseboard_fab2_lib.baseboard_fab2(sch_1):page164_i76:b"
				( attribute "PN" "2"
					( Origin gPackager )
				)
				( objectStatus "R6W47.2" )
			)
			( pin "@baseboard_fab2_lib.baseboard_fab2(sch_1):page164_i66:a"
				( attribute "PN" "1"
					( Origin gPackager )
				)
				( objectStatus "C6W14.1" )
			)
			( pin "@baseboard_fab2_lib.baseboard_fab2(sch_1):page164_i66:b"
				( attribute "PN" "2"
					( Origin gPackager )
				)
				( objectStatus "C6W14.2" )
			)
			( pin "@baseboard_fab2_lib.baseboard_fab2(sch_1):page175_i4:a"
				( attribute "PN" "1"
					( Origin gPackager )
				)
				( objectStatus "R1L31.1" )
			)
			( pin "@baseboard_fab2_lib.baseboard_fab2(sch_1):page175_i4:b"
				( attribute "PN" "2"
					( Origin gPackager )
				)
				( objectStatus "R1L31.2" )
			)
			( pin "@baseboard_fab2_lib.baseboard_fab2(sch_1):page175_i5:a"
				( attribute "PN" "1"
					( Origin gPackager )
				)
				( objectStatus "R1L27.1" )
			)
			( pin "@baseboard_fab2_lib.baseboard_fab2(sch_1):page175_i5:b"
				( attribute "PN" "2"
					( Origin gPackager )
				)
				( objectStatus "R1L27.2" )
			)
			( pin "@baseboard_fab2_lib.baseboard_fab2(sch_1):page175_i11:a"
				( attribute "PN" "1"
					( Origin gPackager )
				)
				( objectStatus "C1L18.1" )
			)
			( pin "@baseboard_fab2_lib.baseboard_fab2(sch_1):page175_i11:b"
				( attribute "PN" "2"
					( Origin gPackager )
				)
				( objectStatus "C1L18.2" )
			)
			( pin "@baseboard_fab2_lib.baseboard_fab2(sch_1):page175_i13:a"
				( attribute "PN" "1"
					( Origin gPackager )
				)
				( objectStatus "R1L26.1" )
			)
			( pin "@baseboard_fab2_lib.baseboard_fab2(sch_1):page175_i13:b"
				( attribute "PN" "2"
					( Origin gPackager )
				)
				( objectStatus "R1L26.2" )
			)
			( pin "@baseboard_fab2_lib.baseboard_fab2(sch_1):page175_i19:a"
				( attribute "PN" "1"
					( Origin gPackager )
				)
				( objectStatus "C1L10.1" )
			)
			( pin "@baseboard_fab2_lib.baseboard_fab2(sch_1):page175_i19:b"
				( attribute "PN" "2"
					( Origin gPackager )
				)
				( objectStatus "C1L10.2" )
			)
			( pin "@baseboard_fab2_lib.baseboard_fab2(sch_1):page175_i22:a"
				( attribute "PN" "1"
					( Origin gPackager )
				)
				( objectStatus "R1L22.1" )
			)
			( pin "@baseboard_fab2_lib.baseboard_fab2(sch_1):page175_i22:b"
				( attribute "PN" "2"
					( Origin gPackager )
				)
				( objectStatus "R1L22.2" )
			)
			( pin "@baseboard_fab2_lib.baseboard_fab2(sch_1):page111_i97:a"
				( attribute "PN" "1"
					( Origin gPackager )
				)
				( objectStatus "R1L28.1" )
			)
			( pin "@baseboard_fab2_lib.baseboard_fab2(sch_1):page111_i97:b"
				( attribute "PN" "2"
					( Origin gPackager )
				)
				( objectStatus "R1L28.2" )
			)
			( pin "@baseboard_fab2_lib.baseboard_fab2(sch_1):page175_i37:a"
				( attribute "PN" "1"
					( Origin gPackager )
				)
				( objectStatus "C1L17.1" )
			)
			( pin "@baseboard_fab2_lib.baseboard_fab2(sch_1):page175_i37:b"
				( attribute "PN" "2"
					( Origin gPackager )
				)
				( objectStatus "C1L17.2" )
			)
			( pin "@baseboard_fab2_lib.baseboard_fab2(sch_1):page175_i38:a"
				( attribute "PN" "1"
					( Origin gPackager )
				)
				( objectStatus "C1L9.1" )
			)
			( pin "@baseboard_fab2_lib.baseboard_fab2(sch_1):page175_i38:b"
				( attribute "PN" "2"
					( Origin gPackager )
				)
				( objectStatus "C1L9.2" )
			)
			( pin "@baseboard_fab2_lib.baseboard_fab2(sch_1):page175_i40:a"
				( attribute "PN" "1"
					( Origin gPackager )
				)
				( objectStatus "C9A3.1" )
			)
			( pin "@baseboard_fab2_lib.baseboard_fab2(sch_1):page175_i40:b"
				( attribute "PN" "2"
					( Origin gPackager )
				)
				( objectStatus "C9A3.2" )
			)
			( pin "@baseboard_fab2_lib.baseboard_fab2(sch_1):page175_i45:a"
				( attribute "PN" "1"
					( Origin gPackager )
				)
				( objectStatus "R1L33.1" )
			)
			( pin "@baseboard_fab2_lib.baseboard_fab2(sch_1):page175_i45:b"
				( attribute "PN" "2"
					( Origin gPackager )
				)
				( objectStatus "R1L33.2" )
			)
			( pin "@baseboard_fab2_lib.baseboard_fab2(sch_1):page175_i49:drn"
				( attribute "PN" "3"
					( Origin gPackager )
				)
				( objectStatus "Q9A3.3" )
			)
			( pin "@baseboard_fab2_lib.baseboard_fab2(sch_1):page175_i49:gate"
				( attribute "PN" "1"
					( Origin gPackager )
				)
				( objectStatus "Q9A3.1" )
			)
			( pin "@baseboard_fab2_lib.baseboard_fab2(sch_1):page175_i49:src"
				( attribute "PN" "2"
					( Origin gPackager )
				)
				( objectStatus "Q9A3.2" )
			)
			( pin "@baseboard_fab2_lib.baseboard_fab2(sch_1):page175_i50:a"
				( attribute "PN" "2"
					( Origin gPackager )
				)
				( objectStatus "DS9A1.2" )
			)
			( pin "@baseboard_fab2_lib.baseboard_fab2(sch_1):page175_i50:c"
				( attribute "PN" "1"
					( Origin gPackager )
				)
				( objectStatus "DS9A1.1" )
			)
			( pin "@baseboard_fab2_lib.baseboard_fab2(sch_1):page175_i57:a"
				( attribute "PN" "1"
					( Origin gPackager )
				)
				( objectStatus "U1L2.1" )
			)
			( pin "@baseboard_fab2_lib.baseboard_fab2(sch_1):page175_i57:b"
				( attribute "PN" "2"
					( Origin gPackager )
				)
				( objectStatus "U1L2.2" )
			)
			( pin "@baseboard_fab2_lib.baseboard_fab2(sch_1):page175_i57:y"
				( attribute "PN" "4"
					( Origin gPackager )
				)
				( objectStatus "U1L2.4" )
			)
			( pin "@baseboard_fab2_lib.baseboard_fab2(sch_1):page175_i58:a"
				( attribute "PN" "1"
					( Origin gPackager )
				)
				( objectStatus "R1L8.1" )
			)
			( pin "@baseboard_fab2_lib.baseboard_fab2(sch_1):page175_i58:b"
				( attribute "PN" "2"
					( Origin gPackager )
				)
				( objectStatus "R1L8.2" )
			)
			( pin "@baseboard_fab2_lib.baseboard_fab2(sch_1):page175_i63:a"
				( attribute "PN" "1"
					( Origin gPackager )
				)
				( objectStatus "R1L12.1" )
			)
			( pin "@baseboard_fab2_lib.baseboard_fab2(sch_1):page175_i63:b"
				( attribute "PN" "2"
					( Origin gPackager )
				)
				( objectStatus "R1L12.2" )
			)
			( pin "@baseboard_fab2_lib.baseboard_fab2(sch_1):page175_i64:a"
				( attribute "PN" "1"
					( Origin gPackager )
				)
				( objectStatus "C1L4.1" )
			)
			( pin "@baseboard_fab2_lib.baseboard_fab2(sch_1):page175_i64:b"
				( attribute "PN" "2"
					( Origin gPackager )
				)
				( objectStatus "C1L4.2" )
			)
			( pin "@baseboard_fab2_lib.baseboard_fab2(sch_1):page175_i67:a"
				( attribute "PN" "2"
					( Origin gPackager )
				)
				( objectStatus "DS9A3.2" )
			)
			( pin "@baseboard_fab2_lib.baseboard_fab2(sch_1):page175_i67:c"
				( attribute "PN" "1"
					( Origin gPackager )
				)
				( objectStatus "DS9A3.1" )
			)
			( pin "@baseboard_fab2_lib.baseboard_fab2(sch_1):page175_i78:pin1"
				( attribute "PN" "1"
					( Origin gPackager )
				)
				( objectStatus "S9A1.1" )
			)
			( pin "@baseboard_fab2_lib.baseboard_fab2(sch_1):page175_i78:pin2"
				( attribute "PN" "2"
					( Origin gPackager )
				)
				( objectStatus "S9A1.2" )
			)
			( pin "@baseboard_fab2_lib.baseboard_fab2(sch_1):page175_i78:pin3"
				( attribute "PN" "3"
					( Origin gPackager )
				)
				( objectStatus "S9A1.3" )
			)
			( pin "@baseboard_fab2_lib.baseboard_fab2(sch_1):page175_i78:pin4"
				( attribute "PN" "4"
					( Origin gPackager )
				)
				( objectStatus "S9A1.4" )
			)
			( pin "@baseboard_fab2_lib.baseboard_fab2(sch_1):page153_i185:clk"
				( attribute "PN" "16"
					( Origin gPackager )
				)
				( objectStatus "U3T1.16" )
			)
			( pin "@baseboard_fab2_lib.baseboard_fab2(sch_1):page153_i185:\cs#\"
				( attribute "PN" "7"
					( Origin gPackager )
				)
				( objectStatus "U3T1.7" )
			)
			( pin "@baseboard_fab2_lib.baseboard_fab2(sch_1):page153_i185:\di/io0\"
				( attribute "PN" "15"
					( Origin gPackager )
				)
				( objectStatus "U3T1.15" )
			)
			( pin "@baseboard_fab2_lib.baseboard_fab2(sch_1):page153_i185:\do/io1\"
				( attribute "PN" "8"
					( Origin gPackager )
				)
				( objectStatus "U3T1.8" )
			)
			( pin "@baseboard_fab2_lib.baseboard_fab2(sch_1):page153_i185:gnd"
				( attribute "PN" "10"
					( Origin gPackager )
				)
				( objectStatus "U3T1.10" )
			)
			( pin "@baseboard_fab2_lib.baseboard_fab2(sch_1):page153_i185:\hold#/io3\"
				( attribute "PN" "1"
					( Origin gPackager )
				)
				( objectStatus "U3T1.1" )
			)
			( pin "@baseboard_fab2_lib.baseboard_fab2(sch_1):page153_i185:\nc#4\"
				( attribute "PN" "4"
					( Origin gPackager )
				)
				( objectStatus "U3T1.4" )
			)
			( pin "@baseboard_fab2_lib.baseboard_fab2(sch_1):page153_i185:\nc#5\"
				( attribute "PN" "5"
					( Origin gPackager )
				)
				( objectStatus "U3T1.5" )
			)
			( pin "@baseboard_fab2_lib.baseboard_fab2(sch_1):page153_i185:\nc#6\"
				( attribute "PN" "6"
					( Origin gPackager )
				)
				( objectStatus "U3T1.6" )
			)
			( pin "@baseboard_fab2_lib.baseboard_fab2(sch_1):page153_i185:\nc#11\"
				( attribute "PN" "11"
					( Origin gPackager )
				)
				( objectStatus "U3T1.11" )
			)
			( pin "@baseboard_fab2_lib.baseboard_fab2(sch_1):page153_i185:\nc#12\"
				( attribute "PN" "12"
					( Origin gPackager )
				)
				( objectStatus "U3T1.12" )
			)
			( pin "@baseboard_fab2_lib.baseboard_fab2(sch_1):page153_i185:\nc#13\"
				( attribute "PN" "13"
					( Origin gPackager )
				)
				( objectStatus "U3T1.13" )
			)
			( pin "@baseboard_fab2_lib.baseboard_fab2(sch_1):page153_i185:\nc#14\"
				( attribute "PN" "14"
					( Origin gPackager )
				)
				( objectStatus "U3T1.14" )
			)
			( pin "@baseboard_fab2_lib.baseboard_fab2(sch_1):page153_i185:\reset#\"
				( attribute "PN" "3"
					( Origin gPackager )
				)
				( objectStatus "U3T1.3" )
			)
			( pin "@baseboard_fab2_lib.baseboard_fab2(sch_1):page153_i185:vcc"
				( attribute "PN" "2"
					( Origin gPackager )
				)
				( objectStatus "U3T1.2" )
			)
			( pin "@baseboard_fab2_lib.baseboard_fab2(sch_1):page153_i185:\wp#/io2\"
				( attribute "PN" "9"
					( Origin gPackager )
				)
				( objectStatus "U3T1.9" )
			)
			( pin "@baseboard_fab2_lib.baseboard_fab2(sch_1):page176_i16:a"
				( attribute "PN" "1"
					( Origin gPackager )
				)
				( objectStatus "R1M5.1" )
			)
			( pin "@baseboard_fab2_lib.baseboard_fab2(sch_1):page176_i16:b"
				( attribute "PN" "2"
					( Origin gPackager )
				)
				( objectStatus "R1M5.2" )
			)
			( pin "@baseboard_fab2_lib.baseboard_fab2(sch_1):page176_i31:a"
				( attribute "PN" "1"
					( Origin gPackager )
				)
				( objectStatus "R1M6.1" )
			)
			( pin "@baseboard_fab2_lib.baseboard_fab2(sch_1):page176_i31:b"
				( attribute "PN" "2"
					( Origin gPackager )
				)
				( objectStatus "R1M6.2" )
			)
			( pin "@baseboard_fab2_lib.baseboard_fab2(sch_1):page176_i69:dn"
				( attribute "PN" "2"
					( Origin gPackager )
				)
				( objectStatus "J9B1.2" )
			)
			( pin "@baseboard_fab2_lib.baseboard_fab2(sch_1):page176_i69:dp"
				( attribute "PN" "3"
					( Origin gPackager )
				)
				( objectStatus "J9B1.3" )
			)
			( pin "@baseboard_fab2_lib.baseboard_fab2(sch_1):page176_i69:gnd"
				( attribute "PN" "4"
					( Origin gPackager )
				)
				( objectStatus "J9B1.4" )
			)
			( pin "@baseboard_fab2_lib.baseboard_fab2(sch_1):page176_i69:gnd_drain"
				( attribute "PN" "7"
					( Origin gPackager )
				)
				( objectStatus "J9B1.7" )
			)
			( pin "@baseboard_fab2_lib.baseboard_fab2(sch_1):page176_i69:mh1"
				( attribute "PN" "MH1"
					( Origin gPackager )
				)
				( objectStatus "J9B1.MH1" )
			)
			( pin "@baseboard_fab2_lib.baseboard_fab2(sch_1):page176_i69:mh2"
				( attribute "PN" "MH2"
					( Origin gPackager )
				)
				( objectStatus "J9B1.MH2" )
			)
			( pin "@baseboard_fab2_lib.baseboard_fab2(sch_1):page176_i69:mh3"
				( attribute "PN" "MH3"
					( Origin gPackager )
				)
				( objectStatus "J9B1.MH3" )
			)
			( pin "@baseboard_fab2_lib.baseboard_fab2(sch_1):page176_i69:mh4"
				( attribute "PN" "MH4"
					( Origin gPackager )
				)
				( objectStatus "J9B1.MH4" )
			)
			( pin "@baseboard_fab2_lib.baseboard_fab2(sch_1):page176_i69:stda_ssrxn"
				( attribute "PN" "5"
					( Origin gPackager )
				)
				( objectStatus "J9B1.5" )
			)
			( pin "@baseboard_fab2_lib.baseboard_fab2(sch_1):page176_i69:stda_ssrxp"
				( attribute "PN" "6"
					( Origin gPackager )
				)
				( objectStatus "J9B1.6" )
			)
			( pin "@baseboard_fab2_lib.baseboard_fab2(sch_1):page176_i69:stda_sstxn"
				( attribute "PN" "8"
					( Origin gPackager )
				)
				( objectStatus "J9B1.8" )
			)
			( pin "@baseboard_fab2_lib.baseboard_fab2(sch_1):page176_i69:stda_sstxp"
				( attribute "PN" "9"
					( Origin gPackager )
				)
				( objectStatus "J9B1.9" )
			)
			( pin "@baseboard_fab2_lib.baseboard_fab2(sch_1):page176_i69:vbus"
				( attribute "PN" "1"
					( Origin gPackager )
				)
				( objectStatus "J9B1.1" )
			)
			( pin "@baseboard_fab2_lib.baseboard_fab2(sch_1):page176_i98:ac0"
				( attribute "PN" "1"
					( Origin gPackager )
				)
				( objectStatus "CR1M2.1" )
			)
			( pin "@baseboard_fab2_lib.baseboard_fab2(sch_1):page176_i98:ac1"
				( attribute "PN" "2"
					( Origin gPackager )
				)
				( objectStatus "CR1M2.2" )
			)
			( pin "@baseboard_fab2_lib.baseboard_fab2(sch_1):page176_i98:ac2"
				( attribute "PN" "4"
					( Origin gPackager )
				)
				( objectStatus "CR1M2.4" )
			)
			( pin "@baseboard_fab2_lib.baseboard_fab2(sch_1):page176_i98:ac3"
				( attribute "PN" "5"
					( Origin gPackager )
				)
				( objectStatus "CR1M2.5" )
			)
			( pin "@baseboard_fab2_lib.baseboard_fab2(sch_1):page176_i98:gnd(0)"
				( attribute "PN" "3"
					( Origin gPackager )
				)
				( objectStatus "CR1M2.3" )
			)
			( pin "@baseboard_fab2_lib.baseboard_fab2(sch_1):page176_i98:out0"
				( attribute "PN" "9"
					( Origin gPackager )
				)
				( objectStatus "CR1M2.9" )
			)
			( pin "@baseboard_fab2_lib.baseboard_fab2(sch_1):page176_i98:out1"
				( attribute "PN" "8"
					( Origin gPackager )
				)
				( objectStatus "CR1M2.8" )
			)
			( pin "@baseboard_fab2_lib.baseboard_fab2(sch_1):page176_i98:out2"
				( attribute "PN" "7"
					( Origin gPackager )
				)
				( objectStatus "CR1M2.7" )
			)
			( pin "@baseboard_fab2_lib.baseboard_fab2(sch_1):page176_i98:out3"
				( attribute "PN" "6"
					( Origin gPackager )
				)
				( objectStatus "CR1M2.6" )
			)
			( pin "@baseboard_fab2_lib.baseboard_fab2(sch_1):page176_i100:en_n"
				( attribute "PN" "4"
					( Origin gPackager )
				)
				( objectStatus "U1M3.4" )
			)
			( pin "@baseboard_fab2_lib.baseboard_fab2(sch_1):page176_i100:gnd"
				( attribute "PN" "2"
					( Origin gPackager )
				)
				( objectStatus "U1M3.2" )
			)
			( pin "@baseboard_fab2_lib.baseboard_fab2(sch_1):page176_i100:\in\"
				( attribute "PN" "5"
					( Origin gPackager )
				)
				( objectStatus "U1M3.5" )
			)
			( pin "@baseboard_fab2_lib.baseboard_fab2(sch_1):page176_i100:oc_n"
				( attribute "PN" "3"
					( Origin gPackager )
				)
				( objectStatus "U1M3.3" )
			)
			( pin "@baseboard_fab2_lib.baseboard_fab2(sch_1):page176_i100:\out\"
				( attribute "PN" "1"
					( Origin gPackager )
				)
				( objectStatus "U1M3.1" )
			)
			( pin "@baseboard_fab2_lib.baseboard_fab2(sch_1):page176_i105:a"
				( attribute "PN" "1"
					( Origin gPackager )
				)
				( objectStatus "R1M24.1" )
			)
			( pin "@baseboard_fab2_lib.baseboard_fab2(sch_1):page176_i105:b"
				( attribute "PN" "2"
					( Origin gPackager )
				)
				( objectStatus "R1M24.2" )
			)
			( pin "@baseboard_fab2_lib.baseboard_fab2(sch_1):page176_i108:a"
				( attribute "PN" "1"
					( Origin gPackager )
				)
				( objectStatus "C1M38.1" )
			)
			( pin "@baseboard_fab2_lib.baseboard_fab2(sch_1):page176_i108:b"
				( attribute "PN" "2"
					( Origin gPackager )
				)
				( objectStatus "C1M38.2" )
			)
			( pin "@baseboard_fab2_lib.baseboard_fab2(sch_1):page176_i111:a"
				( attribute "PN" "1"
					( Origin gPackager )
				)
				( objectStatus "R1M25.1" )
			)
			( pin "@baseboard_fab2_lib.baseboard_fab2(sch_1):page176_i111:b"
				( attribute "PN" "2"
					( Origin gPackager )
				)
				( objectStatus "R1M25.2" )
			)
			( pin "@baseboard_fab2_lib.baseboard_fab2(sch_1):page176_i113:a"
				( attribute "PN" "1"
					( Origin gPackager )
				)
				( objectStatus "C9B8.1" )
			)
			( pin "@baseboard_fab2_lib.baseboard_fab2(sch_1):page176_i113:b"
				( attribute "PN" "2"
					( Origin gPackager )
				)
				( objectStatus "C9B8.2" )
			)
			( pin "@baseboard_fab2_lib.baseboard_fab2(sch_1):page177_i3:a"
				( attribute "PN" "1"
					( Origin gPackager )
				)
				( objectStatus "R1M13.1" )
			)
			( pin "@baseboard_fab2_lib.baseboard_fab2(sch_1):page177_i3:b"
				( attribute "PN" "2"
					( Origin gPackager )
				)
				( objectStatus "R1M13.2" )
			)
			( pin "@baseboard_fab2_lib.baseboard_fab2(sch_1):page177_i6:a"
				( attribute "PN" "1"
					( Origin gPackager )
				)
				( objectStatus "R1M10.1" )
			)
			( pin "@baseboard_fab2_lib.baseboard_fab2(sch_1):page177_i6:b"
				( attribute "PN" "2"
					( Origin gPackager )
				)
				( objectStatus "R1M10.2" )
			)
			( pin "@baseboard_fab2_lib.baseboard_fab2(sch_1):page177_i8:a"
				( attribute "PN" "1"
					( Origin gPackager )
				)
				( objectStatus "R1M12.1" )
			)
			( pin "@baseboard_fab2_lib.baseboard_fab2(sch_1):page177_i8:b"
				( attribute "PN" "2"
					( Origin gPackager )
				)
				( objectStatus "R1M12.2" )
			)
			( pin "@baseboard_fab2_lib.baseboard_fab2(sch_1):page177_i9:a"
				( attribute "PN" "1"
					( Origin gPackager )
				)
				( objectStatus "R1M11.1" )
			)
			( pin "@baseboard_fab2_lib.baseboard_fab2(sch_1):page177_i9:b"
				( attribute "PN" "2"
					( Origin gPackager )
				)
				( objectStatus "R1M11.2" )
			)
			( pin "@baseboard_fab2_lib.baseboard_fab2(sch_1):page177_i20:a"
				( attribute "PN" "1"
					( Origin gPackager )
				)
				( objectStatus "C1M3.1" )
			)
			( pin "@baseboard_fab2_lib.baseboard_fab2(sch_1):page177_i20:b"
				( attribute "PN" "2"
					( Origin gPackager )
				)
				( objectStatus "C1M3.2" )
			)
			( pin "@baseboard_fab2_lib.baseboard_fab2(sch_1):page177_i31:a"
				( attribute "PN" "1"
					( Origin gPackager )
				)
				( objectStatus "DS9A6.1" )
			)
			( pin "@baseboard_fab2_lib.baseboard_fab2(sch_1):page177_i31:c"
				( attribute "PN" "2"
					( Origin gPackager )
				)
				( objectStatus "DS9A6.2" )
			)
			( pin "@baseboard_fab2_lib.baseboard_fab2(sch_1):page177_i33:a"
				( attribute "PN" "1"
					( Origin gPackager )
				)
				( objectStatus "R1L37.1" )
			)
			( pin "@baseboard_fab2_lib.baseboard_fab2(sch_1):page177_i33:b"
				( attribute "PN" "2"
					( Origin gPackager )
				)
				( objectStatus "R1L37.2" )
			)
			( pin "@baseboard_fab2_lib.baseboard_fab2(sch_1):page177_i42:a"
				( attribute "PN" "2"
					( Origin gPackager )
				)
				( objectStatus "DS9A2.2" )
			)
			( pin "@baseboard_fab2_lib.baseboard_fab2(sch_1):page177_i42:c"
				( attribute "PN" "1"
					( Origin gPackager )
				)
				( objectStatus "DS9A2.1" )
			)
			( pin "@baseboard_fab2_lib.baseboard_fab2(sch_1):page177_i43:a"
				( attribute "PN" "1"
					( Origin gPackager )
				)
				( objectStatus "R1L21.1" )
			)
			( pin "@baseboard_fab2_lib.baseboard_fab2(sch_1):page177_i43:b"
				( attribute "PN" "2"
					( Origin gPackager )
				)
				( objectStatus "R1L21.2" )
			)
			( pin "@baseboard_fab2_lib.baseboard_fab2(sch_1):page177_i70:a(0)"
				( attribute "PN" "1"
					( Origin gPackager )
				)
				( objectStatus "U1M1.1" )
			)
			( pin "@baseboard_fab2_lib.baseboard_fab2(sch_1):page177_i70:b(0)"
				( attribute "PN" "2"
					( Origin gPackager )
				)
				( objectStatus "U1M1.2" )
			)
			( pin "@baseboard_fab2_lib.baseboard_fab2(sch_1):page177_i70:y(0)"
				( attribute "PN" "4"
					( Origin gPackager )
				)
				( objectStatus "U1M1.4" )
			)
			( pin "@baseboard_fab2_lib.baseboard_fab2(sch_1):page177_i71:a"
				( attribute "PN" "1"
					( Origin gPackager )
				)
				( objectStatus "DS9F1.1" )
			)
			( pin "@baseboard_fab2_lib.baseboard_fab2(sch_1):page177_i71:c"
				( attribute "PN" "2"
					( Origin gPackager )
				)
				( objectStatus "DS9F1.2" )
			)
			( pin "@baseboard_fab2_lib.baseboard_fab2(sch_1):page177_i72:a"
				( attribute "PN" "1"
					( Origin gPackager )
				)
				( objectStatus "R9F28.1" )
			)
			( pin "@baseboard_fab2_lib.baseboard_fab2(sch_1):page177_i72:b"
				( attribute "PN" "2"
					( Origin gPackager )
				)
				( objectStatus "R9F28.2" )
			)
			( pin "@baseboard_fab2_lib.baseboard_fab2(sch_1):page177_i76:a"
				( attribute "PN" "1"
					( Origin gPackager )
				)
				( objectStatus "R9F30.1" )
			)
			( pin "@baseboard_fab2_lib.baseboard_fab2(sch_1):page177_i76:b"
				( attribute "PN" "2"
					( Origin gPackager )
				)
				( objectStatus "R9F30.2" )
			)
			( pin "@baseboard_fab2_lib.baseboard_fab2(sch_1):page177_i79:drain(0)"
				( attribute "PN" "3"
					( Origin gPackager )
				)
				( objectStatus "Q9F1.3" )
			)
			( pin "@baseboard_fab2_lib.baseboard_fab2(sch_1):page177_i79:gate(0)"
				( attribute "PN" "5"
					( Origin gPackager )
				)
				( objectStatus "Q9F1.5" )
			)
			( pin "@baseboard_fab2_lib.baseboard_fab2(sch_1):page177_i79:source(0)"
				( attribute "PN" "4"
					( Origin gPackager )
				)
				( objectStatus "Q9F1.4" )
			)
			( pin "@baseboard_fab2_lib.baseboard_fab2(sch_1):page177_i80:drain(0)"
				( attribute "PN" "6"
					( Origin gPackager )
				)
				( objectStatus "Q9F1.6" )
			)
			( pin "@baseboard_fab2_lib.baseboard_fab2(sch_1):page177_i80:gate(0)"
				( attribute "PN" "2"
					( Origin gPackager )
				)
				( objectStatus "Q9F1.2" )
			)
			( pin "@baseboard_fab2_lib.baseboard_fab2(sch_1):page177_i80:source(0)"
				( attribute "PN" "1"
					( Origin gPackager )
				)
				( objectStatus "Q9F1.1" )
			)
			( pin "@baseboard_fab2_lib.baseboard_fab2(sch_1):page177_i82:a"
				( attribute "PN" "1"
					( Origin gPackager )
				)
				( objectStatus "R9F52.1" )
			)
			( pin "@baseboard_fab2_lib.baseboard_fab2(sch_1):page177_i82:b"
				( attribute "PN" "2"
					( Origin gPackager )
				)
				( objectStatus "R9F52.2" )
			)
			( pin "@baseboard_fab2_lib.baseboard_fab2(sch_1):page178_i1:a"
				( attribute "PN" "1"
					( Origin gPackager )
				)
				( objectStatus "R8D20.1" )
			)
			( pin "@baseboard_fab2_lib.baseboard_fab2(sch_1):page178_i1:b"
				( attribute "PN" "2"
					( Origin gPackager )
				)
				( objectStatus "R8D20.2" )
			)
			( pin "@baseboard_fab2_lib.baseboard_fab2(sch_1):page178_i2:a"
				( attribute "PN" "1"
					( Origin gPackager )
				)
				( objectStatus "R2L12.1" )
			)
			( pin "@baseboard_fab2_lib.baseboard_fab2(sch_1):page178_i2:b"
				( attribute "PN" "2"
					( Origin gPackager )
				)
				( objectStatus "R2L12.2" )
			)
			( pin "@baseboard_fab2_lib.baseboard_fab2(sch_1):page178_i8:a"
				( attribute "PN" "1"
					( Origin gPackager )
				)
				( objectStatus "R8D19.1" )
			)
			( pin "@baseboard_fab2_lib.baseboard_fab2(sch_1):page178_i8:b"
				( attribute "PN" "2"
					( Origin gPackager )
				)
				( objectStatus "R8D19.2" )
			)
			( pin "@baseboard_fab2_lib.baseboard_fab2(sch_1):page178_i11:a"
				( attribute "PN" "1"
					( Origin gPackager )
				)
				( objectStatus "R2N31.1" )
			)
			( pin "@baseboard_fab2_lib.baseboard_fab2(sch_1):page178_i11:b"
				( attribute "PN" "2"
					( Origin gPackager )
				)
				( objectStatus "R2N31.2" )
			)
			( pin "@baseboard_fab2_lib.baseboard_fab2(sch_1):page178_i12:a"
				( attribute "PN" "1"
					( Origin gPackager )
				)
				( objectStatus "R2L15.1" )
			)
			( pin "@baseboard_fab2_lib.baseboard_fab2(sch_1):page178_i12:b"
				( attribute "PN" "2"
					( Origin gPackager )
				)
				( objectStatus "R2L15.2" )
			)
			( pin "@baseboard_fab2_lib.baseboard_fab2(sch_1):page178_i13:a"
				( attribute "PN" "1"
					( Origin gPackager )
				)
				( objectStatus "R2L11.1" )
			)
			( pin "@baseboard_fab2_lib.baseboard_fab2(sch_1):page178_i13:b"
				( attribute "PN" "2"
					( Origin gPackager )
				)
				( objectStatus "R2L11.2" )
			)
			( pin "@baseboard_fab2_lib.baseboard_fab2(sch_1):page178_i17:a"
				( attribute "PN" "1"
					( Origin gPackager )
				)
				( objectStatus "R2L6.1" )
			)
			( pin "@baseboard_fab2_lib.baseboard_fab2(sch_1):page178_i17:b"
				( attribute "PN" "2"
					( Origin gPackager )
				)
				( objectStatus "R2L6.2" )
			)
			( pin "@baseboard_fab2_lib.baseboard_fab2(sch_1):page178_i18:a"
				( attribute "PN" "1"
					( Origin gPackager )
				)
				( objectStatus "R2L4.1" )
			)
			( pin "@baseboard_fab2_lib.baseboard_fab2(sch_1):page178_i18:b"
				( attribute "PN" "2"
					( Origin gPackager )
				)
				( objectStatus "R2L4.2" )
			)
			( pin "@baseboard_fab2_lib.baseboard_fab2(sch_1):page178_i20:a"
				( attribute "PN" "1"
					( Origin gPackager )
				)
				( objectStatus "R2L5.1" )
			)
			( pin "@baseboard_fab2_lib.baseboard_fab2(sch_1):page178_i20:b"
				( attribute "PN" "2"
					( Origin gPackager )
				)
				( objectStatus "R2L5.2" )
			)
			( pin "@baseboard_fab2_lib.baseboard_fab2(sch_1):page178_i21:a"
				( attribute "PN" "1"
					( Origin gPackager )
				)
				( objectStatus "R8B29.1" )
			)
			( pin "@baseboard_fab2_lib.baseboard_fab2(sch_1):page178_i21:b"
				( attribute "PN" "2"
					( Origin gPackager )
				)
				( objectStatus "R8B29.2" )
			)
			( pin "@baseboard_fab2_lib.baseboard_fab2(sch_1):page178_i22:a"
				( attribute "PN" "1"
					( Origin gPackager )
				)
				( objectStatus "R2N19.1" )
			)
			( pin "@baseboard_fab2_lib.baseboard_fab2(sch_1):page178_i22:b"
				( attribute "PN" "2"
					( Origin gPackager )
				)
				( objectStatus "R2N19.2" )
			)
			( pin "@baseboard_fab2_lib.baseboard_fab2(sch_1):page178_i23:a"
				( attribute "PN" "1"
					( Origin gPackager )
				)
				( objectStatus "R2N22.1" )
			)
			( pin "@baseboard_fab2_lib.baseboard_fab2(sch_1):page178_i23:b"
				( attribute "PN" "2"
					( Origin gPackager )
				)
				( objectStatus "R2N22.2" )
			)
			( pin "@baseboard_fab2_lib.baseboard_fab2(sch_1):page182_i38:a"
				( attribute "PN" "1"
					( Origin gPackager )
				)
				( objectStatus "C9N17.1" )
			)
			( pin "@baseboard_fab2_lib.baseboard_fab2(sch_1):page182_i38:b"
				( attribute "PN" "2"
					( Origin gPackager )
				)
				( objectStatus "C9N17.2" )
			)
			( pin "@baseboard_fab2_lib.baseboard_fab2(sch_1):page182_i39:a"
				( attribute "PN" "1"
					( Origin gPackager )
				)
				( objectStatus "C9N18.1" )
			)
			( pin "@baseboard_fab2_lib.baseboard_fab2(sch_1):page182_i39:b"
				( attribute "PN" "2"
					( Origin gPackager )
				)
				( objectStatus "C9N18.2" )
			)
			( pin "@baseboard_fab2_lib.baseboard_fab2(sch_1):page182_i40:a"
				( attribute "PN" "1"
					( Origin gPackager )
				)
				( objectStatus "C9N1.1" )
			)
			( pin "@baseboard_fab2_lib.baseboard_fab2(sch_1):page182_i40:b"
				( attribute "PN" "2"
					( Origin gPackager )
				)
				( objectStatus "C9N1.2" )
			)
			( pin "@baseboard_fab2_lib.baseboard_fab2(sch_1):page158_i150:a"
				( attribute "PN" "1"
					( Origin gPackager )
				)
				( objectStatus "R9F69.1" )
			)
			( pin "@baseboard_fab2_lib.baseboard_fab2(sch_1):page158_i150:b"
				( attribute "PN" "2"
					( Origin gPackager )
				)
				( objectStatus "R9F69.2" )
			)
			( pin "@baseboard_fab2_lib.baseboard_fab2(sch_1):page158_i149:a"
				( attribute "PN" "1"
					( Origin gPackager )
				)
				( objectStatus "R9F68.1" )
			)
			( pin "@baseboard_fab2_lib.baseboard_fab2(sch_1):page158_i149:b"
				( attribute "PN" "2"
					( Origin gPackager )
				)
				( objectStatus "R9F68.2" )
			)
			( pin "@baseboard_fab2_lib.baseboard_fab2(sch_1):page182_i41:a"
				( attribute "PN" "1"
					( Origin gPackager )
				)
				( objectStatus "C9N15.1" )
			)
			( pin "@baseboard_fab2_lib.baseboard_fab2(sch_1):page182_i41:b"
				( attribute "PN" "2"
					( Origin gPackager )
				)
				( objectStatus "C9N15.2" )
			)
			( pin "@baseboard_fab2_lib.baseboard_fab2(sch_1):page182_i42:a"
				( attribute "PN" "1"
					( Origin gPackager )
				)
				( objectStatus "C9N6.1" )
			)
			( pin "@baseboard_fab2_lib.baseboard_fab2(sch_1):page182_i42:b"
				( attribute "PN" "2"
					( Origin gPackager )
				)
				( objectStatus "C9N6.2" )
			)
			( pin "@baseboard_fab2_lib.baseboard_fab2(sch_1):page182_i43:a"
				( attribute "PN" "1"
					( Origin gPackager )
				)
				( objectStatus "C9N14.1" )
			)
			( pin "@baseboard_fab2_lib.baseboard_fab2(sch_1):page182_i43:b"
				( attribute "PN" "2"
					( Origin gPackager )
				)
				( objectStatus "C9N14.2" )
			)
			( pin "@baseboard_fab2_lib.baseboard_fab2(sch_1):page182_i44:a"
				( attribute "PN" "1"
					( Origin gPackager )
				)
				( objectStatus "C9N4.1" )
			)
			( pin "@baseboard_fab2_lib.baseboard_fab2(sch_1):page182_i44:b"
				( attribute "PN" "2"
					( Origin gPackager )
				)
				( objectStatus "C9N4.2" )
			)
			( pin "@baseboard_fab2_lib.baseboard_fab2(sch_1):page182_i45:a"
				( attribute "PN" "1"
					( Origin gPackager )
				)
				( objectStatus "C9N5.1" )
			)
			( pin "@baseboard_fab2_lib.baseboard_fab2(sch_1):page182_i45:b"
				( attribute "PN" "2"
					( Origin gPackager )
				)
				( objectStatus "C9N5.2" )
			)
			( pin "@baseboard_fab2_lib.baseboard_fab2(sch_1):page182_i46:a"
				( attribute "PN" "1"
					( Origin gPackager )
				)
				( objectStatus "C9N16.1" )
			)
			( pin "@baseboard_fab2_lib.baseboard_fab2(sch_1):page182_i46:b"
				( attribute "PN" "2"
					( Origin gPackager )
				)
				( objectStatus "C9N16.2" )
			)
			( pin "@baseboard_fab2_lib.baseboard_fab2(sch_1):page182_i47:a"
				( attribute "PN" "1"
					( Origin gPackager )
				)
				( objectStatus "C9N3.1" )
			)
			( pin "@baseboard_fab2_lib.baseboard_fab2(sch_1):page182_i47:b"
				( attribute "PN" "2"
					( Origin gPackager )
				)
				( objectStatus "C9N3.2" )
			)
			( pin "@baseboard_fab2_lib.baseboard_fab2(sch_1):page182_i48:a"
				( attribute "PN" "1"
					( Origin gPackager )
				)
				( objectStatus "C9N7.1" )
			)
			( pin "@baseboard_fab2_lib.baseboard_fab2(sch_1):page182_i48:b"
				( attribute "PN" "2"
					( Origin gPackager )
				)
				( objectStatus "C9N7.2" )
			)
			( pin "@baseboard_fab2_lib.baseboard_fab2(sch_1):page182_i49:a"
				( attribute "PN" "1"
					( Origin gPackager )
				)
				( objectStatus "C9N10.1" )
			)
			( pin "@baseboard_fab2_lib.baseboard_fab2(sch_1):page182_i49:b"
				( attribute "PN" "2"
					( Origin gPackager )
				)
				( objectStatus "C9N10.2" )
			)
			( pin "@baseboard_fab2_lib.baseboard_fab2(sch_1):page182_i52:a"
				( attribute "PN" "1"
					( Origin gPackager )
				)
				( objectStatus "C9N9.1" )
			)
			( pin "@baseboard_fab2_lib.baseboard_fab2(sch_1):page182_i52:b"
				( attribute "PN" "2"
					( Origin gPackager )
				)
				( objectStatus "C9N9.2" )
			)
			( pin "@baseboard_fab2_lib.baseboard_fab2(sch_1):page182_i53:a"
				( attribute "PN" "1"
					( Origin gPackager )
				)
				( objectStatus "C9N8.1" )
			)
			( pin "@baseboard_fab2_lib.baseboard_fab2(sch_1):page182_i53:b"
				( attribute "PN" "2"
					( Origin gPackager )
				)
				( objectStatus "C9N8.2" )
			)
			( pin "@baseboard_fab2_lib.baseboard_fab2(sch_1):page184_i87:io1"
				( attribute "PN" "1"
					( Origin gPackager )
				)
				( objectStatus "J8E1.1" )
			)
			( pin "@baseboard_fab2_lib.baseboard_fab2(sch_1):page184_i87:io2"
				( attribute "PN" "2"
					( Origin gPackager )
				)
				( objectStatus "J8E1.2" )
			)
			( pin "@baseboard_fab2_lib.baseboard_fab2(sch_1):page184_i87:io3"
				( attribute "PN" "3"
					( Origin gPackager )
				)
				( objectStatus "J8E1.3" )
			)
			( pin "@baseboard_fab2_lib.baseboard_fab2(sch_1):page184_i87:io4"
				( attribute "PN" "4"
					( Origin gPackager )
				)
				( objectStatus "J8E1.4" )
			)
			( pin "@baseboard_fab2_lib.baseboard_fab2(sch_1):page184_i87:io5"
				( attribute "PN" "5"
					( Origin gPackager )
				)
				( objectStatus "J8E1.5" )
			)
			( pin "@baseboard_fab2_lib.baseboard_fab2(sch_1):page184_i87:io6"
				( attribute "PN" "6"
					( Origin gPackager )
				)
				( objectStatus "J8E1.6" )
			)
			( pin "@baseboard_fab2_lib.baseboard_fab2(sch_1):page184_i87:io7"
				( attribute "PN" "7"
					( Origin gPackager )
				)
				( objectStatus "J8E1.7" )
			)
			( pin "@baseboard_fab2_lib.baseboard_fab2(sch_1):page184_i87:io8"
				( attribute "PN" "8"
					( Origin gPackager )
				)
				( objectStatus "J8E1.8" )
			)
			( pin "@baseboard_fab2_lib.baseboard_fab2(sch_1):page184_i87:io9"
				( attribute "PN" "9"
					( Origin gPackager )
				)
				( objectStatus "J8E1.9" )
			)
			( pin "@baseboard_fab2_lib.baseboard_fab2(sch_1):page184_i87:io10"
				( attribute "PN" "10"
					( Origin gPackager )
				)
				( objectStatus "J8E1.10" )
			)
			( pin "@baseboard_fab2_lib.baseboard_fab2(sch_1):page184_i87:io11"
				( attribute "PN" "11"
					( Origin gPackager )
				)
				( objectStatus "J8E1.11" )
			)
			( pin "@baseboard_fab2_lib.baseboard_fab2(sch_1):page184_i87:mp1"
				( attribute "PN" "MP1"
					( Origin gPackager )
				)
				( objectStatus "J8E1.MP1" )
			)
			( pin "@baseboard_fab2_lib.baseboard_fab2(sch_1):page184_i87:mp2"
				( attribute "PN" "MP2"
					( Origin gPackager )
				)
				( objectStatus "J8E1.MP2" )
			)
			( pin "@baseboard_fab2_lib.baseboard_fab2(sch_1):page184_i88:a"
				( attribute "PN" "1"
					( Origin gPackager )
				)
				( objectStatus "R8E9.1" )
			)
			( pin "@baseboard_fab2_lib.baseboard_fab2(sch_1):page184_i88:b"
				( attribute "PN" "2"
					( Origin gPackager )
				)
				( objectStatus "R8E9.2" )
			)
			( pin "@baseboard_fab2_lib.baseboard_fab2(sch_1):page184_i92:a"
				( attribute "PN" "1"
					( Origin gPackager )
				)
				( objectStatus "R8D35.1" )
			)
			( pin "@baseboard_fab2_lib.baseboard_fab2(sch_1):page184_i92:b"
				( attribute "PN" "2"
					( Origin gPackager )
				)
				( objectStatus "R8D35.2" )
			)
			( pin "@baseboard_fab2_lib.baseboard_fab2(sch_1):page184_i93:a"
				( attribute "PN" "1"
					( Origin gPackager )
				)
				( objectStatus "R8E13.1" )
			)
			( pin "@baseboard_fab2_lib.baseboard_fab2(sch_1):page184_i93:b"
				( attribute "PN" "2"
					( Origin gPackager )
				)
				( objectStatus "R8E13.2" )
			)
			( pin "@baseboard_fab2_lib.baseboard_fab2(sch_1):page184_i95:a"
				( attribute "PN" "1"
					( Origin gPackager )
				)
				( objectStatus "R8E10.1" )
			)
			( pin "@baseboard_fab2_lib.baseboard_fab2(sch_1):page184_i95:b"
				( attribute "PN" "2"
					( Origin gPackager )
				)
				( objectStatus "R8E10.2" )
			)
			( pin "@baseboard_fab2_lib.baseboard_fab2(sch_1):page184_i99:a"
				( attribute "PN" "1"
					( Origin gPackager )
				)
				( objectStatus "R8E1.1" )
			)
			( pin "@baseboard_fab2_lib.baseboard_fab2(sch_1):page184_i99:b"
				( attribute "PN" "2"
					( Origin gPackager )
				)
				( objectStatus "R8E1.2" )
			)
			( pin "@baseboard_fab2_lib.baseboard_fab2(sch_1):page184_i104:io1"
				( attribute "PN" "1"
					( Origin gPackager )
				)
				( objectStatus "RM8D1.1" )
			)
			( pin "@baseboard_fab2_lib.baseboard_fab2(sch_1):page185_i172:a"
				( attribute "PN" "1"
					( Origin gPackager )
				)
				( objectStatus "C2T13.1" )
			)
			( pin "@baseboard_fab2_lib.baseboard_fab2(sch_1):page185_i172:b"
				( attribute "PN" "2"
					( Origin gPackager )
				)
				( objectStatus "C2T13.2" )
			)
			( pin "@baseboard_fab2_lib.baseboard_fab2(sch_1):page185_i171:a"
				( attribute "PN" "1"
					( Origin gPackager )
				)
				( objectStatus "C2T14.1" )
			)
			( pin "@baseboard_fab2_lib.baseboard_fab2(sch_1):page185_i171:b"
				( attribute "PN" "2"
					( Origin gPackager )
				)
				( objectStatus "C2T14.2" )
			)
			( pin "@baseboard_fab2_lib.baseboard_fab2(sch_1):page185_i180:a"
				( attribute "PN" "1"
					( Origin gPackager )
				)
				( objectStatus "C2T23.1" )
			)
			( pin "@baseboard_fab2_lib.baseboard_fab2(sch_1):page185_i180:b"
				( attribute "PN" "2"
					( Origin gPackager )
				)
				( objectStatus "C2T23.2" )
			)
			( pin "@baseboard_fab2_lib.baseboard_fab2(sch_1):page185_i179:a"
				( attribute "PN" "1"
					( Origin gPackager )
				)
				( objectStatus "C2T20.1" )
			)
			( pin "@baseboard_fab2_lib.baseboard_fab2(sch_1):page185_i179:b"
				( attribute "PN" "2"
					( Origin gPackager )
				)
				( objectStatus "C2T20.2" )
			)
			( pin "@baseboard_fab2_lib.baseboard_fab2(sch_1):page107_i477:a"
				( attribute "PN" "1"
					( Origin gPackager )
				)
				( objectStatus "C3P33.1" )
			)
			( pin "@baseboard_fab2_lib.baseboard_fab2(sch_1):page107_i477:b"
				( attribute "PN" "2"
					( Origin gPackager )
				)
				( objectStatus "C3P33.2" )
			)
			( pin "@baseboard_fab2_lib.baseboard_fab2(sch_1):page185_i139:a"
				( attribute "PN" "1"
					( Origin gPackager )
				)
				( objectStatus "C8F11.1" )
			)
			( pin "@baseboard_fab2_lib.baseboard_fab2(sch_1):page185_i139:b"
				( attribute "PN" "2"
					( Origin gPackager )
				)
				( objectStatus "C8F11.2" )
			)
			( pin "@baseboard_fab2_lib.baseboard_fab2(sch_1):page185_i96:a"
				( attribute "PN" "1"
					( Origin gPackager )
				)
				( objectStatus "C8F7.1" )
			)
			( pin "@baseboard_fab2_lib.baseboard_fab2(sch_1):page185_i96:b"
				( attribute "PN" "2"
					( Origin gPackager )
				)
				( objectStatus "C8F7.2" )
			)
			( pin "@baseboard_fab2_lib.baseboard_fab2(sch_1):page107_i476:a"
				( attribute "PN" "1"
					( Origin gPackager )
				)
				( objectStatus "C3P16.1" )
			)
			( pin "@baseboard_fab2_lib.baseboard_fab2(sch_1):page107_i476:b"
				( attribute "PN" "2"
					( Origin gPackager )
				)
				( objectStatus "C3P16.2" )
			)
			( pin "@baseboard_fab2_lib.baseboard_fab2(sch_1):page107_i475:a"
				( attribute "PN" "1"
					( Origin gPackager )
				)
				( objectStatus "C3P36.1" )
			)
			( pin "@baseboard_fab2_lib.baseboard_fab2(sch_1):page107_i475:b"
				( attribute "PN" "2"
					( Origin gPackager )
				)
				( objectStatus "C3P36.2" )
			)
			( pin "@baseboard_fab2_lib.baseboard_fab2(sch_1):page107_i474:a"
				( attribute "PN" "1"
					( Origin gPackager )
				)
				( objectStatus "C3P41.1" )
			)
			( pin "@baseboard_fab2_lib.baseboard_fab2(sch_1):page107_i474:b"
				( attribute "PN" "2"
					( Origin gPackager )
				)
				( objectStatus "C3P41.2" )
			)
			( pin "@baseboard_fab2_lib.baseboard_fab2(sch_1):page185_i105:a"
				( attribute "PN" "1"
					( Origin gPackager )
				)
				( objectStatus "R8F18.1" )
			)
			( pin "@baseboard_fab2_lib.baseboard_fab2(sch_1):page185_i105:b"
				( attribute "PN" "2"
					( Origin gPackager )
				)
				( objectStatus "R8F18.2" )
			)
			( pin "@baseboard_fab2_lib.baseboard_fab2(sch_1):page185_i106:a"
				( attribute "PN" "1"
					( Origin gPackager )
				)
				( objectStatus "R8F21.1" )
			)
			( pin "@baseboard_fab2_lib.baseboard_fab2(sch_1):page185_i106:b"
				( attribute "PN" "2"
					( Origin gPackager )
				)
				( objectStatus "R8F21.2" )
			)
			( pin "@baseboard_fab2_lib.baseboard_fab2(sch_1):page185_i110:a"
				( attribute "PN" "2"
					( Origin gPackager )
				)
				( objectStatus "U2P1.2" )
			)
			( pin "@baseboard_fab2_lib.baseboard_fab2(sch_1):page185_i110:y"
				( attribute "PN" "4"
					( Origin gPackager )
				)
				( objectStatus "U2P1.4" )
			)
			( pin "@baseboard_fab2_lib.baseboard_fab2(sch_1):page185_i111:a"
				( attribute "PN" "1"
					( Origin gPackager )
				)
				( objectStatus "R2P15.1" )
			)
			( pin "@baseboard_fab2_lib.baseboard_fab2(sch_1):page185_i111:b"
				( attribute "PN" "2"
					( Origin gPackager )
				)
				( objectStatus "R2P15.2" )
			)
			( pin "@baseboard_fab2_lib.baseboard_fab2(sch_1):page185_i113:a"
				( attribute "PN" "1"
					( Origin gPackager )
				)
				( objectStatus "R2P16.1" )
			)
			( pin "@baseboard_fab2_lib.baseboard_fab2(sch_1):page185_i113:b"
				( attribute "PN" "2"
					( Origin gPackager )
				)
				( objectStatus "R2P16.2" )
			)
			( pin "@baseboard_fab2_lib.baseboard_fab2(sch_1):page185_i115:a"
				( attribute "PN" "1"
					( Origin gPackager )
				)
				( objectStatus "R2P14.1" )
			)
			( pin "@baseboard_fab2_lib.baseboard_fab2(sch_1):page185_i115:b"
				( attribute "PN" "2"
					( Origin gPackager )
				)
				( objectStatus "R2P14.2" )
			)
			( pin "@baseboard_fab2_lib.baseboard_fab2(sch_1):page185_i117:a"
				( attribute "PN" "1"
					( Origin gPackager )
				)
				( objectStatus "C2P9.1" )
			)
			( pin "@baseboard_fab2_lib.baseboard_fab2(sch_1):page185_i117:b"
				( attribute "PN" "2"
					( Origin gPackager )
				)
				( objectStatus "C2P9.2" )
			)
			( pin "@baseboard_fab2_lib.baseboard_fab2(sch_1):page185_i120:a"
				( attribute "PN" "1"
					( Origin gPackager )
				)
				( objectStatus "C2T29.1" )
			)
			( pin "@baseboard_fab2_lib.baseboard_fab2(sch_1):page185_i120:b"
				( attribute "PN" "2"
					( Origin gPackager )
				)
				( objectStatus "C2T29.2" )
			)
			( pin "@baseboard_fab2_lib.baseboard_fab2(sch_1):page185_i123:a"
				( attribute "PN" "1"
					( Origin gPackager )
				)
				( objectStatus "C2T26.1" )
			)
			( pin "@baseboard_fab2_lib.baseboard_fab2(sch_1):page185_i123:b"
				( attribute "PN" "2"
					( Origin gPackager )
				)
				( objectStatus "C2T26.2" )
			)
			( pin "@baseboard_fab2_lib.baseboard_fab2(sch_1):page185_i124:a"
				( attribute "PN" "1"
					( Origin gPackager )
				)
				( objectStatus "C2T21.1" )
			)
			( pin "@baseboard_fab2_lib.baseboard_fab2(sch_1):page185_i124:b"
				( attribute "PN" "2"
					( Origin gPackager )
				)
				( objectStatus "C2T21.2" )
			)
			( pin "@baseboard_fab2_lib.baseboard_fab2(sch_1):page185_i126:a"
				( attribute "PN" "1"
					( Origin gPackager )
				)
				( objectStatus "C2T16.1" )
			)
			( pin "@baseboard_fab2_lib.baseboard_fab2(sch_1):page185_i126:b"
				( attribute "PN" "2"
					( Origin gPackager )
				)
				( objectStatus "C2T16.2" )
			)
			( pin "@baseboard_fab2_lib.baseboard_fab2(sch_1):page185_i127:a"
				( attribute "PN" "1"
					( Origin gPackager )
				)
				( objectStatus "C2T15.1" )
			)
			( pin "@baseboard_fab2_lib.baseboard_fab2(sch_1):page185_i127:b"
				( attribute "PN" "2"
					( Origin gPackager )
				)
				( objectStatus "C2T15.2" )
			)
			( pin "@baseboard_fab2_lib.baseboard_fab2(sch_1):page185_i129:a"
				( attribute "PN" "1"
					( Origin gPackager )
				)
				( objectStatus "C2T24.1" )
			)
			( pin "@baseboard_fab2_lib.baseboard_fab2(sch_1):page185_i129:b"
				( attribute "PN" "2"
					( Origin gPackager )
				)
				( objectStatus "C2T24.2" )
			)
			( pin "@baseboard_fab2_lib.baseboard_fab2(sch_1):page185_i131:a"
				( attribute "PN" "1"
					( Origin gPackager )
				)
				( objectStatus "C2T2.1" )
			)
			( pin "@baseboard_fab2_lib.baseboard_fab2(sch_1):page185_i131:b"
				( attribute "PN" "2"
					( Origin gPackager )
				)
				( objectStatus "C2T2.2" )
			)
			( pin "@baseboard_fab2_lib.baseboard_fab2(sch_1):page185_i132:a"
				( attribute "PN" "1"
					( Origin gPackager )
				)
				( objectStatus "C2T4.1" )
			)
			( pin "@baseboard_fab2_lib.baseboard_fab2(sch_1):page185_i132:b"
				( attribute "PN" "2"
					( Origin gPackager )
				)
				( objectStatus "C2T4.2" )
			)
			( pin "@baseboard_fab2_lib.baseboard_fab2(sch_1):page185_i135:a"
				( attribute "PN" "1"
					( Origin gPackager )
				)
				( objectStatus "C2T5.1" )
			)
			( pin "@baseboard_fab2_lib.baseboard_fab2(sch_1):page185_i135:b"
				( attribute "PN" "2"
					( Origin gPackager )
				)
				( objectStatus "C2T5.2" )
			)
			( pin "@baseboard_fab2_lib.baseboard_fab2(sch_1):page185_i136:a"
				( attribute "PN" "1"
					( Origin gPackager )
				)
				( objectStatus "R8F36.1" )
			)
			( pin "@baseboard_fab2_lib.baseboard_fab2(sch_1):page185_i136:b"
				( attribute "PN" "2"
					( Origin gPackager )
				)
				( objectStatus "R8F36.2" )
			)
			( pin "@baseboard_fab2_lib.baseboard_fab2(sch_1):page186_i3:a"
				( attribute "PN" "1"
					( Origin gPackager )
				)
				( objectStatus "C1M27.1" )
			)
			( pin "@baseboard_fab2_lib.baseboard_fab2(sch_1):page186_i3:b"
				( attribute "PN" "2"
					( Origin gPackager )
				)
				( objectStatus "C1M27.2" )
			)
			( pin "@baseboard_fab2_lib.baseboard_fab2(sch_1):page186_i6:a"
				( attribute "PN" "1"
					( Origin gPackager )
				)
				( objectStatus "C1M26.1" )
			)
			( pin "@baseboard_fab2_lib.baseboard_fab2(sch_1):page186_i6:b"
				( attribute "PN" "2"
					( Origin gPackager )
				)
				( objectStatus "C1M26.2" )
			)
			( pin "@baseboard_fab2_lib.baseboard_fab2(sch_1):page186_i7:a"
				( attribute "PN" "1"
					( Origin gPackager )
				)
				( objectStatus "C1M23.1" )
			)
			( pin "@baseboard_fab2_lib.baseboard_fab2(sch_1):page186_i7:b"
				( attribute "PN" "2"
					( Origin gPackager )
				)
				( objectStatus "C1M23.2" )
			)
			( pin "@baseboard_fab2_lib.baseboard_fab2(sch_1):page186_i8:a"
				( attribute "PN" "1"
					( Origin gPackager )
				)
				( objectStatus "C1M22.1" )
			)
			( pin "@baseboard_fab2_lib.baseboard_fab2(sch_1):page186_i8:b"
				( attribute "PN" "2"
					( Origin gPackager )
				)
				( objectStatus "C1M22.2" )
			)
			( pin "@baseboard_fab2_lib.baseboard_fab2(sch_1):page186_i10:a"
				( attribute "PN" "1"
					( Origin gPackager )
				)
				( objectStatus "C1M24.1" )
			)
			( pin "@baseboard_fab2_lib.baseboard_fab2(sch_1):page186_i10:b"
				( attribute "PN" "2"
					( Origin gPackager )
				)
				( objectStatus "C1M24.2" )
			)
			( pin "@baseboard_fab2_lib.baseboard_fab2(sch_1):page186_i220:a"
				( attribute "PN" "1"
					( Origin gPackager )
				)
				( objectStatus "R1M14.1" )
			)
			( pin "@baseboard_fab2_lib.baseboard_fab2(sch_1):page186_i220:b"
				( attribute "PN" "2"
					( Origin gPackager )
				)
				( objectStatus "R1M14.2" )
			)
			( pin "@baseboard_fab2_lib.baseboard_fab2(sch_1):page202_i114:\1\"
				( attribute "PN" "1"
					( Origin gPackager )
				)
				( objectStatus "RT2.1" )
			)
			( pin "@baseboard_fab2_lib.baseboard_fab2(sch_1):page202_i114:\2\"
				( attribute "PN" "2"
					( Origin gPackager )
				)
				( objectStatus "RT2.2" )
			)
			( pin "@baseboard_fab2_lib.baseboard_fab2(sch_1):page186_i270:a"
				( attribute "PN" "1"
					( Origin gPackager )
				)
				( objectStatus "C1M20.1" )
			)
			( pin "@baseboard_fab2_lib.baseboard_fab2(sch_1):page186_i270:b"
				( attribute "PN" "2"
					( Origin gPackager )
				)
				( objectStatus "C1M20.2" )
			)
			( pin "@baseboard_fab2_lib.baseboard_fab2(sch_1):page186_i334:a"
				( attribute "PN" "1"
					( Origin gPackager )
				)
				( objectStatus "C1M21.1" )
			)
			( pin "@baseboard_fab2_lib.baseboard_fab2(sch_1):page186_i334:b"
				( attribute "PN" "2"
					( Origin gPackager )
				)
				( objectStatus "C1M21.2" )
			)
			( pin "@baseboard_fab2_lib.baseboard_fab2(sch_1):page186_i335:a"
				( attribute "PN" "1"
					( Origin gPackager )
				)
				( objectStatus "C1M25.1" )
			)
			( pin "@baseboard_fab2_lib.baseboard_fab2(sch_1):page186_i335:b"
				( attribute "PN" "2"
					( Origin gPackager )
				)
				( objectStatus "C1M25.2" )
			)
			( pin "@baseboard_fab2_lib.baseboard_fab2(sch_1):page186_i336:io1"
				( attribute "PN" "1"
					( Origin gPackager )
				)
				( objectStatus "J9B3.1" )
			)
			( pin "@baseboard_fab2_lib.baseboard_fab2(sch_1):page186_i336:io2"
				( attribute "PN" "2"
					( Origin gPackager )
				)
				( objectStatus "J9B3.2" )
			)
			( pin "@baseboard_fab2_lib.baseboard_fab2(sch_1):page186_i336:io3"
				( attribute "PN" "3"
					( Origin gPackager )
				)
				( objectStatus "J9B3.3" )
			)
			( pin "@baseboard_fab2_lib.baseboard_fab2(sch_1):page186_i336:io4"
				( attribute "PN" "4"
					( Origin gPackager )
				)
				( objectStatus "J9B3.4" )
			)
			( pin "@baseboard_fab2_lib.baseboard_fab2(sch_1):page186_i336:io5"
				( attribute "PN" "5"
					( Origin gPackager )
				)
				( objectStatus "J9B3.5" )
			)
			( pin "@baseboard_fab2_lib.baseboard_fab2(sch_1):page186_i336:io6"
				( attribute "PN" "6"
					( Origin gPackager )
				)
				( objectStatus "J9B3.6" )
			)
			( pin "@baseboard_fab2_lib.baseboard_fab2(sch_1):page186_i336:io7"
				( attribute "PN" "7"
					( Origin gPackager )
				)
				( objectStatus "J9B3.7" )
			)
			( pin "@baseboard_fab2_lib.baseboard_fab2(sch_1):page186_i336:io8"
				( attribute "PN" "8"
					( Origin gPackager )
				)
				( objectStatus "J9B3.8" )
			)
			( pin "@baseboard_fab2_lib.baseboard_fab2(sch_1):page186_i336:io9"
				( attribute "PN" "9"
					( Origin gPackager )
				)
				( objectStatus "J9B3.9" )
			)
			( pin "@baseboard_fab2_lib.baseboard_fab2(sch_1):page186_i336:io10"
				( attribute "PN" "10"
					( Origin gPackager )
				)
				( objectStatus "J9B3.10" )
			)
			( pin "@baseboard_fab2_lib.baseboard_fab2(sch_1):page186_i336:io11"
				( attribute "PN" "11"
					( Origin gPackager )
				)
				( objectStatus "J9B3.11" )
			)
			( pin "@baseboard_fab2_lib.baseboard_fab2(sch_1):page186_i336:io12"
				( attribute "PN" "12"
					( Origin gPackager )
				)
				( objectStatus "J9B3.12" )
			)
			( pin "@baseboard_fab2_lib.baseboard_fab2(sch_1):page186_i336:io13"
				( attribute "PN" "13"
					( Origin gPackager )
				)
				( objectStatus "J9B3.13" )
			)
			( pin "@baseboard_fab2_lib.baseboard_fab2(sch_1):page186_i336:io14"
				( attribute "PN" "14"
					( Origin gPackager )
				)
				( objectStatus "J9B3.14" )
			)
			( pin "@baseboard_fab2_lib.baseboard_fab2(sch_1):page186_i336:io15"
				( attribute "PN" "15"
					( Origin gPackager )
				)
				( objectStatus "J9B3.15" )
			)
			( pin "@baseboard_fab2_lib.baseboard_fab2(sch_1):page186_i336:io16"
				( attribute "PN" "16"
					( Origin gPackager )
				)
				( objectStatus "J9B3.16" )
			)
			( pin "@baseboard_fab2_lib.baseboard_fab2(sch_1):page186_i336:io17"
				( attribute "PN" "17"
					( Origin gPackager )
				)
				( objectStatus "J9B3.17" )
			)
			( pin "@baseboard_fab2_lib.baseboard_fab2(sch_1):page186_i336:io18"
				( attribute "PN" "18"
					( Origin gPackager )
				)
				( objectStatus "J9B3.18" )
			)
			( pin "@baseboard_fab2_lib.baseboard_fab2(sch_1):page186_i336:io19"
				( attribute "PN" "19"
					( Origin gPackager )
				)
				( objectStatus "J9B3.19" )
			)
			( pin "@baseboard_fab2_lib.baseboard_fab2(sch_1):page186_i336:io20"
				( attribute "PN" "20"
					( Origin gPackager )
				)
				( objectStatus "J9B3.20" )
			)
			( pin "@baseboard_fab2_lib.baseboard_fab2(sch_1):page186_i336:io21"
				( attribute "PN" "21"
					( Origin gPackager )
				)
				( objectStatus "J9B3.21" )
			)
			( pin "@baseboard_fab2_lib.baseboard_fab2(sch_1):page186_i336:io22"
				( attribute "PN" "22"
					( Origin gPackager )
				)
				( objectStatus "J9B3.22" )
			)
			( pin "@baseboard_fab2_lib.baseboard_fab2(sch_1):page186_i336:io23"
				( attribute "PN" "23"
					( Origin gPackager )
				)
				( objectStatus "J9B3.23" )
			)
			( pin "@baseboard_fab2_lib.baseboard_fab2(sch_1):page186_i336:io24"
				( attribute "PN" "24"
					( Origin gPackager )
				)
				( objectStatus "J9B3.24" )
			)
			( pin "@baseboard_fab2_lib.baseboard_fab2(sch_1):page186_i336:io25"
				( attribute "PN" "25"
					( Origin gPackager )
				)
				( objectStatus "J9B3.25" )
			)
			( pin "@baseboard_fab2_lib.baseboard_fab2(sch_1):page186_i336:io26"
				( attribute "PN" "26"
					( Origin gPackager )
				)
				( objectStatus "J9B3.26" )
			)
			( pin "@baseboard_fab2_lib.baseboard_fab2(sch_1):page186_i336:io27"
				( attribute "PN" "27"
					( Origin gPackager )
				)
				( objectStatus "J9B3.27" )
			)
			( pin "@baseboard_fab2_lib.baseboard_fab2(sch_1):page186_i336:io28"
				( attribute "PN" "28"
					( Origin gPackager )
				)
				( objectStatus "J9B3.28" )
			)
			( pin "@baseboard_fab2_lib.baseboard_fab2(sch_1):page186_i336:io29"
				( attribute "PN" "29"
					( Origin gPackager )
				)
				( objectStatus "J9B3.29" )
			)
			( pin "@baseboard_fab2_lib.baseboard_fab2(sch_1):page186_i336:io30"
				( attribute "PN" "30"
					( Origin gPackager )
				)
				( objectStatus "J9B3.30" )
			)
			( pin "@baseboard_fab2_lib.baseboard_fab2(sch_1):page186_i336:io31"
				( attribute "PN" "31"
					( Origin gPackager )
				)
				( objectStatus "J9B3.31" )
			)
			( pin "@baseboard_fab2_lib.baseboard_fab2(sch_1):page186_i336:io32"
				( attribute "PN" "32"
					( Origin gPackager )
				)
				( objectStatus "J9B3.32" )
			)
			( pin "@baseboard_fab2_lib.baseboard_fab2(sch_1):page186_i336:io33"
				( attribute "PN" "33"
					( Origin gPackager )
				)
				( objectStatus "J9B3.33" )
			)
			( pin "@baseboard_fab2_lib.baseboard_fab2(sch_1):page186_i336:io34"
				( attribute "PN" "34"
					( Origin gPackager )
				)
				( objectStatus "J9B3.34" )
			)
			( pin "@baseboard_fab2_lib.baseboard_fab2(sch_1):page186_i336:io35"
				( attribute "PN" "35"
					( Origin gPackager )
				)
				( objectStatus "J9B3.35" )
			)
			( pin "@baseboard_fab2_lib.baseboard_fab2(sch_1):page186_i336:io36"
				( attribute "PN" "36"
					( Origin gPackager )
				)
				( objectStatus "J9B3.36" )
			)
			( pin "@baseboard_fab2_lib.baseboard_fab2(sch_1):page186_i336:io37"
				( attribute "PN" "37"
					( Origin gPackager )
				)
				( objectStatus "J9B3.37" )
			)
			( pin "@baseboard_fab2_lib.baseboard_fab2(sch_1):page186_i336:io38"
				( attribute "PN" "38"
					( Origin gPackager )
				)
				( objectStatus "J9B3.38" )
			)
			( pin "@baseboard_fab2_lib.baseboard_fab2(sch_1):page186_i336:io39"
				( attribute "PN" "39"
					( Origin gPackager )
				)
				( objectStatus "J9B3.39" )
			)
			( pin "@baseboard_fab2_lib.baseboard_fab2(sch_1):page186_i336:io40"
				( attribute "PN" "40"
					( Origin gPackager )
				)
				( objectStatus "J9B3.40" )
			)
			( pin "@baseboard_fab2_lib.baseboard_fab2(sch_1):page186_i336:io41"
				( attribute "PN" "41"
					( Origin gPackager )
				)
				( objectStatus "J9B3.41" )
			)
			( pin "@baseboard_fab2_lib.baseboard_fab2(sch_1):page186_i336:io42"
				( attribute "PN" "42"
					( Origin gPackager )
				)
				( objectStatus "J9B3.42" )
			)
			( pin "@baseboard_fab2_lib.baseboard_fab2(sch_1):page186_i336:io43"
				( attribute "PN" "43"
					( Origin gPackager )
				)
				( objectStatus "J9B3.43" )
			)
			( pin "@baseboard_fab2_lib.baseboard_fab2(sch_1):page186_i336:io44"
				( attribute "PN" "44"
					( Origin gPackager )
				)
				( objectStatus "J9B3.44" )
			)
			( pin "@baseboard_fab2_lib.baseboard_fab2(sch_1):page186_i336:io45"
				( attribute "PN" "45"
					( Origin gPackager )
				)
				( objectStatus "J9B3.45" )
			)
			( pin "@baseboard_fab2_lib.baseboard_fab2(sch_1):page186_i336:io46"
				( attribute "PN" "46"
					( Origin gPackager )
				)
				( objectStatus "J9B3.46" )
			)
			( pin "@baseboard_fab2_lib.baseboard_fab2(sch_1):page186_i336:io47"
				( attribute "PN" "47"
					( Origin gPackager )
				)
				( objectStatus "J9B3.47" )
			)
			( pin "@baseboard_fab2_lib.baseboard_fab2(sch_1):page186_i336:io48"
				( attribute "PN" "48"
					( Origin gPackager )
				)
				( objectStatus "J9B3.48" )
			)
			( pin "@baseboard_fab2_lib.baseboard_fab2(sch_1):page186_i336:io49"
				( attribute "PN" "49"
					( Origin gPackager )
				)
				( objectStatus "J9B3.49" )
			)
			( pin "@baseboard_fab2_lib.baseboard_fab2(sch_1):page186_i336:io50"
				( attribute "PN" "50"
					( Origin gPackager )
				)
				( objectStatus "J9B3.50" )
			)
			( pin "@baseboard_fab2_lib.baseboard_fab2(sch_1):page186_i336:io51"
				( attribute "PN" "51"
					( Origin gPackager )
				)
				( objectStatus "J9B3.51" )
			)
			( pin "@baseboard_fab2_lib.baseboard_fab2(sch_1):page186_i336:io52"
				( attribute "PN" "52"
					( Origin gPackager )
				)
				( objectStatus "J9B3.52" )
			)
			( pin "@baseboard_fab2_lib.baseboard_fab2(sch_1):page186_i336:io53"
				( attribute "PN" "53"
					( Origin gPackager )
				)
				( objectStatus "J9B3.53" )
			)
			( pin "@baseboard_fab2_lib.baseboard_fab2(sch_1):page186_i336:io54"
				( attribute "PN" "54"
					( Origin gPackager )
				)
				( objectStatus "J9B3.54" )
			)
			( pin "@baseboard_fab2_lib.baseboard_fab2(sch_1):page186_i336:io55"
				( attribute "PN" "55"
					( Origin gPackager )
				)
				( objectStatus "J9B3.55" )
			)
			( pin "@baseboard_fab2_lib.baseboard_fab2(sch_1):page186_i336:io56"
				( attribute "PN" "56"
					( Origin gPackager )
				)
				( objectStatus "J9B3.56" )
			)
			( pin "@baseboard_fab2_lib.baseboard_fab2(sch_1):page186_i336:io57"
				( attribute "PN" "57"
					( Origin gPackager )
				)
				( objectStatus "J9B3.57" )
			)
			( pin "@baseboard_fab2_lib.baseboard_fab2(sch_1):page186_i336:io58"
				( attribute "PN" "58"
					( Origin gPackager )
				)
				( objectStatus "J9B3.58" )
			)
			( pin "@baseboard_fab2_lib.baseboard_fab2(sch_1):page186_i336:io59"
				( attribute "PN" "59"
					( Origin gPackager )
				)
				( objectStatus "J9B3.59" )
			)
			( pin "@baseboard_fab2_lib.baseboard_fab2(sch_1):page186_i336:io60"
				( attribute "PN" "60"
					( Origin gPackager )
				)
				( objectStatus "J9B3.60" )
			)
			( pin "@baseboard_fab2_lib.baseboard_fab2(sch_1):page186_i336:io61"
				( attribute "PN" "61"
					( Origin gPackager )
				)
				( objectStatus "J9B3.61" )
			)
			( pin "@baseboard_fab2_lib.baseboard_fab2(sch_1):page186_i336:io62"
				( attribute "PN" "62"
					( Origin gPackager )
				)
				( objectStatus "J9B3.62" )
			)
			( pin "@baseboard_fab2_lib.baseboard_fab2(sch_1):page186_i336:io63"
				( attribute "PN" "63"
					( Origin gPackager )
				)
				( objectStatus "J9B3.63" )
			)
			( pin "@baseboard_fab2_lib.baseboard_fab2(sch_1):page186_i336:io64"
				( attribute "PN" "64"
					( Origin gPackager )
				)
				( objectStatus "J9B3.64" )
			)
			( pin "@baseboard_fab2_lib.baseboard_fab2(sch_1):page186_i336:io65"
				( attribute "PN" "65"
					( Origin gPackager )
				)
				( objectStatus "J9B3.65" )
			)
			( pin "@baseboard_fab2_lib.baseboard_fab2(sch_1):page186_i336:io66"
				( attribute "PN" "66"
					( Origin gPackager )
				)
				( objectStatus "J9B3.66" )
			)
			( pin "@baseboard_fab2_lib.baseboard_fab2(sch_1):page186_i336:io67"
				( attribute "PN" "67"
					( Origin gPackager )
				)
				( objectStatus "J9B3.67" )
			)
			( pin "@baseboard_fab2_lib.baseboard_fab2(sch_1):page186_i336:io68"
				( attribute "PN" "68"
					( Origin gPackager )
				)
				( objectStatus "J9B3.68" )
			)
			( pin "@baseboard_fab2_lib.baseboard_fab2(sch_1):page186_i336:io69"
				( attribute "PN" "69"
					( Origin gPackager )
				)
				( objectStatus "J9B3.69" )
			)
			( pin "@baseboard_fab2_lib.baseboard_fab2(sch_1):page186_i336:io70"
				( attribute "PN" "70"
					( Origin gPackager )
				)
				( objectStatus "J9B3.70" )
			)
			( pin "@baseboard_fab2_lib.baseboard_fab2(sch_1):page186_i336:io71"
				( attribute "PN" "71"
					( Origin gPackager )
				)
				( objectStatus "J9B3.71" )
			)
			( pin "@baseboard_fab2_lib.baseboard_fab2(sch_1):page186_i336:io72"
				( attribute "PN" "72"
					( Origin gPackager )
				)
				( objectStatus "J9B3.72" )
			)
			( pin "@baseboard_fab2_lib.baseboard_fab2(sch_1):page186_i336:io73"
				( attribute "PN" "73"
					( Origin gPackager )
				)
				( objectStatus "J9B3.73" )
			)
			( pin "@baseboard_fab2_lib.baseboard_fab2(sch_1):page186_i336:io74"
				( attribute "PN" "74"
					( Origin gPackager )
				)
				( objectStatus "J9B3.74" )
			)
			( pin "@baseboard_fab2_lib.baseboard_fab2(sch_1):page186_i336:io75"
				( attribute "PN" "75"
					( Origin gPackager )
				)
				( objectStatus "J9B3.75" )
			)
			( pin "@baseboard_fab2_lib.baseboard_fab2(sch_1):page186_i336:io76"
				( attribute "PN" "76"
					( Origin gPackager )
				)
				( objectStatus "J9B3.76" )
			)
			( pin "@baseboard_fab2_lib.baseboard_fab2(sch_1):page186_i336:io77"
				( attribute "PN" "77"
					( Origin gPackager )
				)
				( objectStatus "J9B3.77" )
			)
			( pin "@baseboard_fab2_lib.baseboard_fab2(sch_1):page186_i336:io78"
				( attribute "PN" "78"
					( Origin gPackager )
				)
				( objectStatus "J9B3.78" )
			)
			( pin "@baseboard_fab2_lib.baseboard_fab2(sch_1):page186_i336:io79"
				( attribute "PN" "79"
					( Origin gPackager )
				)
				( objectStatus "J9B3.79" )
			)
			( pin "@baseboard_fab2_lib.baseboard_fab2(sch_1):page186_i336:io80"
				( attribute "PN" "80"
					( Origin gPackager )
				)
				( objectStatus "J9B3.80" )
			)
			( pin "@baseboard_fab2_lib.baseboard_fab2(sch_1):page186_i336:io81"
				( attribute "PN" "81"
					( Origin gPackager )
				)
				( objectStatus "J9B3.81" )
			)
			( pin "@baseboard_fab2_lib.baseboard_fab2(sch_1):page186_i336:io82"
				( attribute "PN" "82"
					( Origin gPackager )
				)
				( objectStatus "J9B3.82" )
			)
			( pin "@baseboard_fab2_lib.baseboard_fab2(sch_1):page186_i336:io83"
				( attribute "PN" "83"
					( Origin gPackager )
				)
				( objectStatus "J9B3.83" )
			)
			( pin "@baseboard_fab2_lib.baseboard_fab2(sch_1):page186_i336:io84"
				( attribute "PN" "84"
					( Origin gPackager )
				)
				( objectStatus "J9B3.84" )
			)
			( pin "@baseboard_fab2_lib.baseboard_fab2(sch_1):page186_i336:io85"
				( attribute "PN" "85"
					( Origin gPackager )
				)
				( objectStatus "J9B3.85" )
			)
			( pin "@baseboard_fab2_lib.baseboard_fab2(sch_1):page186_i336:io86"
				( attribute "PN" "86"
					( Origin gPackager )
				)
				( objectStatus "J9B3.86" )
			)
			( pin "@baseboard_fab2_lib.baseboard_fab2(sch_1):page186_i336:io87"
				( attribute "PN" "87"
					( Origin gPackager )
				)
				( objectStatus "J9B3.87" )
			)
			( pin "@baseboard_fab2_lib.baseboard_fab2(sch_1):page186_i336:io88"
				( attribute "PN" "88"
					( Origin gPackager )
				)
				( objectStatus "J9B3.88" )
			)
			( pin "@baseboard_fab2_lib.baseboard_fab2(sch_1):page186_i336:io89"
				( attribute "PN" "89"
					( Origin gPackager )
				)
				( objectStatus "J9B3.89" )
			)
			( pin "@baseboard_fab2_lib.baseboard_fab2(sch_1):page186_i336:io90"
				( attribute "PN" "90"
					( Origin gPackager )
				)
				( objectStatus "J9B3.90" )
			)
			( pin "@baseboard_fab2_lib.baseboard_fab2(sch_1):page186_i336:io91"
				( attribute "PN" "91"
					( Origin gPackager )
				)
				( objectStatus "J9B3.91" )
			)
			( pin "@baseboard_fab2_lib.baseboard_fab2(sch_1):page186_i336:io92"
				( attribute "PN" "92"
					( Origin gPackager )
				)
				( objectStatus "J9B3.92" )
			)
			( pin "@baseboard_fab2_lib.baseboard_fab2(sch_1):page186_i336:io93"
				( attribute "PN" "93"
					( Origin gPackager )
				)
				( objectStatus "J9B3.93" )
			)
			( pin "@baseboard_fab2_lib.baseboard_fab2(sch_1):page186_i336:io94"
				( attribute "PN" "94"
					( Origin gPackager )
				)
				( objectStatus "J9B3.94" )
			)
			( pin "@baseboard_fab2_lib.baseboard_fab2(sch_1):page186_i336:io95"
				( attribute "PN" "95"
					( Origin gPackager )
				)
				( objectStatus "J9B3.95" )
			)
			( pin "@baseboard_fab2_lib.baseboard_fab2(sch_1):page186_i336:io96"
				( attribute "PN" "96"
					( Origin gPackager )
				)
				( objectStatus "J9B3.96" )
			)
			( pin "@baseboard_fab2_lib.baseboard_fab2(sch_1):page186_i336:io97"
				( attribute "PN" "97"
					( Origin gPackager )
				)
				( objectStatus "J9B3.97" )
			)
			( pin "@baseboard_fab2_lib.baseboard_fab2(sch_1):page186_i336:io98"
				( attribute "PN" "98"
					( Origin gPackager )
				)
				( objectStatus "J9B3.98" )
			)
			( pin "@baseboard_fab2_lib.baseboard_fab2(sch_1):page186_i336:io99"
				( attribute "PN" "99"
					( Origin gPackager )
				)
				( objectStatus "J9B3.99" )
			)
			( pin "@baseboard_fab2_lib.baseboard_fab2(sch_1):page186_i336:io100"
				( attribute "PN" "100"
					( Origin gPackager )
				)
				( objectStatus "J9B3.100" )
			)
			( pin "@baseboard_fab2_lib.baseboard_fab2(sch_1):page186_i336:io101"
				( attribute "PN" "101"
					( Origin gPackager )
				)
				( objectStatus "J9B3.101" )
			)
			( pin "@baseboard_fab2_lib.baseboard_fab2(sch_1):page186_i336:io102"
				( attribute "PN" "102"
					( Origin gPackager )
				)
				( objectStatus "J9B3.102" )
			)
			( pin "@baseboard_fab2_lib.baseboard_fab2(sch_1):page186_i336:io103"
				( attribute "PN" "103"
					( Origin gPackager )
				)
				( objectStatus "J9B3.103" )
			)
			( pin "@baseboard_fab2_lib.baseboard_fab2(sch_1):page186_i336:io104"
				( attribute "PN" "104"
					( Origin gPackager )
				)
				( objectStatus "J9B3.104" )
			)
			( pin "@baseboard_fab2_lib.baseboard_fab2(sch_1):page186_i336:io105"
				( attribute "PN" "105"
					( Origin gPackager )
				)
				( objectStatus "J9B3.105" )
			)
			( pin "@baseboard_fab2_lib.baseboard_fab2(sch_1):page186_i336:io106"
				( attribute "PN" "106"
					( Origin gPackager )
				)
				( objectStatus "J9B3.106" )
			)
			( pin "@baseboard_fab2_lib.baseboard_fab2(sch_1):page186_i336:io107"
				( attribute "PN" "107"
					( Origin gPackager )
				)
				( objectStatus "J9B3.107" )
			)
			( pin "@baseboard_fab2_lib.baseboard_fab2(sch_1):page186_i336:io108"
				( attribute "PN" "108"
					( Origin gPackager )
				)
				( objectStatus "J9B3.108" )
			)
			( pin "@baseboard_fab2_lib.baseboard_fab2(sch_1):page186_i336:io109"
				( attribute "PN" "109"
					( Origin gPackager )
				)
				( objectStatus "J9B3.109" )
			)
			( pin "@baseboard_fab2_lib.baseboard_fab2(sch_1):page186_i336:io110"
				( attribute "PN" "110"
					( Origin gPackager )
				)
				( objectStatus "J9B3.110" )
			)
			( pin "@baseboard_fab2_lib.baseboard_fab2(sch_1):page186_i336:io111"
				( attribute "PN" "111"
					( Origin gPackager )
				)
				( objectStatus "J9B3.111" )
			)
			( pin "@baseboard_fab2_lib.baseboard_fab2(sch_1):page186_i336:io112"
				( attribute "PN" "112"
					( Origin gPackager )
				)
				( objectStatus "J9B3.112" )
			)
			( pin "@baseboard_fab2_lib.baseboard_fab2(sch_1):page186_i336:io113"
				( attribute "PN" "113"
					( Origin gPackager )
				)
				( objectStatus "J9B3.113" )
			)
			( pin "@baseboard_fab2_lib.baseboard_fab2(sch_1):page186_i336:io114"
				( attribute "PN" "114"
					( Origin gPackager )
				)
				( objectStatus "J9B3.114" )
			)
			( pin "@baseboard_fab2_lib.baseboard_fab2(sch_1):page186_i336:io115"
				( attribute "PN" "115"
					( Origin gPackager )
				)
				( objectStatus "J9B3.115" )
			)
			( pin "@baseboard_fab2_lib.baseboard_fab2(sch_1):page186_i336:io116"
				( attribute "PN" "116"
					( Origin gPackager )
				)
				( objectStatus "J9B3.116" )
			)
			( pin "@baseboard_fab2_lib.baseboard_fab2(sch_1):page186_i336:io117"
				( attribute "PN" "117"
					( Origin gPackager )
				)
				( objectStatus "J9B3.117" )
			)
			( pin "@baseboard_fab2_lib.baseboard_fab2(sch_1):page186_i336:io118"
				( attribute "PN" "118"
					( Origin gPackager )
				)
				( objectStatus "J9B3.118" )
			)
			( pin "@baseboard_fab2_lib.baseboard_fab2(sch_1):page186_i336:io119"
				( attribute "PN" "119"
					( Origin gPackager )
				)
				( objectStatus "J9B3.119" )
			)
			( pin "@baseboard_fab2_lib.baseboard_fab2(sch_1):page186_i336:io120"
				( attribute "PN" "120"
					( Origin gPackager )
				)
				( objectStatus "J9B3.120" )
			)
			( pin "@baseboard_fab2_lib.baseboard_fab2(sch_1):page186_i337:a"
				( attribute "PN" "1"
					( Origin gPackager )
				)
				( objectStatus "R1M16.1" )
			)
			( pin "@baseboard_fab2_lib.baseboard_fab2(sch_1):page186_i337:b"
				( attribute "PN" "2"
					( Origin gPackager )
				)
				( objectStatus "R1M16.2" )
			)
			( pin "@baseboard_fab2_lib.baseboard_fab2(sch_1):page186_i338:a"
				( attribute "PN" "1"
					( Origin gPackager )
				)
				( objectStatus "R1M17.1" )
			)
			( pin "@baseboard_fab2_lib.baseboard_fab2(sch_1):page186_i338:b"
				( attribute "PN" "2"
					( Origin gPackager )
				)
				( objectStatus "R1M17.2" )
			)
			( pin "@baseboard_fab2_lib.baseboard_fab2(sch_1):page186_i339:a"
				( attribute "PN" "1"
					( Origin gPackager )
				)
				( objectStatus "R1M15.1" )
			)
			( pin "@baseboard_fab2_lib.baseboard_fab2(sch_1):page186_i339:b"
				( attribute "PN" "2"
					( Origin gPackager )
				)
				( objectStatus "R1M15.2" )
			)
			( pin "@baseboard_fab2_lib.baseboard_fab2(sch_1):page186_i340:a"
				( attribute "PN" "1"
					( Origin gPackager )
				)
				( objectStatus "R1M18.1" )
			)
			( pin "@baseboard_fab2_lib.baseboard_fab2(sch_1):page186_i340:b"
				( attribute "PN" "2"
					( Origin gPackager )
				)
				( objectStatus "R1M18.2" )
			)
			( pin "@baseboard_fab2_lib.baseboard_fab2(sch_1):page186_i345:a"
				( attribute "PN" "1"
					( Origin gPackager )
				)
				( objectStatus "C9B10.1" )
			)
			( pin "@baseboard_fab2_lib.baseboard_fab2(sch_1):page186_i345:b"
				( attribute "PN" "2"
					( Origin gPackager )
				)
				( objectStatus "C9B10.2" )
			)
			( pin "@baseboard_fab2_lib.baseboard_fab2(sch_1):page209_i89:\1\"
				( attribute "PN" "1"
					( Origin gPackager )
				)
				( objectStatus "C1C18.1" )
			)
			( pin "@baseboard_fab2_lib.baseboard_fab2(sch_1):page209_i89:\2\"
				( attribute "PN" "2"
					( Origin gPackager )
				)
				( objectStatus "C1C18.2" )
			)
			( pin "@baseboard_fab2_lib.baseboard_fab2(sch_1):page187_i119:io1"
				( attribute "PN" "1"
					( Origin gPackager )
				)
				( objectStatus "J8E3.1" )
			)
			( pin "@baseboard_fab2_lib.baseboard_fab2(sch_1):page187_i119:io2"
				( attribute "PN" "2"
					( Origin gPackager )
				)
				( objectStatus "J8E3.2" )
			)
			( pin "@baseboard_fab2_lib.baseboard_fab2(sch_1):page187_i119:io3"
				( attribute "PN" "3"
					( Origin gPackager )
				)
				( objectStatus "J8E3.3" )
			)
			( pin "@baseboard_fab2_lib.baseboard_fab2(sch_1):page187_i119:io4"
				( attribute "PN" "4"
					( Origin gPackager )
				)
				( objectStatus "J8E3.4" )
			)
			( pin "@baseboard_fab2_lib.baseboard_fab2(sch_1):page187_i119:io5"
				( attribute "PN" "5"
					( Origin gPackager )
				)
				( objectStatus "J8E3.5" )
			)
			( pin "@baseboard_fab2_lib.baseboard_fab2(sch_1):page187_i119:io6"
				( attribute "PN" "6"
					( Origin gPackager )
				)
				( objectStatus "J8E3.6" )
			)
			( pin "@baseboard_fab2_lib.baseboard_fab2(sch_1):page187_i119:io7"
				( attribute "PN" "7"
					( Origin gPackager )
				)
				( objectStatus "J8E3.7" )
			)
			( pin "@baseboard_fab2_lib.baseboard_fab2(sch_1):page187_i119:io8"
				( attribute "PN" "8"
					( Origin gPackager )
				)
				( objectStatus "J8E3.8" )
			)
			( pin "@baseboard_fab2_lib.baseboard_fab2(sch_1):page187_i119:io9"
				( attribute "PN" "9"
					( Origin gPackager )
				)
				( objectStatus "J8E3.9" )
			)
			( pin "@baseboard_fab2_lib.baseboard_fab2(sch_1):page187_i119:io10"
				( attribute "PN" "10"
					( Origin gPackager )
				)
				( objectStatus "J8E3.10" )
			)
			( pin "@baseboard_fab2_lib.baseboard_fab2(sch_1):page187_i119:io11"
				( attribute "PN" "11"
					( Origin gPackager )
				)
				( objectStatus "J8E3.11" )
			)
			( pin "@baseboard_fab2_lib.baseboard_fab2(sch_1):page187_i119:io12"
				( attribute "PN" "12"
					( Origin gPackager )
				)
				( objectStatus "J8E3.12" )
			)
			( pin "@baseboard_fab2_lib.baseboard_fab2(sch_1):page187_i119:io13"
				( attribute "PN" "13"
					( Origin gPackager )
				)
				( objectStatus "J8E3.13" )
			)
			( pin "@baseboard_fab2_lib.baseboard_fab2(sch_1):page187_i119:io14"
				( attribute "PN" "14"
					( Origin gPackager )
				)
				( objectStatus "J8E3.14" )
			)
			( pin "@baseboard_fab2_lib.baseboard_fab2(sch_1):page187_i119:io15"
				( attribute "PN" "15"
					( Origin gPackager )
				)
				( objectStatus "J8E3.15" )
			)
			( pin "@baseboard_fab2_lib.baseboard_fab2(sch_1):page187_i119:io16"
				( attribute "PN" "16"
					( Origin gPackager )
				)
				( objectStatus "J8E3.16" )
			)
			( pin "@baseboard_fab2_lib.baseboard_fab2(sch_1):page187_i119:io17"
				( attribute "PN" "17"
					( Origin gPackager )
				)
				( objectStatus "J8E3.17" )
			)
			( pin "@baseboard_fab2_lib.baseboard_fab2(sch_1):page187_i119:io18"
				( attribute "PN" "18"
					( Origin gPackager )
				)
				( objectStatus "J8E3.18" )
			)
			( pin "@baseboard_fab2_lib.baseboard_fab2(sch_1):page187_i119:io19"
				( attribute "PN" "19"
					( Origin gPackager )
				)
				( objectStatus "J8E3.19" )
			)
			( pin "@baseboard_fab2_lib.baseboard_fab2(sch_1):page187_i119:io20"
				( attribute "PN" "20"
					( Origin gPackager )
				)
				( objectStatus "J8E3.20" )
			)
			( pin "@baseboard_fab2_lib.baseboard_fab2(sch_1):page187_i119:io21"
				( attribute "PN" "21"
					( Origin gPackager )
				)
				( objectStatus "J8E3.21" )
			)
			( pin "@baseboard_fab2_lib.baseboard_fab2(sch_1):page187_i119:io22"
				( attribute "PN" "22"
					( Origin gPackager )
				)
				( objectStatus "J8E3.22" )
			)
			( pin "@baseboard_fab2_lib.baseboard_fab2(sch_1):page187_i119:io23"
				( attribute "PN" "23"
					( Origin gPackager )
				)
				( objectStatus "J8E3.23" )
			)
			( pin "@baseboard_fab2_lib.baseboard_fab2(sch_1):page187_i119:io24"
				( attribute "PN" "24"
					( Origin gPackager )
				)
				( objectStatus "J8E3.24" )
			)
			( pin "@baseboard_fab2_lib.baseboard_fab2(sch_1):page187_i119:io25"
				( attribute "PN" "25"
					( Origin gPackager )
				)
				( objectStatus "J8E3.25" )
			)
			( pin "@baseboard_fab2_lib.baseboard_fab2(sch_1):page187_i119:io26"
				( attribute "PN" "26"
					( Origin gPackager )
				)
				( objectStatus "J8E3.26" )
			)
			( pin "@baseboard_fab2_lib.baseboard_fab2(sch_1):page187_i119:io27"
				( attribute "PN" "27"
					( Origin gPackager )
				)
				( objectStatus "J8E3.27" )
			)
			( pin "@baseboard_fab2_lib.baseboard_fab2(sch_1):page187_i119:io28"
				( attribute "PN" "28"
					( Origin gPackager )
				)
				( objectStatus "J8E3.28" )
			)
			( pin "@baseboard_fab2_lib.baseboard_fab2(sch_1):page187_i119:io29"
				( attribute "PN" "29"
					( Origin gPackager )
				)
				( objectStatus "J8E3.29" )
			)
			( pin "@baseboard_fab2_lib.baseboard_fab2(sch_1):page187_i119:io30"
				( attribute "PN" "30"
					( Origin gPackager )
				)
				( objectStatus "J8E3.30" )
			)
			( pin "@baseboard_fab2_lib.baseboard_fab2(sch_1):page187_i119:io31"
				( attribute "PN" "31"
					( Origin gPackager )
				)
				( objectStatus "J8E3.31" )
			)
			( pin "@baseboard_fab2_lib.baseboard_fab2(sch_1):page187_i119:io32"
				( attribute "PN" "32"
					( Origin gPackager )
				)
				( objectStatus "J8E3.32" )
			)
			( pin "@baseboard_fab2_lib.baseboard_fab2(sch_1):page187_i119:io33"
				( attribute "PN" "33"
					( Origin gPackager )
				)
				( objectStatus "J8E3.33" )
			)
			( pin "@baseboard_fab2_lib.baseboard_fab2(sch_1):page187_i119:io34"
				( attribute "PN" "34"
					( Origin gPackager )
				)
				( objectStatus "J8E3.34" )
			)
			( pin "@baseboard_fab2_lib.baseboard_fab2(sch_1):page187_i119:io35"
				( attribute "PN" "35"
					( Origin gPackager )
				)
				( objectStatus "J8E3.35" )
			)
			( pin "@baseboard_fab2_lib.baseboard_fab2(sch_1):page187_i119:io36"
				( attribute "PN" "36"
					( Origin gPackager )
				)
				( objectStatus "J8E3.36" )
			)
			( pin "@baseboard_fab2_lib.baseboard_fab2(sch_1):page187_i119:io37"
				( attribute "PN" "37"
					( Origin gPackager )
				)
				( objectStatus "J8E3.37" )
			)
			( pin "@baseboard_fab2_lib.baseboard_fab2(sch_1):page187_i119:io38"
				( attribute "PN" "38"
					( Origin gPackager )
				)
				( objectStatus "J8E3.38" )
			)
			( pin "@baseboard_fab2_lib.baseboard_fab2(sch_1):page187_i119:io39"
				( attribute "PN" "39"
					( Origin gPackager )
				)
				( objectStatus "J8E3.39" )
			)
			( pin "@baseboard_fab2_lib.baseboard_fab2(sch_1):page187_i119:io40"
				( attribute "PN" "40"
					( Origin gPackager )
				)
				( objectStatus "J8E3.40" )
			)
			( pin "@baseboard_fab2_lib.baseboard_fab2(sch_1):page187_i119:io41"
				( attribute "PN" "41"
					( Origin gPackager )
				)
				( objectStatus "J8E3.41" )
			)
			( pin "@baseboard_fab2_lib.baseboard_fab2(sch_1):page187_i119:io42"
				( attribute "PN" "42"
					( Origin gPackager )
				)
				( objectStatus "J8E3.42" )
			)
			( pin "@baseboard_fab2_lib.baseboard_fab2(sch_1):page187_i119:io43"
				( attribute "PN" "43"
					( Origin gPackager )
				)
				( objectStatus "J8E3.43" )
			)
			( pin "@baseboard_fab2_lib.baseboard_fab2(sch_1):page187_i119:io44"
				( attribute "PN" "44"
					( Origin gPackager )
				)
				( objectStatus "J8E3.44" )
			)
			( pin "@baseboard_fab2_lib.baseboard_fab2(sch_1):page187_i119:io45"
				( attribute "PN" "45"
					( Origin gPackager )
				)
				( objectStatus "J8E3.45" )
			)
			( pin "@baseboard_fab2_lib.baseboard_fab2(sch_1):page187_i119:io46"
				( attribute "PN" "46"
					( Origin gPackager )
				)
				( objectStatus "J8E3.46" )
			)
			( pin "@baseboard_fab2_lib.baseboard_fab2(sch_1):page187_i119:io47"
				( attribute "PN" "47"
					( Origin gPackager )
				)
				( objectStatus "J8E3.47" )
			)
			( pin "@baseboard_fab2_lib.baseboard_fab2(sch_1):page187_i119:io48"
				( attribute "PN" "48"
					( Origin gPackager )
				)
				( objectStatus "J8E3.48" )
			)
			( pin "@baseboard_fab2_lib.baseboard_fab2(sch_1):page187_i119:io49"
				( attribute "PN" "49"
					( Origin gPackager )
				)
				( objectStatus "J8E3.49" )
			)
			( pin "@baseboard_fab2_lib.baseboard_fab2(sch_1):page187_i119:io50"
				( attribute "PN" "50"
					( Origin gPackager )
				)
				( objectStatus "J8E3.50" )
			)
			( pin "@baseboard_fab2_lib.baseboard_fab2(sch_1):page187_i119:io51"
				( attribute "PN" "51"
					( Origin gPackager )
				)
				( objectStatus "J8E3.51" )
			)
			( pin "@baseboard_fab2_lib.baseboard_fab2(sch_1):page187_i119:io52"
				( attribute "PN" "52"
					( Origin gPackager )
				)
				( objectStatus "J8E3.52" )
			)
			( pin "@baseboard_fab2_lib.baseboard_fab2(sch_1):page187_i119:io53"
				( attribute "PN" "53"
					( Origin gPackager )
				)
				( objectStatus "J8E3.53" )
			)
			( pin "@baseboard_fab2_lib.baseboard_fab2(sch_1):page187_i119:io54"
				( attribute "PN" "54"
					( Origin gPackager )
				)
				( objectStatus "J8E3.54" )
			)
			( pin "@baseboard_fab2_lib.baseboard_fab2(sch_1):page187_i119:io55"
				( attribute "PN" "55"
					( Origin gPackager )
				)
				( objectStatus "J8E3.55" )
			)
			( pin "@baseboard_fab2_lib.baseboard_fab2(sch_1):page187_i119:io56"
				( attribute "PN" "56"
					( Origin gPackager )
				)
				( objectStatus "J8E3.56" )
			)
			( pin "@baseboard_fab2_lib.baseboard_fab2(sch_1):page187_i119:io57"
				( attribute "PN" "57"
					( Origin gPackager )
				)
				( objectStatus "J8E3.57" )
			)
			( pin "@baseboard_fab2_lib.baseboard_fab2(sch_1):page187_i119:io58"
				( attribute "PN" "58"
					( Origin gPackager )
				)
				( objectStatus "J8E3.58" )
			)
			( pin "@baseboard_fab2_lib.baseboard_fab2(sch_1):page187_i119:io59"
				( attribute "PN" "59"
					( Origin gPackager )
				)
				( objectStatus "J8E3.59" )
			)
			( pin "@baseboard_fab2_lib.baseboard_fab2(sch_1):page187_i119:io60"
				( attribute "PN" "60"
					( Origin gPackager )
				)
				( objectStatus "J8E3.60" )
			)
			( pin "@baseboard_fab2_lib.baseboard_fab2(sch_1):page187_i119:io61"
				( attribute "PN" "61"
					( Origin gPackager )
				)
				( objectStatus "J8E3.61" )
			)
			( pin "@baseboard_fab2_lib.baseboard_fab2(sch_1):page187_i119:io62"
				( attribute "PN" "62"
					( Origin gPackager )
				)
				( objectStatus "J8E3.62" )
			)
			( pin "@baseboard_fab2_lib.baseboard_fab2(sch_1):page187_i119:io63"
				( attribute "PN" "63"
					( Origin gPackager )
				)
				( objectStatus "J8E3.63" )
			)
			( pin "@baseboard_fab2_lib.baseboard_fab2(sch_1):page187_i119:io64"
				( attribute "PN" "64"
					( Origin gPackager )
				)
				( objectStatus "J8E3.64" )
			)
			( pin "@baseboard_fab2_lib.baseboard_fab2(sch_1):page187_i119:io65"
				( attribute "PN" "65"
					( Origin gPackager )
				)
				( objectStatus "J8E3.65" )
			)
			( pin "@baseboard_fab2_lib.baseboard_fab2(sch_1):page187_i119:io66"
				( attribute "PN" "66"
					( Origin gPackager )
				)
				( objectStatus "J8E3.66" )
			)
			( pin "@baseboard_fab2_lib.baseboard_fab2(sch_1):page187_i119:io67"
				( attribute "PN" "67"
					( Origin gPackager )
				)
				( objectStatus "J8E3.67" )
			)
			( pin "@baseboard_fab2_lib.baseboard_fab2(sch_1):page187_i119:io68"
				( attribute "PN" "68"
					( Origin gPackager )
				)
				( objectStatus "J8E3.68" )
			)
			( pin "@baseboard_fab2_lib.baseboard_fab2(sch_1):page187_i119:io69"
				( attribute "PN" "69"
					( Origin gPackager )
				)
				( objectStatus "J8E3.69" )
			)
			( pin "@baseboard_fab2_lib.baseboard_fab2(sch_1):page187_i119:io70"
				( attribute "PN" "70"
					( Origin gPackager )
				)
				( objectStatus "J8E3.70" )
			)
			( pin "@baseboard_fab2_lib.baseboard_fab2(sch_1):page187_i119:io71"
				( attribute "PN" "71"
					( Origin gPackager )
				)
				( objectStatus "J8E3.71" )
			)
			( pin "@baseboard_fab2_lib.baseboard_fab2(sch_1):page187_i119:io72"
				( attribute "PN" "72"
					( Origin gPackager )
				)
				( objectStatus "J8E3.72" )
			)
			( pin "@baseboard_fab2_lib.baseboard_fab2(sch_1):page187_i119:io73"
				( attribute "PN" "73"
					( Origin gPackager )
				)
				( objectStatus "J8E3.73" )
			)
			( pin "@baseboard_fab2_lib.baseboard_fab2(sch_1):page187_i119:io74"
				( attribute "PN" "74"
					( Origin gPackager )
				)
				( objectStatus "J8E3.74" )
			)
			( pin "@baseboard_fab2_lib.baseboard_fab2(sch_1):page187_i119:io75"
				( attribute "PN" "75"
					( Origin gPackager )
				)
				( objectStatus "J8E3.75" )
			)
			( pin "@baseboard_fab2_lib.baseboard_fab2(sch_1):page187_i119:io76"
				( attribute "PN" "76"
					( Origin gPackager )
				)
				( objectStatus "J8E3.76" )
			)
			( pin "@baseboard_fab2_lib.baseboard_fab2(sch_1):page187_i119:io77"
				( attribute "PN" "77"
					( Origin gPackager )
				)
				( objectStatus "J8E3.77" )
			)
			( pin "@baseboard_fab2_lib.baseboard_fab2(sch_1):page187_i119:io78"
				( attribute "PN" "78"
					( Origin gPackager )
				)
				( objectStatus "J8E3.78" )
			)
			( pin "@baseboard_fab2_lib.baseboard_fab2(sch_1):page187_i119:io79"
				( attribute "PN" "79"
					( Origin gPackager )
				)
				( objectStatus "J8E3.79" )
			)
			( pin "@baseboard_fab2_lib.baseboard_fab2(sch_1):page187_i119:io80"
				( attribute "PN" "80"
					( Origin gPackager )
				)
				( objectStatus "J8E3.80" )
			)
			( pin "@baseboard_fab2_lib.baseboard_fab2(sch_1):page187_i145:a"
				( attribute "PN" "1"
					( Origin gPackager )
				)
				( objectStatus "R9E10.1" )
			)
			( pin "@baseboard_fab2_lib.baseboard_fab2(sch_1):page187_i145:b"
				( attribute "PN" "2"
					( Origin gPackager )
				)
				( objectStatus "R9E10.2" )
			)
			( pin "@baseboard_fab2_lib.baseboard_fab2(sch_1):page187_i150:a"
				( attribute "PN" "1"
					( Origin gPackager )
				)
				( objectStatus "R9E11.1" )
			)
			( pin "@baseboard_fab2_lib.baseboard_fab2(sch_1):page187_i150:b"
				( attribute "PN" "2"
					( Origin gPackager )
				)
				( objectStatus "R9E11.2" )
			)
			( pin "@baseboard_fab2_lib.baseboard_fab2(sch_1):page187_i153:a"
				( attribute "PN" "1"
					( Origin gPackager )
				)
				( objectStatus "R9E12.1" )
			)
			( pin "@baseboard_fab2_lib.baseboard_fab2(sch_1):page187_i153:b"
				( attribute "PN" "2"
					( Origin gPackager )
				)
				( objectStatus "R9E12.2" )
			)
			( pin "@baseboard_fab2_lib.baseboard_fab2(sch_1):page188_i2:a"
				( attribute "PN" "1"
					( Origin gPackager )
				)
				( objectStatus "C2R15.1" )
			)
			( pin "@baseboard_fab2_lib.baseboard_fab2(sch_1):page188_i2:b"
				( attribute "PN" "2"
					( Origin gPackager )
				)
				( objectStatus "C2R15.2" )
			)
			( pin "@baseboard_fab2_lib.baseboard_fab2(sch_1):page188_i3:a"
				( attribute "PN" "1"
					( Origin gPackager )
				)
				( objectStatus "C2R18.1" )
			)
			( pin "@baseboard_fab2_lib.baseboard_fab2(sch_1):page188_i3:b"
				( attribute "PN" "2"
					( Origin gPackager )
				)
				( objectStatus "C2R18.2" )
			)
			( pin "@baseboard_fab2_lib.baseboard_fab2(sch_1):page188_i21:a"
				( attribute "PN" "1"
					( Origin gPackager )
				)
				( objectStatus "C2P11.1" )
			)
			( pin "@baseboard_fab2_lib.baseboard_fab2(sch_1):page188_i21:b"
				( attribute "PN" "2"
					( Origin gPackager )
				)
				( objectStatus "C2P11.2" )
			)
			( pin "@baseboard_fab2_lib.baseboard_fab2(sch_1):page188_i23:a"
				( attribute "PN" "1"
					( Origin gPackager )
				)
				( objectStatus "C2P12.1" )
			)
			( pin "@baseboard_fab2_lib.baseboard_fab2(sch_1):page188_i23:b"
				( attribute "PN" "2"
					( Origin gPackager )
				)
				( objectStatus "C2P12.2" )
			)
			( pin "@baseboard_fab2_lib.baseboard_fab2(sch_1):page188_i25:a"
				( attribute "PN" "1"
					( Origin gPackager )
				)
				( objectStatus "C2R17.1" )
			)
			( pin "@baseboard_fab2_lib.baseboard_fab2(sch_1):page188_i25:b"
				( attribute "PN" "2"
					( Origin gPackager )
				)
				( objectStatus "C2R17.2" )
			)
			( pin "@baseboard_fab2_lib.baseboard_fab2(sch_1):page188_i27:io1"
				( attribute "PN" "1"
					( Origin gPackager )
				)
				( objectStatus "J8E4.1" )
			)
			( pin "@baseboard_fab2_lib.baseboard_fab2(sch_1):page188_i27:io2"
				( attribute "PN" "2"
					( Origin gPackager )
				)
				( objectStatus "J8E4.2" )
			)
			( pin "@baseboard_fab2_lib.baseboard_fab2(sch_1):page188_i27:io3"
				( attribute "PN" "3"
					( Origin gPackager )
				)
				( objectStatus "J8E4.3" )
			)
			( pin "@baseboard_fab2_lib.baseboard_fab2(sch_1):page188_i27:io4"
				( attribute "PN" "4"
					( Origin gPackager )
				)
				( objectStatus "J8E4.4" )
			)
			( pin "@baseboard_fab2_lib.baseboard_fab2(sch_1):page188_i27:io5"
				( attribute "PN" "5"
					( Origin gPackager )
				)
				( objectStatus "J8E4.5" )
			)
			( pin "@baseboard_fab2_lib.baseboard_fab2(sch_1):page188_i27:io6"
				( attribute "PN" "6"
					( Origin gPackager )
				)
				( objectStatus "J8E4.6" )
			)
			( pin "@baseboard_fab2_lib.baseboard_fab2(sch_1):page188_i27:io7"
				( attribute "PN" "7"
					( Origin gPackager )
				)
				( objectStatus "J8E4.7" )
			)
			( pin "@baseboard_fab2_lib.baseboard_fab2(sch_1):page188_i27:io8"
				( attribute "PN" "8"
					( Origin gPackager )
				)
				( objectStatus "J8E4.8" )
			)
			( pin "@baseboard_fab2_lib.baseboard_fab2(sch_1):page188_i27:io9"
				( attribute "PN" "9"
					( Origin gPackager )
				)
				( objectStatus "J8E4.9" )
			)
			( pin "@baseboard_fab2_lib.baseboard_fab2(sch_1):page188_i27:io10"
				( attribute "PN" "10"
					( Origin gPackager )
				)
				( objectStatus "J8E4.10" )
			)
			( pin "@baseboard_fab2_lib.baseboard_fab2(sch_1):page188_i27:io11"
				( attribute "PN" "11"
					( Origin gPackager )
				)
				( objectStatus "J8E4.11" )
			)
			( pin "@baseboard_fab2_lib.baseboard_fab2(sch_1):page188_i27:io12"
				( attribute "PN" "12"
					( Origin gPackager )
				)
				( objectStatus "J8E4.12" )
			)
			( pin "@baseboard_fab2_lib.baseboard_fab2(sch_1):page188_i27:io13"
				( attribute "PN" "13"
					( Origin gPackager )
				)
				( objectStatus "J8E4.13" )
			)
			( pin "@baseboard_fab2_lib.baseboard_fab2(sch_1):page188_i27:io14"
				( attribute "PN" "14"
					( Origin gPackager )
				)
				( objectStatus "J8E4.14" )
			)
			( pin "@baseboard_fab2_lib.baseboard_fab2(sch_1):page188_i27:io15"
				( attribute "PN" "15"
					( Origin gPackager )
				)
				( objectStatus "J8E4.15" )
			)
			( pin "@baseboard_fab2_lib.baseboard_fab2(sch_1):page188_i27:io16"
				( attribute "PN" "16"
					( Origin gPackager )
				)
				( objectStatus "J8E4.16" )
			)
			( pin "@baseboard_fab2_lib.baseboard_fab2(sch_1):page188_i27:io17"
				( attribute "PN" "17"
					( Origin gPackager )
				)
				( objectStatus "J8E4.17" )
			)
			( pin "@baseboard_fab2_lib.baseboard_fab2(sch_1):page188_i27:io18"
				( attribute "PN" "18"
					( Origin gPackager )
				)
				( objectStatus "J8E4.18" )
			)
			( pin "@baseboard_fab2_lib.baseboard_fab2(sch_1):page188_i27:io19"
				( attribute "PN" "19"
					( Origin gPackager )
				)
				( objectStatus "J8E4.19" )
			)
			( pin "@baseboard_fab2_lib.baseboard_fab2(sch_1):page188_i27:io20"
				( attribute "PN" "20"
					( Origin gPackager )
				)
				( objectStatus "J8E4.20" )
			)
			( pin "@baseboard_fab2_lib.baseboard_fab2(sch_1):page188_i27:io21"
				( attribute "PN" "21"
					( Origin gPackager )
				)
				( objectStatus "J8E4.21" )
			)
			( pin "@baseboard_fab2_lib.baseboard_fab2(sch_1):page188_i27:io22"
				( attribute "PN" "22"
					( Origin gPackager )
				)
				( objectStatus "J8E4.22" )
			)
			( pin "@baseboard_fab2_lib.baseboard_fab2(sch_1):page188_i27:io23"
				( attribute "PN" "23"
					( Origin gPackager )
				)
				( objectStatus "J8E4.23" )
			)
			( pin "@baseboard_fab2_lib.baseboard_fab2(sch_1):page188_i27:io24"
				( attribute "PN" "24"
					( Origin gPackager )
				)
				( objectStatus "J8E4.24" )
			)
			( pin "@baseboard_fab2_lib.baseboard_fab2(sch_1):page188_i27:io25"
				( attribute "PN" "25"
					( Origin gPackager )
				)
				( objectStatus "J8E4.25" )
			)
			( pin "@baseboard_fab2_lib.baseboard_fab2(sch_1):page188_i27:io26"
				( attribute "PN" "26"
					( Origin gPackager )
				)
				( objectStatus "J8E4.26" )
			)
			( pin "@baseboard_fab2_lib.baseboard_fab2(sch_1):page188_i27:io27"
				( attribute "PN" "27"
					( Origin gPackager )
				)
				( objectStatus "J8E4.27" )
			)
			( pin "@baseboard_fab2_lib.baseboard_fab2(sch_1):page188_i27:io28"
				( attribute "PN" "28"
					( Origin gPackager )
				)
				( objectStatus "J8E4.28" )
			)
			( pin "@baseboard_fab2_lib.baseboard_fab2(sch_1):page188_i27:io29"
				( attribute "PN" "29"
					( Origin gPackager )
				)
				( objectStatus "J8E4.29" )
			)
			( pin "@baseboard_fab2_lib.baseboard_fab2(sch_1):page188_i27:io30"
				( attribute "PN" "30"
					( Origin gPackager )
				)
				( objectStatus "J8E4.30" )
			)
			( pin "@baseboard_fab2_lib.baseboard_fab2(sch_1):page188_i27:io31"
				( attribute "PN" "31"
					( Origin gPackager )
				)
				( objectStatus "J8E4.31" )
			)
			( pin "@baseboard_fab2_lib.baseboard_fab2(sch_1):page188_i27:io32"
				( attribute "PN" "32"
					( Origin gPackager )
				)
				( objectStatus "J8E4.32" )
			)
			( pin "@baseboard_fab2_lib.baseboard_fab2(sch_1):page188_i27:io33"
				( attribute "PN" "33"
					( Origin gPackager )
				)
				( objectStatus "J8E4.33" )
			)
			( pin "@baseboard_fab2_lib.baseboard_fab2(sch_1):page188_i27:io34"
				( attribute "PN" "34"
					( Origin gPackager )
				)
				( objectStatus "J8E4.34" )
			)
			( pin "@baseboard_fab2_lib.baseboard_fab2(sch_1):page188_i27:io35"
				( attribute "PN" "35"
					( Origin gPackager )
				)
				( objectStatus "J8E4.35" )
			)
			( pin "@baseboard_fab2_lib.baseboard_fab2(sch_1):page188_i27:io36"
				( attribute "PN" "36"
					( Origin gPackager )
				)
				( objectStatus "J8E4.36" )
			)
			( pin "@baseboard_fab2_lib.baseboard_fab2(sch_1):page188_i27:io37"
				( attribute "PN" "37"
					( Origin gPackager )
				)
				( objectStatus "J8E4.37" )
			)
			( pin "@baseboard_fab2_lib.baseboard_fab2(sch_1):page188_i27:io38"
				( attribute "PN" "38"
					( Origin gPackager )
				)
				( objectStatus "J8E4.38" )
			)
			( pin "@baseboard_fab2_lib.baseboard_fab2(sch_1):page188_i27:io39"
				( attribute "PN" "39"
					( Origin gPackager )
				)
				( objectStatus "J8E4.39" )
			)
			( pin "@baseboard_fab2_lib.baseboard_fab2(sch_1):page188_i27:io40"
				( attribute "PN" "40"
					( Origin gPackager )
				)
				( objectStatus "J8E4.40" )
			)
			( pin "@baseboard_fab2_lib.baseboard_fab2(sch_1):page188_i27:io41"
				( attribute "PN" "41"
					( Origin gPackager )
				)
				( objectStatus "J8E4.41" )
			)
			( pin "@baseboard_fab2_lib.baseboard_fab2(sch_1):page188_i27:io42"
				( attribute "PN" "42"
					( Origin gPackager )
				)
				( objectStatus "J8E4.42" )
			)
			( pin "@baseboard_fab2_lib.baseboard_fab2(sch_1):page188_i27:io43"
				( attribute "PN" "43"
					( Origin gPackager )
				)
				( objectStatus "J8E4.43" )
			)
			( pin "@baseboard_fab2_lib.baseboard_fab2(sch_1):page188_i27:io44"
				( attribute "PN" "44"
					( Origin gPackager )
				)
				( objectStatus "J8E4.44" )
			)
			( pin "@baseboard_fab2_lib.baseboard_fab2(sch_1):page188_i27:io45"
				( attribute "PN" "45"
					( Origin gPackager )
				)
				( objectStatus "J8E4.45" )
			)
			( pin "@baseboard_fab2_lib.baseboard_fab2(sch_1):page188_i27:io46"
				( attribute "PN" "46"
					( Origin gPackager )
				)
				( objectStatus "J8E4.46" )
			)
			( pin "@baseboard_fab2_lib.baseboard_fab2(sch_1):page188_i27:io47"
				( attribute "PN" "47"
					( Origin gPackager )
				)
				( objectStatus "J8E4.47" )
			)
			( pin "@baseboard_fab2_lib.baseboard_fab2(sch_1):page188_i27:io48"
				( attribute "PN" "48"
					( Origin gPackager )
				)
				( objectStatus "J8E4.48" )
			)
			( pin "@baseboard_fab2_lib.baseboard_fab2(sch_1):page188_i27:io49"
				( attribute "PN" "49"
					( Origin gPackager )
				)
				( objectStatus "J8E4.49" )
			)
			( pin "@baseboard_fab2_lib.baseboard_fab2(sch_1):page188_i27:io50"
				( attribute "PN" "50"
					( Origin gPackager )
				)
				( objectStatus "J8E4.50" )
			)
			( pin "@baseboard_fab2_lib.baseboard_fab2(sch_1):page188_i27:io51"
				( attribute "PN" "51"
					( Origin gPackager )
				)
				( objectStatus "J8E4.51" )
			)
			( pin "@baseboard_fab2_lib.baseboard_fab2(sch_1):page188_i27:io52"
				( attribute "PN" "52"
					( Origin gPackager )
				)
				( objectStatus "J8E4.52" )
			)
			( pin "@baseboard_fab2_lib.baseboard_fab2(sch_1):page188_i27:io53"
				( attribute "PN" "53"
					( Origin gPackager )
				)
				( objectStatus "J8E4.53" )
			)
			( pin "@baseboard_fab2_lib.baseboard_fab2(sch_1):page188_i27:io54"
				( attribute "PN" "54"
					( Origin gPackager )
				)
				( objectStatus "J8E4.54" )
			)
			( pin "@baseboard_fab2_lib.baseboard_fab2(sch_1):page188_i27:io55"
				( attribute "PN" "55"
					( Origin gPackager )
				)
				( objectStatus "J8E4.55" )
			)
			( pin "@baseboard_fab2_lib.baseboard_fab2(sch_1):page188_i27:io56"
				( attribute "PN" "56"
					( Origin gPackager )
				)
				( objectStatus "J8E4.56" )
			)
			( pin "@baseboard_fab2_lib.baseboard_fab2(sch_1):page188_i27:io57"
				( attribute "PN" "57"
					( Origin gPackager )
				)
				( objectStatus "J8E4.57" )
			)
			( pin "@baseboard_fab2_lib.baseboard_fab2(sch_1):page188_i27:io58"
				( attribute "PN" "58"
					( Origin gPackager )
				)
				( objectStatus "J8E4.58" )
			)
			( pin "@baseboard_fab2_lib.baseboard_fab2(sch_1):page188_i27:io59"
				( attribute "PN" "59"
					( Origin gPackager )
				)
				( objectStatus "J8E4.59" )
			)
			( pin "@baseboard_fab2_lib.baseboard_fab2(sch_1):page188_i27:io60"
				( attribute "PN" "60"
					( Origin gPackager )
				)
				( objectStatus "J8E4.60" )
			)
			( pin "@baseboard_fab2_lib.baseboard_fab2(sch_1):page188_i27:io61"
				( attribute "PN" "61"
					( Origin gPackager )
				)
				( objectStatus "J8E4.61" )
			)
			( pin "@baseboard_fab2_lib.baseboard_fab2(sch_1):page188_i27:io62"
				( attribute "PN" "62"
					( Origin gPackager )
				)
				( objectStatus "J8E4.62" )
			)
			( pin "@baseboard_fab2_lib.baseboard_fab2(sch_1):page188_i27:io63"
				( attribute "PN" "63"
					( Origin gPackager )
				)
				( objectStatus "J8E4.63" )
			)
			( pin "@baseboard_fab2_lib.baseboard_fab2(sch_1):page188_i27:io64"
				( attribute "PN" "64"
					( Origin gPackager )
				)
				( objectStatus "J8E4.64" )
			)
			( pin "@baseboard_fab2_lib.baseboard_fab2(sch_1):page188_i40:a"
				( attribute "PN" "1"
					( Origin gPackager )
				)
				( objectStatus "C2R16.1" )
			)
			( pin "@baseboard_fab2_lib.baseboard_fab2(sch_1):page188_i40:b"
				( attribute "PN" "2"
					( Origin gPackager )
				)
				( objectStatus "C2R16.2" )
			)
			( pin "@baseboard_fab2_lib.baseboard_fab2(sch_1):page188_i41:a"
				( attribute "PN" "1"
					( Origin gPackager )
				)
				( objectStatus "C2P10.1" )
			)
			( pin "@baseboard_fab2_lib.baseboard_fab2(sch_1):page188_i41:b"
				( attribute "PN" "2"
					( Origin gPackager )
				)
				( objectStatus "C2P10.2" )
			)
			( pin "@baseboard_fab2_lib.baseboard_fab2(sch_1):page188_i53:a"
				( attribute "PN" "1"
					( Origin gPackager )
				)
				( objectStatus "C2P16.1" )
			)
			( pin "@baseboard_fab2_lib.baseboard_fab2(sch_1):page188_i53:b"
				( attribute "PN" "2"
					( Origin gPackager )
				)
				( objectStatus "C2P16.2" )
			)
			( pin "@baseboard_fab2_lib.baseboard_fab2(sch_1):page188_i55:a"
				( attribute "PN" "1"
					( Origin gPackager )
				)
				( objectStatus "C2P15.1" )
			)
			( pin "@baseboard_fab2_lib.baseboard_fab2(sch_1):page188_i55:b"
				( attribute "PN" "2"
					( Origin gPackager )
				)
				( objectStatus "C2P15.2" )
			)
			( pin "@baseboard_fab2_lib.baseboard_fab2(sch_1):page188_i56:a"
				( attribute "PN" "1"
					( Origin gPackager )
				)
				( objectStatus "C2P14.1" )
			)
			( pin "@baseboard_fab2_lib.baseboard_fab2(sch_1):page188_i56:b"
				( attribute "PN" "2"
					( Origin gPackager )
				)
				( objectStatus "C2P14.2" )
			)
			( pin "@baseboard_fab2_lib.baseboard_fab2(sch_1):page188_i57:a"
				( attribute "PN" "1"
					( Origin gPackager )
				)
				( objectStatus "C2P13.1" )
			)
			( pin "@baseboard_fab2_lib.baseboard_fab2(sch_1):page188_i57:b"
				( attribute "PN" "2"
					( Origin gPackager )
				)
				( objectStatus "C2P13.2" )
			)
			( pin "@baseboard_fab2_lib.baseboard_fab2(sch_1):page188_i82:a"
				( attribute "PN" "1"
					( Origin gPackager )
				)
				( objectStatus "C8C15.1" )
			)
			( pin "@baseboard_fab2_lib.baseboard_fab2(sch_1):page188_i82:b"
				( attribute "PN" "2"
					( Origin gPackager )
				)
				( objectStatus "C8C15.2" )
			)
			( pin "@baseboard_fab2_lib.baseboard_fab2(sch_1):page188_i86:a"
				( attribute "PN" "1"
					( Origin gPackager )
				)
				( objectStatus "C8C14.1" )
			)
			( pin "@baseboard_fab2_lib.baseboard_fab2(sch_1):page188_i86:b"
				( attribute "PN" "2"
					( Origin gPackager )
				)
				( objectStatus "C8C14.2" )
			)
			( pin "@baseboard_fab2_lib.baseboard_fab2(sch_1):page188_i88:a"
				( attribute "PN" "1"
					( Origin gPackager )
				)
				( objectStatus "R1R18.1" )
			)
			( pin "@baseboard_fab2_lib.baseboard_fab2(sch_1):page188_i88:b"
				( attribute "PN" "2"
					( Origin gPackager )
				)
				( objectStatus "R1R18.2" )
			)
			( pin "@baseboard_fab2_lib.baseboard_fab2(sch_1):page188_i89:a"
				( attribute "PN" "1"
					( Origin gPackager )
				)
				( objectStatus "R1R19.1" )
			)
			( pin "@baseboard_fab2_lib.baseboard_fab2(sch_1):page188_i89:b"
				( attribute "PN" "2"
					( Origin gPackager )
				)
				( objectStatus "R1R19.2" )
			)
			( pin "@baseboard_fab2_lib.baseboard_fab2(sch_1):page188_i90:a"
				( attribute "PN" "1"
					( Origin gPackager )
				)
				( objectStatus "R1R21.1" )
			)
			( pin "@baseboard_fab2_lib.baseboard_fab2(sch_1):page188_i90:b"
				( attribute "PN" "2"
					( Origin gPackager )
				)
				( objectStatus "R1R21.2" )
			)
			( pin "@baseboard_fab2_lib.baseboard_fab2(sch_1):page188_i91:a"
				( attribute "PN" "1"
					( Origin gPackager )
				)
				( objectStatus "R1R20.1" )
			)
			( pin "@baseboard_fab2_lib.baseboard_fab2(sch_1):page188_i91:b"
				( attribute "PN" "2"
					( Origin gPackager )
				)
				( objectStatus "R1R20.2" )
			)
			( pin "@baseboard_fab2_lib.baseboard_fab2(sch_1):page188_i92:a"
				( attribute "PN" "1"
					( Origin gPackager )
				)
				( objectStatus "R1R22.1" )
			)
			( pin "@baseboard_fab2_lib.baseboard_fab2(sch_1):page188_i92:b"
				( attribute "PN" "2"
					( Origin gPackager )
				)
				( objectStatus "R1R22.2" )
			)
			( pin "@baseboard_fab2_lib.baseboard_fab2(sch_1):page188_i93:a"
				( attribute "PN" "1"
					( Origin gPackager )
				)
				( objectStatus "R1R16.1" )
			)
			( pin "@baseboard_fab2_lib.baseboard_fab2(sch_1):page188_i93:b"
				( attribute "PN" "2"
					( Origin gPackager )
				)
				( objectStatus "R1R16.2" )
			)
			( pin "@baseboard_fab2_lib.baseboard_fab2(sch_1):page188_i94:a"
				( attribute "PN" "1"
					( Origin gPackager )
				)
				( objectStatus "R1R17.1" )
			)
			( pin "@baseboard_fab2_lib.baseboard_fab2(sch_1):page188_i94:b"
				( attribute "PN" "2"
					( Origin gPackager )
				)
				( objectStatus "R1R17.2" )
			)
			( pin "@baseboard_fab2_lib.baseboard_fab2(sch_1):page188_i95:a"
				( attribute "PN" "1"
					( Origin gPackager )
				)
				( objectStatus "R1R23.1" )
			)
			( pin "@baseboard_fab2_lib.baseboard_fab2(sch_1):page188_i95:b"
				( attribute "PN" "2"
					( Origin gPackager )
				)
				( objectStatus "R1R23.2" )
			)
			( pin "@baseboard_fab2_lib.baseboard_fab2(sch_1):page189_i7:a"
				( attribute "PN" "1"
					( Origin gPackager )
				)
				( objectStatus "R8G10.1" )
			)
			( pin "@baseboard_fab2_lib.baseboard_fab2(sch_1):page189_i7:b"
				( attribute "PN" "2"
					( Origin gPackager )
				)
				( objectStatus "R8G10.2" )
			)
			( pin "@baseboard_fab2_lib.baseboard_fab2(sch_1):page189_i8:a"
				( attribute "PN" "1"
					( Origin gPackager )
				)
				( objectStatus "R7G19.1" )
			)
			( pin "@baseboard_fab2_lib.baseboard_fab2(sch_1):page189_i8:b"
				( attribute "PN" "2"
					( Origin gPackager )
				)
				( objectStatus "R7G19.2" )
			)
			( pin "@baseboard_fab2_lib.baseboard_fab2(sch_1):page189_i9:a"
				( attribute "PN" "1"
					( Origin gPackager )
				)
				( objectStatus "R8G9.1" )
			)
			( pin "@baseboard_fab2_lib.baseboard_fab2(sch_1):page189_i9:b"
				( attribute "PN" "2"
					( Origin gPackager )
				)
				( objectStatus "R8G9.2" )
			)
			( pin "@baseboard_fab2_lib.baseboard_fab2(sch_1):page189_i13:a"
				( attribute "PN" "1"
					( Origin gPackager )
				)
				( objectStatus "R7G18.1" )
			)
			( pin "@baseboard_fab2_lib.baseboard_fab2(sch_1):page189_i13:b"
				( attribute "PN" "2"
					( Origin gPackager )
				)
				( objectStatus "R7G18.2" )
			)
			( pin "@baseboard_fab2_lib.baseboard_fab2(sch_1):page189_i17:a"
				( attribute "PN" "1"
					( Origin gPackager )
				)
				( objectStatus "R8G8.1" )
			)
			( pin "@baseboard_fab2_lib.baseboard_fab2(sch_1):page189_i17:b"
				( attribute "PN" "2"
					( Origin gPackager )
				)
				( objectStatus "R8G8.2" )
			)
			( pin "@baseboard_fab2_lib.baseboard_fab2(sch_1):page189_i18:a"
				( attribute "PN" "1"
					( Origin gPackager )
				)
				( objectStatus "R8G7.1" )
			)
			( pin "@baseboard_fab2_lib.baseboard_fab2(sch_1):page189_i18:b"
				( attribute "PN" "2"
					( Origin gPackager )
				)
				( objectStatus "R8G7.2" )
			)
			( pin "@baseboard_fab2_lib.baseboard_fab2(sch_1):page189_i19:a"
				( attribute "PN" "1"
					( Origin gPackager )
				)
				( objectStatus "R8G11.1" )
			)
			( pin "@baseboard_fab2_lib.baseboard_fab2(sch_1):page189_i19:b"
				( attribute "PN" "2"
					( Origin gPackager )
				)
				( objectStatus "R8G11.2" )
			)
			( pin "@baseboard_fab2_lib.baseboard_fab2(sch_1):page189_i20:a"
				( attribute "PN" "1"
					( Origin gPackager )
				)
				( objectStatus "R8G14.1" )
			)
			( pin "@baseboard_fab2_lib.baseboard_fab2(sch_1):page189_i20:b"
				( attribute "PN" "2"
					( Origin gPackager )
				)
				( objectStatus "R8G14.2" )
			)
			( pin "@baseboard_fab2_lib.baseboard_fab2(sch_1):page189_i21:a"
				( attribute "PN" "1"
					( Origin gPackager )
				)
				( objectStatus "R8G12.1" )
			)
			( pin "@baseboard_fab2_lib.baseboard_fab2(sch_1):page189_i21:b"
				( attribute "PN" "2"
					( Origin gPackager )
				)
				( objectStatus "R8G12.2" )
			)
			( pin "@baseboard_fab2_lib.baseboard_fab2(sch_1):page189_i22:a"
				( attribute "PN" "1"
					( Origin gPackager )
				)
				( objectStatus "R8G16.1" )
			)
			( pin "@baseboard_fab2_lib.baseboard_fab2(sch_1):page189_i22:b"
				( attribute "PN" "2"
					( Origin gPackager )
				)
				( objectStatus "R8G16.2" )
			)
			( pin "@baseboard_fab2_lib.baseboard_fab2(sch_1):page189_i23:a"
				( attribute "PN" "1"
					( Origin gPackager )
				)
				( objectStatus "R8G13.1" )
			)
			( pin "@baseboard_fab2_lib.baseboard_fab2(sch_1):page189_i23:b"
				( attribute "PN" "2"
					( Origin gPackager )
				)
				( objectStatus "R8G13.2" )
			)
			( pin "@baseboard_fab2_lib.baseboard_fab2(sch_1):page189_i24:a"
				( attribute "PN" "1"
					( Origin gPackager )
				)
				( objectStatus "R8G15.1" )
			)
			( pin "@baseboard_fab2_lib.baseboard_fab2(sch_1):page189_i24:b"
				( attribute "PN" "2"
					( Origin gPackager )
				)
				( objectStatus "R8G15.2" )
			)
			( pin "@baseboard_fab2_lib.baseboard_fab2(sch_1):page189_i25:a"
				( attribute "PN" "1"
					( Origin gPackager )
				)
				( objectStatus "R8G17.1" )
			)
			( pin "@baseboard_fab2_lib.baseboard_fab2(sch_1):page189_i25:b"
				( attribute "PN" "2"
					( Origin gPackager )
				)
				( objectStatus "R8G17.2" )
			)
			( pin "@baseboard_fab2_lib.baseboard_fab2(sch_1):page189_i26:a"
				( attribute "PN" "1"
					( Origin gPackager )
				)
				( objectStatus "R8G18.1" )
			)
			( pin "@baseboard_fab2_lib.baseboard_fab2(sch_1):page189_i26:b"
				( attribute "PN" "2"
					( Origin gPackager )
				)
				( objectStatus "R8G18.2" )
			)
			( pin "@baseboard_fab2_lib.baseboard_fab2(sch_1):page189_i27:a"
				( attribute "PN" "1"
					( Origin gPackager )
				)
				( objectStatus "R7G16.1" )
			)
			( pin "@baseboard_fab2_lib.baseboard_fab2(sch_1):page189_i27:b"
				( attribute "PN" "2"
					( Origin gPackager )
				)
				( objectStatus "R7G16.2" )
			)
			( pin "@baseboard_fab2_lib.baseboard_fab2(sch_1):page189_i36:a"
				( attribute "PN" "1"
					( Origin gPackager )
				)
				( objectStatus "R7G15.1" )
			)
			( pin "@baseboard_fab2_lib.baseboard_fab2(sch_1):page189_i36:b"
				( attribute "PN" "2"
					( Origin gPackager )
				)
				( objectStatus "R7G15.2" )
			)
			( pin "@baseboard_fab2_lib.baseboard_fab2(sch_1):page189_i37:a"
				( attribute "PN" "1"
					( Origin gPackager )
				)
				( objectStatus "R7G17.1" )
			)
			( pin "@baseboard_fab2_lib.baseboard_fab2(sch_1):page189_i37:b"
				( attribute "PN" "2"
					( Origin gPackager )
				)
				( objectStatus "R7G17.2" )
			)
			( pin "@baseboard_fab2_lib.baseboard_fab2(sch_1):page189_i38:a"
				( attribute "PN" "1"
					( Origin gPackager )
				)
				( objectStatus "R7G14.1" )
			)
			( pin "@baseboard_fab2_lib.baseboard_fab2(sch_1):page189_i38:b"
				( attribute "PN" "2"
					( Origin gPackager )
				)
				( objectStatus "R7G14.2" )
			)
			( pin "@baseboard_fab2_lib.baseboard_fab2(sch_1):page189_i44:a"
				( attribute "PN" "1"
					( Origin gPackager )
				)
				( objectStatus "R3R15.1" )
			)
			( pin "@baseboard_fab2_lib.baseboard_fab2(sch_1):page189_i44:b"
				( attribute "PN" "2"
					( Origin gPackager )
				)
				( objectStatus "R3R15.2" )
			)
			( pin "@baseboard_fab2_lib.baseboard_fab2(sch_1):page189_i45:a"
				( attribute "PN" "1"
					( Origin gPackager )
				)
				( objectStatus "R3R11.1" )
			)
			( pin "@baseboard_fab2_lib.baseboard_fab2(sch_1):page189_i45:b"
				( attribute "PN" "2"
					( Origin gPackager )
				)
				( objectStatus "R3R11.2" )
			)
			( pin "@baseboard_fab2_lib.baseboard_fab2(sch_1):page189_i47:io1"
				( attribute "PN" "1"
					( Origin gPackager )
				)
				( objectStatus "J7G2.1" )
			)
			( pin "@baseboard_fab2_lib.baseboard_fab2(sch_1):page189_i47:io2"
				( attribute "PN" "2"
					( Origin gPackager )
				)
				( objectStatus "J7G2.2" )
			)
			( pin "@baseboard_fab2_lib.baseboard_fab2(sch_1):page189_i47:io3"
				( attribute "PN" "3"
					( Origin gPackager )
				)
				( objectStatus "J7G2.3" )
			)
			( pin "@baseboard_fab2_lib.baseboard_fab2(sch_1):page189_i47:io4"
				( attribute "PN" "4"
					( Origin gPackager )
				)
				( objectStatus "J7G2.4" )
			)
			( pin "@baseboard_fab2_lib.baseboard_fab2(sch_1):page189_i47:io5"
				( attribute "PN" "5"
					( Origin gPackager )
				)
				( objectStatus "J7G2.5" )
			)
			( pin "@baseboard_fab2_lib.baseboard_fab2(sch_1):page189_i47:io6"
				( attribute "PN" "6"
					( Origin gPackager )
				)
				( objectStatus "J7G2.6" )
			)
			( pin "@baseboard_fab2_lib.baseboard_fab2(sch_1):page189_i47:io7"
				( attribute "PN" "7"
					( Origin gPackager )
				)
				( objectStatus "J7G2.7" )
			)
			( pin "@baseboard_fab2_lib.baseboard_fab2(sch_1):page189_i47:io8"
				( attribute "PN" "8"
					( Origin gPackager )
				)
				( objectStatus "J7G2.8" )
			)
			( pin "@baseboard_fab2_lib.baseboard_fab2(sch_1):page189_i49:a"
				( attribute "PN" "2"
					( Origin gPackager )
				)
				( objectStatus "CR3U1.2" )
			)
			( pin "@baseboard_fab2_lib.baseboard_fab2(sch_1):page189_i49:c"
				( attribute "PN" "1"
					( Origin gPackager )
				)
				( objectStatus "CR3U1.1" )
			)
			( pin "@baseboard_fab2_lib.baseboard_fab2(sch_1):page189_i50:a"
				( attribute "PN" "1"
					( Origin gPackager )
				)
				( objectStatus "R8G20.1" )
			)
			( pin "@baseboard_fab2_lib.baseboard_fab2(sch_1):page189_i50:b"
				( attribute "PN" "2"
					( Origin gPackager )
				)
				( objectStatus "R8G20.2" )
			)
			( pin "@baseboard_fab2_lib.baseboard_fab2(sch_1):page189_i51:a"
				( attribute "PN" "1"
					( Origin gPackager )
				)
				( objectStatus "R7G23.1" )
			)
			( pin "@baseboard_fab2_lib.baseboard_fab2(sch_1):page189_i51:b"
				( attribute "PN" "2"
					( Origin gPackager )
				)
				( objectStatus "R7G23.2" )
			)
			( pin "@baseboard_fab2_lib.baseboard_fab2(sch_1):page189_i53:a"
				( attribute "PN" "1"
					( Origin gPackager )
				)
				( objectStatus "R7G22.1" )
			)
			( pin "@baseboard_fab2_lib.baseboard_fab2(sch_1):page189_i53:b"
				( attribute "PN" "2"
					( Origin gPackager )
				)
				( objectStatus "R7G22.2" )
			)
			( pin "@baseboard_fab2_lib.baseboard_fab2(sch_1):page189_i56:a"
				( attribute "PN" "1"
					( Origin gPackager )
				)
				( objectStatus "R8G23.1" )
			)
			( pin "@baseboard_fab2_lib.baseboard_fab2(sch_1):page189_i56:b"
				( attribute "PN" "2"
					( Origin gPackager )
				)
				( objectStatus "R8G23.2" )
			)
			( pin "@baseboard_fab2_lib.baseboard_fab2(sch_1):page189_i63:a"
				( attribute "PN" "1"
					( Origin gPackager )
				)
				( objectStatus "R7G21.1" )
			)
			( pin "@baseboard_fab2_lib.baseboard_fab2(sch_1):page189_i63:b"
				( attribute "PN" "2"
					( Origin gPackager )
				)
				( objectStatus "R7G21.2" )
			)
			( pin "@baseboard_fab2_lib.baseboard_fab2(sch_1):page189_i64:a"
				( attribute "PN" "1"
					( Origin gPackager )
				)
				( objectStatus "R8G19.1" )
			)
			( pin "@baseboard_fab2_lib.baseboard_fab2(sch_1):page189_i64:b"
				( attribute "PN" "2"
					( Origin gPackager )
				)
				( objectStatus "R8G19.2" )
			)
			( pin "@baseboard_fab2_lib.baseboard_fab2(sch_1):page189_i65:a"
				( attribute "PN" "1"
					( Origin gPackager )
				)
				( objectStatus "R8G21.1" )
			)
			( pin "@baseboard_fab2_lib.baseboard_fab2(sch_1):page189_i65:b"
				( attribute "PN" "2"
					( Origin gPackager )
				)
				( objectStatus "R8G21.2" )
			)
			( pin "@baseboard_fab2_lib.baseboard_fab2(sch_1):page189_i66:a"
				( attribute "PN" "1"
					( Origin gPackager )
				)
				( objectStatus "R8G22.1" )
			)
			( pin "@baseboard_fab2_lib.baseboard_fab2(sch_1):page189_i66:b"
				( attribute "PN" "2"
					( Origin gPackager )
				)
				( objectStatus "R8G22.2" )
			)
			( pin "@baseboard_fab2_lib.baseboard_fab2(sch_1):page190_i116:a"
				( attribute "PN" "1"
					( Origin gPackager )
				)
				( objectStatus "R3P34.1" )
			)
			( pin "@baseboard_fab2_lib.baseboard_fab2(sch_1):page190_i116:b"
				( attribute "PN" "2"
					( Origin gPackager )
				)
				( objectStatus "R3P34.2" )
			)
			( pin "@baseboard_fab2_lib.baseboard_fab2(sch_1):page190_i117:a"
				( attribute "PN" "1"
					( Origin gPackager )
				)
				( objectStatus "R3P35.1" )
			)
			( pin "@baseboard_fab2_lib.baseboard_fab2(sch_1):page190_i117:b"
				( attribute "PN" "2"
					( Origin gPackager )
				)
				( objectStatus "R3P35.2" )
			)
			( pin "@baseboard_fab2_lib.baseboard_fab2(sch_1):page190_i179:pb3a"
				( attribute "PN" "P4"
					( Origin gPackager )
				)
				( objectStatus "U8D7.P4" )
			)
			( pin "@baseboard_fab2_lib.baseboard_fab2(sch_1):page190_i179:pb3b"
				( attribute "PN" "T4"
					( Origin gPackager )
				)
				( objectStatus "U8D7.T4" )
			)
			( pin "@baseboard_fab2_lib.baseboard_fab2(sch_1):page190_i179:pb3c"
				( attribute "PN" "T2"
					( Origin gPackager )
				)
				( objectStatus "U8D7.T2" )
			)
			( pin "@baseboard_fab2_lib.baseboard_fab2(sch_1):page190_i179:pb3d"
				( attribute "PN" "R3"
					( Origin gPackager )
				)
				( objectStatus "U8D7.R3" )
			)
			( pin "@baseboard_fab2_lib.baseboard_fab2(sch_1):page190_i179:pb5a_csspin"
				( attribute "PN" "R5"
					( Origin gPackager )
				)
				( objectStatus "U8D7.R5" )
			)
			( pin "@baseboard_fab2_lib.baseboard_fab2(sch_1):page190_i179:pb5b"
				( attribute "PN" "P5"
					( Origin gPackager )
				)
				( objectStatus "U8D7.P5" )
			)
			( pin "@baseboard_fab2_lib.baseboard_fab2(sch_1):page190_i179:pb6a"
				( attribute "PN" "T5"
					( Origin gPackager )
				)
				( objectStatus "U8D7.T5" )
			)
			( pin "@baseboard_fab2_lib.baseboard_fab2(sch_1):page190_i179:pb6b"
				( attribute "PN" "R6"
					( Origin gPackager )
				)
				( objectStatus "U8D7.R6" )
			)
			( pin "@baseboard_fab2_lib.baseboard_fab2(sch_1):page190_i179:pb6c"
				( attribute "PN" "T3"
					( Origin gPackager )
				)
				( objectStatus "U8D7.T3" )
			)
			( pin "@baseboard_fab2_lib.baseboard_fab2(sch_1):page190_i179:pb6d"
				( attribute "PN" "R4"
					( Origin gPackager )
				)
				( objectStatus "U8D7.R4" )
			)
			( pin "@baseboard_fab2_lib.baseboard_fab2(sch_1):page190_i179:pb8a_mclk_cclk"
				( attribute "PN" "P6"
					( Origin gPackager )
				)
				( objectStatus "U8D7.P6" )
			)
			( pin "@baseboard_fab2_lib.baseboard_fab2(sch_1):page190_i179:pb8b_so_spiso"
				( attribute "PN" "T6"
					( Origin gPackager )
				)
				( objectStatus "U8D7.T6" )
			)
			( pin "@baseboard_fab2_lib.baseboard_fab2(sch_1):page190_i179:pb8c"
				( attribute "PN" "N6"
					( Origin gPackager )
				)
				( objectStatus "U8D7.N6" )
			)
			( pin "@baseboard_fab2_lib.baseboard_fab2(sch_1):page190_i179:pb8d"
				( attribute "PN" "L7"
					( Origin gPackager )
				)
				( objectStatus "U8D7.L7" )
			)
			( pin "@baseboard_fab2_lib.baseboard_fab2(sch_1):page190_i179:pb9a"
				( attribute "PN" "R7"
					( Origin gPackager )
				)
				( objectStatus "U8D7.R7" )
			)
			( pin "@baseboard_fab2_lib.baseboard_fab2(sch_1):page190_i179:pb9b"
				( attribute "PN" "P7"
					( Origin gPackager )
				)
				( objectStatus "U8D7.P7" )
			)
			( pin "@baseboard_fab2_lib.baseboard_fab2(sch_1):page190_i179:pb9c"
				( attribute "PN" "M7"
					( Origin gPackager )
				)
				( objectStatus "U8D7.M7" )
			)
			( pin "@baseboard_fab2_lib.baseboard_fab2(sch_1):page190_i179:pb9d"
				( attribute "PN" "N7"
					( Origin gPackager )
				)
				( objectStatus "U8D7.N7" )
			)
			( pin "@baseboard_fab2_lib.baseboard_fab2(sch_1):page190_i179:pb11a_pclkt2_0"
				( attribute "PN" "T7"
					( Origin gPackager )
				)
				( objectStatus "U8D7.T7" )
			)
			( pin "@baseboard_fab2_lib.baseboard_fab2(sch_1):page190_i179:pb11b_pclkc2_0"
				( attribute "PN" "R8"
					( Origin gPackager )
				)
				( objectStatus "U8D7.R8" )
			)
			( pin "@baseboard_fab2_lib.baseboard_fab2(sch_1):page190_i179:pb11c"
				( attribute "PN" "M6"
					( Origin gPackager )
				)
				( objectStatus "U8D7.M6" )
			)
			( pin "@baseboard_fab2_lib.baseboard_fab2(sch_1):page190_i179:pb11d"
				( attribute "PN" "L8"
					( Origin gPackager )
				)
				( objectStatus "U8D7.L8" )
			)
			( pin "@baseboard_fab2_lib.baseboard_fab2(sch_1):page190_i179:pb12a"
				( attribute "PN" "P8"
					( Origin gPackager )
				)
				( objectStatus "U8D7.P8" )
			)
			( pin "@baseboard_fab2_lib.baseboard_fab2(sch_1):page190_i179:pb12b"
				( attribute "PN" "T8"
					( Origin gPackager )
				)
				( objectStatus "U8D7.T8" )
			)
			( pin "@baseboard_fab2_lib.baseboard_fab2(sch_1):page190_i179:pb12c"
				( attribute "PN" "N8"
					( Origin gPackager )
				)
				( objectStatus "U8D7.N8" )
			)
			( pin "@baseboard_fab2_lib.baseboard_fab2(sch_1):page190_i179:pb12d"
				( attribute "PN" "L9"
					( Origin gPackager )
				)
				( objectStatus "U8D7.L9" )
			)
			( pin "@baseboard_fab2_lib.baseboard_fab2(sch_1):page190_i179:pb16a_pclkt2_1"
				( attribute "PN" "T9"
					( Origin gPackager )
				)
				( objectStatus "U8D7.T9" )
			)
			( pin "@baseboard_fab2_lib.baseboard_fab2(sch_1):page190_i179:pb16b_pclkc2_1"
				( attribute "PN" "P9"
					( Origin gPackager )
				)
				( objectStatus "U8D7.P9" )
			)
			( pin "@baseboard_fab2_lib.baseboard_fab2(sch_1):page190_i179:pb16c"
				( attribute "PN" "M8"
					( Origin gPackager )
				)
				( objectStatus "U8D7.M8" )
			)
			( pin "@baseboard_fab2_lib.baseboard_fab2(sch_1):page190_i179:pb16d"
				( attribute "PN" "N9"
					( Origin gPackager )
				)
				( objectStatus "U8D7.N9" )
			)
			( pin "@baseboard_fab2_lib.baseboard_fab2(sch_1):page190_i179:pb18a"
				( attribute "PN" "R9"
					( Origin gPackager )
				)
				( objectStatus "U8D7.R9" )
			)
			( pin "@baseboard_fab2_lib.baseboard_fab2(sch_1):page190_i179:pb18b"
				( attribute "PN" "T10"
					( Origin gPackager )
				)
				( objectStatus "U8D7.T10" )
			)
			( pin "@baseboard_fab2_lib.baseboard_fab2(sch_1):page190_i179:pb18c"
				( attribute "PN" "M9"
					( Origin gPackager )
				)
				( objectStatus "U8D7.M9" )
			)
			( pin "@baseboard_fab2_lib.baseboard_fab2(sch_1):page190_i179:pb18d"
				( attribute "PN" "L10"
					( Origin gPackager )
				)
				( objectStatus "U8D7.L10" )
			)
			( pin "@baseboard_fab2_lib.baseboard_fab2(sch_1):page190_i179:pb19a"
				( attribute "PN" "P10"
					( Origin gPackager )
				)
				( objectStatus "U8D7.P10" )
			)
			( pin "@baseboard_fab2_lib.baseboard_fab2(sch_1):page190_i179:pb19b"
				( attribute "PN" "R10"
					( Origin gPackager )
				)
				( objectStatus "U8D7.R10" )
			)
			( pin "@baseboard_fab2_lib.baseboard_fab2(sch_1):page190_i179:pb19c"
				( attribute "PN" "N10"
					( Origin gPackager )
				)
				( objectStatus "U8D7.N10" )
			)
			( pin "@baseboard_fab2_lib.baseboard_fab2(sch_1):page190_i179:pb19d"
				( attribute "PN" "M11"
					( Origin gPackager )
				)
				( objectStatus "U8D7.M11" )
			)
			( pin "@baseboard_fab2_lib.baseboard_fab2(sch_1):page190_i179:pb21a"
				( attribute "PN" "T11"
					( Origin gPackager )
				)
				( objectStatus "U8D7.T11" )
			)
			( pin "@baseboard_fab2_lib.baseboard_fab2(sch_1):page190_i179:pb21b"
				( attribute "PN" "P11"
					( Origin gPackager )
				)
				( objectStatus "U8D7.P11" )
			)
			( pin "@baseboard_fab2_lib.baseboard_fab2(sch_1):page190_i179:pb21c"
				( attribute "PN" "M10"
					( Origin gPackager )
				)
				( objectStatus "U8D7.M10" )
			)
			( pin "@baseboard_fab2_lib.baseboard_fab2(sch_1):page190_i179:pb21d"
				( attribute "PN" "N11"
					( Origin gPackager )
				)
				( objectStatus "U8D7.N11" )
			)
			( pin "@baseboard_fab2_lib.baseboard_fab2(sch_1):page190_i179:pb22a"
				( attribute "PN" "R11"
					( Origin gPackager )
				)
				( objectStatus "U8D7.R11" )
			)
			( pin "@baseboard_fab2_lib.baseboard_fab2(sch_1):page190_i179:pb22b"
				( attribute "PN" "T12"
					( Origin gPackager )
				)
				( objectStatus "U8D7.T12" )
			)
			( pin "@baseboard_fab2_lib.baseboard_fab2(sch_1):page190_i179:pb22c"
				( attribute "PN" "R13"
					( Origin gPackager )
				)
				( objectStatus "U8D7.R13" )
			)
			( pin "@baseboard_fab2_lib.baseboard_fab2(sch_1):page190_i179:pb22d"
				( attribute "PN" "T14"
					( Origin gPackager )
				)
				( objectStatus "U8D7.T14" )
			)
			( pin "@baseboard_fab2_lib.baseboard_fab2(sch_1):page190_i179:pb24a"
				( attribute "PN" "P12"
					( Origin gPackager )
				)
				( objectStatus "U8D7.P12" )
			)
			( pin "@baseboard_fab2_lib.baseboard_fab2(sch_1):page190_i179:pb24b"
				( attribute "PN" "T13"
					( Origin gPackager )
				)
				( objectStatus "U8D7.T13" )
			)
			( pin "@baseboard_fab2_lib.baseboard_fab2(sch_1):page190_i179:pb25a_sn"
				( attribute "PN" "R12"
					( Origin gPackager )
				)
				( objectStatus "U8D7.R12" )
			)
			( pin "@baseboard_fab2_lib.baseboard_fab2(sch_1):page190_i179:pb25b_si_sispi"
				( attribute "PN" "P13"
					( Origin gPackager )
				)
				( objectStatus "U8D7.P13" )
			)
			( pin "@baseboard_fab2_lib.baseboard_fab2(sch_1):page190_i179:pb25c"
				( attribute "PN" "T15"
					( Origin gPackager )
				)
				( objectStatus "U8D7.T15" )
			)
			( pin "@baseboard_fab2_lib.baseboard_fab2(sch_1):page190_i179:pb25d"
				( attribute "PN" "R14"
					( Origin gPackager )
				)
				( objectStatus "U8D7.R14" )
			)
			( pin "@baseboard_fab2_lib.baseboard_fab2(sch_1):page190_i179:pl1a_l_gpllt_fb"
				( attribute "PN" "D3"
					( Origin gPackager )
				)
				( objectStatus "U8D7.D3" )
			)
			( pin "@baseboard_fab2_lib.baseboard_fab2(sch_1):page190_i179:pl1b_l_gpllc_fb"
				( attribute "PN" "D1"
					( Origin gPackager )
				)
				( objectStatus "U8D7.D1" )
			)
			( pin "@baseboard_fab2_lib.baseboard_fab2(sch_1):page190_i179:pl1c"
				( attribute "PN" "B1"
					( Origin gPackager )
				)
				( objectStatus "U8D7.B1" )
			)
			( pin "@baseboard_fab2_lib.baseboard_fab2(sch_1):page190_i179:pl1d"
				( attribute "PN" "C2"
					( Origin gPackager )
				)
				( objectStatus "U8D7.C2" )
			)
			( pin "@baseboard_fab2_lib.baseboard_fab2(sch_1):page190_i179:pl2a_l_gpllt_in"
				( attribute "PN" "E2"
					( Origin gPackager )
				)
				( objectStatus "U8D7.E2" )
			)
			( pin "@baseboard_fab2_lib.baseboard_fab2(sch_1):page190_i179:pl2b_l_gpllc_in"
				( attribute "PN" "E3"
					( Origin gPackager )
				)
				( objectStatus "U8D7.E3" )
			)
			( pin "@baseboard_fab2_lib.baseboard_fab2(sch_1):page190_i179:pl2c"
				( attribute "PN" "C1"
					( Origin gPackager )
				)
				( objectStatus "U8D7.C1" )
			)
			( pin "@baseboard_fab2_lib.baseboard_fab2(sch_1):page190_i179:pl2d"
				( attribute "PN" "D2"
					( Origin gPackager )
				)
				( objectStatus "U8D7.D2" )
			)
			( pin "@baseboard_fab2_lib.baseboard_fab2(sch_1):page190_i179:pl3a_pclkt5_0"
				( attribute "PN" "E1"
					( Origin gPackager )
				)
				( objectStatus "U8D7.E1" )
			)
			( pin "@baseboard_fab2_lib.baseboard_fab2(sch_1):page190_i179:pl3b_pclkc5_0"
				( attribute "PN" "F2"
					( Origin gPackager )
				)
				( objectStatus "U8D7.F2" )
			)
			( pin "@baseboard_fab2_lib.baseboard_fab2(sch_1):page190_i179:pl3c"
				( attribute "PN" "F4"
					( Origin gPackager )
				)
				( objectStatus "U8D7.F4" )
			)
			( pin "@baseboard_fab2_lib.baseboard_fab2(sch_1):page190_i179:pl3d"
				( attribute "PN" "G6"
					( Origin gPackager )
				)
				( objectStatus "U8D7.G6" )
			)
			( pin "@baseboard_fab2_lib.baseboard_fab2(sch_1):page190_i179:pl4a"
				( attribute "PN" "F3"
					( Origin gPackager )
				)
				( objectStatus "U8D7.F3" )
			)
			( pin "@baseboard_fab2_lib.baseboard_fab2(sch_1):page190_i179:pl4b"
				( attribute "PN" "F1"
					( Origin gPackager )
				)
				( objectStatus "U8D7.F1" )
			)
			( pin "@baseboard_fab2_lib.baseboard_fab2(sch_1):page190_i179:pl4c"
				( attribute "PN" "G5"
					( Origin gPackager )
				)
				( objectStatus "U8D7.G5" )
			)
			( pin "@baseboard_fab2_lib.baseboard_fab2(sch_1):page190_i179:pl4d"
				( attribute "PN" "G4"
					( Origin gPackager )
				)
				( objectStatus "U8D7.G4" )
			)
			( pin "@baseboard_fab2_lib.baseboard_fab2(sch_1):page190_i179:pl5a"
				( attribute "PN" "G2"
					( Origin gPackager )
				)
				( objectStatus "U8D7.G2" )
			)
			( pin "@baseboard_fab2_lib.baseboard_fab2(sch_1):page190_i179:pl5b"
				( attribute "PN" "G3"
					( Origin gPackager )
				)
				( objectStatus "U8D7.G3" )
			)
			( pin "@baseboard_fab2_lib.baseboard_fab2(sch_1):page190_i179:pl5c"
				( attribute "PN" "F5"
					( Origin gPackager )
				)
				( objectStatus "U8D7.F5" )
			)
			( pin "@baseboard_fab2_lib.baseboard_fab2(sch_1):page190_i179:pl5d"
				( attribute "PN" "H6"
					( Origin gPackager )
				)
				( objectStatus "U8D7.H6" )
			)
			( pin "@baseboard_fab2_lib.baseboard_fab2(sch_1):page190_i179:pl6a"
				( attribute "PN" "G1"
					( Origin gPackager )
				)
				( objectStatus "U8D7.G1" )
			)
			( pin "@baseboard_fab2_lib.baseboard_fab2(sch_1):page190_i179:pl6b"
				( attribute "PN" "H2"
					( Origin gPackager )
				)
				( objectStatus "U8D7.H2" )
			)
			( pin "@baseboard_fab2_lib.baseboard_fab2(sch_1):page190_i179:pl6c"
				( attribute "PN" "H4"
					( Origin gPackager )
				)
				( objectStatus "U8D7.H4" )
			)
			( pin "@baseboard_fab2_lib.baseboard_fab2(sch_1):page190_i179:pl6d"
				( attribute "PN" "J6"
					( Origin gPackager )
				)
				( objectStatus "U8D7.J6" )
			)
			( pin "@baseboard_fab2_lib.baseboard_fab2(sch_1):page190_i179:pl7a"
				( attribute "PN" "H3"
					( Origin gPackager )
				)
				( objectStatus "U8D7.H3" )
			)
			( pin "@baseboard_fab2_lib.baseboard_fab2(sch_1):page190_i179:pl7b"
				( attribute "PN" "H1"
					( Origin gPackager )
				)
				( objectStatus "U8D7.H1" )
			)
			( pin "@baseboard_fab2_lib.baseboard_fab2(sch_1):page190_i179:pl7c_pclkt4_0"
				( attribute "PN" "J1"
					( Origin gPackager )
				)
				( objectStatus "U8D7.J1" )
			)
			( pin "@baseboard_fab2_lib.baseboard_fab2(sch_1):page190_i179:pl7d_pclkc4_0"
				( attribute "PN" "J3"
					( Origin gPackager )
				)
				( objectStatus "U8D7.J3" )
			)
			( pin "@baseboard_fab2_lib.baseboard_fab2(sch_1):page190_i179:pl9a"
				( attribute "PN" "J2"
					( Origin gPackager )
				)
				( objectStatus "U8D7.J2" )
			)
			( pin "@baseboard_fab2_lib.baseboard_fab2(sch_1):page190_i179:pl9b"
				( attribute "PN" "K1"
					( Origin gPackager )
				)
				( objectStatus "U8D7.K1" )
			)
			( pin "@baseboard_fab2_lib.baseboard_fab2(sch_1):page190_i179:pl9c"
				( attribute "PN" "H5"
					( Origin gPackager )
				)
				( objectStatus "U8D7.H5" )
			)
			( pin "@baseboard_fab2_lib.baseboard_fab2(sch_1):page190_i179:pl9d"
				( attribute "PN" "J4"
					( Origin gPackager )
				)
				( objectStatus "U8D7.J4" )
			)
			( pin "@baseboard_fab2_lib.baseboard_fab2(sch_1):page190_i179:pl10a"
				( attribute "PN" "K3"
					( Origin gPackager )
				)
				( objectStatus "U8D7.K3" )
			)
			( pin "@baseboard_fab2_lib.baseboard_fab2(sch_1):page190_i179:pl10b"
				( attribute "PN" "K2"
					( Origin gPackager )
				)
				( objectStatus "U8D7.K2" )
			)
			( pin "@baseboard_fab2_lib.baseboard_fab2(sch_1):page190_i179:pl10c"
				( attribute "PN" "J5"
					( Origin gPackager )
				)
				( objectStatus "U8D7.J5" )
			)
			( pin "@baseboard_fab2_lib.baseboard_fab2(sch_1):page190_i179:pl10d"
				( attribute "PN" "K6"
					( Origin gPackager )
				)
				( objectStatus "U8D7.K6" )
			)
			( pin "@baseboard_fab2_lib.baseboard_fab2(sch_1):page190_i179:pl11a"
				( attribute "PN" "L1"
					( Origin gPackager )
				)
				( objectStatus "U8D7.L1" )
			)
			( pin "@baseboard_fab2_lib.baseboard_fab2(sch_1):page190_i179:pl11b"
				( attribute "PN" "L3"
					( Origin gPackager )
				)
				( objectStatus "U8D7.L3" )
			)
			( pin "@baseboard_fab2_lib.baseboard_fab2(sch_1):page190_i179:pl11c"
				( attribute "PN" "K4"
					( Origin gPackager )
				)
				( objectStatus "U8D7.K4" )
			)
			( pin "@baseboard_fab2_lib.baseboard_fab2(sch_1):page190_i179:pl11d"
				( attribute "PN" "L5"
					( Origin gPackager )
				)
				( objectStatus "U8D7.L5" )
			)
			( pin "@baseboard_fab2_lib.baseboard_fab2(sch_1):page190_i179:pl12a_pclkt3_0"
				( attribute "PN" "L2"
					( Origin gPackager )
				)
				( objectStatus "U8D7.L2" )
			)
			( pin "@baseboard_fab2_lib.baseboard_fab2(sch_1):page190_i179:pl12b_pclkc3_0"
				( attribute "PN" "M1"
					( Origin gPackager )
				)
				( objectStatus "U8D7.M1" )
			)
			( pin "@baseboard_fab2_lib.baseboard_fab2(sch_1):page190_i179:pl12c"
				( attribute "PN" "K5"
					( Origin gPackager )
				)
				( objectStatus "U8D7.K5" )
			)
			( pin "@baseboard_fab2_lib.baseboard_fab2(sch_1):page190_i179:pl12d"
				( attribute "PN" "L4"
					( Origin gPackager )
				)
				( objectStatus "U8D7.L4" )
			)
			( pin "@baseboard_fab2_lib.baseboard_fab2(sch_1):page190_i179:pl13a"
				( attribute "PN" "M3"
					( Origin gPackager )
				)
				( objectStatus "U8D7.M3" )
			)
			( pin "@baseboard_fab2_lib.baseboard_fab2(sch_1):page190_i179:pl13b"
				( attribute "PN" "N1"
					( Origin gPackager )
				)
				( objectStatus "U8D7.N1" )
			)
			( pin "@baseboard_fab2_lib.baseboard_fab2(sch_1):page190_i179:pl13c"
				( attribute "PN" "N2"
					( Origin gPackager )
				)
				( objectStatus "U8D7.N2" )
			)
			( pin "@baseboard_fab2_lib.baseboard_fab2(sch_1):page190_i179:pl13d"
				( attribute "PN" "P1"
					( Origin gPackager )
				)
				( objectStatus "U8D7.P1" )
			)
			( pin "@baseboard_fab2_lib.baseboard_fab2(sch_1):page190_i179:pl14a"
				( attribute "PN" "M2"
					( Origin gPackager )
				)
				( objectStatus "U8D7.M2" )
			)
			( pin "@baseboard_fab2_lib.baseboard_fab2(sch_1):page190_i179:pl14b"
				( attribute "PN" "N3"
					( Origin gPackager )
				)
				( objectStatus "U8D7.N3" )
			)
			( pin "@baseboard_fab2_lib.baseboard_fab2(sch_1):page190_i179:pl14c"
				( attribute "PN" "R1"
					( Origin gPackager )
				)
				( objectStatus "U8D7.R1" )
			)
			( pin "@baseboard_fab2_lib.baseboard_fab2(sch_1):page190_i179:pl14d"
				( attribute "PN" "P2"
					( Origin gPackager )
				)
				( objectStatus "U8D7.P2" )
			)
			( pin "@baseboard_fab2_lib.baseboard_fab2(sch_1):page190_i338:a"
				( attribute "PN" "1"
					( Origin gPackager )
				)
				( objectStatus "R2R2.1" )
			)
			( pin "@baseboard_fab2_lib.baseboard_fab2(sch_1):page190_i338:b"
				( attribute "PN" "2"
					( Origin gPackager )
				)
				( objectStatus "R2R2.2" )
			)
			( pin "@baseboard_fab2_lib.baseboard_fab2(sch_1):page191_i59:pr1a"
				( attribute "PN" "D14"
					( Origin gPackager )
				)
				( objectStatus "U8D7.D14" )
			)
			( pin "@baseboard_fab2_lib.baseboard_fab2(sch_1):page191_i59:pr1b"
				( attribute "PN" "E15"
					( Origin gPackager )
				)
				( objectStatus "U8D7.E15" )
			)
			( pin "@baseboard_fab2_lib.baseboard_fab2(sch_1):page191_i59:pr1c"
				( attribute "PN" "C15"
					( Origin gPackager )
				)
				( objectStatus "U8D7.C15" )
			)
			( pin "@baseboard_fab2_lib.baseboard_fab2(sch_1):page191_i59:pr1d"
				( attribute "PN" "B16"
					( Origin gPackager )
				)
				( objectStatus "U8D7.B16" )
			)
			( pin "@baseboard_fab2_lib.baseboard_fab2(sch_1):page191_i59:pr2a"
				( attribute "PN" "D16"
					( Origin gPackager )
				)
				( objectStatus "U8D7.D16" )
			)
			( pin "@baseboard_fab2_lib.baseboard_fab2(sch_1):page191_i59:pr2b"
				( attribute "PN" "E14"
					( Origin gPackager )
				)
				( objectStatus "U8D7.E14" )
			)
			( pin "@baseboard_fab2_lib.baseboard_fab2(sch_1):page191_i59:pr2c"
				( attribute "PN" "C16"
					( Origin gPackager )
				)
				( objectStatus "U8D7.C16" )
			)
			( pin "@baseboard_fab2_lib.baseboard_fab2(sch_1):page191_i59:pr2d"
				( attribute "PN" "D15"
					( Origin gPackager )
				)
				( objectStatus "U8D7.D15" )
			)
			( pin "@baseboard_fab2_lib.baseboard_fab2(sch_1):page191_i59:pr3a"
				( attribute "PN" "E16"
					( Origin gPackager )
				)
				( objectStatus "U8D7.E16" )
			)
			( pin "@baseboard_fab2_lib.baseboard_fab2(sch_1):page191_i59:pr3b"
				( attribute "PN" "F15"
					( Origin gPackager )
				)
				( objectStatus "U8D7.F15" )
			)
			( pin "@baseboard_fab2_lib.baseboard_fab2(sch_1):page191_i59:pr3c"
				( attribute "PN" "F13"
					( Origin gPackager )
				)
				( objectStatus "U8D7.F13" )
			)
			( pin "@baseboard_fab2_lib.baseboard_fab2(sch_1):page191_i59:pr3d"
				( attribute "PN" "G12"
					( Origin gPackager )
				)
				( objectStatus "U8D7.G12" )
			)
			( pin "@baseboard_fab2_lib.baseboard_fab2(sch_1):page191_i59:pr4a"
				( attribute "PN" "F14"
					( Origin gPackager )
				)
				( objectStatus "U8D7.F14" )
			)
			( pin "@baseboard_fab2_lib.baseboard_fab2(sch_1):page191_i59:pr4b"
				( attribute "PN" "F16"
					( Origin gPackager )
				)
				( objectStatus "U8D7.F16" )
			)
			( pin "@baseboard_fab2_lib.baseboard_fab2(sch_1):page191_i59:pr4c"
				( attribute "PN" "F12"
					( Origin gPackager )
				)
				( objectStatus "U8D7.F12" )
			)
			( pin "@baseboard_fab2_lib.baseboard_fab2(sch_1):page191_i59:pr4d"
				( attribute "PN" "G13"
					( Origin gPackager )
				)
				( objectStatus "U8D7.G13" )
			)
			( pin "@baseboard_fab2_lib.baseboard_fab2(sch_1):page191_i59:pr5a"
				( attribute "PN" "G15"
					( Origin gPackager )
				)
				( objectStatus "U8D7.G15" )
			)
			( pin "@baseboard_fab2_lib.baseboard_fab2(sch_1):page191_i59:pr5b"
				( attribute "PN" "G14"
					( Origin gPackager )
				)
				( objectStatus "U8D7.G14" )
			)
			( pin "@baseboard_fab2_lib.baseboard_fab2(sch_1):page191_i59:pr5c"
				( attribute "PN" "G11"
					( Origin gPackager )
				)
				( objectStatus "U8D7.G11" )
			)
			( pin "@baseboard_fab2_lib.baseboard_fab2(sch_1):page191_i59:pr5d"
				( attribute "PN" "H12"
					( Origin gPackager )
				)
				( objectStatus "U8D7.H12" )
			)
			( pin "@baseboard_fab2_lib.baseboard_fab2(sch_1):page191_i59:pr6a"
				( attribute "PN" "G16"
					( Origin gPackager )
				)
				( objectStatus "U8D7.G16" )
			)
			( pin "@baseboard_fab2_lib.baseboard_fab2(sch_1):page191_i59:pr6b"
				( attribute "PN" "H15"
					( Origin gPackager )
				)
				( objectStatus "U8D7.H15" )
			)
			( pin "@baseboard_fab2_lib.baseboard_fab2(sch_1):page191_i59:pr6c"
				( attribute "PN" "H13"
					( Origin gPackager )
				)
				( objectStatus "U8D7.H13" )
			)
			( pin "@baseboard_fab2_lib.baseboard_fab2(sch_1):page191_i59:pr6d"
				( attribute "PN" "J12"
					( Origin gPackager )
				)
				( objectStatus "U8D7.J12" )
			)
			( pin "@baseboard_fab2_lib.baseboard_fab2(sch_1):page191_i59:pr7a_pclkt1_0"
				( attribute "PN" "H14"
					( Origin gPackager )
				)
				( objectStatus "U8D7.H14" )
			)
			( pin "@baseboard_fab2_lib.baseboard_fab2(sch_1):page191_i59:pr7b_pclkc1_0"
				( attribute "PN" "H16"
					( Origin gPackager )
				)
				( objectStatus "U8D7.H16" )
			)
			( pin "@baseboard_fab2_lib.baseboard_fab2(sch_1):page191_i59:pr7c"
				( attribute "PN" "J16"
					( Origin gPackager )
				)
				( objectStatus "U8D7.J16" )
			)
			( pin "@baseboard_fab2_lib.baseboard_fab2(sch_1):page191_i59:pr7d"
				( attribute "PN" "J14"
					( Origin gPackager )
				)
				( objectStatus "U8D7.J14" )
			)
			( pin "@baseboard_fab2_lib.baseboard_fab2(sch_1):page191_i59:pr9a"
				( attribute "PN" "J15"
					( Origin gPackager )
				)
				( objectStatus "U8D7.J15" )
			)
			( pin "@baseboard_fab2_lib.baseboard_fab2(sch_1):page191_i59:pr9b"
				( attribute "PN" "K16"
					( Origin gPackager )
				)
				( objectStatus "U8D7.K16" )
			)
			( pin "@baseboard_fab2_lib.baseboard_fab2(sch_1):page191_i59:pr9c"
				( attribute "PN" "H11"
					( Origin gPackager )
				)
				( objectStatus "U8D7.H11" )
			)
			( pin "@baseboard_fab2_lib.baseboard_fab2(sch_1):page191_i59:pr9d"
				( attribute "PN" "J13"
					( Origin gPackager )
				)
				( objectStatus "U8D7.J13" )
			)
			( pin "@baseboard_fab2_lib.baseboard_fab2(sch_1):page191_i59:pr10a"
				( attribute "PN" "K14"
					( Origin gPackager )
				)
				( objectStatus "U8D7.K14" )
			)
			( pin "@baseboard_fab2_lib.baseboard_fab2(sch_1):page191_i59:pr10b"
				( attribute "PN" "K15"
					( Origin gPackager )
				)
				( objectStatus "U8D7.K15" )
			)
			( pin "@baseboard_fab2_lib.baseboard_fab2(sch_1):page191_i59:pr10c"
				( attribute "PN" "J11"
					( Origin gPackager )
				)
				( objectStatus "U8D7.J11" )
			)
			( pin "@baseboard_fab2_lib.baseboard_fab2(sch_1):page191_i59:pr10d"
				( attribute "PN" "L12"
					( Origin gPackager )
				)
				( objectStatus "U8D7.L12" )
			)
			( pin "@baseboard_fab2_lib.baseboard_fab2(sch_1):page191_i59:pr11a"
				( attribute "PN" "L16"
					( Origin gPackager )
				)
				( objectStatus "U8D7.L16" )
			)
			( pin "@baseboard_fab2_lib.baseboard_fab2(sch_1):page191_i59:pr11b"
				( attribute "PN" "L14"
					( Origin gPackager )
				)
				( objectStatus "U8D7.L14" )
			)
			( pin "@baseboard_fab2_lib.baseboard_fab2(sch_1):page191_i59:pr11c"
				( attribute "PN" "K13"
					( Origin gPackager )
				)
				( objectStatus "U8D7.K13" )
			)
			( pin "@baseboard_fab2_lib.baseboard_fab2(sch_1):page191_i59:pr11d"
				( attribute "PN" "K12"
					( Origin gPackager )
				)
				( objectStatus "U8D7.K12" )
			)
			( pin "@baseboard_fab2_lib.baseboard_fab2(sch_1):page191_i59:pr12a"
				( attribute "PN" "L15"
					( Origin gPackager )
				)
				( objectStatus "U8D7.L15" )
			)
			( pin "@baseboard_fab2_lib.baseboard_fab2(sch_1):page191_i59:pr12b"
				( attribute "PN" "M16"
					( Origin gPackager )
				)
				( objectStatus "U8D7.M16" )
			)
			( pin "@baseboard_fab2_lib.baseboard_fab2(sch_1):page191_i59:pr12c"
				( attribute "PN" "K11"
					( Origin gPackager )
				)
				( objectStatus "U8D7.K11" )
			)
			( pin "@baseboard_fab2_lib.baseboard_fab2(sch_1):page191_i59:pr12d"
				( attribute "PN" "L13"
					( Origin gPackager )
				)
				( objectStatus "U8D7.L13" )
			)
			( pin "@baseboard_fab2_lib.baseboard_fab2(sch_1):page191_i59:pr13a"
				( attribute "PN" "M14"
					( Origin gPackager )
				)
				( objectStatus "U8D7.M14" )
			)
			( pin "@baseboard_fab2_lib.baseboard_fab2(sch_1):page191_i59:pr13b"
				( attribute "PN" "M15"
					( Origin gPackager )
				)
				( objectStatus "U8D7.M15" )
			)
			( pin "@baseboard_fab2_lib.baseboard_fab2(sch_1):page191_i59:pr13c"
				( attribute "PN" "N15"
					( Origin gPackager )
				)
				( objectStatus "U8D7.N15" )
			)
			( pin "@baseboard_fab2_lib.baseboard_fab2(sch_1):page191_i59:pr13d"
				( attribute "PN" "P16"
					( Origin gPackager )
				)
				( objectStatus "U8D7.P16" )
			)
			( pin "@baseboard_fab2_lib.baseboard_fab2(sch_1):page191_i59:pr14a"
				( attribute "PN" "N16"
					( Origin gPackager )
				)
				( objectStatus "U8D7.N16" )
			)
			( pin "@baseboard_fab2_lib.baseboard_fab2(sch_1):page191_i59:pr14b"
				( attribute "PN" "N14"
					( Origin gPackager )
				)
				( objectStatus "U8D7.N14" )
			)
			( pin "@baseboard_fab2_lib.baseboard_fab2(sch_1):page191_i59:pr14c"
				( attribute "PN" "P15"
					( Origin gPackager )
				)
				( objectStatus "U8D7.P15" )
			)
			( pin "@baseboard_fab2_lib.baseboard_fab2(sch_1):page191_i59:pr14d"
				( attribute "PN" "R16"
					( Origin gPackager )
				)
				( objectStatus "U8D7.R16" )
			)
			( pin "@baseboard_fab2_lib.baseboard_fab2(sch_1):page191_i59:pt9a"
				( attribute "PN" "C4"
					( Origin gPackager )
				)
				( objectStatus "U8D7.C4" )
			)
			( pin "@baseboard_fab2_lib.baseboard_fab2(sch_1):page191_i59:pt9b"
				( attribute "PN" "B5"
					( Origin gPackager )
				)
				( objectStatus "U8D7.B5" )
			)
			( pin "@baseboard_fab2_lib.baseboard_fab2(sch_1):page191_i59:pt9c"
				( attribute "PN" "B3"
					( Origin gPackager )
				)
				( objectStatus "U8D7.B3" )
			)
			( pin "@baseboard_fab2_lib.baseboard_fab2(sch_1):page191_i59:pt10a"
				( attribute "PN" "A4"
					( Origin gPackager )
				)
				( objectStatus "U8D7.A4" )
			)
			( pin "@baseboard_fab2_lib.baseboard_fab2(sch_1):page191_i59:pt10b"
				( attribute "PN" "C5"
					( Origin gPackager )
				)
				( objectStatus "U8D7.C5" )
			)
			( pin "@baseboard_fab2_lib.baseboard_fab2(sch_1):page191_i59:pt11a"
				( attribute "PN" "A5"
					( Origin gPackager )
				)
				( objectStatus "U8D7.A5" )
			)
			( pin "@baseboard_fab2_lib.baseboard_fab2(sch_1):page191_i59:pt11b"
				( attribute "PN" "B6"
					( Origin gPackager )
				)
				( objectStatus "U8D7.B6" )
			)
			( pin "@baseboard_fab2_lib.baseboard_fab2(sch_1):page191_i59:pt11c"
				( attribute "PN" "A3"
					( Origin gPackager )
				)
				( objectStatus "U8D7.A3" )
			)
			( pin "@baseboard_fab2_lib.baseboard_fab2(sch_1):page191_i59:pt11d"
				( attribute "PN" "B4"
					( Origin gPackager )
				)
				( objectStatus "U8D7.B4" )
			)
			( pin "@baseboard_fab2_lib.baseboard_fab2(sch_1):page191_i59:pt12a"
				( attribute "PN" "D6"
					( Origin gPackager )
				)
				( objectStatus "U8D7.D6" )
			)
			( pin "@baseboard_fab2_lib.baseboard_fab2(sch_1):page191_i59:pt12b"
				( attribute "PN" "E7"
					( Origin gPackager )
				)
				( objectStatus "U8D7.E7" )
			)
			( pin "@baseboard_fab2_lib.baseboard_fab2(sch_1):page191_i59:pt12c_tdo"
				( attribute "PN" "C6"
					( Origin gPackager )
				)
				( objectStatus "U8D7.C6" )
			)
			( pin "@baseboard_fab2_lib.baseboard_fab2(sch_1):page191_i59:pt12d_tdi"
				( attribute "PN" "A6"
					( Origin gPackager )
				)
				( objectStatus "U8D7.A6" )
			)
			( pin "@baseboard_fab2_lib.baseboard_fab2(sch_1):page191_i59:pt13a"
				( attribute "PN" "B7"
					( Origin gPackager )
				)
				( objectStatus "U8D7.B7" )
			)
			( pin "@baseboard_fab2_lib.baseboard_fab2(sch_1):page191_i59:pt13b"
				( attribute "PN" "C7"
					( Origin gPackager )
				)
				( objectStatus "U8D7.C7" )
			)
			( pin "@baseboard_fab2_lib.baseboard_fab2(sch_1):page191_i59:pt13c"
				( attribute "PN" "E6"
					( Origin gPackager )
				)
				( objectStatus "U8D7.E6" )
			)
			( pin "@baseboard_fab2_lib.baseboard_fab2(sch_1):page191_i59:pt13d"
				( attribute "PN" "D7"
					( Origin gPackager )
				)
				( objectStatus "U8D7.D7" )
			)
			( pin "@baseboard_fab2_lib.baseboard_fab2(sch_1):page191_i59:pt16a"
				( attribute "PN" "F7"
					( Origin gPackager )
				)
				( objectStatus "U8D7.F7" )
			)
			( pin "@baseboard_fab2_lib.baseboard_fab2(sch_1):page191_i59:pt16b"
				( attribute "PN" "E8"
					( Origin gPackager )
				)
				( objectStatus "U8D7.E8" )
			)
			( pin "@baseboard_fab2_lib.baseboard_fab2(sch_1):page191_i59:pt16c_tck"
				( attribute "PN" "A7"
					( Origin gPackager )
				)
				( objectStatus "U8D7.A7" )
			)
			( pin "@baseboard_fab2_lib.baseboard_fab2(sch_1):page191_i59:pt16d_tms"
				( attribute "PN" "B8"
					( Origin gPackager )
				)
				( objectStatus "U8D7.B8" )
			)
			( pin "@baseboard_fab2_lib.baseboard_fab2(sch_1):page191_i59:pt17a_pclkt0_1"
				( attribute "PN" "C8"
					( Origin gPackager )
				)
				( objectStatus "U8D7.C8" )
			)
			( pin "@baseboard_fab2_lib.baseboard_fab2(sch_1):page191_i59:pt17b_pclkc0_1"
				( attribute "PN" "A8"
					( Origin gPackager )
				)
				( objectStatus "U8D7.A8" )
			)
			( pin "@baseboard_fab2_lib.baseboard_fab2(sch_1):page191_i59:pt17c"
				( attribute "PN" "D8"
					( Origin gPackager )
				)
				( objectStatus "U8D7.D8" )
			)
			( pin "@baseboard_fab2_lib.baseboard_fab2(sch_1):page191_i59:pt17d"
				( attribute "PN" "E9"
					( Origin gPackager )
				)
				( objectStatus "U8D7.E9" )
			)
			( pin "@baseboard_fab2_lib.baseboard_fab2(sch_1):page191_i59:pt18a"
				( attribute "PN" "F8"
					( Origin gPackager )
				)
				( objectStatus "U8D7.F8" )
			)
			( pin "@baseboard_fab2_lib.baseboard_fab2(sch_1):page191_i59:pt18b"
				( attribute "PN" "D9"
					( Origin gPackager )
				)
				( objectStatus "U8D7.D9" )
			)
			( pin "@baseboard_fab2_lib.baseboard_fab2(sch_1):page191_i59:pt18c_scl_pclkt0_0"
				( attribute "PN" "A9"
					( Origin gPackager )
				)
				( objectStatus "U8D7.A9" )
			)
			( pin "@baseboard_fab2_lib.baseboard_fab2(sch_1):page191_i59:pt18d_sda_pclkc0_0"
				( attribute "PN" "C9"
					( Origin gPackager )
				)
				( objectStatus "U8D7.C9" )
			)
			( pin "@baseboard_fab2_lib.baseboard_fab2(sch_1):page191_i59:pt19a"
				( attribute "PN" "B9"
					( Origin gPackager )
				)
				( objectStatus "U8D7.B9" )
			)
			( pin "@baseboard_fab2_lib.baseboard_fab2(sch_1):page191_i59:pt19b"
				( attribute "PN" "A10"
					( Origin gPackager )
				)
				( objectStatus "U8D7.A10" )
			)
			( pin "@baseboard_fab2_lib.baseboard_fab2(sch_1):page191_i59:pt19c"
				( attribute "PN" "F9"
					( Origin gPackager )
				)
				( objectStatus "U8D7.F9" )
			)
			( pin "@baseboard_fab2_lib.baseboard_fab2(sch_1):page191_i59:pt19d"
				( attribute "PN" "E11"
					( Origin gPackager )
				)
				( objectStatus "U8D7.E11" )
			)
			( pin "@baseboard_fab2_lib.baseboard_fab2(sch_1):page191_i59:pt20a"
				( attribute "PN" "D10"
					( Origin gPackager )
				)
				( objectStatus "U8D7.D10" )
			)
			( pin "@baseboard_fab2_lib.baseboard_fab2(sch_1):page191_i59:pt20b"
				( attribute "PN" "E10"
					( Origin gPackager )
				)
				( objectStatus "U8D7.E10" )
			)
			( pin "@baseboard_fab2_lib.baseboard_fab2(sch_1):page191_i59:pt20c_jtagenb"
				( attribute "PN" "C10"
					( Origin gPackager )
				)
				( objectStatus "U8D7.C10" )
			)
			( pin "@baseboard_fab2_lib.baseboard_fab2(sch_1):page191_i59:pt20d_programn"
				( attribute "PN" "B10"
					( Origin gPackager )
				)
				( objectStatus "U8D7.B10" )
			)
			( pin "@baseboard_fab2_lib.baseboard_fab2(sch_1):page191_i59:pt21a"
				( attribute "PN" "A11"
					( Origin gPackager )
				)
				( objectStatus "U8D7.A11" )
			)
			( pin "@baseboard_fab2_lib.baseboard_fab2(sch_1):page191_i59:pt21b"
				( attribute "PN" "C11"
					( Origin gPackager )
				)
				( objectStatus "U8D7.C11" )
			)
			( pin "@baseboard_fab2_lib.baseboard_fab2(sch_1):page191_i59:pt21c"
				( attribute "PN" "F10"
					( Origin gPackager )
				)
				( objectStatus "U8D7.F10" )
			)
			( pin "@baseboard_fab2_lib.baseboard_fab2(sch_1):page191_i59:pt21d"
				( attribute "PN" "D11"
					( Origin gPackager )
				)
				( objectStatus "U8D7.D11" )
			)
			( pin "@baseboard_fab2_lib.baseboard_fab2(sch_1):page191_i59:pt22a"
				( attribute "PN" "B11"
					( Origin gPackager )
				)
				( objectStatus "U8D7.B11" )
			)
			( pin "@baseboard_fab2_lib.baseboard_fab2(sch_1):page191_i59:pt22b"
				( attribute "PN" "A12"
					( Origin gPackager )
				)
				( objectStatus "U8D7.A12" )
			)
			( pin "@baseboard_fab2_lib.baseboard_fab2(sch_1):page191_i59:pt22c"
				( attribute "PN" "B13"
					( Origin gPackager )
				)
				( objectStatus "U8D7.B13" )
			)
			( pin "@baseboard_fab2_lib.baseboard_fab2(sch_1):page191_i59:pt22d"
				( attribute "PN" "A14"
					( Origin gPackager )
				)
				( objectStatus "U8D7.A14" )
			)
			( pin "@baseboard_fab2_lib.baseboard_fab2(sch_1):page191_i59:pt23a"
				( attribute "PN" "C12"
					( Origin gPackager )
				)
				( objectStatus "U8D7.C12" )
			)
			( pin "@baseboard_fab2_lib.baseboard_fab2(sch_1):page191_i59:pt23b"
				( attribute "PN" "B12"
					( Origin gPackager )
				)
				( objectStatus "U8D7.B12" )
			)
			( pin "@baseboard_fab2_lib.baseboard_fab2(sch_1):page191_i59:pt24a"
				( attribute "PN" "B14"
					( Origin gPackager )
				)
				( objectStatus "U8D7.B14" )
			)
			( pin "@baseboard_fab2_lib.baseboard_fab2(sch_1):page191_i59:pt24b"
				( attribute "PN" "A15"
					( Origin gPackager )
				)
				( objectStatus "U8D7.A15" )
			)
			( pin "@baseboard_fab2_lib.baseboard_fab2(sch_1):page191_i59:pt24c_initn"
				( attribute "PN" "A13"
					( Origin gPackager )
				)
				( objectStatus "U8D7.A13" )
			)
			( pin "@baseboard_fab2_lib.baseboard_fab2(sch_1):page191_i59:pt24d_done"
				( attribute "PN" "C13"
					( Origin gPackager )
				)
				( objectStatus "U8D7.C13" )
			)
			( pin "@baseboard_fab2_lib.baseboard_fab2(sch_1):page191_i166:a"
				( attribute "PN" "1"
					( Origin gPackager )
				)
				( objectStatus "R2R6.1" )
			)
			( pin "@baseboard_fab2_lib.baseboard_fab2(sch_1):page191_i166:b"
				( attribute "PN" "2"
					( Origin gPackager )
				)
				( objectStatus "R2R6.2" )
			)
			( pin "@baseboard_fab2_lib.baseboard_fab2(sch_1):page191_i172:a"
				( attribute "PN" "1"
					( Origin gPackager )
				)
				( objectStatus "R2R7.1" )
			)
			( pin "@baseboard_fab2_lib.baseboard_fab2(sch_1):page191_i172:b"
				( attribute "PN" "2"
					( Origin gPackager )
				)
				( objectStatus "R2R7.2" )
			)
			( pin "@baseboard_fab2_lib.baseboard_fab2(sch_1):page191_i184:a"
				( attribute "PN" "1"
					( Origin gPackager )
				)
				( objectStatus "R2R4.1" )
			)
			( pin "@baseboard_fab2_lib.baseboard_fab2(sch_1):page191_i184:b"
				( attribute "PN" "2"
					( Origin gPackager )
				)
				( objectStatus "R2R4.2" )
			)
			( pin "@baseboard_fab2_lib.baseboard_fab2(sch_1):page191_i193:a"
				( attribute "PN" "1"
					( Origin gPackager )
				)
				( objectStatus "R7D42.1" )
			)
			( pin "@baseboard_fab2_lib.baseboard_fab2(sch_1):page191_i193:b"
				( attribute "PN" "2"
					( Origin gPackager )
				)
				( objectStatus "R7D42.2" )
			)
			( pin "@baseboard_fab2_lib.baseboard_fab2(sch_1):page192_i1:a"
				( attribute "PN" "1"
					( Origin gPackager )
				)
				( objectStatus "C2P8.1" )
			)
			( pin "@baseboard_fab2_lib.baseboard_fab2(sch_1):page192_i1:b"
				( attribute "PN" "2"
					( Origin gPackager )
				)
				( objectStatus "C2P8.2" )
			)
			( pin "@baseboard_fab2_lib.baseboard_fab2(sch_1):page192_i3:a"
				( attribute "PN" "1"
					( Origin gPackager )
				)
				( objectStatus "C2P5.1" )
			)
			( pin "@baseboard_fab2_lib.baseboard_fab2(sch_1):page192_i3:b"
				( attribute "PN" "2"
					( Origin gPackager )
				)
				( objectStatus "C2P5.2" )
			)
			( pin "@baseboard_fab2_lib.baseboard_fab2(sch_1):page192_i4:a"
				( attribute "PN" "1"
					( Origin gPackager )
				)
				( objectStatus "C3R1.1" )
			)
			( pin "@baseboard_fab2_lib.baseboard_fab2(sch_1):page192_i4:b"
				( attribute "PN" "2"
					( Origin gPackager )
				)
				( objectStatus "C3R1.2" )
			)
			( pin "@baseboard_fab2_lib.baseboard_fab2(sch_1):page192_i6:a"
				( attribute "PN" "1"
					( Origin gPackager )
				)
				( objectStatus "C3P43.1" )
			)
			( pin "@baseboard_fab2_lib.baseboard_fab2(sch_1):page192_i6:b"
				( attribute "PN" "2"
					( Origin gPackager )
				)
				( objectStatus "C3P43.2" )
			)
			( pin "@baseboard_fab2_lib.baseboard_fab2(sch_1):page192_i7:a"
				( attribute "PN" "1"
					( Origin gPackager )
				)
				( objectStatus "C3R3.1" )
			)
			( pin "@baseboard_fab2_lib.baseboard_fab2(sch_1):page192_i7:b"
				( attribute "PN" "2"
					( Origin gPackager )
				)
				( objectStatus "C3R3.2" )
			)
			( pin "@baseboard_fab2_lib.baseboard_fab2(sch_1):page192_i8:a"
				( attribute "PN" "1"
					( Origin gPackager )
				)
				( objectStatus "C2R1.1" )
			)
			( pin "@baseboard_fab2_lib.baseboard_fab2(sch_1):page192_i8:b"
				( attribute "PN" "2"
					( Origin gPackager )
				)
				( objectStatus "C2R1.2" )
			)
			( pin "@baseboard_fab2_lib.baseboard_fab2(sch_1):page192_i9:a"
				( attribute "PN" "1"
					( Origin gPackager )
				)
				( objectStatus "C2P2.1" )
			)
			( pin "@baseboard_fab2_lib.baseboard_fab2(sch_1):page192_i9:b"
				( attribute "PN" "2"
					( Origin gPackager )
				)
				( objectStatus "C2P2.2" )
			)
			( pin "@baseboard_fab2_lib.baseboard_fab2(sch_1):page192_i10:a"
				( attribute "PN" "1"
					( Origin gPackager )
				)
				( objectStatus "C3R2.1" )
			)
			( pin "@baseboard_fab2_lib.baseboard_fab2(sch_1):page192_i10:b"
				( attribute "PN" "2"
					( Origin gPackager )
				)
				( objectStatus "C3R2.2" )
			)
			( pin "@baseboard_fab2_lib.baseboard_fab2(sch_1):page192_i11:a"
				( attribute "PN" "1"
					( Origin gPackager )
				)
				( objectStatus "C3P51.1" )
			)
			( pin "@baseboard_fab2_lib.baseboard_fab2(sch_1):page192_i11:b"
				( attribute "PN" "2"
					( Origin gPackager )
				)
				( objectStatus "C3P51.2" )
			)
			( pin "@baseboard_fab2_lib.baseboard_fab2(sch_1):page192_i12:a"
				( attribute "PN" "1"
					( Origin gPackager )
				)
				( objectStatus "C3P47.1" )
			)
			( pin "@baseboard_fab2_lib.baseboard_fab2(sch_1):page192_i12:b"
				( attribute "PN" "2"
					( Origin gPackager )
				)
				( objectStatus "C3P47.2" )
			)
			( pin "@baseboard_fab2_lib.baseboard_fab2(sch_1):page192_i14:gnd(0)"
				( attribute "PN" "B2"
					( Origin gPackager )
				)
				( objectStatus "U8D7.B2" )
			)
			( pin "@baseboard_fab2_lib.baseboard_fab2(sch_1):page192_i14:gnd(1)"
				( attribute "PN" "B15"
					( Origin gPackager )
				)
				( objectStatus "U8D7.B15" )
			)
			( pin "@baseboard_fab2_lib.baseboard_fab2(sch_1):page192_i14:gnd(2)"
				( attribute "PN" "C3"
					( Origin gPackager )
				)
				( objectStatus "U8D7.C3" )
			)
			( pin "@baseboard_fab2_lib.baseboard_fab2(sch_1):page192_i14:gnd(3)"
				( attribute "PN" "C14"
					( Origin gPackager )
				)
				( objectStatus "U8D7.C14" )
			)
			( pin "@baseboard_fab2_lib.baseboard_fab2(sch_1):page192_i14:gnd(4)"
				( attribute "PN" "D4"
					( Origin gPackager )
				)
				( objectStatus "U8D7.D4" )
			)
			( pin "@baseboard_fab2_lib.baseboard_fab2(sch_1):page192_i14:gnd(5)"
				( attribute "PN" "D13"
					( Origin gPackager )
				)
				( objectStatus "U8D7.D13" )
			)
			( pin "@baseboard_fab2_lib.baseboard_fab2(sch_1):page192_i14:gnd(6)"
				( attribute "PN" "E5"
					( Origin gPackager )
				)
				( objectStatus "U8D7.E5" )
			)
			( pin "@baseboard_fab2_lib.baseboard_fab2(sch_1):page192_i14:gnd(7)"
				( attribute "PN" "E12"
					( Origin gPackager )
				)
				( objectStatus "U8D7.E12" )
			)
			( pin "@baseboard_fab2_lib.baseboard_fab2(sch_1):page192_i14:gnd(8)"
				( attribute "PN" "F6"
					( Origin gPackager )
				)
				( objectStatus "U8D7.F6" )
			)
			( pin "@baseboard_fab2_lib.baseboard_fab2(sch_1):page192_i14:gnd(9)"
				( attribute "PN" "F11"
					( Origin gPackager )
				)
				( objectStatus "U8D7.F11" )
			)
			( pin "@baseboard_fab2_lib.baseboard_fab2(sch_1):page192_i14:gnd(10)"
				( attribute "PN" "H8"
					( Origin gPackager )
				)
				( objectStatus "U8D7.H8" )
			)
			( pin "@baseboard_fab2_lib.baseboard_fab2(sch_1):page192_i14:gnd(11)"
				( attribute "PN" "H9"
					( Origin gPackager )
				)
				( objectStatus "U8D7.H9" )
			)
			( pin "@baseboard_fab2_lib.baseboard_fab2(sch_1):page192_i14:gnd(12)"
				( attribute "PN" "J8"
					( Origin gPackager )
				)
				( objectStatus "U8D7.J8" )
			)
			( pin "@baseboard_fab2_lib.baseboard_fab2(sch_1):page192_i14:gnd(13)"
				( attribute "PN" "J9"
					( Origin gPackager )
				)
				( objectStatus "U8D7.J9" )
			)
			( pin "@baseboard_fab2_lib.baseboard_fab2(sch_1):page192_i14:gnd(14)"
				( attribute "PN" "L6"
					( Origin gPackager )
				)
				( objectStatus "U8D7.L6" )
			)
			( pin "@baseboard_fab2_lib.baseboard_fab2(sch_1):page192_i14:gnd(15)"
				( attribute "PN" "L11"
					( Origin gPackager )
				)
				( objectStatus "U8D7.L11" )
			)
			( pin "@baseboard_fab2_lib.baseboard_fab2(sch_1):page192_i14:gnd(16)"
				( attribute "PN" "M5"
					( Origin gPackager )
				)
				( objectStatus "U8D7.M5" )
			)
			( pin "@baseboard_fab2_lib.baseboard_fab2(sch_1):page192_i14:gnd(17)"
				( attribute "PN" "M12"
					( Origin gPackager )
				)
				( objectStatus "U8D7.M12" )
			)
			( pin "@baseboard_fab2_lib.baseboard_fab2(sch_1):page192_i14:gnd(18)"
				( attribute "PN" "N4"
					( Origin gPackager )
				)
				( objectStatus "U8D7.N4" )
			)
			( pin "@baseboard_fab2_lib.baseboard_fab2(sch_1):page192_i14:gnd(19)"
				( attribute "PN" "N13"
					( Origin gPackager )
				)
				( objectStatus "U8D7.N13" )
			)
			( pin "@baseboard_fab2_lib.baseboard_fab2(sch_1):page192_i14:gnd(20)"
				( attribute "PN" "P3"
					( Origin gPackager )
				)
				( objectStatus "U8D7.P3" )
			)
			( pin "@baseboard_fab2_lib.baseboard_fab2(sch_1):page192_i14:gnd(21)"
				( attribute "PN" "P14"
					( Origin gPackager )
				)
				( objectStatus "U8D7.P14" )
			)
			( pin "@baseboard_fab2_lib.baseboard_fab2(sch_1):page192_i14:gnd(22)"
				( attribute "PN" "R2"
					( Origin gPackager )
				)
				( objectStatus "U8D7.R2" )
			)
			( pin "@baseboard_fab2_lib.baseboard_fab2(sch_1):page192_i14:gnd(23)"
				( attribute "PN" "R15"
					( Origin gPackager )
				)
				( objectStatus "U8D7.R15" )
			)
			( pin "@baseboard_fab2_lib.baseboard_fab2(sch_1):page192_i14:nc(0)"
				( attribute "PN" "A2"
					( Origin gPackager )
				)
				( objectStatus "U8D7.A2" )
			)
			( pin "@baseboard_fab2_lib.baseboard_fab2(sch_1):page192_i14:vcc(0)"
				( attribute "PN" "A1"
					( Origin gPackager )
				)
				( objectStatus "U8D7.A1" )
			)
			( pin "@baseboard_fab2_lib.baseboard_fab2(sch_1):page192_i14:vcc(1)"
				( attribute "PN" "A16"
					( Origin gPackager )
				)
				( objectStatus "U8D7.A16" )
			)
			( pin "@baseboard_fab2_lib.baseboard_fab2(sch_1):page192_i14:vcc(2)"
				( attribute "PN" "T1"
					( Origin gPackager )
				)
				( objectStatus "U8D7.T1" )
			)
			( pin "@baseboard_fab2_lib.baseboard_fab2(sch_1):page192_i14:vcc(3)"
				( attribute "PN" "T16"
					( Origin gPackager )
				)
				( objectStatus "U8D7.T16" )
			)
			( pin "@baseboard_fab2_lib.baseboard_fab2(sch_1):page192_i14:vcc(4)"
				( attribute "PN" "G7"
					( Origin gPackager )
				)
				( objectStatus "U8D7.G7" )
			)
			( pin "@baseboard_fab2_lib.baseboard_fab2(sch_1):page192_i14:vcc(5)"
				( attribute "PN" "G10"
					( Origin gPackager )
				)
				( objectStatus "U8D7.G10" )
			)
			( pin "@baseboard_fab2_lib.baseboard_fab2(sch_1):page192_i14:vcc(6)"
				( attribute "PN" "K7"
					( Origin gPackager )
				)
				( objectStatus "U8D7.K7" )
			)
			( pin "@baseboard_fab2_lib.baseboard_fab2(sch_1):page192_i14:vcc(7)"
				( attribute "PN" "K10"
					( Origin gPackager )
				)
				( objectStatus "U8D7.K10" )
			)
			( pin "@baseboard_fab2_lib.baseboard_fab2(sch_1):page192_i14:vccio0(0)"
				( attribute "PN" "G8"
					( Origin gPackager )
				)
				( objectStatus "U8D7.G8" )
			)
			( pin "@baseboard_fab2_lib.baseboard_fab2(sch_1):page192_i14:vccio0(1)"
				( attribute "PN" "D12"
					( Origin gPackager )
				)
				( objectStatus "U8D7.D12" )
			)
			( pin "@baseboard_fab2_lib.baseboard_fab2(sch_1):page192_i14:vccio0(2)"
				( attribute "PN" "G9"
					( Origin gPackager )
				)
				( objectStatus "U8D7.G9" )
			)
			( pin "@baseboard_fab2_lib.baseboard_fab2(sch_1):page192_i14:vccio0(3)"
				( attribute "PN" "D5"
					( Origin gPackager )
				)
				( objectStatus "U8D7.D5" )
			)
			( pin "@baseboard_fab2_lib.baseboard_fab2(sch_1):page192_i14:vccio1(0)"
				( attribute "PN" "E13"
					( Origin gPackager )
				)
				( objectStatus "U8D7.E13" )
			)
			( pin "@baseboard_fab2_lib.baseboard_fab2(sch_1):page192_i14:vccio1(1)"
				( attribute "PN" "H10"
					( Origin gPackager )
				)
				( objectStatus "U8D7.H10" )
			)
			( pin "@baseboard_fab2_lib.baseboard_fab2(sch_1):page192_i14:vccio1(2)"
				( attribute "PN" "J10"
					( Origin gPackager )
				)
				( objectStatus "U8D7.J10" )
			)
			( pin "@baseboard_fab2_lib.baseboard_fab2(sch_1):page192_i14:vccio1(3)"
				( attribute "PN" "M13"
					( Origin gPackager )
				)
				( objectStatus "U8D7.M13" )
			)
			( pin "@baseboard_fab2_lib.baseboard_fab2(sch_1):page192_i14:vccio2(0)"
				( attribute "PN" "K9"
					( Origin gPackager )
				)
				( objectStatus "U8D7.K9" )
			)
			( pin "@baseboard_fab2_lib.baseboard_fab2(sch_1):page192_i14:vccio2(1)"
				( attribute "PN" "N12"
					( Origin gPackager )
				)
				( objectStatus "U8D7.N12" )
			)
			( pin "@baseboard_fab2_lib.baseboard_fab2(sch_1):page192_i14:vccio2(2)"
				( attribute "PN" "K8"
					( Origin gPackager )
				)
				( objectStatus "U8D7.K8" )
			)
			( pin "@baseboard_fab2_lib.baseboard_fab2(sch_1):page192_i14:vccio2(3)"
				( attribute "PN" "N5"
					( Origin gPackager )
				)
				( objectStatus "U8D7.N5" )
			)
			( pin "@baseboard_fab2_lib.baseboard_fab2(sch_1):page192_i14:vccio3(0)"
				( attribute "PN" "M4"
					( Origin gPackager )
				)
				( objectStatus "U8D7.M4" )
			)
			( pin "@baseboard_fab2_lib.baseboard_fab2(sch_1):page192_i14:vccio4(0)"
				( attribute "PN" "J7"
					( Origin gPackager )
				)
				( objectStatus "U8D7.J7" )
			)
			( pin "@baseboard_fab2_lib.baseboard_fab2(sch_1):page192_i14:vccio4(1)"
				( attribute "PN" "H7"
					( Origin gPackager )
				)
				( objectStatus "U8D7.H7" )
			)
			( pin "@baseboard_fab2_lib.baseboard_fab2(sch_1):page192_i14:vccio5(0)"
				( attribute "PN" "E4"
					( Origin gPackager )
				)
				( objectStatus "U8D7.E4" )
			)
			( pin "@baseboard_fab2_lib.baseboard_fab2(sch_1):page192_i15:a"
				( attribute "PN" "1"
					( Origin gPackager )
				)
				( objectStatus "C2R5.1" )
			)
			( pin "@baseboard_fab2_lib.baseboard_fab2(sch_1):page192_i15:b"
				( attribute "PN" "2"
					( Origin gPackager )
				)
				( objectStatus "C2R5.2" )
			)
			( pin "@baseboard_fab2_lib.baseboard_fab2(sch_1):page192_i16:a"
				( attribute "PN" "1"
					( Origin gPackager )
				)
				( objectStatus "C2P4.1" )
			)
			( pin "@baseboard_fab2_lib.baseboard_fab2(sch_1):page192_i16:b"
				( attribute "PN" "2"
					( Origin gPackager )
				)
				( objectStatus "C2P4.2" )
			)
			( pin "@baseboard_fab2_lib.baseboard_fab2(sch_1):page192_i17:a"
				( attribute "PN" "1"
					( Origin gPackager )
				)
				( objectStatus "C3P52.1" )
			)
			( pin "@baseboard_fab2_lib.baseboard_fab2(sch_1):page192_i17:b"
				( attribute "PN" "2"
					( Origin gPackager )
				)
				( objectStatus "C3P52.2" )
			)
			( pin "@baseboard_fab2_lib.baseboard_fab2(sch_1):page192_i18:a"
				( attribute "PN" "1"
					( Origin gPackager )
				)
				( objectStatus "C2P6.1" )
			)
			( pin "@baseboard_fab2_lib.baseboard_fab2(sch_1):page192_i18:b"
				( attribute "PN" "2"
					( Origin gPackager )
				)
				( objectStatus "C2P6.2" )
			)
			( pin "@baseboard_fab2_lib.baseboard_fab2(sch_1):page192_i19:a"
				( attribute "PN" "1"
					( Origin gPackager )
				)
				( objectStatus "C2R3.1" )
			)
			( pin "@baseboard_fab2_lib.baseboard_fab2(sch_1):page192_i19:b"
				( attribute "PN" "2"
					( Origin gPackager )
				)
				( objectStatus "C2R3.2" )
			)
			( pin "@baseboard_fab2_lib.baseboard_fab2(sch_1):page192_i20:a"
				( attribute "PN" "1"
					( Origin gPackager )
				)
				( objectStatus "C2P7.1" )
			)
			( pin "@baseboard_fab2_lib.baseboard_fab2(sch_1):page192_i20:b"
				( attribute "PN" "2"
					( Origin gPackager )
				)
				( objectStatus "C2P7.2" )
			)
			( pin "@baseboard_fab2_lib.baseboard_fab2(sch_1):page192_i21:a"
				( attribute "PN" "1"
					( Origin gPackager )
				)
				( objectStatus "C2R4.1" )
			)
			( pin "@baseboard_fab2_lib.baseboard_fab2(sch_1):page192_i21:b"
				( attribute "PN" "2"
					( Origin gPackager )
				)
				( objectStatus "C2R4.2" )
			)
			( pin "@baseboard_fab2_lib.baseboard_fab2(sch_1):page192_i22:a"
				( attribute "PN" "1"
					( Origin gPackager )
				)
				( objectStatus "C2P3.1" )
			)
			( pin "@baseboard_fab2_lib.baseboard_fab2(sch_1):page192_i22:b"
				( attribute "PN" "2"
					( Origin gPackager )
				)
				( objectStatus "C2P3.2" )
			)
			( pin "@baseboard_fab2_lib.baseboard_fab2(sch_1):page192_i23:a"
				( attribute "PN" "1"
					( Origin gPackager )
				)
				( objectStatus "C3P44.1" )
			)
			( pin "@baseboard_fab2_lib.baseboard_fab2(sch_1):page192_i23:b"
				( attribute "PN" "2"
					( Origin gPackager )
				)
				( objectStatus "C3P44.2" )
			)
			( pin "@baseboard_fab2_lib.baseboard_fab2(sch_1):page192_i25:a"
				( attribute "PN" "1"
					( Origin gPackager )
				)
				( objectStatus "C3P48.1" )
			)
			( pin "@baseboard_fab2_lib.baseboard_fab2(sch_1):page192_i25:b"
				( attribute "PN" "2"
					( Origin gPackager )
				)
				( objectStatus "C3P48.2" )
			)
			( pin "@baseboard_fab2_lib.baseboard_fab2(sch_1):page192_i28:a"
				( attribute "PN" "1"
					( Origin gPackager )
				)
				( objectStatus "C2R2.1" )
			)
			( pin "@baseboard_fab2_lib.baseboard_fab2(sch_1):page192_i28:b"
				( attribute "PN" "2"
					( Origin gPackager )
				)
				( objectStatus "C2R2.2" )
			)
			( pin "@baseboard_fab2_lib.baseboard_fab2(sch_1):page192_i33:a"
				( attribute "PN" "1"
					( Origin gPackager )
				)
				( objectStatus "R7E6.1" )
			)
			( pin "@baseboard_fab2_lib.baseboard_fab2(sch_1):page192_i33:b"
				( attribute "PN" "2"
					( Origin gPackager )
				)
				( objectStatus "R7E6.2" )
			)
			( pin "@baseboard_fab2_lib.baseboard_fab2(sch_1):page192_i34:a"
				( attribute "PN" "1"
					( Origin gPackager )
				)
				( objectStatus "R2R1.1" )
			)
			( pin "@baseboard_fab2_lib.baseboard_fab2(sch_1):page192_i34:b"
				( attribute "PN" "2"
					( Origin gPackager )
				)
				( objectStatus "R2R1.2" )
			)
			( pin "@baseboard_fab2_lib.baseboard_fab2(sch_1):page192_i38:a"
				( attribute "PN" "1"
					( Origin gPackager )
				)
				( objectStatus "R7E5.1" )
			)
			( pin "@baseboard_fab2_lib.baseboard_fab2(sch_1):page192_i38:b"
				( attribute "PN" "2"
					( Origin gPackager )
				)
				( objectStatus "R7E5.2" )
			)
			( pin "@baseboard_fab2_lib.baseboard_fab2(sch_1):page192_i41:a"
				( attribute "PN" "1"
					( Origin gPackager )
				)
				( objectStatus "R2R3.1" )
			)
			( pin "@baseboard_fab2_lib.baseboard_fab2(sch_1):page192_i41:b"
				( attribute "PN" "2"
					( Origin gPackager )
				)
				( objectStatus "R2R3.2" )
			)
			( pin "@baseboard_fab2_lib.baseboard_fab2(sch_1):page192_i48:a"
				( attribute "PN" "1"
					( Origin gPackager )
				)
				( objectStatus "R3R16.1" )
			)
			( pin "@baseboard_fab2_lib.baseboard_fab2(sch_1):page192_i48:b"
				( attribute "PN" "2"
					( Origin gPackager )
				)
				( objectStatus "R3R16.2" )
			)
			( pin "@baseboard_fab2_lib.baseboard_fab2(sch_1):page192_i49:a"
				( attribute "PN" "1"
					( Origin gPackager )
				)
				( objectStatus "R6M9.1" )
			)
			( pin "@baseboard_fab2_lib.baseboard_fab2(sch_1):page192_i49:b"
				( attribute "PN" "2"
					( Origin gPackager )
				)
				( objectStatus "R6M9.2" )
			)
			( pin "@baseboard_fab2_lib.baseboard_fab2(sch_1):page192_i55:a"
				( attribute "PN" "1"
					( Origin gPackager )
				)
				( objectStatus "R7E18.1" )
			)
			( pin "@baseboard_fab2_lib.baseboard_fab2(sch_1):page192_i55:b"
				( attribute "PN" "2"
					( Origin gPackager )
				)
				( objectStatus "R7E18.2" )
			)
			( pin "@baseboard_fab2_lib.baseboard_fab2(sch_1):page192_i57:a"
				( attribute "PN" "1"
					( Origin gPackager )
				)
				( objectStatus "R7E19.1" )
			)
			( pin "@baseboard_fab2_lib.baseboard_fab2(sch_1):page192_i57:b"
				( attribute "PN" "2"
					( Origin gPackager )
				)
				( objectStatus "R7E19.2" )
			)
			( pin "@baseboard_fab2_lib.baseboard_fab2(sch_1):page192_i59:a"
				( attribute "PN" "1"
					( Origin gPackager )
				)
				( objectStatus "R7E20.1" )
			)
			( pin "@baseboard_fab2_lib.baseboard_fab2(sch_1):page192_i59:b"
				( attribute "PN" "2"
					( Origin gPackager )
				)
				( objectStatus "R7E20.2" )
			)
			( pin "@baseboard_fab2_lib.baseboard_fab2(sch_1):page193_i29:a"
				( attribute "PN" "1"
					( Origin gPackager )
				)
				( objectStatus "C4C1.1" )
			)
			( pin "@baseboard_fab2_lib.baseboard_fab2(sch_1):page193_i29:b"
				( attribute "PN" "2"
					( Origin gPackager )
				)
				( objectStatus "C4C1.2" )
			)
			( pin "@baseboard_fab2_lib.baseboard_fab2(sch_1):page193_i31:a"
				( attribute "PN" "1"
					( Origin gPackager )
				)
				( objectStatus "C3C2.1" )
			)
			( pin "@baseboard_fab2_lib.baseboard_fab2(sch_1):page193_i31:b"
				( attribute "PN" "2"
					( Origin gPackager )
				)
				( objectStatus "C3C2.2" )
			)
			( pin "@baseboard_fab2_lib.baseboard_fab2(sch_1):page193_i38:a"
				( attribute "PN" "1"
					( Origin gPackager )
				)
				( objectStatus "C3C1.1" )
			)
			( pin "@baseboard_fab2_lib.baseboard_fab2(sch_1):page193_i38:b"
				( attribute "PN" "2"
					( Origin gPackager )
				)
				( objectStatus "C3C1.2" )
			)
			( pin "@baseboard_fab2_lib.baseboard_fab2(sch_1):page193_i45:ioa1"
				( attribute "PN" "A1"
					( Origin gPackager )
				)
				( objectStatus "J4E1.A1" )
			)
			( pin "@baseboard_fab2_lib.baseboard_fab2(sch_1):page193_i45:ioa2"
				( attribute "PN" "A2"
					( Origin gPackager )
				)
				( objectStatus "J4E1.A2" )
			)
			( pin "@baseboard_fab2_lib.baseboard_fab2(sch_1):page193_i45:ioa3"
				( attribute "PN" "A3"
					( Origin gPackager )
				)
				( objectStatus "J4E1.A3" )
			)
			( pin "@baseboard_fab2_lib.baseboard_fab2(sch_1):page193_i45:ioa4"
				( attribute "PN" "A4"
					( Origin gPackager )
				)
				( objectStatus "J4E1.A4" )
			)
			( pin "@baseboard_fab2_lib.baseboard_fab2(sch_1):page193_i45:ioa5"
				( attribute "PN" "A5"
					( Origin gPackager )
				)
				( objectStatus "J4E1.A5" )
			)
			( pin "@baseboard_fab2_lib.baseboard_fab2(sch_1):page193_i45:ioa6"
				( attribute "PN" "A6"
					( Origin gPackager )
				)
				( objectStatus "J4E1.A6" )
			)
			( pin "@baseboard_fab2_lib.baseboard_fab2(sch_1):page193_i45:ioa7"
				( attribute "PN" "A7"
					( Origin gPackager )
				)
				( objectStatus "J4E1.A7" )
			)
			( pin "@baseboard_fab2_lib.baseboard_fab2(sch_1):page193_i45:ioa8"
				( attribute "PN" "A8"
					( Origin gPackager )
				)
				( objectStatus "J4E1.A8" )
			)
			( pin "@baseboard_fab2_lib.baseboard_fab2(sch_1):page193_i45:ioa9"
				( attribute "PN" "A9"
					( Origin gPackager )
				)
				( objectStatus "J4E1.A9" )
			)
			( pin "@baseboard_fab2_lib.baseboard_fab2(sch_1):page193_i45:ioa10"
				( attribute "PN" "A10"
					( Origin gPackager )
				)
				( objectStatus "J4E1.A10" )
			)
			( pin "@baseboard_fab2_lib.baseboard_fab2(sch_1):page193_i45:ioa11"
				( attribute "PN" "A11"
					( Origin gPackager )
				)
				( objectStatus "J4E1.A11" )
			)
			( pin "@baseboard_fab2_lib.baseboard_fab2(sch_1):page193_i45:ioa12"
				( attribute "PN" "A12"
					( Origin gPackager )
				)
				( objectStatus "J4E1.A12" )
			)
			( pin "@baseboard_fab2_lib.baseboard_fab2(sch_1):page193_i45:ioa13"
				( attribute "PN" "A13"
					( Origin gPackager )
				)
				( objectStatus "J4E1.A13" )
			)
			( pin "@baseboard_fab2_lib.baseboard_fab2(sch_1):page193_i45:ioa14"
				( attribute "PN" "A14"
					( Origin gPackager )
				)
				( objectStatus "J4E1.A14" )
			)
			( pin "@baseboard_fab2_lib.baseboard_fab2(sch_1):page193_i45:ioa15"
				( attribute "PN" "A15"
					( Origin gPackager )
				)
				( objectStatus "J4E1.A15" )
			)
			( pin "@baseboard_fab2_lib.baseboard_fab2(sch_1):page193_i45:ioa16"
				( attribute "PN" "A16"
					( Origin gPackager )
				)
				( objectStatus "J4E1.A16" )
			)
			( pin "@baseboard_fab2_lib.baseboard_fab2(sch_1):page193_i45:ioa17"
				( attribute "PN" "A17"
					( Origin gPackager )
				)
				( objectStatus "J4E1.A17" )
			)
			( pin "@baseboard_fab2_lib.baseboard_fab2(sch_1):page193_i45:ioa18"
				( attribute "PN" "A18"
					( Origin gPackager )
				)
				( objectStatus "J4E1.A18" )
			)
			( pin "@baseboard_fab2_lib.baseboard_fab2(sch_1):page193_i45:ioa19"
				( attribute "PN" "A19"
					( Origin gPackager )
				)
				( objectStatus "J4E1.A19" )
			)
			( pin "@baseboard_fab2_lib.baseboard_fab2(sch_1):page193_i45:ioa20"
				( attribute "PN" "A20"
					( Origin gPackager )
				)
				( objectStatus "J4E1.A20" )
			)
			( pin "@baseboard_fab2_lib.baseboard_fab2(sch_1):page193_i45:iob1"
				( attribute "PN" "B1"
					( Origin gPackager )
				)
				( objectStatus "J4E1.B1" )
			)
			( pin "@baseboard_fab2_lib.baseboard_fab2(sch_1):page193_i45:iob2"
				( attribute "PN" "B2"
					( Origin gPackager )
				)
				( objectStatus "J4E1.B2" )
			)
			( pin "@baseboard_fab2_lib.baseboard_fab2(sch_1):page193_i45:iob3"
				( attribute "PN" "B3"
					( Origin gPackager )
				)
				( objectStatus "J4E1.B3" )
			)
			( pin "@baseboard_fab2_lib.baseboard_fab2(sch_1):page193_i45:iob4"
				( attribute "PN" "B4"
					( Origin gPackager )
				)
				( objectStatus "J4E1.B4" )
			)
			( pin "@baseboard_fab2_lib.baseboard_fab2(sch_1):page193_i45:iob5"
				( attribute "PN" "B5"
					( Origin gPackager )
				)
				( objectStatus "J4E1.B5" )
			)
			( pin "@baseboard_fab2_lib.baseboard_fab2(sch_1):page193_i45:iob6"
				( attribute "PN" "B6"
					( Origin gPackager )
				)
				( objectStatus "J4E1.B6" )
			)
			( pin "@baseboard_fab2_lib.baseboard_fab2(sch_1):page193_i45:iob7"
				( attribute "PN" "B7"
					( Origin gPackager )
				)
				( objectStatus "J4E1.B7" )
			)
			( pin "@baseboard_fab2_lib.baseboard_fab2(sch_1):page193_i45:iob8"
				( attribute "PN" "B8"
					( Origin gPackager )
				)
				( objectStatus "J4E1.B8" )
			)
			( pin "@baseboard_fab2_lib.baseboard_fab2(sch_1):page193_i45:iob9"
				( attribute "PN" "B9"
					( Origin gPackager )
				)
				( objectStatus "J4E1.B9" )
			)
			( pin "@baseboard_fab2_lib.baseboard_fab2(sch_1):page193_i45:iob10"
				( attribute "PN" "B10"
					( Origin gPackager )
				)
				( objectStatus "J4E1.B10" )
			)
			( pin "@baseboard_fab2_lib.baseboard_fab2(sch_1):page193_i45:iob11"
				( attribute "PN" "B11"
					( Origin gPackager )
				)
				( objectStatus "J4E1.B11" )
			)
			( pin "@baseboard_fab2_lib.baseboard_fab2(sch_1):page193_i45:iob12"
				( attribute "PN" "B12"
					( Origin gPackager )
				)
				( objectStatus "J4E1.B12" )
			)
			( pin "@baseboard_fab2_lib.baseboard_fab2(sch_1):page193_i45:iob13"
				( attribute "PN" "B13"
					( Origin gPackager )
				)
				( objectStatus "J4E1.B13" )
			)
			( pin "@baseboard_fab2_lib.baseboard_fab2(sch_1):page193_i45:iob14"
				( attribute "PN" "B14"
					( Origin gPackager )
				)
				( objectStatus "J4E1.B14" )
			)
			( pin "@baseboard_fab2_lib.baseboard_fab2(sch_1):page193_i45:iob15"
				( attribute "PN" "B15"
					( Origin gPackager )
				)
				( objectStatus "J4E1.B15" )
			)
			( pin "@baseboard_fab2_lib.baseboard_fab2(sch_1):page193_i45:iob16"
				( attribute "PN" "B16"
					( Origin gPackager )
				)
				( objectStatus "J4E1.B16" )
			)
			( pin "@baseboard_fab2_lib.baseboard_fab2(sch_1):page193_i45:iob17"
				( attribute "PN" "B17"
					( Origin gPackager )
				)
				( objectStatus "J4E1.B17" )
			)
			( pin "@baseboard_fab2_lib.baseboard_fab2(sch_1):page193_i45:iob18"
				( attribute "PN" "B18"
					( Origin gPackager )
				)
				( objectStatus "J4E1.B18" )
			)
			( pin "@baseboard_fab2_lib.baseboard_fab2(sch_1):page193_i45:iob19"
				( attribute "PN" "B19"
					( Origin gPackager )
				)
				( objectStatus "J4E1.B19" )
			)
			( pin "@baseboard_fab2_lib.baseboard_fab2(sch_1):page193_i45:iob20"
				( attribute "PN" "B20"
					( Origin gPackager )
				)
				( objectStatus "J4E1.B20" )
			)
			( pin "@baseboard_fab2_lib.baseboard_fab2(sch_1):page193_i45:ioc1"
				( attribute "PN" "C1"
					( Origin gPackager )
				)
				( objectStatus "J4E1.C1" )
			)
			( pin "@baseboard_fab2_lib.baseboard_fab2(sch_1):page193_i45:ioc2"
				( attribute "PN" "C2"
					( Origin gPackager )
				)
				( objectStatus "J4E1.C2" )
			)
			( pin "@baseboard_fab2_lib.baseboard_fab2(sch_1):page193_i45:ioc3"
				( attribute "PN" "C3"
					( Origin gPackager )
				)
				( objectStatus "J4E1.C3" )
			)
			( pin "@baseboard_fab2_lib.baseboard_fab2(sch_1):page193_i45:ioc4"
				( attribute "PN" "C4"
					( Origin gPackager )
				)
				( objectStatus "J4E1.C4" )
			)
			( pin "@baseboard_fab2_lib.baseboard_fab2(sch_1):page193_i45:ioc5"
				( attribute "PN" "C5"
					( Origin gPackager )
				)
				( objectStatus "J4E1.C5" )
			)
			( pin "@baseboard_fab2_lib.baseboard_fab2(sch_1):page193_i45:ioc6"
				( attribute "PN" "C6"
					( Origin gPackager )
				)
				( objectStatus "J4E1.C6" )
			)
			( pin "@baseboard_fab2_lib.baseboard_fab2(sch_1):page193_i45:ioc7"
				( attribute "PN" "C7"
					( Origin gPackager )
				)
				( objectStatus "J4E1.C7" )
			)
			( pin "@baseboard_fab2_lib.baseboard_fab2(sch_1):page193_i45:ioc8"
				( attribute "PN" "C8"
					( Origin gPackager )
				)
				( objectStatus "J4E1.C8" )
			)
			( pin "@baseboard_fab2_lib.baseboard_fab2(sch_1):page193_i45:ioc9"
				( attribute "PN" "C9"
					( Origin gPackager )
				)
				( objectStatus "J4E1.C9" )
			)
			( pin "@baseboard_fab2_lib.baseboard_fab2(sch_1):page193_i45:ioc10"
				( attribute "PN" "C10"
					( Origin gPackager )
				)
				( objectStatus "J4E1.C10" )
			)
			( pin "@baseboard_fab2_lib.baseboard_fab2(sch_1):page193_i45:ioc11"
				( attribute "PN" "C11"
					( Origin gPackager )
				)
				( objectStatus "J4E1.C11" )
			)
			( pin "@baseboard_fab2_lib.baseboard_fab2(sch_1):page193_i45:ioc12"
				( attribute "PN" "C12"
					( Origin gPackager )
				)
				( objectStatus "J4E1.C12" )
			)
			( pin "@baseboard_fab2_lib.baseboard_fab2(sch_1):page193_i45:ioc13"
				( attribute "PN" "C13"
					( Origin gPackager )
				)
				( objectStatus "J4E1.C13" )
			)
			( pin "@baseboard_fab2_lib.baseboard_fab2(sch_1):page193_i45:ioc14"
				( attribute "PN" "C14"
					( Origin gPackager )
				)
				( objectStatus "J4E1.C14" )
			)
			( pin "@baseboard_fab2_lib.baseboard_fab2(sch_1):page193_i45:ioc15"
				( attribute "PN" "C15"
					( Origin gPackager )
				)
				( objectStatus "J4E1.C15" )
			)
			( pin "@baseboard_fab2_lib.baseboard_fab2(sch_1):page193_i45:ioc16"
				( attribute "PN" "C16"
					( Origin gPackager )
				)
				( objectStatus "J4E1.C16" )
			)
			( pin "@baseboard_fab2_lib.baseboard_fab2(sch_1):page193_i45:ioc17"
				( attribute "PN" "C17"
					( Origin gPackager )
				)
				( objectStatus "J4E1.C17" )
			)
			( pin "@baseboard_fab2_lib.baseboard_fab2(sch_1):page193_i45:ioc18"
				( attribute "PN" "C18"
					( Origin gPackager )
				)
				( objectStatus "J4E1.C18" )
			)
			( pin "@baseboard_fab2_lib.baseboard_fab2(sch_1):page193_i45:ioc19"
				( attribute "PN" "C19"
					( Origin gPackager )
				)
				( objectStatus "J4E1.C19" )
			)
			( pin "@baseboard_fab2_lib.baseboard_fab2(sch_1):page193_i45:ioc20"
				( attribute "PN" "C20"
					( Origin gPackager )
				)
				( objectStatus "J4E1.C20" )
			)
			( pin "@baseboard_fab2_lib.baseboard_fab2(sch_1):page193_i45:iod1"
				( attribute "PN" "D1"
					( Origin gPackager )
				)
				( objectStatus "J4E1.D1" )
			)
			( pin "@baseboard_fab2_lib.baseboard_fab2(sch_1):page193_i45:iod2"
				( attribute "PN" "D2"
					( Origin gPackager )
				)
				( objectStatus "J4E1.D2" )
			)
			( pin "@baseboard_fab2_lib.baseboard_fab2(sch_1):page193_i45:iod3"
				( attribute "PN" "D3"
					( Origin gPackager )
				)
				( objectStatus "J4E1.D3" )
			)
			( pin "@baseboard_fab2_lib.baseboard_fab2(sch_1):page193_i45:iod4"
				( attribute "PN" "D4"
					( Origin gPackager )
				)
				( objectStatus "J4E1.D4" )
			)
			( pin "@baseboard_fab2_lib.baseboard_fab2(sch_1):page193_i45:iod5"
				( attribute "PN" "D5"
					( Origin gPackager )
				)
				( objectStatus "J4E1.D5" )
			)
			( pin "@baseboard_fab2_lib.baseboard_fab2(sch_1):page193_i45:iod6"
				( attribute "PN" "D6"
					( Origin gPackager )
				)
				( objectStatus "J4E1.D6" )
			)
			( pin "@baseboard_fab2_lib.baseboard_fab2(sch_1):page193_i45:iod7"
				( attribute "PN" "D7"
					( Origin gPackager )
				)
				( objectStatus "J4E1.D7" )
			)
			( pin "@baseboard_fab2_lib.baseboard_fab2(sch_1):page193_i45:iod8"
				( attribute "PN" "D8"
					( Origin gPackager )
				)
				( objectStatus "J4E1.D8" )
			)
			( pin "@baseboard_fab2_lib.baseboard_fab2(sch_1):page193_i45:iod9"
				( attribute "PN" "D9"
					( Origin gPackager )
				)
				( objectStatus "J4E1.D9" )
			)
			( pin "@baseboard_fab2_lib.baseboard_fab2(sch_1):page193_i45:iod10"
				( attribute "PN" "D10"
					( Origin gPackager )
				)
				( objectStatus "J4E1.D10" )
			)
			( pin "@baseboard_fab2_lib.baseboard_fab2(sch_1):page193_i45:iod11"
				( attribute "PN" "D11"
					( Origin gPackager )
				)
				( objectStatus "J4E1.D11" )
			)
			( pin "@baseboard_fab2_lib.baseboard_fab2(sch_1):page193_i45:iod12"
				( attribute "PN" "D12"
					( Origin gPackager )
				)
				( objectStatus "J4E1.D12" )
			)
			( pin "@baseboard_fab2_lib.baseboard_fab2(sch_1):page193_i45:iod13"
				( attribute "PN" "D13"
					( Origin gPackager )
				)
				( objectStatus "J4E1.D13" )
			)
			( pin "@baseboard_fab2_lib.baseboard_fab2(sch_1):page193_i45:iod14"
				( attribute "PN" "D14"
					( Origin gPackager )
				)
				( objectStatus "J4E1.D14" )
			)
			( pin "@baseboard_fab2_lib.baseboard_fab2(sch_1):page193_i45:iod15"
				( attribute "PN" "D15"
					( Origin gPackager )
				)
				( objectStatus "J4E1.D15" )
			)
			( pin "@baseboard_fab2_lib.baseboard_fab2(sch_1):page193_i45:iod16"
				( attribute "PN" "D16"
					( Origin gPackager )
				)
				( objectStatus "J4E1.D16" )
			)
			( pin "@baseboard_fab2_lib.baseboard_fab2(sch_1):page193_i45:iod17"
				( attribute "PN" "D17"
					( Origin gPackager )
				)
				( objectStatus "J4E1.D17" )
			)
			( pin "@baseboard_fab2_lib.baseboard_fab2(sch_1):page193_i45:iod18"
				( attribute "PN" "D18"
					( Origin gPackager )
				)
				( objectStatus "J4E1.D18" )
			)
			( pin "@baseboard_fab2_lib.baseboard_fab2(sch_1):page193_i45:iod19"
				( attribute "PN" "D19"
					( Origin gPackager )
				)
				( objectStatus "J4E1.D19" )
			)
			( pin "@baseboard_fab2_lib.baseboard_fab2(sch_1):page193_i45:iod20"
				( attribute "PN" "D20"
					( Origin gPackager )
				)
				( objectStatus "J4E1.D20" )
			)
			( pin "@baseboard_fab2_lib.baseboard_fab2(sch_1):page193_i45:ioe1"
				( attribute "PN" "E1"
					( Origin gPackager )
				)
				( objectStatus "J4E1.E1" )
			)
			( pin "@baseboard_fab2_lib.baseboard_fab2(sch_1):page193_i45:ioe2"
				( attribute "PN" "E2"
					( Origin gPackager )
				)
				( objectStatus "J4E1.E2" )
			)
			( pin "@baseboard_fab2_lib.baseboard_fab2(sch_1):page193_i45:ioe3"
				( attribute "PN" "E3"
					( Origin gPackager )
				)
				( objectStatus "J4E1.E3" )
			)
			( pin "@baseboard_fab2_lib.baseboard_fab2(sch_1):page193_i45:ioe4"
				( attribute "PN" "E4"
					( Origin gPackager )
				)
				( objectStatus "J4E1.E4" )
			)
			( pin "@baseboard_fab2_lib.baseboard_fab2(sch_1):page193_i45:ioe5"
				( attribute "PN" "E5"
					( Origin gPackager )
				)
				( objectStatus "J4E1.E5" )
			)
			( pin "@baseboard_fab2_lib.baseboard_fab2(sch_1):page193_i45:ioe6"
				( attribute "PN" "E6"
					( Origin gPackager )
				)
				( objectStatus "J4E1.E6" )
			)
			( pin "@baseboard_fab2_lib.baseboard_fab2(sch_1):page193_i45:ioe7"
				( attribute "PN" "E7"
					( Origin gPackager )
				)
				( objectStatus "J4E1.E7" )
			)
			( pin "@baseboard_fab2_lib.baseboard_fab2(sch_1):page193_i45:ioe8"
				( attribute "PN" "E8"
					( Origin gPackager )
				)
				( objectStatus "J4E1.E8" )
			)
			( pin "@baseboard_fab2_lib.baseboard_fab2(sch_1):page193_i45:ioe9"
				( attribute "PN" "E9"
					( Origin gPackager )
				)
				( objectStatus "J4E1.E9" )
			)
			( pin "@baseboard_fab2_lib.baseboard_fab2(sch_1):page193_i45:ioe10"
				( attribute "PN" "E10"
					( Origin gPackager )
				)
				( objectStatus "J4E1.E10" )
			)
			( pin "@baseboard_fab2_lib.baseboard_fab2(sch_1):page193_i45:ioe11"
				( attribute "PN" "E11"
					( Origin gPackager )
				)
				( objectStatus "J4E1.E11" )
			)
			( pin "@baseboard_fab2_lib.baseboard_fab2(sch_1):page193_i45:ioe12"
				( attribute "PN" "E12"
					( Origin gPackager )
				)
				( objectStatus "J4E1.E12" )
			)
			( pin "@baseboard_fab2_lib.baseboard_fab2(sch_1):page193_i45:ioe13"
				( attribute "PN" "E13"
					( Origin gPackager )
				)
				( objectStatus "J4E1.E13" )
			)
			( pin "@baseboard_fab2_lib.baseboard_fab2(sch_1):page193_i45:ioe14"
				( attribute "PN" "E14"
					( Origin gPackager )
				)
				( objectStatus "J4E1.E14" )
			)
			( pin "@baseboard_fab2_lib.baseboard_fab2(sch_1):page193_i45:ioe15"
				( attribute "PN" "E15"
					( Origin gPackager )
				)
				( objectStatus "J4E1.E15" )
			)
			( pin "@baseboard_fab2_lib.baseboard_fab2(sch_1):page193_i45:ioe16"
				( attribute "PN" "E16"
					( Origin gPackager )
				)
				( objectStatus "J4E1.E16" )
			)
			( pin "@baseboard_fab2_lib.baseboard_fab2(sch_1):page193_i45:ioe17"
				( attribute "PN" "E17"
					( Origin gPackager )
				)
				( objectStatus "J4E1.E17" )
			)
			( pin "@baseboard_fab2_lib.baseboard_fab2(sch_1):page193_i45:ioe18"
				( attribute "PN" "E18"
					( Origin gPackager )
				)
				( objectStatus "J4E1.E18" )
			)
			( pin "@baseboard_fab2_lib.baseboard_fab2(sch_1):page193_i45:ioe19"
				( attribute "PN" "E19"
					( Origin gPackager )
				)
				( objectStatus "J4E1.E19" )
			)
			( pin "@baseboard_fab2_lib.baseboard_fab2(sch_1):page193_i45:ioe20"
				( attribute "PN" "E20"
					( Origin gPackager )
				)
				( objectStatus "J4E1.E20" )
			)
			( pin "@baseboard_fab2_lib.baseboard_fab2(sch_1):page193_i45:iof1"
				( attribute "PN" "F1"
					( Origin gPackager )
				)
				( objectStatus "J4E1.F1" )
			)
			( pin "@baseboard_fab2_lib.baseboard_fab2(sch_1):page193_i45:iof2"
				( attribute "PN" "F2"
					( Origin gPackager )
				)
				( objectStatus "J4E1.F2" )
			)
			( pin "@baseboard_fab2_lib.baseboard_fab2(sch_1):page193_i45:iof3"
				( attribute "PN" "F3"
					( Origin gPackager )
				)
				( objectStatus "J4E1.F3" )
			)
			( pin "@baseboard_fab2_lib.baseboard_fab2(sch_1):page193_i45:iof4"
				( attribute "PN" "F4"
					( Origin gPackager )
				)
				( objectStatus "J4E1.F4" )
			)
			( pin "@baseboard_fab2_lib.baseboard_fab2(sch_1):page193_i45:iof5"
				( attribute "PN" "F5"
					( Origin gPackager )
				)
				( objectStatus "J4E1.F5" )
			)
			( pin "@baseboard_fab2_lib.baseboard_fab2(sch_1):page193_i45:iof6"
				( attribute "PN" "F6"
					( Origin gPackager )
				)
				( objectStatus "J4E1.F6" )
			)
			( pin "@baseboard_fab2_lib.baseboard_fab2(sch_1):page193_i45:iof7"
				( attribute "PN" "F7"
					( Origin gPackager )
				)
				( objectStatus "J4E1.F7" )
			)
			( pin "@baseboard_fab2_lib.baseboard_fab2(sch_1):page193_i45:iof8"
				( attribute "PN" "F8"
					( Origin gPackager )
				)
				( objectStatus "J4E1.F8" )
			)
			( pin "@baseboard_fab2_lib.baseboard_fab2(sch_1):page193_i45:iof9"
				( attribute "PN" "F9"
					( Origin gPackager )
				)
				( objectStatus "J4E1.F9" )
			)
			( pin "@baseboard_fab2_lib.baseboard_fab2(sch_1):page193_i45:iof10"
				( attribute "PN" "F10"
					( Origin gPackager )
				)
				( objectStatus "J4E1.F10" )
			)
			( pin "@baseboard_fab2_lib.baseboard_fab2(sch_1):page193_i45:iof11"
				( attribute "PN" "F11"
					( Origin gPackager )
				)
				( objectStatus "J4E1.F11" )
			)
			( pin "@baseboard_fab2_lib.baseboard_fab2(sch_1):page193_i45:iof12"
				( attribute "PN" "F12"
					( Origin gPackager )
				)
				( objectStatus "J4E1.F12" )
			)
			( pin "@baseboard_fab2_lib.baseboard_fab2(sch_1):page193_i45:iof13"
				( attribute "PN" "F13"
					( Origin gPackager )
				)
				( objectStatus "J4E1.F13" )
			)
			( pin "@baseboard_fab2_lib.baseboard_fab2(sch_1):page193_i45:iof14"
				( attribute "PN" "F14"
					( Origin gPackager )
				)
				( objectStatus "J4E1.F14" )
			)
			( pin "@baseboard_fab2_lib.baseboard_fab2(sch_1):page193_i45:iof15"
				( attribute "PN" "F15"
					( Origin gPackager )
				)
				( objectStatus "J4E1.F15" )
			)
			( pin "@baseboard_fab2_lib.baseboard_fab2(sch_1):page193_i45:iof16"
				( attribute "PN" "F16"
					( Origin gPackager )
				)
				( objectStatus "J4E1.F16" )
			)
			( pin "@baseboard_fab2_lib.baseboard_fab2(sch_1):page193_i45:iof17"
				( attribute "PN" "F17"
					( Origin gPackager )
				)
				( objectStatus "J4E1.F17" )
			)
			( pin "@baseboard_fab2_lib.baseboard_fab2(sch_1):page193_i45:iof18"
				( attribute "PN" "F18"
					( Origin gPackager )
				)
				( objectStatus "J4E1.F18" )
			)
			( pin "@baseboard_fab2_lib.baseboard_fab2(sch_1):page193_i45:iof19"
				( attribute "PN" "F19"
					( Origin gPackager )
				)
				( objectStatus "J4E1.F19" )
			)
			( pin "@baseboard_fab2_lib.baseboard_fab2(sch_1):page193_i45:iof20"
				( attribute "PN" "F20"
					( Origin gPackager )
				)
				( objectStatus "J4E1.F20" )
			)
			( pin "@baseboard_fab2_lib.baseboard_fab2(sch_1):page193_i46:ioa1"
				( attribute "PN" "A1"
					( Origin gPackager )
				)
				( objectStatus "J4B2.A1" )
			)
			( pin "@baseboard_fab2_lib.baseboard_fab2(sch_1):page193_i46:ioa2"
				( attribute "PN" "A2"
					( Origin gPackager )
				)
				( objectStatus "J4B2.A2" )
			)
			( pin "@baseboard_fab2_lib.baseboard_fab2(sch_1):page193_i46:ioa3"
				( attribute "PN" "A3"
					( Origin gPackager )
				)
				( objectStatus "J4B2.A3" )
			)
			( pin "@baseboard_fab2_lib.baseboard_fab2(sch_1):page193_i46:ioa4"
				( attribute "PN" "A4"
					( Origin gPackager )
				)
				( objectStatus "J4B2.A4" )
			)
			( pin "@baseboard_fab2_lib.baseboard_fab2(sch_1):page193_i46:ioa5"
				( attribute "PN" "A5"
					( Origin gPackager )
				)
				( objectStatus "J4B2.A5" )
			)
			( pin "@baseboard_fab2_lib.baseboard_fab2(sch_1):page193_i46:ioa6"
				( attribute "PN" "A6"
					( Origin gPackager )
				)
				( objectStatus "J4B2.A6" )
			)
			( pin "@baseboard_fab2_lib.baseboard_fab2(sch_1):page193_i46:ioa7"
				( attribute "PN" "A7"
					( Origin gPackager )
				)
				( objectStatus "J4B2.A7" )
			)
			( pin "@baseboard_fab2_lib.baseboard_fab2(sch_1):page193_i46:ioa8"
				( attribute "PN" "A8"
					( Origin gPackager )
				)
				( objectStatus "J4B2.A8" )
			)
			( pin "@baseboard_fab2_lib.baseboard_fab2(sch_1):page193_i46:ioa9"
				( attribute "PN" "A9"
					( Origin gPackager )
				)
				( objectStatus "J4B2.A9" )
			)
			( pin "@baseboard_fab2_lib.baseboard_fab2(sch_1):page193_i46:ioa10"
				( attribute "PN" "A10"
					( Origin gPackager )
				)
				( objectStatus "J4B2.A10" )
			)
			( pin "@baseboard_fab2_lib.baseboard_fab2(sch_1):page193_i46:ioa11"
				( attribute "PN" "A11"
					( Origin gPackager )
				)
				( objectStatus "J4B2.A11" )
			)
			( pin "@baseboard_fab2_lib.baseboard_fab2(sch_1):page193_i46:ioa12"
				( attribute "PN" "A12"
					( Origin gPackager )
				)
				( objectStatus "J4B2.A12" )
			)
			( pin "@baseboard_fab2_lib.baseboard_fab2(sch_1):page193_i46:ioa13"
				( attribute "PN" "A13"
					( Origin gPackager )
				)
				( objectStatus "J4B2.A13" )
			)
			( pin "@baseboard_fab2_lib.baseboard_fab2(sch_1):page193_i46:ioa14"
				( attribute "PN" "A14"
					( Origin gPackager )
				)
				( objectStatus "J4B2.A14" )
			)
			( pin "@baseboard_fab2_lib.baseboard_fab2(sch_1):page193_i46:ioa15"
				( attribute "PN" "A15"
					( Origin gPackager )
				)
				( objectStatus "J4B2.A15" )
			)
			( pin "@baseboard_fab2_lib.baseboard_fab2(sch_1):page193_i46:ioa16"
				( attribute "PN" "A16"
					( Origin gPackager )
				)
				( objectStatus "J4B2.A16" )
			)
			( pin "@baseboard_fab2_lib.baseboard_fab2(sch_1):page193_i46:ioa17"
				( attribute "PN" "A17"
					( Origin gPackager )
				)
				( objectStatus "J4B2.A17" )
			)
			( pin "@baseboard_fab2_lib.baseboard_fab2(sch_1):page193_i46:ioa18"
				( attribute "PN" "A18"
					( Origin gPackager )
				)
				( objectStatus "J4B2.A18" )
			)
			( pin "@baseboard_fab2_lib.baseboard_fab2(sch_1):page193_i46:ioa19"
				( attribute "PN" "A19"
					( Origin gPackager )
				)
				( objectStatus "J4B2.A19" )
			)
			( pin "@baseboard_fab2_lib.baseboard_fab2(sch_1):page193_i46:ioa20"
				( attribute "PN" "A20"
					( Origin gPackager )
				)
				( objectStatus "J4B2.A20" )
			)
			( pin "@baseboard_fab2_lib.baseboard_fab2(sch_1):page193_i46:iob1"
				( attribute "PN" "B1"
					( Origin gPackager )
				)
				( objectStatus "J4B2.B1" )
			)
			( pin "@baseboard_fab2_lib.baseboard_fab2(sch_1):page193_i46:iob2"
				( attribute "PN" "B2"
					( Origin gPackager )
				)
				( objectStatus "J4B2.B2" )
			)
			( pin "@baseboard_fab2_lib.baseboard_fab2(sch_1):page193_i46:iob3"
				( attribute "PN" "B3"
					( Origin gPackager )
				)
				( objectStatus "J4B2.B3" )
			)
			( pin "@baseboard_fab2_lib.baseboard_fab2(sch_1):page193_i46:iob4"
				( attribute "PN" "B4"
					( Origin gPackager )
				)
				( objectStatus "J4B2.B4" )
			)
			( pin "@baseboard_fab2_lib.baseboard_fab2(sch_1):page193_i46:iob5"
				( attribute "PN" "B5"
					( Origin gPackager )
				)
				( objectStatus "J4B2.B5" )
			)
			( pin "@baseboard_fab2_lib.baseboard_fab2(sch_1):page193_i46:iob6"
				( attribute "PN" "B6"
					( Origin gPackager )
				)
				( objectStatus "J4B2.B6" )
			)
			( pin "@baseboard_fab2_lib.baseboard_fab2(sch_1):page193_i46:iob7"
				( attribute "PN" "B7"
					( Origin gPackager )
				)
				( objectStatus "J4B2.B7" )
			)
			( pin "@baseboard_fab2_lib.baseboard_fab2(sch_1):page193_i46:iob8"
				( attribute "PN" "B8"
					( Origin gPackager )
				)
				( objectStatus "J4B2.B8" )
			)
			( pin "@baseboard_fab2_lib.baseboard_fab2(sch_1):page193_i46:iob9"
				( attribute "PN" "B9"
					( Origin gPackager )
				)
				( objectStatus "J4B2.B9" )
			)
			( pin "@baseboard_fab2_lib.baseboard_fab2(sch_1):page193_i46:iob10"
				( attribute "PN" "B10"
					( Origin gPackager )
				)
				( objectStatus "J4B2.B10" )
			)
			( pin "@baseboard_fab2_lib.baseboard_fab2(sch_1):page193_i46:iob11"
				( attribute "PN" "B11"
					( Origin gPackager )
				)
				( objectStatus "J4B2.B11" )
			)
			( pin "@baseboard_fab2_lib.baseboard_fab2(sch_1):page193_i46:iob12"
				( attribute "PN" "B12"
					( Origin gPackager )
				)
				( objectStatus "J4B2.B12" )
			)
			( pin "@baseboard_fab2_lib.baseboard_fab2(sch_1):page193_i46:iob13"
				( attribute "PN" "B13"
					( Origin gPackager )
				)
				( objectStatus "J4B2.B13" )
			)
			( pin "@baseboard_fab2_lib.baseboard_fab2(sch_1):page193_i46:iob14"
				( attribute "PN" "B14"
					( Origin gPackager )
				)
				( objectStatus "J4B2.B14" )
			)
			( pin "@baseboard_fab2_lib.baseboard_fab2(sch_1):page193_i46:iob15"
				( attribute "PN" "B15"
					( Origin gPackager )
				)
				( objectStatus "J4B2.B15" )
			)
			( pin "@baseboard_fab2_lib.baseboard_fab2(sch_1):page193_i46:iob16"
				( attribute "PN" "B16"
					( Origin gPackager )
				)
				( objectStatus "J4B2.B16" )
			)
			( pin "@baseboard_fab2_lib.baseboard_fab2(sch_1):page193_i46:iob17"
				( attribute "PN" "B17"
					( Origin gPackager )
				)
				( objectStatus "J4B2.B17" )
			)
			( pin "@baseboard_fab2_lib.baseboard_fab2(sch_1):page193_i46:iob18"
				( attribute "PN" "B18"
					( Origin gPackager )
				)
				( objectStatus "J4B2.B18" )
			)
			( pin "@baseboard_fab2_lib.baseboard_fab2(sch_1):page193_i46:iob19"
				( attribute "PN" "B19"
					( Origin gPackager )
				)
				( objectStatus "J4B2.B19" )
			)
			( pin "@baseboard_fab2_lib.baseboard_fab2(sch_1):page193_i46:iob20"
				( attribute "PN" "B20"
					( Origin gPackager )
				)
				( objectStatus "J4B2.B20" )
			)
			( pin "@baseboard_fab2_lib.baseboard_fab2(sch_1):page193_i46:ioc1"
				( attribute "PN" "C1"
					( Origin gPackager )
				)
				( objectStatus "J4B2.C1" )
			)
			( pin "@baseboard_fab2_lib.baseboard_fab2(sch_1):page193_i46:ioc2"
				( attribute "PN" "C2"
					( Origin gPackager )
				)
				( objectStatus "J4B2.C2" )
			)
			( pin "@baseboard_fab2_lib.baseboard_fab2(sch_1):page193_i46:ioc3"
				( attribute "PN" "C3"
					( Origin gPackager )
				)
				( objectStatus "J4B2.C3" )
			)
			( pin "@baseboard_fab2_lib.baseboard_fab2(sch_1):page193_i46:ioc4"
				( attribute "PN" "C4"
					( Origin gPackager )
				)
				( objectStatus "J4B2.C4" )
			)
			( pin "@baseboard_fab2_lib.baseboard_fab2(sch_1):page193_i46:ioc5"
				( attribute "PN" "C5"
					( Origin gPackager )
				)
				( objectStatus "J4B2.C5" )
			)
			( pin "@baseboard_fab2_lib.baseboard_fab2(sch_1):page193_i46:ioc6"
				( attribute "PN" "C6"
					( Origin gPackager )
				)
				( objectStatus "J4B2.C6" )
			)
			( pin "@baseboard_fab2_lib.baseboard_fab2(sch_1):page193_i46:ioc7"
				( attribute "PN" "C7"
					( Origin gPackager )
				)
				( objectStatus "J4B2.C7" )
			)
			( pin "@baseboard_fab2_lib.baseboard_fab2(sch_1):page193_i46:ioc8"
				( attribute "PN" "C8"
					( Origin gPackager )
				)
				( objectStatus "J4B2.C8" )
			)
			( pin "@baseboard_fab2_lib.baseboard_fab2(sch_1):page193_i46:ioc9"
				( attribute "PN" "C9"
					( Origin gPackager )
				)
				( objectStatus "J4B2.C9" )
			)
			( pin "@baseboard_fab2_lib.baseboard_fab2(sch_1):page193_i46:ioc10"
				( attribute "PN" "C10"
					( Origin gPackager )
				)
				( objectStatus "J4B2.C10" )
			)
			( pin "@baseboard_fab2_lib.baseboard_fab2(sch_1):page193_i46:ioc11"
				( attribute "PN" "C11"
					( Origin gPackager )
				)
				( objectStatus "J4B2.C11" )
			)
			( pin "@baseboard_fab2_lib.baseboard_fab2(sch_1):page193_i46:ioc12"
				( attribute "PN" "C12"
					( Origin gPackager )
				)
				( objectStatus "J4B2.C12" )
			)
			( pin "@baseboard_fab2_lib.baseboard_fab2(sch_1):page193_i46:ioc13"
				( attribute "PN" "C13"
					( Origin gPackager )
				)
				( objectStatus "J4B2.C13" )
			)
			( pin "@baseboard_fab2_lib.baseboard_fab2(sch_1):page193_i46:ioc14"
				( attribute "PN" "C14"
					( Origin gPackager )
				)
				( objectStatus "J4B2.C14" )
			)
			( pin "@baseboard_fab2_lib.baseboard_fab2(sch_1):page193_i46:ioc15"
				( attribute "PN" "C15"
					( Origin gPackager )
				)
				( objectStatus "J4B2.C15" )
			)
			( pin "@baseboard_fab2_lib.baseboard_fab2(sch_1):page193_i46:ioc16"
				( attribute "PN" "C16"
					( Origin gPackager )
				)
				( objectStatus "J4B2.C16" )
			)
			( pin "@baseboard_fab2_lib.baseboard_fab2(sch_1):page193_i46:ioc17"
				( attribute "PN" "C17"
					( Origin gPackager )
				)
				( objectStatus "J4B2.C17" )
			)
			( pin "@baseboard_fab2_lib.baseboard_fab2(sch_1):page193_i46:ioc18"
				( attribute "PN" "C18"
					( Origin gPackager )
				)
				( objectStatus "J4B2.C18" )
			)
			( pin "@baseboard_fab2_lib.baseboard_fab2(sch_1):page193_i46:ioc19"
				( attribute "PN" "C19"
					( Origin gPackager )
				)
				( objectStatus "J4B2.C19" )
			)
			( pin "@baseboard_fab2_lib.baseboard_fab2(sch_1):page193_i46:ioc20"
				( attribute "PN" "C20"
					( Origin gPackager )
				)
				( objectStatus "J4B2.C20" )
			)
			( pin "@baseboard_fab2_lib.baseboard_fab2(sch_1):page193_i46:iod1"
				( attribute "PN" "D1"
					( Origin gPackager )
				)
				( objectStatus "J4B2.D1" )
			)
			( pin "@baseboard_fab2_lib.baseboard_fab2(sch_1):page193_i46:iod2"
				( attribute "PN" "D2"
					( Origin gPackager )
				)
				( objectStatus "J4B2.D2" )
			)
			( pin "@baseboard_fab2_lib.baseboard_fab2(sch_1):page193_i46:iod3"
				( attribute "PN" "D3"
					( Origin gPackager )
				)
				( objectStatus "J4B2.D3" )
			)
			( pin "@baseboard_fab2_lib.baseboard_fab2(sch_1):page193_i46:iod4"
				( attribute "PN" "D4"
					( Origin gPackager )
				)
				( objectStatus "J4B2.D4" )
			)
			( pin "@baseboard_fab2_lib.baseboard_fab2(sch_1):page193_i46:iod5"
				( attribute "PN" "D5"
					( Origin gPackager )
				)
				( objectStatus "J4B2.D5" )
			)
			( pin "@baseboard_fab2_lib.baseboard_fab2(sch_1):page193_i46:iod6"
				( attribute "PN" "D6"
					( Origin gPackager )
				)
				( objectStatus "J4B2.D6" )
			)
			( pin "@baseboard_fab2_lib.baseboard_fab2(sch_1):page193_i46:iod7"
				( attribute "PN" "D7"
					( Origin gPackager )
				)
				( objectStatus "J4B2.D7" )
			)
			( pin "@baseboard_fab2_lib.baseboard_fab2(sch_1):page193_i46:iod8"
				( attribute "PN" "D8"
					( Origin gPackager )
				)
				( objectStatus "J4B2.D8" )
			)
			( pin "@baseboard_fab2_lib.baseboard_fab2(sch_1):page193_i46:iod9"
				( attribute "PN" "D9"
					( Origin gPackager )
				)
				( objectStatus "J4B2.D9" )
			)
			( pin "@baseboard_fab2_lib.baseboard_fab2(sch_1):page193_i46:iod10"
				( attribute "PN" "D10"
					( Origin gPackager )
				)
				( objectStatus "J4B2.D10" )
			)
			( pin "@baseboard_fab2_lib.baseboard_fab2(sch_1):page193_i46:iod11"
				( attribute "PN" "D11"
					( Origin gPackager )
				)
				( objectStatus "J4B2.D11" )
			)
			( pin "@baseboard_fab2_lib.baseboard_fab2(sch_1):page193_i46:iod12"
				( attribute "PN" "D12"
					( Origin gPackager )
				)
				( objectStatus "J4B2.D12" )
			)
			( pin "@baseboard_fab2_lib.baseboard_fab2(sch_1):page193_i46:iod13"
				( attribute "PN" "D13"
					( Origin gPackager )
				)
				( objectStatus "J4B2.D13" )
			)
			( pin "@baseboard_fab2_lib.baseboard_fab2(sch_1):page193_i46:iod14"
				( attribute "PN" "D14"
					( Origin gPackager )
				)
				( objectStatus "J4B2.D14" )
			)
			( pin "@baseboard_fab2_lib.baseboard_fab2(sch_1):page193_i46:iod15"
				( attribute "PN" "D15"
					( Origin gPackager )
				)
				( objectStatus "J4B2.D15" )
			)
			( pin "@baseboard_fab2_lib.baseboard_fab2(sch_1):page193_i46:iod16"
				( attribute "PN" "D16"
					( Origin gPackager )
				)
				( objectStatus "J4B2.D16" )
			)
			( pin "@baseboard_fab2_lib.baseboard_fab2(sch_1):page193_i46:iod17"
				( attribute "PN" "D17"
					( Origin gPackager )
				)
				( objectStatus "J4B2.D17" )
			)
			( pin "@baseboard_fab2_lib.baseboard_fab2(sch_1):page193_i46:iod18"
				( attribute "PN" "D18"
					( Origin gPackager )
				)
				( objectStatus "J4B2.D18" )
			)
			( pin "@baseboard_fab2_lib.baseboard_fab2(sch_1):page193_i46:iod19"
				( attribute "PN" "D19"
					( Origin gPackager )
				)
				( objectStatus "J4B2.D19" )
			)
			( pin "@baseboard_fab2_lib.baseboard_fab2(sch_1):page193_i46:iod20"
				( attribute "PN" "D20"
					( Origin gPackager )
				)
				( objectStatus "J4B2.D20" )
			)
			( pin "@baseboard_fab2_lib.baseboard_fab2(sch_1):page193_i46:ioe1"
				( attribute "PN" "E1"
					( Origin gPackager )
				)
				( objectStatus "J4B2.E1" )
			)
			( pin "@baseboard_fab2_lib.baseboard_fab2(sch_1):page193_i46:ioe2"
				( attribute "PN" "E2"
					( Origin gPackager )
				)
				( objectStatus "J4B2.E2" )
			)
			( pin "@baseboard_fab2_lib.baseboard_fab2(sch_1):page193_i46:ioe3"
				( attribute "PN" "E3"
					( Origin gPackager )
				)
				( objectStatus "J4B2.E3" )
			)
			( pin "@baseboard_fab2_lib.baseboard_fab2(sch_1):page193_i46:ioe4"
				( attribute "PN" "E4"
					( Origin gPackager )
				)
				( objectStatus "J4B2.E4" )
			)
			( pin "@baseboard_fab2_lib.baseboard_fab2(sch_1):page193_i46:ioe5"
				( attribute "PN" "E5"
					( Origin gPackager )
				)
				( objectStatus "J4B2.E5" )
			)
			( pin "@baseboard_fab2_lib.baseboard_fab2(sch_1):page193_i46:ioe6"
				( attribute "PN" "E6"
					( Origin gPackager )
				)
				( objectStatus "J4B2.E6" )
			)
			( pin "@baseboard_fab2_lib.baseboard_fab2(sch_1):page193_i46:ioe7"
				( attribute "PN" "E7"
					( Origin gPackager )
				)
				( objectStatus "J4B2.E7" )
			)
			( pin "@baseboard_fab2_lib.baseboard_fab2(sch_1):page193_i46:ioe8"
				( attribute "PN" "E8"
					( Origin gPackager )
				)
				( objectStatus "J4B2.E8" )
			)
			( pin "@baseboard_fab2_lib.baseboard_fab2(sch_1):page193_i46:ioe9"
				( attribute "PN" "E9"
					( Origin gPackager )
				)
				( objectStatus "J4B2.E9" )
			)
			( pin "@baseboard_fab2_lib.baseboard_fab2(sch_1):page193_i46:ioe10"
				( attribute "PN" "E10"
					( Origin gPackager )
				)
				( objectStatus "J4B2.E10" )
			)
			( pin "@baseboard_fab2_lib.baseboard_fab2(sch_1):page193_i46:ioe11"
				( attribute "PN" "E11"
					( Origin gPackager )
				)
				( objectStatus "J4B2.E11" )
			)
			( pin "@baseboard_fab2_lib.baseboard_fab2(sch_1):page193_i46:ioe12"
				( attribute "PN" "E12"
					( Origin gPackager )
				)
				( objectStatus "J4B2.E12" )
			)
			( pin "@baseboard_fab2_lib.baseboard_fab2(sch_1):page193_i46:ioe13"
				( attribute "PN" "E13"
					( Origin gPackager )
				)
				( objectStatus "J4B2.E13" )
			)
			( pin "@baseboard_fab2_lib.baseboard_fab2(sch_1):page193_i46:ioe14"
				( attribute "PN" "E14"
					( Origin gPackager )
				)
				( objectStatus "J4B2.E14" )
			)
			( pin "@baseboard_fab2_lib.baseboard_fab2(sch_1):page193_i46:ioe15"
				( attribute "PN" "E15"
					( Origin gPackager )
				)
				( objectStatus "J4B2.E15" )
			)
			( pin "@baseboard_fab2_lib.baseboard_fab2(sch_1):page193_i46:ioe16"
				( attribute "PN" "E16"
					( Origin gPackager )
				)
				( objectStatus "J4B2.E16" )
			)
			( pin "@baseboard_fab2_lib.baseboard_fab2(sch_1):page193_i46:ioe17"
				( attribute "PN" "E17"
					( Origin gPackager )
				)
				( objectStatus "J4B2.E17" )
			)
			( pin "@baseboard_fab2_lib.baseboard_fab2(sch_1):page193_i46:ioe18"
				( attribute "PN" "E18"
					( Origin gPackager )
				)
				( objectStatus "J4B2.E18" )
			)
			( pin "@baseboard_fab2_lib.baseboard_fab2(sch_1):page193_i46:ioe19"
				( attribute "PN" "E19"
					( Origin gPackager )
				)
				( objectStatus "J4B2.E19" )
			)
			( pin "@baseboard_fab2_lib.baseboard_fab2(sch_1):page193_i46:ioe20"
				( attribute "PN" "E20"
					( Origin gPackager )
				)
				( objectStatus "J4B2.E20" )
			)
			( pin "@baseboard_fab2_lib.baseboard_fab2(sch_1):page193_i46:iof1"
				( attribute "PN" "F1"
					( Origin gPackager )
				)
				( objectStatus "J4B2.F1" )
			)
			( pin "@baseboard_fab2_lib.baseboard_fab2(sch_1):page193_i46:iof2"
				( attribute "PN" "F2"
					( Origin gPackager )
				)
				( objectStatus "J4B2.F2" )
			)
			( pin "@baseboard_fab2_lib.baseboard_fab2(sch_1):page193_i46:iof3"
				( attribute "PN" "F3"
					( Origin gPackager )
				)
				( objectStatus "J4B2.F3" )
			)
			( pin "@baseboard_fab2_lib.baseboard_fab2(sch_1):page193_i46:iof4"
				( attribute "PN" "F4"
					( Origin gPackager )
				)
				( objectStatus "J4B2.F4" )
			)
			( pin "@baseboard_fab2_lib.baseboard_fab2(sch_1):page193_i46:iof5"
				( attribute "PN" "F5"
					( Origin gPackager )
				)
				( objectStatus "J4B2.F5" )
			)
			( pin "@baseboard_fab2_lib.baseboard_fab2(sch_1):page193_i46:iof6"
				( attribute "PN" "F6"
					( Origin gPackager )
				)
				( objectStatus "J4B2.F6" )
			)
			( pin "@baseboard_fab2_lib.baseboard_fab2(sch_1):page193_i46:iof7"
				( attribute "PN" "F7"
					( Origin gPackager )
				)
				( objectStatus "J4B2.F7" )
			)
			( pin "@baseboard_fab2_lib.baseboard_fab2(sch_1):page193_i46:iof8"
				( attribute "PN" "F8"
					( Origin gPackager )
				)
				( objectStatus "J4B2.F8" )
			)
			( pin "@baseboard_fab2_lib.baseboard_fab2(sch_1):page193_i46:iof9"
				( attribute "PN" "F9"
					( Origin gPackager )
				)
				( objectStatus "J4B2.F9" )
			)
			( pin "@baseboard_fab2_lib.baseboard_fab2(sch_1):page193_i46:iof10"
				( attribute "PN" "F10"
					( Origin gPackager )
				)
				( objectStatus "J4B2.F10" )
			)
			( pin "@baseboard_fab2_lib.baseboard_fab2(sch_1):page193_i46:iof11"
				( attribute "PN" "F11"
					( Origin gPackager )
				)
				( objectStatus "J4B2.F11" )
			)
			( pin "@baseboard_fab2_lib.baseboard_fab2(sch_1):page193_i46:iof12"
				( attribute "PN" "F12"
					( Origin gPackager )
				)
				( objectStatus "J4B2.F12" )
			)
			( pin "@baseboard_fab2_lib.baseboard_fab2(sch_1):page193_i46:iof13"
				( attribute "PN" "F13"
					( Origin gPackager )
				)
				( objectStatus "J4B2.F13" )
			)
			( pin "@baseboard_fab2_lib.baseboard_fab2(sch_1):page193_i46:iof14"
				( attribute "PN" "F14"
					( Origin gPackager )
				)
				( objectStatus "J4B2.F14" )
			)
			( pin "@baseboard_fab2_lib.baseboard_fab2(sch_1):page193_i46:iof15"
				( attribute "PN" "F15"
					( Origin gPackager )
				)
				( objectStatus "J4B2.F15" )
			)
			( pin "@baseboard_fab2_lib.baseboard_fab2(sch_1):page193_i46:iof16"
				( attribute "PN" "F16"
					( Origin gPackager )
				)
				( objectStatus "J4B2.F16" )
			)
			( pin "@baseboard_fab2_lib.baseboard_fab2(sch_1):page193_i46:iof17"
				( attribute "PN" "F17"
					( Origin gPackager )
				)
				( objectStatus "J4B2.F17" )
			)
			( pin "@baseboard_fab2_lib.baseboard_fab2(sch_1):page193_i46:iof18"
				( attribute "PN" "F18"
					( Origin gPackager )
				)
				( objectStatus "J4B2.F18" )
			)
			( pin "@baseboard_fab2_lib.baseboard_fab2(sch_1):page193_i46:iof19"
				( attribute "PN" "F19"
					( Origin gPackager )
				)
				( objectStatus "J4B2.F19" )
			)
			( pin "@baseboard_fab2_lib.baseboard_fab2(sch_1):page193_i46:iof20"
				( attribute "PN" "F20"
					( Origin gPackager )
				)
				( objectStatus "J4B2.F20" )
			)
			( pin "@baseboard_fab2_lib.baseboard_fab2(sch_1):page193_i61:a"
				( attribute "PN" "1"
					( Origin gPackager )
				)
				( objectStatus "C4E24.1" )
			)
			( pin "@baseboard_fab2_lib.baseboard_fab2(sch_1):page193_i61:b"
				( attribute "PN" "2"
					( Origin gPackager )
				)
				( objectStatus "C4E24.2" )
			)
			( pin "@baseboard_fab2_lib.baseboard_fab2(sch_1):page193_i62:a"
				( attribute "PN" "1"
					( Origin gPackager )
				)
				( objectStatus "C6R16.1" )
			)
			( pin "@baseboard_fab2_lib.baseboard_fab2(sch_1):page193_i62:b"
				( attribute "PN" "2"
					( Origin gPackager )
				)
				( objectStatus "C6R16.2" )
			)
			( pin "@baseboard_fab2_lib.baseboard_fab2(sch_1):page193_i68:a"
				( attribute "PN" "1"
					( Origin gPackager )
				)
				( objectStatus "C4F1.1" )
			)
			( pin "@baseboard_fab2_lib.baseboard_fab2(sch_1):page193_i68:b"
				( attribute "PN" "2"
					( Origin gPackager )
				)
				( objectStatus "C4F1.2" )
			)
			( pin "@baseboard_fab2_lib.baseboard_fab2(sch_1):page193_i70:a"
				( attribute "PN" "1"
					( Origin gPackager )
				)
				( objectStatus "C4F3.1" )
			)
			( pin "@baseboard_fab2_lib.baseboard_fab2(sch_1):page193_i70:b"
				( attribute "PN" "2"
					( Origin gPackager )
				)
				( objectStatus "C4F3.2" )
			)
			( pin "@baseboard_fab2_lib.baseboard_fab2(sch_1):page193_i140:a"
				( attribute "PN" "1"
					( Origin gPackager )
				)
				( objectStatus "C3F1.1" )
			)
			( pin "@baseboard_fab2_lib.baseboard_fab2(sch_1):page193_i140:b"
				( attribute "PN" "2"
					( Origin gPackager )
				)
				( objectStatus "C3F1.2" )
			)
			( pin "@baseboard_fab2_lib.baseboard_fab2(sch_1):page193_i141:a"
				( attribute "PN" "1"
					( Origin gPackager )
				)
				( objectStatus "C4F2.1" )
			)
			( pin "@baseboard_fab2_lib.baseboard_fab2(sch_1):page193_i141:b"
				( attribute "PN" "2"
					( Origin gPackager )
				)
				( objectStatus "C4F2.2" )
			)
			( pin "@baseboard_fab2_lib.baseboard_fab2(sch_1):page193_i169:a"
				( attribute "PN" "1"
					( Origin gPackager )
				)
				( objectStatus "R4C12.1" )
			)
			( pin "@baseboard_fab2_lib.baseboard_fab2(sch_1):page193_i169:b"
				( attribute "PN" "2"
					( Origin gPackager )
				)
				( objectStatus "R4C12.2" )
			)
			( pin "@baseboard_fab2_lib.baseboard_fab2(sch_1):page193_i170:a"
				( attribute "PN" "1"
					( Origin gPackager )
				)
				( objectStatus "R4C11.1" )
			)
			( pin "@baseboard_fab2_lib.baseboard_fab2(sch_1):page193_i170:b"
				( attribute "PN" "2"
					( Origin gPackager )
				)
				( objectStatus "R4C11.2" )
			)
			( pin "@baseboard_fab2_lib.baseboard_fab2(sch_1):page194_i9:a"
				( attribute "PN" "1"
					( Origin gPackager )
				)
				( objectStatus "C4T2.1" )
			)
			( pin "@baseboard_fab2_lib.baseboard_fab2(sch_1):page194_i9:b"
				( attribute "PN" "2"
					( Origin gPackager )
				)
				( objectStatus "C4T2.2" )
			)
			( pin "@baseboard_fab2_lib.baseboard_fab2(sch_1):page194_i16:a"
				( attribute "PN" "1"
					( Origin gPackager )
				)
				( objectStatus "C4T1.1" )
			)
			( pin "@baseboard_fab2_lib.baseboard_fab2(sch_1):page194_i16:b"
				( attribute "PN" "2"
					( Origin gPackager )
				)
				( objectStatus "C4T1.2" )
			)
			( pin "@baseboard_fab2_lib.baseboard_fab2(sch_1):page194_i29:a"
				( attribute "PN" "1"
					( Origin gPackager )
				)
				( objectStatus "C4R1.1" )
			)
			( pin "@baseboard_fab2_lib.baseboard_fab2(sch_1):page194_i29:b"
				( attribute "PN" "2"
					( Origin gPackager )
				)
				( objectStatus "C4R1.2" )
			)
			( pin "@baseboard_fab2_lib.baseboard_fab2(sch_1):page194_i31:a"
				( attribute "PN" "1"
					( Origin gPackager )
				)
				( objectStatus "C3R4.1" )
			)
			( pin "@baseboard_fab2_lib.baseboard_fab2(sch_1):page194_i31:b"
				( attribute "PN" "2"
					( Origin gPackager )
				)
				( objectStatus "C3R4.2" )
			)
			( pin "@baseboard_fab2_lib.baseboard_fab2(sch_1):page194_i55:ioa1"
				( attribute "PN" "A1"
					( Origin gPackager )
				)
				( objectStatus "J6E1.A1" )
			)
			( pin "@baseboard_fab2_lib.baseboard_fab2(sch_1):page194_i55:ioa2"
				( attribute "PN" "A2"
					( Origin gPackager )
				)
				( objectStatus "J6E1.A2" )
			)
			( pin "@baseboard_fab2_lib.baseboard_fab2(sch_1):page194_i55:ioa3"
				( attribute "PN" "A3"
					( Origin gPackager )
				)
				( objectStatus "J6E1.A3" )
			)
			( pin "@baseboard_fab2_lib.baseboard_fab2(sch_1):page194_i55:ioa4"
				( attribute "PN" "A4"
					( Origin gPackager )
				)
				( objectStatus "J6E1.A4" )
			)
			( pin "@baseboard_fab2_lib.baseboard_fab2(sch_1):page194_i55:ioa5"
				( attribute "PN" "A5"
					( Origin gPackager )
				)
				( objectStatus "J6E1.A5" )
			)
			( pin "@baseboard_fab2_lib.baseboard_fab2(sch_1):page194_i55:ioa6"
				( attribute "PN" "A6"
					( Origin gPackager )
				)
				( objectStatus "J6E1.A6" )
			)
			( pin "@baseboard_fab2_lib.baseboard_fab2(sch_1):page194_i55:ioa7"
				( attribute "PN" "A7"
					( Origin gPackager )
				)
				( objectStatus "J6E1.A7" )
			)
			( pin "@baseboard_fab2_lib.baseboard_fab2(sch_1):page194_i55:ioa8"
				( attribute "PN" "A8"
					( Origin gPackager )
				)
				( objectStatus "J6E1.A8" )
			)
			( pin "@baseboard_fab2_lib.baseboard_fab2(sch_1):page194_i55:ioa9"
				( attribute "PN" "A9"
					( Origin gPackager )
				)
				( objectStatus "J6E1.A9" )
			)
			( pin "@baseboard_fab2_lib.baseboard_fab2(sch_1):page194_i55:ioa10"
				( attribute "PN" "A10"
					( Origin gPackager )
				)
				( objectStatus "J6E1.A10" )
			)
			( pin "@baseboard_fab2_lib.baseboard_fab2(sch_1):page194_i55:ioa11"
				( attribute "PN" "A11"
					( Origin gPackager )
				)
				( objectStatus "J6E1.A11" )
			)
			( pin "@baseboard_fab2_lib.baseboard_fab2(sch_1):page194_i55:ioa12"
				( attribute "PN" "A12"
					( Origin gPackager )
				)
				( objectStatus "J6E1.A12" )
			)
			( pin "@baseboard_fab2_lib.baseboard_fab2(sch_1):page194_i55:ioa13"
				( attribute "PN" "A13"
					( Origin gPackager )
				)
				( objectStatus "J6E1.A13" )
			)
			( pin "@baseboard_fab2_lib.baseboard_fab2(sch_1):page194_i55:ioa14"
				( attribute "PN" "A14"
					( Origin gPackager )
				)
				( objectStatus "J6E1.A14" )
			)
			( pin "@baseboard_fab2_lib.baseboard_fab2(sch_1):page194_i55:ioa15"
				( attribute "PN" "A15"
					( Origin gPackager )
				)
				( objectStatus "J6E1.A15" )
			)
			( pin "@baseboard_fab2_lib.baseboard_fab2(sch_1):page194_i55:ioa16"
				( attribute "PN" "A16"
					( Origin gPackager )
				)
				( objectStatus "J6E1.A16" )
			)
			( pin "@baseboard_fab2_lib.baseboard_fab2(sch_1):page194_i55:ioa17"
				( attribute "PN" "A17"
					( Origin gPackager )
				)
				( objectStatus "J6E1.A17" )
			)
			( pin "@baseboard_fab2_lib.baseboard_fab2(sch_1):page194_i55:ioa18"
				( attribute "PN" "A18"
					( Origin gPackager )
				)
				( objectStatus "J6E1.A18" )
			)
			( pin "@baseboard_fab2_lib.baseboard_fab2(sch_1):page194_i55:ioa19"
				( attribute "PN" "A19"
					( Origin gPackager )
				)
				( objectStatus "J6E1.A19" )
			)
			( pin "@baseboard_fab2_lib.baseboard_fab2(sch_1):page194_i55:ioa20"
				( attribute "PN" "A20"
					( Origin gPackager )
				)
				( objectStatus "J6E1.A20" )
			)
			( pin "@baseboard_fab2_lib.baseboard_fab2(sch_1):page194_i55:iob1"
				( attribute "PN" "B1"
					( Origin gPackager )
				)
				( objectStatus "J6E1.B1" )
			)
			( pin "@baseboard_fab2_lib.baseboard_fab2(sch_1):page194_i55:iob2"
				( attribute "PN" "B2"
					( Origin gPackager )
				)
				( objectStatus "J6E1.B2" )
			)
			( pin "@baseboard_fab2_lib.baseboard_fab2(sch_1):page194_i55:iob3"
				( attribute "PN" "B3"
					( Origin gPackager )
				)
				( objectStatus "J6E1.B3" )
			)
			( pin "@baseboard_fab2_lib.baseboard_fab2(sch_1):page194_i55:iob4"
				( attribute "PN" "B4"
					( Origin gPackager )
				)
				( objectStatus "J6E1.B4" )
			)
			( pin "@baseboard_fab2_lib.baseboard_fab2(sch_1):page194_i55:iob5"
				( attribute "PN" "B5"
					( Origin gPackager )
				)
				( objectStatus "J6E1.B5" )
			)
			( pin "@baseboard_fab2_lib.baseboard_fab2(sch_1):page194_i55:iob6"
				( attribute "PN" "B6"
					( Origin gPackager )
				)
				( objectStatus "J6E1.B6" )
			)
			( pin "@baseboard_fab2_lib.baseboard_fab2(sch_1):page194_i55:iob7"
				( attribute "PN" "B7"
					( Origin gPackager )
				)
				( objectStatus "J6E1.B7" )
			)
			( pin "@baseboard_fab2_lib.baseboard_fab2(sch_1):page194_i55:iob8"
				( attribute "PN" "B8"
					( Origin gPackager )
				)
				( objectStatus "J6E1.B8" )
			)
			( pin "@baseboard_fab2_lib.baseboard_fab2(sch_1):page194_i55:iob9"
				( attribute "PN" "B9"
					( Origin gPackager )
				)
				( objectStatus "J6E1.B9" )
			)
			( pin "@baseboard_fab2_lib.baseboard_fab2(sch_1):page194_i55:iob10"
				( attribute "PN" "B10"
					( Origin gPackager )
				)
				( objectStatus "J6E1.B10" )
			)
			( pin "@baseboard_fab2_lib.baseboard_fab2(sch_1):page194_i55:iob11"
				( attribute "PN" "B11"
					( Origin gPackager )
				)
				( objectStatus "J6E1.B11" )
			)
			( pin "@baseboard_fab2_lib.baseboard_fab2(sch_1):page194_i55:iob12"
				( attribute "PN" "B12"
					( Origin gPackager )
				)
				( objectStatus "J6E1.B12" )
			)
			( pin "@baseboard_fab2_lib.baseboard_fab2(sch_1):page194_i55:iob13"
				( attribute "PN" "B13"
					( Origin gPackager )
				)
				( objectStatus "J6E1.B13" )
			)
			( pin "@baseboard_fab2_lib.baseboard_fab2(sch_1):page194_i55:iob14"
				( attribute "PN" "B14"
					( Origin gPackager )
				)
				( objectStatus "J6E1.B14" )
			)
			( pin "@baseboard_fab2_lib.baseboard_fab2(sch_1):page194_i55:iob15"
				( attribute "PN" "B15"
					( Origin gPackager )
				)
				( objectStatus "J6E1.B15" )
			)
			( pin "@baseboard_fab2_lib.baseboard_fab2(sch_1):page194_i55:iob16"
				( attribute "PN" "B16"
					( Origin gPackager )
				)
				( objectStatus "J6E1.B16" )
			)
			( pin "@baseboard_fab2_lib.baseboard_fab2(sch_1):page194_i55:iob17"
				( attribute "PN" "B17"
					( Origin gPackager )
				)
				( objectStatus "J6E1.B17" )
			)
			( pin "@baseboard_fab2_lib.baseboard_fab2(sch_1):page194_i55:iob18"
				( attribute "PN" "B18"
					( Origin gPackager )
				)
				( objectStatus "J6E1.B18" )
			)
			( pin "@baseboard_fab2_lib.baseboard_fab2(sch_1):page194_i55:iob19"
				( attribute "PN" "B19"
					( Origin gPackager )
				)
				( objectStatus "J6E1.B19" )
			)
			( pin "@baseboard_fab2_lib.baseboard_fab2(sch_1):page194_i55:iob20"
				( attribute "PN" "B20"
					( Origin gPackager )
				)
				( objectStatus "J6E1.B20" )
			)
			( pin "@baseboard_fab2_lib.baseboard_fab2(sch_1):page194_i55:ioc1"
				( attribute "PN" "C1"
					( Origin gPackager )
				)
				( objectStatus "J6E1.C1" )
			)
			( pin "@baseboard_fab2_lib.baseboard_fab2(sch_1):page194_i55:ioc2"
				( attribute "PN" "C2"
					( Origin gPackager )
				)
				( objectStatus "J6E1.C2" )
			)
			( pin "@baseboard_fab2_lib.baseboard_fab2(sch_1):page194_i55:ioc3"
				( attribute "PN" "C3"
					( Origin gPackager )
				)
				( objectStatus "J6E1.C3" )
			)
			( pin "@baseboard_fab2_lib.baseboard_fab2(sch_1):page194_i55:ioc4"
				( attribute "PN" "C4"
					( Origin gPackager )
				)
				( objectStatus "J6E1.C4" )
			)
			( pin "@baseboard_fab2_lib.baseboard_fab2(sch_1):page194_i55:ioc5"
				( attribute "PN" "C5"
					( Origin gPackager )
				)
				( objectStatus "J6E1.C5" )
			)
			( pin "@baseboard_fab2_lib.baseboard_fab2(sch_1):page194_i55:ioc6"
				( attribute "PN" "C6"
					( Origin gPackager )
				)
				( objectStatus "J6E1.C6" )
			)
			( pin "@baseboard_fab2_lib.baseboard_fab2(sch_1):page194_i55:ioc7"
				( attribute "PN" "C7"
					( Origin gPackager )
				)
				( objectStatus "J6E1.C7" )
			)
			( pin "@baseboard_fab2_lib.baseboard_fab2(sch_1):page194_i55:ioc8"
				( attribute "PN" "C8"
					( Origin gPackager )
				)
				( objectStatus "J6E1.C8" )
			)
			( pin "@baseboard_fab2_lib.baseboard_fab2(sch_1):page194_i55:ioc9"
				( attribute "PN" "C9"
					( Origin gPackager )
				)
				( objectStatus "J6E1.C9" )
			)
			( pin "@baseboard_fab2_lib.baseboard_fab2(sch_1):page194_i55:ioc10"
				( attribute "PN" "C10"
					( Origin gPackager )
				)
				( objectStatus "J6E1.C10" )
			)
			( pin "@baseboard_fab2_lib.baseboard_fab2(sch_1):page194_i55:ioc11"
				( attribute "PN" "C11"
					( Origin gPackager )
				)
				( objectStatus "J6E1.C11" )
			)
			( pin "@baseboard_fab2_lib.baseboard_fab2(sch_1):page194_i55:ioc12"
				( attribute "PN" "C12"
					( Origin gPackager )
				)
				( objectStatus "J6E1.C12" )
			)
			( pin "@baseboard_fab2_lib.baseboard_fab2(sch_1):page194_i55:ioc13"
				( attribute "PN" "C13"
					( Origin gPackager )
				)
				( objectStatus "J6E1.C13" )
			)
			( pin "@baseboard_fab2_lib.baseboard_fab2(sch_1):page194_i55:ioc14"
				( attribute "PN" "C14"
					( Origin gPackager )
				)
				( objectStatus "J6E1.C14" )
			)
			( pin "@baseboard_fab2_lib.baseboard_fab2(sch_1):page194_i55:ioc15"
				( attribute "PN" "C15"
					( Origin gPackager )
				)
				( objectStatus "J6E1.C15" )
			)
			( pin "@baseboard_fab2_lib.baseboard_fab2(sch_1):page194_i55:ioc16"
				( attribute "PN" "C16"
					( Origin gPackager )
				)
				( objectStatus "J6E1.C16" )
			)
			( pin "@baseboard_fab2_lib.baseboard_fab2(sch_1):page194_i55:ioc17"
				( attribute "PN" "C17"
					( Origin gPackager )
				)
				( objectStatus "J6E1.C17" )
			)
			( pin "@baseboard_fab2_lib.baseboard_fab2(sch_1):page194_i55:ioc18"
				( attribute "PN" "C18"
					( Origin gPackager )
				)
				( objectStatus "J6E1.C18" )
			)
			( pin "@baseboard_fab2_lib.baseboard_fab2(sch_1):page194_i55:ioc19"
				( attribute "PN" "C19"
					( Origin gPackager )
				)
				( objectStatus "J6E1.C19" )
			)
			( pin "@baseboard_fab2_lib.baseboard_fab2(sch_1):page194_i55:ioc20"
				( attribute "PN" "C20"
					( Origin gPackager )
				)
				( objectStatus "J6E1.C20" )
			)
			( pin "@baseboard_fab2_lib.baseboard_fab2(sch_1):page194_i55:iod1"
				( attribute "PN" "D1"
					( Origin gPackager )
				)
				( objectStatus "J6E1.D1" )
			)
			( pin "@baseboard_fab2_lib.baseboard_fab2(sch_1):page194_i55:iod2"
				( attribute "PN" "D2"
					( Origin gPackager )
				)
				( objectStatus "J6E1.D2" )
			)
			( pin "@baseboard_fab2_lib.baseboard_fab2(sch_1):page194_i55:iod3"
				( attribute "PN" "D3"
					( Origin gPackager )
				)
				( objectStatus "J6E1.D3" )
			)
			( pin "@baseboard_fab2_lib.baseboard_fab2(sch_1):page194_i55:iod4"
				( attribute "PN" "D4"
					( Origin gPackager )
				)
				( objectStatus "J6E1.D4" )
			)
			( pin "@baseboard_fab2_lib.baseboard_fab2(sch_1):page194_i55:iod5"
				( attribute "PN" "D5"
					( Origin gPackager )
				)
				( objectStatus "J6E1.D5" )
			)
			( pin "@baseboard_fab2_lib.baseboard_fab2(sch_1):page194_i55:iod6"
				( attribute "PN" "D6"
					( Origin gPackager )
				)
				( objectStatus "J6E1.D6" )
			)
			( pin "@baseboard_fab2_lib.baseboard_fab2(sch_1):page194_i55:iod7"
				( attribute "PN" "D7"
					( Origin gPackager )
				)
				( objectStatus "J6E1.D7" )
			)
			( pin "@baseboard_fab2_lib.baseboard_fab2(sch_1):page194_i55:iod8"
				( attribute "PN" "D8"
					( Origin gPackager )
				)
				( objectStatus "J6E1.D8" )
			)
			( pin "@baseboard_fab2_lib.baseboard_fab2(sch_1):page194_i55:iod9"
				( attribute "PN" "D9"
					( Origin gPackager )
				)
				( objectStatus "J6E1.D9" )
			)
			( pin "@baseboard_fab2_lib.baseboard_fab2(sch_1):page194_i55:iod10"
				( attribute "PN" "D10"
					( Origin gPackager )
				)
				( objectStatus "J6E1.D10" )
			)
			( pin "@baseboard_fab2_lib.baseboard_fab2(sch_1):page194_i55:iod11"
				( attribute "PN" "D11"
					( Origin gPackager )
				)
				( objectStatus "J6E1.D11" )
			)
			( pin "@baseboard_fab2_lib.baseboard_fab2(sch_1):page194_i55:iod12"
				( attribute "PN" "D12"
					( Origin gPackager )
				)
				( objectStatus "J6E1.D12" )
			)
			( pin "@baseboard_fab2_lib.baseboard_fab2(sch_1):page194_i55:iod13"
				( attribute "PN" "D13"
					( Origin gPackager )
				)
				( objectStatus "J6E1.D13" )
			)
			( pin "@baseboard_fab2_lib.baseboard_fab2(sch_1):page194_i55:iod14"
				( attribute "PN" "D14"
					( Origin gPackager )
				)
				( objectStatus "J6E1.D14" )
			)
			( pin "@baseboard_fab2_lib.baseboard_fab2(sch_1):page194_i55:iod15"
				( attribute "PN" "D15"
					( Origin gPackager )
				)
				( objectStatus "J6E1.D15" )
			)
			( pin "@baseboard_fab2_lib.baseboard_fab2(sch_1):page194_i55:iod16"
				( attribute "PN" "D16"
					( Origin gPackager )
				)
				( objectStatus "J6E1.D16" )
			)
			( pin "@baseboard_fab2_lib.baseboard_fab2(sch_1):page194_i55:iod17"
				( attribute "PN" "D17"
					( Origin gPackager )
				)
				( objectStatus "J6E1.D17" )
			)
			( pin "@baseboard_fab2_lib.baseboard_fab2(sch_1):page194_i55:iod18"
				( attribute "PN" "D18"
					( Origin gPackager )
				)
				( objectStatus "J6E1.D18" )
			)
			( pin "@baseboard_fab2_lib.baseboard_fab2(sch_1):page194_i55:iod19"
				( attribute "PN" "D19"
					( Origin gPackager )
				)
				( objectStatus "J6E1.D19" )
			)
			( pin "@baseboard_fab2_lib.baseboard_fab2(sch_1):page194_i55:iod20"
				( attribute "PN" "D20"
					( Origin gPackager )
				)
				( objectStatus "J6E1.D20" )
			)
			( pin "@baseboard_fab2_lib.baseboard_fab2(sch_1):page194_i55:ioe1"
				( attribute "PN" "E1"
					( Origin gPackager )
				)
				( objectStatus "J6E1.E1" )
			)
			( pin "@baseboard_fab2_lib.baseboard_fab2(sch_1):page194_i55:ioe2"
				( attribute "PN" "E2"
					( Origin gPackager )
				)
				( objectStatus "J6E1.E2" )
			)
			( pin "@baseboard_fab2_lib.baseboard_fab2(sch_1):page194_i55:ioe3"
				( attribute "PN" "E3"
					( Origin gPackager )
				)
				( objectStatus "J6E1.E3" )
			)
			( pin "@baseboard_fab2_lib.baseboard_fab2(sch_1):page194_i55:ioe4"
				( attribute "PN" "E4"
					( Origin gPackager )
				)
				( objectStatus "J6E1.E4" )
			)
			( pin "@baseboard_fab2_lib.baseboard_fab2(sch_1):page194_i55:ioe5"
				( attribute "PN" "E5"
					( Origin gPackager )
				)
				( objectStatus "J6E1.E5" )
			)
			( pin "@baseboard_fab2_lib.baseboard_fab2(sch_1):page194_i55:ioe6"
				( attribute "PN" "E6"
					( Origin gPackager )
				)
				( objectStatus "J6E1.E6" )
			)
			( pin "@baseboard_fab2_lib.baseboard_fab2(sch_1):page194_i55:ioe7"
				( attribute "PN" "E7"
					( Origin gPackager )
				)
				( objectStatus "J6E1.E7" )
			)
			( pin "@baseboard_fab2_lib.baseboard_fab2(sch_1):page194_i55:ioe8"
				( attribute "PN" "E8"
					( Origin gPackager )
				)
				( objectStatus "J6E1.E8" )
			)
			( pin "@baseboard_fab2_lib.baseboard_fab2(sch_1):page194_i55:ioe9"
				( attribute "PN" "E9"
					( Origin gPackager )
				)
				( objectStatus "J6E1.E9" )
			)
			( pin "@baseboard_fab2_lib.baseboard_fab2(sch_1):page194_i55:ioe10"
				( attribute "PN" "E10"
					( Origin gPackager )
				)
				( objectStatus "J6E1.E10" )
			)
			( pin "@baseboard_fab2_lib.baseboard_fab2(sch_1):page194_i55:ioe11"
				( attribute "PN" "E11"
					( Origin gPackager )
				)
				( objectStatus "J6E1.E11" )
			)
			( pin "@baseboard_fab2_lib.baseboard_fab2(sch_1):page194_i55:ioe12"
				( attribute "PN" "E12"
					( Origin gPackager )
				)
				( objectStatus "J6E1.E12" )
			)
			( pin "@baseboard_fab2_lib.baseboard_fab2(sch_1):page194_i55:ioe13"
				( attribute "PN" "E13"
					( Origin gPackager )
				)
				( objectStatus "J6E1.E13" )
			)
			( pin "@baseboard_fab2_lib.baseboard_fab2(sch_1):page194_i55:ioe14"
				( attribute "PN" "E14"
					( Origin gPackager )
				)
				( objectStatus "J6E1.E14" )
			)
			( pin "@baseboard_fab2_lib.baseboard_fab2(sch_1):page194_i55:ioe15"
				( attribute "PN" "E15"
					( Origin gPackager )
				)
				( objectStatus "J6E1.E15" )
			)
			( pin "@baseboard_fab2_lib.baseboard_fab2(sch_1):page194_i55:ioe16"
				( attribute "PN" "E16"
					( Origin gPackager )
				)
				( objectStatus "J6E1.E16" )
			)
			( pin "@baseboard_fab2_lib.baseboard_fab2(sch_1):page194_i55:ioe17"
				( attribute "PN" "E17"
					( Origin gPackager )
				)
				( objectStatus "J6E1.E17" )
			)
			( pin "@baseboard_fab2_lib.baseboard_fab2(sch_1):page194_i55:ioe18"
				( attribute "PN" "E18"
					( Origin gPackager )
				)
				( objectStatus "J6E1.E18" )
			)
			( pin "@baseboard_fab2_lib.baseboard_fab2(sch_1):page194_i55:ioe19"
				( attribute "PN" "E19"
					( Origin gPackager )
				)
				( objectStatus "J6E1.E19" )
			)
			( pin "@baseboard_fab2_lib.baseboard_fab2(sch_1):page194_i55:ioe20"
				( attribute "PN" "E20"
					( Origin gPackager )
				)
				( objectStatus "J6E1.E20" )
			)
			( pin "@baseboard_fab2_lib.baseboard_fab2(sch_1):page194_i55:iof1"
				( attribute "PN" "F1"
					( Origin gPackager )
				)
				( objectStatus "J6E1.F1" )
			)
			( pin "@baseboard_fab2_lib.baseboard_fab2(sch_1):page194_i55:iof2"
				( attribute "PN" "F2"
					( Origin gPackager )
				)
				( objectStatus "J6E1.F2" )
			)
			( pin "@baseboard_fab2_lib.baseboard_fab2(sch_1):page194_i55:iof3"
				( attribute "PN" "F3"
					( Origin gPackager )
				)
				( objectStatus "J6E1.F3" )
			)
			( pin "@baseboard_fab2_lib.baseboard_fab2(sch_1):page194_i55:iof4"
				( attribute "PN" "F4"
					( Origin gPackager )
				)
				( objectStatus "J6E1.F4" )
			)
			( pin "@baseboard_fab2_lib.baseboard_fab2(sch_1):page194_i55:iof5"
				( attribute "PN" "F5"
					( Origin gPackager )
				)
				( objectStatus "J6E1.F5" )
			)
			( pin "@baseboard_fab2_lib.baseboard_fab2(sch_1):page194_i55:iof6"
				( attribute "PN" "F6"
					( Origin gPackager )
				)
				( objectStatus "J6E1.F6" )
			)
			( pin "@baseboard_fab2_lib.baseboard_fab2(sch_1):page194_i55:iof7"
				( attribute "PN" "F7"
					( Origin gPackager )
				)
				( objectStatus "J6E1.F7" )
			)
			( pin "@baseboard_fab2_lib.baseboard_fab2(sch_1):page194_i55:iof8"
				( attribute "PN" "F8"
					( Origin gPackager )
				)
				( objectStatus "J6E1.F8" )
			)
			( pin "@baseboard_fab2_lib.baseboard_fab2(sch_1):page194_i55:iof9"
				( attribute "PN" "F9"
					( Origin gPackager )
				)
				( objectStatus "J6E1.F9" )
			)
			( pin "@baseboard_fab2_lib.baseboard_fab2(sch_1):page194_i55:iof10"
				( attribute "PN" "F10"
					( Origin gPackager )
				)
				( objectStatus "J6E1.F10" )
			)
			( pin "@baseboard_fab2_lib.baseboard_fab2(sch_1):page194_i55:iof11"
				( attribute "PN" "F11"
					( Origin gPackager )
				)
				( objectStatus "J6E1.F11" )
			)
			( pin "@baseboard_fab2_lib.baseboard_fab2(sch_1):page194_i55:iof12"
				( attribute "PN" "F12"
					( Origin gPackager )
				)
				( objectStatus "J6E1.F12" )
			)
			( pin "@baseboard_fab2_lib.baseboard_fab2(sch_1):page194_i55:iof13"
				( attribute "PN" "F13"
					( Origin gPackager )
				)
				( objectStatus "J6E1.F13" )
			)
			( pin "@baseboard_fab2_lib.baseboard_fab2(sch_1):page194_i55:iof14"
				( attribute "PN" "F14"
					( Origin gPackager )
				)
				( objectStatus "J6E1.F14" )
			)
			( pin "@baseboard_fab2_lib.baseboard_fab2(sch_1):page194_i55:iof15"
				( attribute "PN" "F15"
					( Origin gPackager )
				)
				( objectStatus "J6E1.F15" )
			)
			( pin "@baseboard_fab2_lib.baseboard_fab2(sch_1):page194_i55:iof16"
				( attribute "PN" "F16"
					( Origin gPackager )
				)
				( objectStatus "J6E1.F16" )
			)
			( pin "@baseboard_fab2_lib.baseboard_fab2(sch_1):page194_i55:iof17"
				( attribute "PN" "F17"
					( Origin gPackager )
				)
				( objectStatus "J6E1.F17" )
			)
			( pin "@baseboard_fab2_lib.baseboard_fab2(sch_1):page194_i55:iof18"
				( attribute "PN" "F18"
					( Origin gPackager )
				)
				( objectStatus "J6E1.F18" )
			)
			( pin "@baseboard_fab2_lib.baseboard_fab2(sch_1):page194_i55:iof19"
				( attribute "PN" "F19"
					( Origin gPackager )
				)
				( objectStatus "J6E1.F19" )
			)
			( pin "@baseboard_fab2_lib.baseboard_fab2(sch_1):page194_i55:iof20"
				( attribute "PN" "F20"
					( Origin gPackager )
				)
				( objectStatus "J6E1.F20" )
			)
			( pin "@baseboard_fab2_lib.baseboard_fab2(sch_1):page194_i56:ioa1"
				( attribute "PN" "A1"
					( Origin gPackager )
				)
				( objectStatus "J6B1.A1" )
			)
			( pin "@baseboard_fab2_lib.baseboard_fab2(sch_1):page194_i56:ioa2"
				( attribute "PN" "A2"
					( Origin gPackager )
				)
				( objectStatus "J6B1.A2" )
			)
			( pin "@baseboard_fab2_lib.baseboard_fab2(sch_1):page194_i56:ioa3"
				( attribute "PN" "A3"
					( Origin gPackager )
				)
				( objectStatus "J6B1.A3" )
			)
			( pin "@baseboard_fab2_lib.baseboard_fab2(sch_1):page194_i56:ioa4"
				( attribute "PN" "A4"
					( Origin gPackager )
				)
				( objectStatus "J6B1.A4" )
			)
			( pin "@baseboard_fab2_lib.baseboard_fab2(sch_1):page194_i56:ioa5"
				( attribute "PN" "A5"
					( Origin gPackager )
				)
				( objectStatus "J6B1.A5" )
			)
			( pin "@baseboard_fab2_lib.baseboard_fab2(sch_1):page194_i56:ioa6"
				( attribute "PN" "A6"
					( Origin gPackager )
				)
				( objectStatus "J6B1.A6" )
			)
			( pin "@baseboard_fab2_lib.baseboard_fab2(sch_1):page194_i56:ioa7"
				( attribute "PN" "A7"
					( Origin gPackager )
				)
				( objectStatus "J6B1.A7" )
			)
			( pin "@baseboard_fab2_lib.baseboard_fab2(sch_1):page194_i56:ioa8"
				( attribute "PN" "A8"
					( Origin gPackager )
				)
				( objectStatus "J6B1.A8" )
			)
			( pin "@baseboard_fab2_lib.baseboard_fab2(sch_1):page194_i56:ioa9"
				( attribute "PN" "A9"
					( Origin gPackager )
				)
				( objectStatus "J6B1.A9" )
			)
			( pin "@baseboard_fab2_lib.baseboard_fab2(sch_1):page194_i56:ioa10"
				( attribute "PN" "A10"
					( Origin gPackager )
				)
				( objectStatus "J6B1.A10" )
			)
			( pin "@baseboard_fab2_lib.baseboard_fab2(sch_1):page194_i56:ioa11"
				( attribute "PN" "A11"
					( Origin gPackager )
				)
				( objectStatus "J6B1.A11" )
			)
			( pin "@baseboard_fab2_lib.baseboard_fab2(sch_1):page194_i56:ioa12"
				( attribute "PN" "A12"
					( Origin gPackager )
				)
				( objectStatus "J6B1.A12" )
			)
			( pin "@baseboard_fab2_lib.baseboard_fab2(sch_1):page194_i56:ioa13"
				( attribute "PN" "A13"
					( Origin gPackager )
				)
				( objectStatus "J6B1.A13" )
			)
			( pin "@baseboard_fab2_lib.baseboard_fab2(sch_1):page194_i56:ioa14"
				( attribute "PN" "A14"
					( Origin gPackager )
				)
				( objectStatus "J6B1.A14" )
			)
			( pin "@baseboard_fab2_lib.baseboard_fab2(sch_1):page194_i56:ioa15"
				( attribute "PN" "A15"
					( Origin gPackager )
				)
				( objectStatus "J6B1.A15" )
			)
			( pin "@baseboard_fab2_lib.baseboard_fab2(sch_1):page194_i56:ioa16"
				( attribute "PN" "A16"
					( Origin gPackager )
				)
				( objectStatus "J6B1.A16" )
			)
			( pin "@baseboard_fab2_lib.baseboard_fab2(sch_1):page194_i56:ioa17"
				( attribute "PN" "A17"
					( Origin gPackager )
				)
				( objectStatus "J6B1.A17" )
			)
			( pin "@baseboard_fab2_lib.baseboard_fab2(sch_1):page194_i56:ioa18"
				( attribute "PN" "A18"
					( Origin gPackager )
				)
				( objectStatus "J6B1.A18" )
			)
			( pin "@baseboard_fab2_lib.baseboard_fab2(sch_1):page194_i56:ioa19"
				( attribute "PN" "A19"
					( Origin gPackager )
				)
				( objectStatus "J6B1.A19" )
			)
			( pin "@baseboard_fab2_lib.baseboard_fab2(sch_1):page194_i56:ioa20"
				( attribute "PN" "A20"
					( Origin gPackager )
				)
				( objectStatus "J6B1.A20" )
			)
			( pin "@baseboard_fab2_lib.baseboard_fab2(sch_1):page194_i56:iob1"
				( attribute "PN" "B1"
					( Origin gPackager )
				)
				( objectStatus "J6B1.B1" )
			)
			( pin "@baseboard_fab2_lib.baseboard_fab2(sch_1):page194_i56:iob2"
				( attribute "PN" "B2"
					( Origin gPackager )
				)
				( objectStatus "J6B1.B2" )
			)
			( pin "@baseboard_fab2_lib.baseboard_fab2(sch_1):page194_i56:iob3"
				( attribute "PN" "B3"
					( Origin gPackager )
				)
				( objectStatus "J6B1.B3" )
			)
			( pin "@baseboard_fab2_lib.baseboard_fab2(sch_1):page194_i56:iob4"
				( attribute "PN" "B4"
					( Origin gPackager )
				)
				( objectStatus "J6B1.B4" )
			)
			( pin "@baseboard_fab2_lib.baseboard_fab2(sch_1):page194_i56:iob5"
				( attribute "PN" "B5"
					( Origin gPackager )
				)
				( objectStatus "J6B1.B5" )
			)
			( pin "@baseboard_fab2_lib.baseboard_fab2(sch_1):page194_i56:iob6"
				( attribute "PN" "B6"
					( Origin gPackager )
				)
				( objectStatus "J6B1.B6" )
			)
			( pin "@baseboard_fab2_lib.baseboard_fab2(sch_1):page194_i56:iob7"
				( attribute "PN" "B7"
					( Origin gPackager )
				)
				( objectStatus "J6B1.B7" )
			)
			( pin "@baseboard_fab2_lib.baseboard_fab2(sch_1):page194_i56:iob8"
				( attribute "PN" "B8"
					( Origin gPackager )
				)
				( objectStatus "J6B1.B8" )
			)
			( pin "@baseboard_fab2_lib.baseboard_fab2(sch_1):page194_i56:iob9"
				( attribute "PN" "B9"
					( Origin gPackager )
				)
				( objectStatus "J6B1.B9" )
			)
			( pin "@baseboard_fab2_lib.baseboard_fab2(sch_1):page194_i56:iob10"
				( attribute "PN" "B10"
					( Origin gPackager )
				)
				( objectStatus "J6B1.B10" )
			)
			( pin "@baseboard_fab2_lib.baseboard_fab2(sch_1):page194_i56:iob11"
				( attribute "PN" "B11"
					( Origin gPackager )
				)
				( objectStatus "J6B1.B11" )
			)
			( pin "@baseboard_fab2_lib.baseboard_fab2(sch_1):page194_i56:iob12"
				( attribute "PN" "B12"
					( Origin gPackager )
				)
				( objectStatus "J6B1.B12" )
			)
			( pin "@baseboard_fab2_lib.baseboard_fab2(sch_1):page194_i56:iob13"
				( attribute "PN" "B13"
					( Origin gPackager )
				)
				( objectStatus "J6B1.B13" )
			)
			( pin "@baseboard_fab2_lib.baseboard_fab2(sch_1):page194_i56:iob14"
				( attribute "PN" "B14"
					( Origin gPackager )
				)
				( objectStatus "J6B1.B14" )
			)
			( pin "@baseboard_fab2_lib.baseboard_fab2(sch_1):page194_i56:iob15"
				( attribute "PN" "B15"
					( Origin gPackager )
				)
				( objectStatus "J6B1.B15" )
			)
			( pin "@baseboard_fab2_lib.baseboard_fab2(sch_1):page194_i56:iob16"
				( attribute "PN" "B16"
					( Origin gPackager )
				)
				( objectStatus "J6B1.B16" )
			)
			( pin "@baseboard_fab2_lib.baseboard_fab2(sch_1):page194_i56:iob17"
				( attribute "PN" "B17"
					( Origin gPackager )
				)
				( objectStatus "J6B1.B17" )
			)
			( pin "@baseboard_fab2_lib.baseboard_fab2(sch_1):page194_i56:iob18"
				( attribute "PN" "B18"
					( Origin gPackager )
				)
				( objectStatus "J6B1.B18" )
			)
			( pin "@baseboard_fab2_lib.baseboard_fab2(sch_1):page194_i56:iob19"
				( attribute "PN" "B19"
					( Origin gPackager )
				)
				( objectStatus "J6B1.B19" )
			)
			( pin "@baseboard_fab2_lib.baseboard_fab2(sch_1):page194_i56:iob20"
				( attribute "PN" "B20"
					( Origin gPackager )
				)
				( objectStatus "J6B1.B20" )
			)
			( pin "@baseboard_fab2_lib.baseboard_fab2(sch_1):page194_i56:ioc1"
				( attribute "PN" "C1"
					( Origin gPackager )
				)
				( objectStatus "J6B1.C1" )
			)
			( pin "@baseboard_fab2_lib.baseboard_fab2(sch_1):page194_i56:ioc2"
				( attribute "PN" "C2"
					( Origin gPackager )
				)
				( objectStatus "J6B1.C2" )
			)
			( pin "@baseboard_fab2_lib.baseboard_fab2(sch_1):page194_i56:ioc3"
				( attribute "PN" "C3"
					( Origin gPackager )
				)
				( objectStatus "J6B1.C3" )
			)
			( pin "@baseboard_fab2_lib.baseboard_fab2(sch_1):page194_i56:ioc4"
				( attribute "PN" "C4"
					( Origin gPackager )
				)
				( objectStatus "J6B1.C4" )
			)
			( pin "@baseboard_fab2_lib.baseboard_fab2(sch_1):page194_i56:ioc5"
				( attribute "PN" "C5"
					( Origin gPackager )
				)
				( objectStatus "J6B1.C5" )
			)
			( pin "@baseboard_fab2_lib.baseboard_fab2(sch_1):page194_i56:ioc6"
				( attribute "PN" "C6"
					( Origin gPackager )
				)
				( objectStatus "J6B1.C6" )
			)
			( pin "@baseboard_fab2_lib.baseboard_fab2(sch_1):page194_i56:ioc7"
				( attribute "PN" "C7"
					( Origin gPackager )
				)
				( objectStatus "J6B1.C7" )
			)
			( pin "@baseboard_fab2_lib.baseboard_fab2(sch_1):page194_i56:ioc8"
				( attribute "PN" "C8"
					( Origin gPackager )
				)
				( objectStatus "J6B1.C8" )
			)
			( pin "@baseboard_fab2_lib.baseboard_fab2(sch_1):page194_i56:ioc9"
				( attribute "PN" "C9"
					( Origin gPackager )
				)
				( objectStatus "J6B1.C9" )
			)
			( pin "@baseboard_fab2_lib.baseboard_fab2(sch_1):page194_i56:ioc10"
				( attribute "PN" "C10"
					( Origin gPackager )
				)
				( objectStatus "J6B1.C10" )
			)
			( pin "@baseboard_fab2_lib.baseboard_fab2(sch_1):page194_i56:ioc11"
				( attribute "PN" "C11"
					( Origin gPackager )
				)
				( objectStatus "J6B1.C11" )
			)
			( pin "@baseboard_fab2_lib.baseboard_fab2(sch_1):page194_i56:ioc12"
				( attribute "PN" "C12"
					( Origin gPackager )
				)
				( objectStatus "J6B1.C12" )
			)
			( pin "@baseboard_fab2_lib.baseboard_fab2(sch_1):page194_i56:ioc13"
				( attribute "PN" "C13"
					( Origin gPackager )
				)
				( objectStatus "J6B1.C13" )
			)
			( pin "@baseboard_fab2_lib.baseboard_fab2(sch_1):page194_i56:ioc14"
				( attribute "PN" "C14"
					( Origin gPackager )
				)
				( objectStatus "J6B1.C14" )
			)
			( pin "@baseboard_fab2_lib.baseboard_fab2(sch_1):page194_i56:ioc15"
				( attribute "PN" "C15"
					( Origin gPackager )
				)
				( objectStatus "J6B1.C15" )
			)
			( pin "@baseboard_fab2_lib.baseboard_fab2(sch_1):page194_i56:ioc16"
				( attribute "PN" "C16"
					( Origin gPackager )
				)
				( objectStatus "J6B1.C16" )
			)
			( pin "@baseboard_fab2_lib.baseboard_fab2(sch_1):page194_i56:ioc17"
				( attribute "PN" "C17"
					( Origin gPackager )
				)
				( objectStatus "J6B1.C17" )
			)
			( pin "@baseboard_fab2_lib.baseboard_fab2(sch_1):page194_i56:ioc18"
				( attribute "PN" "C18"
					( Origin gPackager )
				)
				( objectStatus "J6B1.C18" )
			)
			( pin "@baseboard_fab2_lib.baseboard_fab2(sch_1):page194_i56:ioc19"
				( attribute "PN" "C19"
					( Origin gPackager )
				)
				( objectStatus "J6B1.C19" )
			)
			( pin "@baseboard_fab2_lib.baseboard_fab2(sch_1):page194_i56:ioc20"
				( attribute "PN" "C20"
					( Origin gPackager )
				)
				( objectStatus "J6B1.C20" )
			)
			( pin "@baseboard_fab2_lib.baseboard_fab2(sch_1):page194_i56:iod1"
				( attribute "PN" "D1"
					( Origin gPackager )
				)
				( objectStatus "J6B1.D1" )
			)
			( pin "@baseboard_fab2_lib.baseboard_fab2(sch_1):page194_i56:iod2"
				( attribute "PN" "D2"
					( Origin gPackager )
				)
				( objectStatus "J6B1.D2" )
			)
			( pin "@baseboard_fab2_lib.baseboard_fab2(sch_1):page194_i56:iod3"
				( attribute "PN" "D3"
					( Origin gPackager )
				)
				( objectStatus "J6B1.D3" )
			)
			( pin "@baseboard_fab2_lib.baseboard_fab2(sch_1):page194_i56:iod4"
				( attribute "PN" "D4"
					( Origin gPackager )
				)
				( objectStatus "J6B1.D4" )
			)
			( pin "@baseboard_fab2_lib.baseboard_fab2(sch_1):page194_i56:iod5"
				( attribute "PN" "D5"
					( Origin gPackager )
				)
				( objectStatus "J6B1.D5" )
			)
			( pin "@baseboard_fab2_lib.baseboard_fab2(sch_1):page194_i56:iod6"
				( attribute "PN" "D6"
					( Origin gPackager )
				)
				( objectStatus "J6B1.D6" )
			)
			( pin "@baseboard_fab2_lib.baseboard_fab2(sch_1):page194_i56:iod7"
				( attribute "PN" "D7"
					( Origin gPackager )
				)
				( objectStatus "J6B1.D7" )
			)
			( pin "@baseboard_fab2_lib.baseboard_fab2(sch_1):page194_i56:iod8"
				( attribute "PN" "D8"
					( Origin gPackager )
				)
				( objectStatus "J6B1.D8" )
			)
			( pin "@baseboard_fab2_lib.baseboard_fab2(sch_1):page194_i56:iod9"
				( attribute "PN" "D9"
					( Origin gPackager )
				)
				( objectStatus "J6B1.D9" )
			)
			( pin "@baseboard_fab2_lib.baseboard_fab2(sch_1):page194_i56:iod10"
				( attribute "PN" "D10"
					( Origin gPackager )
				)
				( objectStatus "J6B1.D10" )
			)
			( pin "@baseboard_fab2_lib.baseboard_fab2(sch_1):page194_i56:iod11"
				( attribute "PN" "D11"
					( Origin gPackager )
				)
				( objectStatus "J6B1.D11" )
			)
			( pin "@baseboard_fab2_lib.baseboard_fab2(sch_1):page194_i56:iod12"
				( attribute "PN" "D12"
					( Origin gPackager )
				)
				( objectStatus "J6B1.D12" )
			)
			( pin "@baseboard_fab2_lib.baseboard_fab2(sch_1):page194_i56:iod13"
				( attribute "PN" "D13"
					( Origin gPackager )
				)
				( objectStatus "J6B1.D13" )
			)
			( pin "@baseboard_fab2_lib.baseboard_fab2(sch_1):page194_i56:iod14"
				( attribute "PN" "D14"
					( Origin gPackager )
				)
				( objectStatus "J6B1.D14" )
			)
			( pin "@baseboard_fab2_lib.baseboard_fab2(sch_1):page194_i56:iod15"
				( attribute "PN" "D15"
					( Origin gPackager )
				)
				( objectStatus "J6B1.D15" )
			)
			( pin "@baseboard_fab2_lib.baseboard_fab2(sch_1):page194_i56:iod16"
				( attribute "PN" "D16"
					( Origin gPackager )
				)
				( objectStatus "J6B1.D16" )
			)
			( pin "@baseboard_fab2_lib.baseboard_fab2(sch_1):page194_i56:iod17"
				( attribute "PN" "D17"
					( Origin gPackager )
				)
				( objectStatus "J6B1.D17" )
			)
			( pin "@baseboard_fab2_lib.baseboard_fab2(sch_1):page194_i56:iod18"
				( attribute "PN" "D18"
					( Origin gPackager )
				)
				( objectStatus "J6B1.D18" )
			)
			( pin "@baseboard_fab2_lib.baseboard_fab2(sch_1):page194_i56:iod19"
				( attribute "PN" "D19"
					( Origin gPackager )
				)
				( objectStatus "J6B1.D19" )
			)
			( pin "@baseboard_fab2_lib.baseboard_fab2(sch_1):page194_i56:iod20"
				( attribute "PN" "D20"
					( Origin gPackager )
				)
				( objectStatus "J6B1.D20" )
			)
			( pin "@baseboard_fab2_lib.baseboard_fab2(sch_1):page194_i56:ioe1"
				( attribute "PN" "E1"
					( Origin gPackager )
				)
				( objectStatus "J6B1.E1" )
			)
			( pin "@baseboard_fab2_lib.baseboard_fab2(sch_1):page194_i56:ioe2"
				( attribute "PN" "E2"
					( Origin gPackager )
				)
				( objectStatus "J6B1.E2" )
			)
			( pin "@baseboard_fab2_lib.baseboard_fab2(sch_1):page194_i56:ioe3"
				( attribute "PN" "E3"
					( Origin gPackager )
				)
				( objectStatus "J6B1.E3" )
			)
			( pin "@baseboard_fab2_lib.baseboard_fab2(sch_1):page194_i56:ioe4"
				( attribute "PN" "E4"
					( Origin gPackager )
				)
				( objectStatus "J6B1.E4" )
			)
			( pin "@baseboard_fab2_lib.baseboard_fab2(sch_1):page194_i56:ioe5"
				( attribute "PN" "E5"
					( Origin gPackager )
				)
				( objectStatus "J6B1.E5" )
			)
			( pin "@baseboard_fab2_lib.baseboard_fab2(sch_1):page194_i56:ioe6"
				( attribute "PN" "E6"
					( Origin gPackager )
				)
				( objectStatus "J6B1.E6" )
			)
			( pin "@baseboard_fab2_lib.baseboard_fab2(sch_1):page194_i56:ioe7"
				( attribute "PN" "E7"
					( Origin gPackager )
				)
				( objectStatus "J6B1.E7" )
			)
			( pin "@baseboard_fab2_lib.baseboard_fab2(sch_1):page194_i56:ioe8"
				( attribute "PN" "E8"
					( Origin gPackager )
				)
				( objectStatus "J6B1.E8" )
			)
			( pin "@baseboard_fab2_lib.baseboard_fab2(sch_1):page194_i56:ioe9"
				( attribute "PN" "E9"
					( Origin gPackager )
				)
				( objectStatus "J6B1.E9" )
			)
			( pin "@baseboard_fab2_lib.baseboard_fab2(sch_1):page194_i56:ioe10"
				( attribute "PN" "E10"
					( Origin gPackager )
				)
				( objectStatus "J6B1.E10" )
			)
			( pin "@baseboard_fab2_lib.baseboard_fab2(sch_1):page194_i56:ioe11"
				( attribute "PN" "E11"
					( Origin gPackager )
				)
				( objectStatus "J6B1.E11" )
			)
			( pin "@baseboard_fab2_lib.baseboard_fab2(sch_1):page194_i56:ioe12"
				( attribute "PN" "E12"
					( Origin gPackager )
				)
				( objectStatus "J6B1.E12" )
			)
			( pin "@baseboard_fab2_lib.baseboard_fab2(sch_1):page194_i56:ioe13"
				( attribute "PN" "E13"
					( Origin gPackager )
				)
				( objectStatus "J6B1.E13" )
			)
			( pin "@baseboard_fab2_lib.baseboard_fab2(sch_1):page194_i56:ioe14"
				( attribute "PN" "E14"
					( Origin gPackager )
				)
				( objectStatus "J6B1.E14" )
			)
			( pin "@baseboard_fab2_lib.baseboard_fab2(sch_1):page194_i56:ioe15"
				( attribute "PN" "E15"
					( Origin gPackager )
				)
				( objectStatus "J6B1.E15" )
			)
			( pin "@baseboard_fab2_lib.baseboard_fab2(sch_1):page194_i56:ioe16"
				( attribute "PN" "E16"
					( Origin gPackager )
				)
				( objectStatus "J6B1.E16" )
			)
			( pin "@baseboard_fab2_lib.baseboard_fab2(sch_1):page194_i56:ioe17"
				( attribute "PN" "E17"
					( Origin gPackager )
				)
				( objectStatus "J6B1.E17" )
			)
			( pin "@baseboard_fab2_lib.baseboard_fab2(sch_1):page194_i56:ioe18"
				( attribute "PN" "E18"
					( Origin gPackager )
				)
				( objectStatus "J6B1.E18" )
			)
			( pin "@baseboard_fab2_lib.baseboard_fab2(sch_1):page194_i56:ioe19"
				( attribute "PN" "E19"
					( Origin gPackager )
				)
				( objectStatus "J6B1.E19" )
			)
			( pin "@baseboard_fab2_lib.baseboard_fab2(sch_1):page194_i56:ioe20"
				( attribute "PN" "E20"
					( Origin gPackager )
				)
				( objectStatus "J6B1.E20" )
			)
			( pin "@baseboard_fab2_lib.baseboard_fab2(sch_1):page194_i56:iof1"
				( attribute "PN" "F1"
					( Origin gPackager )
				)
				( objectStatus "J6B1.F1" )
			)
			( pin "@baseboard_fab2_lib.baseboard_fab2(sch_1):page194_i56:iof2"
				( attribute "PN" "F2"
					( Origin gPackager )
				)
				( objectStatus "J6B1.F2" )
			)
			( pin "@baseboard_fab2_lib.baseboard_fab2(sch_1):page194_i56:iof3"
				( attribute "PN" "F3"
					( Origin gPackager )
				)
				( objectStatus "J6B1.F3" )
			)
			( pin "@baseboard_fab2_lib.baseboard_fab2(sch_1):page194_i56:iof4"
				( attribute "PN" "F4"
					( Origin gPackager )
				)
				( objectStatus "J6B1.F4" )
			)
			( pin "@baseboard_fab2_lib.baseboard_fab2(sch_1):page194_i56:iof5"
				( attribute "PN" "F5"
					( Origin gPackager )
				)
				( objectStatus "J6B1.F5" )
			)
			( pin "@baseboard_fab2_lib.baseboard_fab2(sch_1):page194_i56:iof6"
				( attribute "PN" "F6"
					( Origin gPackager )
				)
				( objectStatus "J6B1.F6" )
			)
			( pin "@baseboard_fab2_lib.baseboard_fab2(sch_1):page194_i56:iof7"
				( attribute "PN" "F7"
					( Origin gPackager )
				)
				( objectStatus "J6B1.F7" )
			)
			( pin "@baseboard_fab2_lib.baseboard_fab2(sch_1):page194_i56:iof8"
				( attribute "PN" "F8"
					( Origin gPackager )
				)
				( objectStatus "J6B1.F8" )
			)
			( pin "@baseboard_fab2_lib.baseboard_fab2(sch_1):page194_i56:iof9"
				( attribute "PN" "F9"
					( Origin gPackager )
				)
				( objectStatus "J6B1.F9" )
			)
			( pin "@baseboard_fab2_lib.baseboard_fab2(sch_1):page194_i56:iof10"
				( attribute "PN" "F10"
					( Origin gPackager )
				)
				( objectStatus "J6B1.F10" )
			)
			( pin "@baseboard_fab2_lib.baseboard_fab2(sch_1):page194_i56:iof11"
				( attribute "PN" "F11"
					( Origin gPackager )
				)
				( objectStatus "J6B1.F11" )
			)
			( pin "@baseboard_fab2_lib.baseboard_fab2(sch_1):page194_i56:iof12"
				( attribute "PN" "F12"
					( Origin gPackager )
				)
				( objectStatus "J6B1.F12" )
			)
			( pin "@baseboard_fab2_lib.baseboard_fab2(sch_1):page194_i56:iof13"
				( attribute "PN" "F13"
					( Origin gPackager )
				)
				( objectStatus "J6B1.F13" )
			)
			( pin "@baseboard_fab2_lib.baseboard_fab2(sch_1):page194_i56:iof14"
				( attribute "PN" "F14"
					( Origin gPackager )
				)
				( objectStatus "J6B1.F14" )
			)
			( pin "@baseboard_fab2_lib.baseboard_fab2(sch_1):page194_i56:iof15"
				( attribute "PN" "F15"
					( Origin gPackager )
				)
				( objectStatus "J6B1.F15" )
			)
			( pin "@baseboard_fab2_lib.baseboard_fab2(sch_1):page194_i56:iof16"
				( attribute "PN" "F16"
					( Origin gPackager )
				)
				( objectStatus "J6B1.F16" )
			)
			( pin "@baseboard_fab2_lib.baseboard_fab2(sch_1):page194_i56:iof17"
				( attribute "PN" "F17"
					( Origin gPackager )
				)
				( objectStatus "J6B1.F17" )
			)
			( pin "@baseboard_fab2_lib.baseboard_fab2(sch_1):page194_i56:iof18"
				( attribute "PN" "F18"
					( Origin gPackager )
				)
				( objectStatus "J6B1.F18" )
			)
			( pin "@baseboard_fab2_lib.baseboard_fab2(sch_1):page194_i56:iof19"
				( attribute "PN" "F19"
					( Origin gPackager )
				)
				( objectStatus "J6B1.F19" )
			)
			( pin "@baseboard_fab2_lib.baseboard_fab2(sch_1):page194_i56:iof20"
				( attribute "PN" "F20"
					( Origin gPackager )
				)
				( objectStatus "J6B1.F20" )
			)
			( pin "@baseboard_fab2_lib.baseboard_fab2(sch_1):page194_i86:a"
				( attribute "PN" "1"
					( Origin gPackager )
				)
				( objectStatus "C3N40.1" )
			)
			( pin "@baseboard_fab2_lib.baseboard_fab2(sch_1):page194_i86:b"
				( attribute "PN" "2"
					( Origin gPackager )
				)
				( objectStatus "C3N40.2" )
			)
			( pin "@baseboard_fab2_lib.baseboard_fab2(sch_1):page194_i99:a"
				( attribute "PN" "1"
					( Origin gPackager )
				)
				( objectStatus "C3M46.1" )
			)
			( pin "@baseboard_fab2_lib.baseboard_fab2(sch_1):page194_i99:b"
				( attribute "PN" "2"
					( Origin gPackager )
				)
				( objectStatus "C3M46.2" )
			)
			( pin "@baseboard_fab2_lib.baseboard_fab2(sch_1):page194_i101:a"
				( attribute "PN" "1"
					( Origin gPackager )
				)
				( objectStatus "C3N14.1" )
			)
			( pin "@baseboard_fab2_lib.baseboard_fab2(sch_1):page194_i101:b"
				( attribute "PN" "2"
					( Origin gPackager )
				)
				( objectStatus "C3N14.2" )
			)
			( pin "@baseboard_fab2_lib.baseboard_fab2(sch_1):page194_i149:a"
				( attribute "PN" "1"
					( Origin gPackager )
				)
				( objectStatus "C3T1.1" )
			)
			( pin "@baseboard_fab2_lib.baseboard_fab2(sch_1):page194_i149:b"
				( attribute "PN" "2"
					( Origin gPackager )
				)
				( objectStatus "C3T1.2" )
			)
			( pin "@baseboard_fab2_lib.baseboard_fab2(sch_1):page194_i150:a"
				( attribute "PN" "1"
					( Origin gPackager )
				)
				( objectStatus "C3T2.1" )
			)
			( pin "@baseboard_fab2_lib.baseboard_fab2(sch_1):page194_i150:b"
				( attribute "PN" "2"
					( Origin gPackager )
				)
				( objectStatus "C3T2.2" )
			)
			( pin "@baseboard_fab2_lib.baseboard_fab2(sch_1):page194_i155:a"
				( attribute "PN" "1"
					( Origin gPackager )
				)
				( objectStatus "R7C24.1" )
			)
			( pin "@baseboard_fab2_lib.baseboard_fab2(sch_1):page194_i155:b"
				( attribute "PN" "2"
					( Origin gPackager )
				)
				( objectStatus "R7C24.2" )
			)
			( pin "@baseboard_fab2_lib.baseboard_fab2(sch_1):page194_i156:a"
				( attribute "PN" "1"
					( Origin gPackager )
				)
				( objectStatus "R3N29.1" )
			)
			( pin "@baseboard_fab2_lib.baseboard_fab2(sch_1):page194_i156:b"
				( attribute "PN" "2"
					( Origin gPackager )
				)
				( objectStatus "R3N29.2" )
			)
			( pin "@baseboard_fab2_lib.baseboard_fab2(sch_1):page195_i26:io1"
				( attribute "PN" "1"
					( Origin gPackager )
				)
				( objectStatus "RM1E1.1" )
			)
			( pin "@baseboard_fab2_lib.baseboard_fab2(sch_1):page195_i26:io2"
				( attribute "PN" "2"
					( Origin gPackager )
				)
				( objectStatus "RM1E1.2" )
			)
			( pin "@baseboard_fab2_lib.baseboard_fab2(sch_1):page195_i26:io3"
				( attribute "PN" "3"
					( Origin gPackager )
				)
				( objectStatus "RM1E1.3" )
			)
			( pin "@baseboard_fab2_lib.baseboard_fab2(sch_1):page195_i31:a"
				( attribute "PN" "1"
					( Origin gPackager )
				)
				( objectStatus "C9R5.1" )
			)
			( pin "@baseboard_fab2_lib.baseboard_fab2(sch_1):page195_i31:b"
				( attribute "PN" "2"
					( Origin gPackager )
				)
				( objectStatus "C9R5.2" )
			)
			( pin "@baseboard_fab2_lib.baseboard_fab2(sch_1):page195_i32:a"
				( attribute "PN" "1"
					( Origin gPackager )
				)
				( objectStatus "C1E12.1" )
			)
			( pin "@baseboard_fab2_lib.baseboard_fab2(sch_1):page195_i32:b"
				( attribute "PN" "2"
					( Origin gPackager )
				)
				( objectStatus "C1E12.2" )
			)
			( pin "@baseboard_fab2_lib.baseboard_fab2(sch_1):page195_i35:a"
				( attribute "PN" "1"
					( Origin gPackager )
				)
				( objectStatus "C1E15.1" )
			)
			( pin "@baseboard_fab2_lib.baseboard_fab2(sch_1):page195_i35:b"
				( attribute "PN" "2"
					( Origin gPackager )
				)
				( objectStatus "C1E15.2" )
			)
			( pin "@baseboard_fab2_lib.baseboard_fab2(sch_1):page195_i36:a"
				( attribute "PN" "1"
					( Origin gPackager )
				)
				( objectStatus "C9R12.1" )
			)
			( pin "@baseboard_fab2_lib.baseboard_fab2(sch_1):page195_i36:b"
				( attribute "PN" "2"
					( Origin gPackager )
				)
				( objectStatus "C9R12.2" )
			)
			( pin "@baseboard_fab2_lib.baseboard_fab2(sch_1):page195_i37:a"
				( attribute "PN" "1"
					( Origin gPackager )
				)
				( objectStatus "C9R6.1" )
			)
			( pin "@baseboard_fab2_lib.baseboard_fab2(sch_1):page195_i37:b"
				( attribute "PN" "2"
					( Origin gPackager )
				)
				( objectStatus "C9R6.2" )
			)
			( pin "@baseboard_fab2_lib.baseboard_fab2(sch_1):page195_i38:a"
				( attribute "PN" "1"
					( Origin gPackager )
				)
				( objectStatus "C1E17.1" )
			)
			( pin "@baseboard_fab2_lib.baseboard_fab2(sch_1):page195_i38:b"
				( attribute "PN" "2"
					( Origin gPackager )
				)
				( objectStatus "C1E17.2" )
			)
			( pin "@baseboard_fab2_lib.baseboard_fab2(sch_1):page195_i39:a"
				( attribute "PN" "1"
					( Origin gPackager )
				)
				( objectStatus "C1E16.1" )
			)
			( pin "@baseboard_fab2_lib.baseboard_fab2(sch_1):page195_i39:b"
				( attribute "PN" "2"
					( Origin gPackager )
				)
				( objectStatus "C1E16.2" )
			)
			( pin "@baseboard_fab2_lib.baseboard_fab2(sch_1):page195_i49:\1\"
				( attribute "PN" "1"
					( Origin gPackager )
				)
				( objectStatus "TH4G1.1" )
			)
			( pin "@baseboard_fab2_lib.baseboard_fab2(sch_1):page195_i52:\1\"
				( attribute "PN" "1"
					( Origin gPackager )
				)
				( objectStatus "TH9G1.1" )
			)
			( pin "@baseboard_fab2_lib.baseboard_fab2(sch_1):page195_i54:\1\"
				( attribute "PN" "1"
					( Origin gPackager )
				)
				( objectStatus "TH9A1.1" )
			)
			( pin "@baseboard_fab2_lib.baseboard_fab2(sch_1):page195_i56:\1\"
				( attribute "PN" "1"
					( Origin gPackager )
				)
				( objectStatus "TH1A1.1" )
			)
			( pin "@baseboard_fab2_lib.baseboard_fab2(sch_1):page195_i62:\1\"
				( attribute "PN" "1"
					( Origin gPackager )
				)
				( objectStatus "TH4A1.1" )
			)
			( pin "@baseboard_fab2_lib.baseboard_fab2(sch_1):page195_i65:\1\"
				( attribute "PN" "1"
					( Origin gPackager )
				)
				( objectStatus "TH7A1.1" )
			)
			( pin "@baseboard_fab2_lib.baseboard_fab2(sch_1):page195_i67:\1\"
				( attribute "PN" "1"
					( Origin gPackager )
				)
				( objectStatus "TH7G1.1" )
			)
			( pin "@baseboard_fab2_lib.baseboard_fab2(sch_1):page195_i82:a"
				( attribute "PN" "1"
					( Origin gPackager )
				)
				( objectStatus "C4F6.1" )
			)
			( pin "@baseboard_fab2_lib.baseboard_fab2(sch_1):page195_i82:b"
				( attribute "PN" "2"
					( Origin gPackager )
				)
				( objectStatus "C4F6.2" )
			)
			( pin "@baseboard_fab2_lib.baseboard_fab2(sch_1):page195_i83:a"
				( attribute "PN" "1"
					( Origin gPackager )
				)
				( objectStatus "C4B13.1" )
			)
			( pin "@baseboard_fab2_lib.baseboard_fab2(sch_1):page195_i83:b"
				( attribute "PN" "2"
					( Origin gPackager )
				)
				( objectStatus "C4B13.2" )
			)
			( pin "@baseboard_fab2_lib.baseboard_fab2(sch_1):page195_i84:a"
				( attribute "PN" "1"
					( Origin gPackager )
				)
				( objectStatus "C1B14.1" )
			)
			( pin "@baseboard_fab2_lib.baseboard_fab2(sch_1):page195_i84:b"
				( attribute "PN" "2"
					( Origin gPackager )
				)
				( objectStatus "C1B14.2" )
			)
			( pin "@baseboard_fab2_lib.baseboard_fab2(sch_1):page195_i85:a"
				( attribute "PN" "1"
					( Origin gPackager )
				)
				( objectStatus "C1F7.1" )
			)
			( pin "@baseboard_fab2_lib.baseboard_fab2(sch_1):page195_i85:b"
				( attribute "PN" "2"
					( Origin gPackager )
				)
				( objectStatus "C1F7.2" )
			)
			( pin "@baseboard_fab2_lib.baseboard_fab2(sch_1):page195_i96:a"
				( attribute "PN" "1"
					( Origin gPackager )
				)
				( objectStatus "C4F5.1" )
			)
			( pin "@baseboard_fab2_lib.baseboard_fab2(sch_1):page195_i96:b"
				( attribute "PN" "2"
					( Origin gPackager )
				)
				( objectStatus "C4F5.2" )
			)
			( pin "@baseboard_fab2_lib.baseboard_fab2(sch_1):page195_i97:a"
				( attribute "PN" "1"
					( Origin gPackager )
				)
				( objectStatus "C4B14.1" )
			)
			( pin "@baseboard_fab2_lib.baseboard_fab2(sch_1):page195_i97:b"
				( attribute "PN" "2"
					( Origin gPackager )
				)
				( objectStatus "C4B14.2" )
			)
			( pin "@baseboard_fab2_lib.baseboard_fab2(sch_1):page195_i98:a"
				( attribute "PN" "1"
					( Origin gPackager )
				)
				( objectStatus "C3T6.1" )
			)
			( pin "@baseboard_fab2_lib.baseboard_fab2(sch_1):page195_i98:b"
				( attribute "PN" "2"
					( Origin gPackager )
				)
				( objectStatus "C3T6.2" )
			)
			( pin "@baseboard_fab2_lib.baseboard_fab2(sch_1):page195_i99:a"
				( attribute "PN" "1"
					( Origin gPackager )
				)
				( objectStatus "C9M3.1" )
			)
			( pin "@baseboard_fab2_lib.baseboard_fab2(sch_1):page195_i99:b"
				( attribute "PN" "2"
					( Origin gPackager )
				)
				( objectStatus "C9M3.2" )
			)
			( pin "@baseboard_fab2_lib.baseboard_fab2(sch_1):page195_i100:a"
				( attribute "PN" "1"
					( Origin gPackager )
				)
				( objectStatus "C3B6.1" )
			)
			( pin "@baseboard_fab2_lib.baseboard_fab2(sch_1):page195_i100:b"
				( attribute "PN" "2"
					( Origin gPackager )
				)
				( objectStatus "C3B6.2" )
			)
			( pin "@baseboard_fab2_lib.baseboard_fab2(sch_1):page195_i101:a"
				( attribute "PN" "1"
					( Origin gPackager )
				)
				( objectStatus "C1R23.1" )
			)
			( pin "@baseboard_fab2_lib.baseboard_fab2(sch_1):page195_i101:b"
				( attribute "PN" "2"
					( Origin gPackager )
				)
				( objectStatus "C1R23.2" )
			)
			( pin "@baseboard_fab2_lib.baseboard_fab2(sch_1):page195_i102:a"
				( attribute "PN" "1"
					( Origin gPackager )
				)
				( objectStatus "C4M6.1" )
			)
			( pin "@baseboard_fab2_lib.baseboard_fab2(sch_1):page195_i102:b"
				( attribute "PN" "2"
					( Origin gPackager )
				)
				( objectStatus "C4M6.2" )
			)
			( pin "@baseboard_fab2_lib.baseboard_fab2(sch_1):page195_i103:a"
				( attribute "PN" "1"
					( Origin gPackager )
				)
				( objectStatus "C1M5.1" )
			)
			( pin "@baseboard_fab2_lib.baseboard_fab2(sch_1):page195_i103:b"
				( attribute "PN" "2"
					( Origin gPackager )
				)
				( objectStatus "C1M5.2" )
			)
			( pin "@baseboard_fab2_lib.baseboard_fab2(sch_1):page195_i104:a"
				( attribute "PN" "1"
					( Origin gPackager )
				)
				( objectStatus "C3T13.1" )
			)
			( pin "@baseboard_fab2_lib.baseboard_fab2(sch_1):page195_i104:b"
				( attribute "PN" "2"
					( Origin gPackager )
				)
				( objectStatus "C3T13.2" )
			)
			( pin "@baseboard_fab2_lib.baseboard_fab2(sch_1):page195_i105:a"
				( attribute "PN" "1"
					( Origin gPackager )
				)
				( objectStatus "C4M7.1" )
			)
			( pin "@baseboard_fab2_lib.baseboard_fab2(sch_1):page195_i105:b"
				( attribute "PN" "2"
					( Origin gPackager )
				)
				( objectStatus "C4M7.2" )
			)
			( pin "@baseboard_fab2_lib.baseboard_fab2(sch_1):page195_i106:a"
				( attribute "PN" "1"
					( Origin gPackager )
				)
				( objectStatus "C3T15.1" )
			)
			( pin "@baseboard_fab2_lib.baseboard_fab2(sch_1):page195_i106:b"
				( attribute "PN" "2"
					( Origin gPackager )
				)
				( objectStatus "C3T15.2" )
			)
			( pin "@baseboard_fab2_lib.baseboard_fab2(sch_1):page195_i108:a"
				( attribute "PN" "1"
					( Origin gPackager )
				)
				( objectStatus "C7M6.1" )
			)
			( pin "@baseboard_fab2_lib.baseboard_fab2(sch_1):page195_i108:b"
				( attribute "PN" "2"
					( Origin gPackager )
				)
				( objectStatus "C7M6.2" )
			)
			( pin "@baseboard_fab2_lib.baseboard_fab2(sch_1):page195_i109:a"
				( attribute "PN" "1"
					( Origin gPackager )
				)
				( objectStatus "C6N5.1" )
			)
			( pin "@baseboard_fab2_lib.baseboard_fab2(sch_1):page195_i109:b"
				( attribute "PN" "2"
					( Origin gPackager )
				)
				( objectStatus "C6N5.2" )
			)
			( pin "@baseboard_fab2_lib.baseboard_fab2(sch_1):page195_i111:a"
				( attribute "PN" "1"
					( Origin gPackager )
				)
				( objectStatus "C9T3.1" )
			)
			( pin "@baseboard_fab2_lib.baseboard_fab2(sch_1):page195_i111:b"
				( attribute "PN" "2"
					( Origin gPackager )
				)
				( objectStatus "C9T3.2" )
			)
			( pin "@baseboard_fab2_lib.baseboard_fab2(sch_1):page195_i112:a"
				( attribute "PN" "1"
					( Origin gPackager )
				)
				( objectStatus "C4F4.1" )
			)
			( pin "@baseboard_fab2_lib.baseboard_fab2(sch_1):page195_i112:b"
				( attribute "PN" "2"
					( Origin gPackager )
				)
				( objectStatus "C4F4.2" )
			)
			( pin "@baseboard_fab2_lib.baseboard_fab2(sch_1):page195_i113:a"
				( attribute "PN" "1"
					( Origin gPackager )
				)
				( objectStatus "C3T3.1" )
			)
			( pin "@baseboard_fab2_lib.baseboard_fab2(sch_1):page195_i113:b"
				( attribute "PN" "2"
					( Origin gPackager )
				)
				( objectStatus "C3T3.2" )
			)
			( pin "@baseboard_fab2_lib.baseboard_fab2(sch_1):page196_i46:a"
				( attribute "PN" "1"
					( Origin gPackager )
				)
				( objectStatus "R2U43.1" )
			)
			( pin "@baseboard_fab2_lib.baseboard_fab2(sch_1):page196_i46:b"
				( attribute "PN" "2"
					( Origin gPackager )
				)
				( objectStatus "R2U43.2" )
			)
			( pin "@baseboard_fab2_lib.baseboard_fab2(sch_1):page196_i51:n"
				( attribute "PN" "3"
					( Origin gPackager )
				)
				( objectStatus "XBT8G1.3" )
			)
			( pin "@baseboard_fab2_lib.baseboard_fab2(sch_1):page196_i51:p1"
				( attribute "PN" "1"
					( Origin gPackager )
				)
				( objectStatus "XBT8G1.1" )
			)
			( pin "@baseboard_fab2_lib.baseboard_fab2(sch_1):page196_i51:p2"
				( attribute "PN" "2"
					( Origin gPackager )
				)
				( objectStatus "XBT8G1.2" )
			)
			( pin "@baseboard_fab2_lib.baseboard_fab2(sch_1):page196_i53:a1"
				( attribute "PN" "1"
					( Origin gPackager )
				)
				( objectStatus "CR2U1.1" )
			)
			( pin "@baseboard_fab2_lib.baseboard_fab2(sch_1):page196_i53:a2"
				( attribute "PN" "2"
					( Origin gPackager )
				)
				( objectStatus "CR2U1.2" )
			)
			( pin "@baseboard_fab2_lib.baseboard_fab2(sch_1):page196_i53:c"
				( attribute "PN" "3"
					( Origin gPackager )
				)
				( objectStatus "CR2U1.3" )
			)
			( pin "@baseboard_fab2_lib.baseboard_fab2(sch_1):page196_i59:a"
				( attribute "PN" "1"
					( Origin gPackager )
				)
				( objectStatus "R3P44.1" )
			)
			( pin "@baseboard_fab2_lib.baseboard_fab2(sch_1):page196_i59:b"
				( attribute "PN" "2"
					( Origin gPackager )
				)
				( objectStatus "R3P44.2" )
			)
			( pin "@baseboard_fab2_lib.baseboard_fab2(sch_1):page196_i60:a"
				( attribute "PN" "1"
					( Origin gPackager )
				)
				( objectStatus "C3P45.1" )
			)
			( pin "@baseboard_fab2_lib.baseboard_fab2(sch_1):page196_i60:b"
				( attribute "PN" "2"
					( Origin gPackager )
				)
				( objectStatus "C3P45.2" )
			)
			( pin "@baseboard_fab2_lib.baseboard_fab2(sch_1):page196_i65:a"
				( attribute "PN" "1"
					( Origin gPackager )
				)
				( objectStatus "R2P20.1" )
			)
			( pin "@baseboard_fab2_lib.baseboard_fab2(sch_1):page196_i65:b"
				( attribute "PN" "2"
					( Origin gPackager )
				)
				( objectStatus "R2P20.2" )
			)
			( pin "@baseboard_fab2_lib.baseboard_fab2(sch_1):page196_i68:a"
				( attribute "PN" "1"
					( Origin gPackager )
				)
				( objectStatus "R1L16.1" )
			)
			( pin "@baseboard_fab2_lib.baseboard_fab2(sch_1):page196_i68:b"
				( attribute "PN" "2"
					( Origin gPackager )
				)
				( objectStatus "R1L16.2" )
			)
			( pin "@baseboard_fab2_lib.baseboard_fab2(sch_1):page196_i70:cext"
				( attribute "PN" "5"
					( Origin gPackager )
				)
				( objectStatus "U7D3.5" )
			)
			( pin "@baseboard_fab2_lib.baseboard_fab2(sch_1):page196_i70:enin"
				( attribute "PN" "1"
					( Origin gPackager )
				)
				( objectStatus "U7D3.1" )
			)
			( pin "@baseboard_fab2_lib.baseboard_fab2(sch_1):page196_i70:enout"
				( attribute "PN" "4"
					( Origin gPackager )
				)
				( objectStatus "U7D3.4" )
			)
			( pin "@baseboard_fab2_lib.baseboard_fab2(sch_1):page196_i70:gnd"
				( attribute "PN" "2"
					( Origin gPackager )
				)
				( objectStatus "U7D3.2" )
			)
			( pin "@baseboard_fab2_lib.baseboard_fab2(sch_1):page196_i70:vcc"
				( attribute "PN" "6"
					( Origin gPackager )
				)
				( objectStatus "U7D3.6" )
			)
			( pin "@baseboard_fab2_lib.baseboard_fab2(sch_1):page196_i70:vin"
				( attribute "PN" "3"
					( Origin gPackager )
				)
				( objectStatus "U7D3.3" )
			)
			( pin "@baseboard_fab2_lib.baseboard_fab2(sch_1):page196_i71:a"
				( attribute "PN" "1"
					( Origin gPackager )
				)
				( objectStatus "R3P50.1" )
			)
			( pin "@baseboard_fab2_lib.baseboard_fab2(sch_1):page196_i71:b"
				( attribute "PN" "2"
					( Origin gPackager )
				)
				( objectStatus "R3P50.2" )
			)
			( pin "@baseboard_fab2_lib.baseboard_fab2(sch_1):page196_i72:a"
				( attribute "PN" "1"
					( Origin gPackager )
				)
				( objectStatus "C3P46.1" )
			)
			( pin "@baseboard_fab2_lib.baseboard_fab2(sch_1):page196_i72:b"
				( attribute "PN" "2"
					( Origin gPackager )
				)
				( objectStatus "C3P46.2" )
			)
			( pin "@baseboard_fab2_lib.baseboard_fab2(sch_1):page196_i74:a"
				( attribute "PN" "1"
					( Origin gPackager )
				)
				( objectStatus "R3P48.1" )
			)
			( pin "@baseboard_fab2_lib.baseboard_fab2(sch_1):page196_i74:b"
				( attribute "PN" "2"
					( Origin gPackager )
				)
				( objectStatus "R3P48.2" )
			)
			( pin "@baseboard_fab2_lib.baseboard_fab2(sch_1):page196_i75:a"
				( attribute "PN" "1"
					( Origin gPackager )
				)
				( objectStatus "R3P51.1" )
			)
			( pin "@baseboard_fab2_lib.baseboard_fab2(sch_1):page196_i75:b"
				( attribute "PN" "2"
					( Origin gPackager )
				)
				( objectStatus "R3P51.2" )
			)
			( pin "@baseboard_fab2_lib.baseboard_fab2(sch_1):page196_i80:reset_n"
				( attribute "PN" "2"
					( Origin gPackager )
				)
				( objectStatus "U1L3.2" )
			)
			( pin "@baseboard_fab2_lib.baseboard_fab2(sch_1):page196_i80:vcc"
				( attribute "PN" "3"
					( Origin gPackager )
				)
				( objectStatus "U1L3.3" )
			)
			( pin "@baseboard_fab2_lib.baseboard_fab2(sch_1):page196_i81:a"
				( attribute "PN" "1"
					( Origin gPackager )
				)
				( objectStatus "C1L16.1" )
			)
			( pin "@baseboard_fab2_lib.baseboard_fab2(sch_1):page196_i81:b"
				( attribute "PN" "2"
					( Origin gPackager )
				)
				( objectStatus "C1L16.2" )
			)
			( pin "@baseboard_fab2_lib.baseboard_fab2(sch_1):page196_i89:reset_n"
				( attribute "PN" "2"
					( Origin gPackager )
				)
				( objectStatus "U8E2.2" )
			)
			( pin "@baseboard_fab2_lib.baseboard_fab2(sch_1):page196_i89:vcc"
				( attribute "PN" "3"
					( Origin gPackager )
				)
				( objectStatus "U8E2.3" )
			)
			( pin "@baseboard_fab2_lib.baseboard_fab2(sch_1):page196_i90:a"
				( attribute "PN" "1"
					( Origin gPackager )
				)
				( objectStatus "R8E7.1" )
			)
			( pin "@baseboard_fab2_lib.baseboard_fab2(sch_1):page196_i90:b"
				( attribute "PN" "2"
					( Origin gPackager )
				)
				( objectStatus "R8E7.2" )
			)
			( pin "@baseboard_fab2_lib.baseboard_fab2(sch_1):page196_i94:a"
				( attribute "PN" "1"
					( Origin gPackager )
				)
				( objectStatus "C8E3.1" )
			)
			( pin "@baseboard_fab2_lib.baseboard_fab2(sch_1):page196_i94:b"
				( attribute "PN" "2"
					( Origin gPackager )
				)
				( objectStatus "C8E3.2" )
			)
			( pin "@baseboard_fab2_lib.baseboard_fab2(sch_1):page196_i102:a"
				( attribute "PN" "1"
					( Origin gPackager )
				)
				( objectStatus "C2U26.1" )
			)
			( pin "@baseboard_fab2_lib.baseboard_fab2(sch_1):page196_i102:b"
				( attribute "PN" "2"
					( Origin gPackager )
				)
				( objectStatus "C2U26.2" )
			)
			( pin "@baseboard_fab2_lib.baseboard_fab2(sch_1):page196_i103:a"
				( attribute "PN" "2"
					( Origin gPackager )
				)
				( objectStatus "CR7E1.2" )
			)
			( pin "@baseboard_fab2_lib.baseboard_fab2(sch_1):page196_i103:c"
				( attribute "PN" "1"
					( Origin gPackager )
				)
				( objectStatus "CR7E1.1" )
			)
			( pin "@baseboard_fab2_lib.baseboard_fab2(sch_1):page196_i104:gnd"
				( attribute "PN" "5"
					( Origin gPackager )
				)
				( objectStatus "U8D8.5" )
			)
			( pin "@baseboard_fab2_lib.baseboard_fab2(sch_1):page196_i104:inap"
				( attribute "PN" "4"
					( Origin gPackager )
				)
				( objectStatus "U8D8.4" )
			)
			( pin "@baseboard_fab2_lib.baseboard_fab2(sch_1):page196_i104:inbn"
				( attribute "PN" "3"
					( Origin gPackager )
				)
				( objectStatus "U8D8.3" )
			)
			( pin "@baseboard_fab2_lib.baseboard_fab2(sch_1):page196_i104:outa"
				( attribute "PN" "6"
					( Origin gPackager )
				)
				( objectStatus "U8D8.6" )
			)
			( pin "@baseboard_fab2_lib.baseboard_fab2(sch_1):page196_i104:outb"
				( attribute "PN" "1"
					( Origin gPackager )
				)
				( objectStatus "U8D8.1" )
			)
			( pin "@baseboard_fab2_lib.baseboard_fab2(sch_1):page196_i104:vdd"
				( attribute "PN" "2"
					( Origin gPackager )
				)
				( objectStatus "U8D8.2" )
			)
			( pin "@baseboard_fab2_lib.baseboard_fab2(sch_1):page196_i105:a"
				( attribute "PN" "1"
					( Origin gPackager )
				)
				( objectStatus "C8D4.1" )
			)
			( pin "@baseboard_fab2_lib.baseboard_fab2(sch_1):page196_i105:b"
				( attribute "PN" "2"
					( Origin gPackager )
				)
				( objectStatus "C8D4.2" )
			)
			( pin "@baseboard_fab2_lib.baseboard_fab2(sch_1):page196_i106:a"
				( attribute "PN" "1"
					( Origin gPackager )
				)
				( objectStatus "R8D42.1" )
			)
			( pin "@baseboard_fab2_lib.baseboard_fab2(sch_1):page196_i106:b"
				( attribute "PN" "2"
					( Origin gPackager )
				)
				( objectStatus "R8D42.2" )
			)
			( pin "@baseboard_fab2_lib.baseboard_fab2(sch_1):page196_i112:a"
				( attribute "PN" "1"
					( Origin gPackager )
				)
				( objectStatus "R8D38.1" )
			)
			( pin "@baseboard_fab2_lib.baseboard_fab2(sch_1):page196_i112:b"
				( attribute "PN" "2"
					( Origin gPackager )
				)
				( objectStatus "R8D38.2" )
			)
			( pin "@baseboard_fab2_lib.baseboard_fab2(sch_1):page200_i251:a"
				( attribute "PN" "1"
					( Origin gPackager )
				)
				( objectStatus "R9P9.1" )
			)
			( pin "@baseboard_fab2_lib.baseboard_fab2(sch_1):page200_i251:b"
				( attribute "PN" "2"
					( Origin gPackager )
				)
				( objectStatus "R9P9.2" )
			)
			( pin "@baseboard_fab2_lib.baseboard_fab2(sch_1):page196_i114:a"
				( attribute "PN" "1"
					( Origin gPackager )
				)
				( objectStatus "R8D39.1" )
			)
			( pin "@baseboard_fab2_lib.baseboard_fab2(sch_1):page196_i114:b"
				( attribute "PN" "2"
					( Origin gPackager )
				)
				( objectStatus "R8D39.2" )
			)
			( pin "@baseboard_fab2_lib.baseboard_fab2(sch_1):page196_i115:a"
				( attribute "PN" "1"
					( Origin gPackager )
				)
				( objectStatus "R8D37.1" )
			)
			( pin "@baseboard_fab2_lib.baseboard_fab2(sch_1):page196_i115:b"
				( attribute "PN" "2"
					( Origin gPackager )
				)
				( objectStatus "R8D37.2" )
			)
			( pin "@baseboard_fab2_lib.baseboard_fab2(sch_1):page196_i120:a"
				( attribute "PN" "1"
					( Origin gPackager )
				)
				( objectStatus "R8D41.1" )
			)
			( pin "@baseboard_fab2_lib.baseboard_fab2(sch_1):page196_i120:b"
				( attribute "PN" "2"
					( Origin gPackager )
				)
				( objectStatus "R8D41.2" )
			)
			( pin "@baseboard_fab2_lib.baseboard_fab2(sch_1):page196_i121:a"
				( attribute "PN" "1"
					( Origin gPackager )
				)
				( objectStatus "R2P18.1" )
			)
			( pin "@baseboard_fab2_lib.baseboard_fab2(sch_1):page196_i121:b"
				( attribute "PN" "2"
					( Origin gPackager )
				)
				( objectStatus "R2P18.2" )
			)
			( pin "@baseboard_fab2_lib.baseboard_fab2(sch_1):page196_i122:a"
				( attribute "PN" "1"
					( Origin gPackager )
				)
				( objectStatus "R2P21.1" )
			)
			( pin "@baseboard_fab2_lib.baseboard_fab2(sch_1):page196_i122:b"
				( attribute "PN" "2"
					( Origin gPackager )
				)
				( objectStatus "R2P21.2" )
			)
			( pin "@baseboard_fab2_lib.baseboard_fab2(sch_1):page134_i14:drn"
				( attribute "PN" "3"
					( Origin gPackager )
				)
				( objectStatus "Q7D1.3" )
			)
			( pin "@baseboard_fab2_lib.baseboard_fab2(sch_1):page134_i14:gate"
				( attribute "PN" "1"
					( Origin gPackager )
				)
				( objectStatus "Q7D1.1" )
			)
			( pin "@baseboard_fab2_lib.baseboard_fab2(sch_1):page134_i14:src"
				( attribute "PN" "2"
					( Origin gPackager )
				)
				( objectStatus "Q7D1.2" )
			)
			( pin "@baseboard_fab2_lib.baseboard_fab2(sch_1):page196_i128:a"
				( attribute "PN" "2"
					( Origin gPackager )
				)
				( objectStatus "CR8E1.2" )
			)
			( pin "@baseboard_fab2_lib.baseboard_fab2(sch_1):page196_i128:c"
				( attribute "PN" "1"
					( Origin gPackager )
				)
				( objectStatus "CR8E1.1" )
			)
			( pin "@baseboard_fab2_lib.baseboard_fab2(sch_1):page198_i1:d"
				( attribute "PN" "5"
					( Origin gPackager )
				)
				( objectStatus "EU2T1.5" )
			)
			( pin "@baseboard_fab2_lib.baseboard_fab2(sch_1):page198_i1:g"
				( attribute "PN" "7"
					( Origin gPackager )
				)
				( objectStatus "EU2T1.7" )
			)
			( pin "@baseboard_fab2_lib.baseboard_fab2(sch_1):page198_i1:gnd"
				( attribute "PN" "4"
					( Origin gPackager )
				)
				( objectStatus "EU2T1.4" )
			)
			( pin "@baseboard_fab2_lib.baseboard_fab2(sch_1):page198_i1:\on\"
				( attribute "PN" "2"
					( Origin gPackager )
				)
				( objectStatus "EU2T1.2" )
			)
			( pin "@baseboard_fab2_lib.baseboard_fab2(sch_1):page198_i1:pg"
				( attribute "PN" "8"
					( Origin gPackager )
				)
				( objectStatus "EU2T1.8" )
			)
			( pin "@baseboard_fab2_lib.baseboard_fab2(sch_1):page198_i1:s"
				( attribute "PN" "6"
					( Origin gPackager )
				)
				( objectStatus "EU2T1.6" )
			)
			( pin "@baseboard_fab2_lib.baseboard_fab2(sch_1):page198_i1:shdn_n"
				( attribute "PN" "3"
					( Origin gPackager )
				)
				( objectStatus "EU2T1.3" )
			)
			( pin "@baseboard_fab2_lib.baseboard_fab2(sch_1):page198_i1:thpad"
				( attribute "PN" "9"
					( Origin gPackager )
				)
				( objectStatus "EU2T1.9" )
			)
			( pin "@baseboard_fab2_lib.baseboard_fab2(sch_1):page198_i1:vcc"
				( attribute "PN" "1"
					( Origin gPackager )
				)
				( objectStatus "EU2T1.1" )
			)
			( pin "@baseboard_fab2_lib.baseboard_fab2(sch_1):page198_i13:d"
				( attribute "PN" "5"
					( Origin gPackager )
				)
				( objectStatus "EU8B1.5" )
			)
			( pin "@baseboard_fab2_lib.baseboard_fab2(sch_1):page198_i13:g"
				( attribute "PN" "7"
					( Origin gPackager )
				)
				( objectStatus "EU8B1.7" )
			)
			( pin "@baseboard_fab2_lib.baseboard_fab2(sch_1):page198_i13:gnd"
				( attribute "PN" "4"
					( Origin gPackager )
				)
				( objectStatus "EU8B1.4" )
			)
			( pin "@baseboard_fab2_lib.baseboard_fab2(sch_1):page198_i13:\on\"
				( attribute "PN" "2"
					( Origin gPackager )
				)
				( objectStatus "EU8B1.2" )
			)
			( pin "@baseboard_fab2_lib.baseboard_fab2(sch_1):page198_i13:pg"
				( attribute "PN" "8"
					( Origin gPackager )
				)
				( objectStatus "EU8B1.8" )
			)
			( pin "@baseboard_fab2_lib.baseboard_fab2(sch_1):page198_i13:s"
				( attribute "PN" "6"
					( Origin gPackager )
				)
				( objectStatus "EU8B1.6" )
			)
			( pin "@baseboard_fab2_lib.baseboard_fab2(sch_1):page198_i13:shdn_n"
				( attribute "PN" "3"
					( Origin gPackager )
				)
				( objectStatus "EU8B1.3" )
			)
			( pin "@baseboard_fab2_lib.baseboard_fab2(sch_1):page198_i13:thpad"
				( attribute "PN" "9"
					( Origin gPackager )
				)
				( objectStatus "EU8B1.9" )
			)
			( pin "@baseboard_fab2_lib.baseboard_fab2(sch_1):page198_i13:vcc"
				( attribute "PN" "1"
					( Origin gPackager )
				)
				( objectStatus "EU8B1.1" )
			)
			( pin "@baseboard_fab2_lib.baseboard_fab2(sch_1):page198_i19:d"
				( attribute "PN" "5"
					( Origin gPackager )
				)
				( objectStatus "EU7E1.5" )
			)
			( pin "@baseboard_fab2_lib.baseboard_fab2(sch_1):page198_i19:g"
				( attribute "PN" "7"
					( Origin gPackager )
				)
				( objectStatus "EU7E1.7" )
			)
			( pin "@baseboard_fab2_lib.baseboard_fab2(sch_1):page198_i19:gnd"
				( attribute "PN" "4"
					( Origin gPackager )
				)
				( objectStatus "EU7E1.4" )
			)
			( pin "@baseboard_fab2_lib.baseboard_fab2(sch_1):page198_i19:\on\"
				( attribute "PN" "2"
					( Origin gPackager )
				)
				( objectStatus "EU7E1.2" )
			)
			( pin "@baseboard_fab2_lib.baseboard_fab2(sch_1):page198_i19:pg"
				( attribute "PN" "8"
					( Origin gPackager )
				)
				( objectStatus "EU7E1.8" )
			)
			( pin "@baseboard_fab2_lib.baseboard_fab2(sch_1):page198_i19:s"
				( attribute "PN" "6"
					( Origin gPackager )
				)
				( objectStatus "EU7E1.6" )
			)
			( pin "@baseboard_fab2_lib.baseboard_fab2(sch_1):page198_i19:shdn_n"
				( attribute "PN" "3"
					( Origin gPackager )
				)
				( objectStatus "EU7E1.3" )
			)
			( pin "@baseboard_fab2_lib.baseboard_fab2(sch_1):page198_i19:thpad"
				( attribute "PN" "9"
					( Origin gPackager )
				)
				( objectStatus "EU7E1.9" )
			)
			( pin "@baseboard_fab2_lib.baseboard_fab2(sch_1):page198_i19:vcc"
				( attribute "PN" "1"
					( Origin gPackager )
				)
				( objectStatus "EU7E1.1" )
			)
			( pin "@baseboard_fab2_lib.baseboard_fab2(sch_1):page198_i24:a"
				( attribute "PN" "1"
					( Origin gPackager )
				)
				( objectStatus "C8F17.1" )
			)
			( pin "@baseboard_fab2_lib.baseboard_fab2(sch_1):page198_i24:b"
				( attribute "PN" "2"
					( Origin gPackager )
				)
				( objectStatus "C8F17.2" )
			)
			( pin "@baseboard_fab2_lib.baseboard_fab2(sch_1):page198_i26:a"
				( attribute "PN" "1"
					( Origin gPackager )
				)
				( objectStatus "C8B8.1" )
			)
			( pin "@baseboard_fab2_lib.baseboard_fab2(sch_1):page198_i26:b"
				( attribute "PN" "2"
					( Origin gPackager )
				)
				( objectStatus "C8B8.2" )
			)
			( pin "@baseboard_fab2_lib.baseboard_fab2(sch_1):page198_i28:a"
				( attribute "PN" "1"
					( Origin gPackager )
				)
				( objectStatus "C8E19.1" )
			)
			( pin "@baseboard_fab2_lib.baseboard_fab2(sch_1):page198_i28:b"
				( attribute "PN" "2"
					( Origin gPackager )
				)
				( objectStatus "C8E19.2" )
			)
			( pin "@baseboard_fab2_lib.baseboard_fab2(sch_1):page198_i37:a"
				( attribute "PN" "1"
					( Origin gPackager )
				)
				( objectStatus "C8B5.1" )
			)
			( pin "@baseboard_fab2_lib.baseboard_fab2(sch_1):page198_i37:b"
				( attribute "PN" "2"
					( Origin gPackager )
				)
				( objectStatus "C8B5.2" )
			)
			( pin "@baseboard_fab2_lib.baseboard_fab2(sch_1):page198_i38:a"
				( attribute "PN" "1"
					( Origin gPackager )
				)
				( objectStatus "C8B12.1" )
			)
			( pin "@baseboard_fab2_lib.baseboard_fab2(sch_1):page198_i38:b"
				( attribute "PN" "2"
					( Origin gPackager )
				)
				( objectStatus "C8B12.2" )
			)
			( pin "@baseboard_fab2_lib.baseboard_fab2(sch_1):page198_i40:a"
				( attribute "PN" "1"
					( Origin gPackager )
				)
				( objectStatus "C8B6.1" )
			)
			( pin "@baseboard_fab2_lib.baseboard_fab2(sch_1):page198_i40:b"
				( attribute "PN" "2"
					( Origin gPackager )
				)
				( objectStatus "C8B6.2" )
			)
			( pin "@baseboard_fab2_lib.baseboard_fab2(sch_1):page198_i41:a"
				( attribute "PN" "1"
					( Origin gPackager )
				)
				( objectStatus "C8B7.1" )
			)
			( pin "@baseboard_fab2_lib.baseboard_fab2(sch_1):page198_i41:b"
				( attribute "PN" "2"
					( Origin gPackager )
				)
				( objectStatus "C8B7.2" )
			)
			( pin "@baseboard_fab2_lib.baseboard_fab2(sch_1):page198_i43:a"
				( attribute "PN" "1"
					( Origin gPackager )
				)
				( objectStatus "C2T36.1" )
			)
			( pin "@baseboard_fab2_lib.baseboard_fab2(sch_1):page198_i43:b"
				( attribute "PN" "2"
					( Origin gPackager )
				)
				( objectStatus "C2T36.2" )
			)
			( pin "@baseboard_fab2_lib.baseboard_fab2(sch_1):page198_i44:a"
				( attribute "PN" "1"
					( Origin gPackager )
				)
				( objectStatus "C2U1.1" )
			)
			( pin "@baseboard_fab2_lib.baseboard_fab2(sch_1):page198_i44:b"
				( attribute "PN" "2"
					( Origin gPackager )
				)
				( objectStatus "C2U1.2" )
			)
			( pin "@baseboard_fab2_lib.baseboard_fab2(sch_1):page198_i46:a"
				( attribute "PN" "1"
					( Origin gPackager )
				)
				( objectStatus "C2U19.1" )
			)
			( pin "@baseboard_fab2_lib.baseboard_fab2(sch_1):page198_i46:b"
				( attribute "PN" "2"
					( Origin gPackager )
				)
				( objectStatus "C2U19.2" )
			)
			( pin "@baseboard_fab2_lib.baseboard_fab2(sch_1):page198_i47:a"
				( attribute "PN" "1"
					( Origin gPackager )
				)
				( objectStatus "C2U2.1" )
			)
			( pin "@baseboard_fab2_lib.baseboard_fab2(sch_1):page198_i47:b"
				( attribute "PN" "2"
					( Origin gPackager )
				)
				( objectStatus "C2U2.2" )
			)
			( pin "@baseboard_fab2_lib.baseboard_fab2(sch_1):page198_i49:a"
				( attribute "PN" "1"
					( Origin gPackager )
				)
				( objectStatus "C7E9.1" )
			)
			( pin "@baseboard_fab2_lib.baseboard_fab2(sch_1):page198_i49:b"
				( attribute "PN" "2"
					( Origin gPackager )
				)
				( objectStatus "C7E9.2" )
			)
			( pin "@baseboard_fab2_lib.baseboard_fab2(sch_1):page198_i50:a"
				( attribute "PN" "1"
					( Origin gPackager )
				)
				( objectStatus "C7E8.1" )
			)
			( pin "@baseboard_fab2_lib.baseboard_fab2(sch_1):page198_i50:b"
				( attribute "PN" "2"
					( Origin gPackager )
				)
				( objectStatus "C7E8.2" )
			)
			( pin "@baseboard_fab2_lib.baseboard_fab2(sch_1):page198_i52:a"
				( attribute "PN" "1"
					( Origin gPackager )
				)
				( objectStatus "C7E5.1" )
			)
			( pin "@baseboard_fab2_lib.baseboard_fab2(sch_1):page198_i52:b"
				( attribute "PN" "2"
					( Origin gPackager )
				)
				( objectStatus "C7E5.2" )
			)
			( pin "@baseboard_fab2_lib.baseboard_fab2(sch_1):page198_i53:a"
				( attribute "PN" "1"
					( Origin gPackager )
				)
				( objectStatus "C7E6.1" )
			)
			( pin "@baseboard_fab2_lib.baseboard_fab2(sch_1):page198_i53:b"
				( attribute "PN" "2"
					( Origin gPackager )
				)
				( objectStatus "C7E6.2" )
			)
			( pin "@baseboard_fab2_lib.baseboard_fab2(sch_1):page198_i61:a"
				( attribute "PN" "1"
					( Origin gPackager )
				)
				( objectStatus "C1B18.1" )
			)
			( pin "@baseboard_fab2_lib.baseboard_fab2(sch_1):page198_i61:b"
				( attribute "PN" "2"
					( Origin gPackager )
				)
				( objectStatus "C1B18.2" )
			)
			( pin "@baseboard_fab2_lib.baseboard_fab2(sch_1):page198_i64:a"
				( attribute "PN" "1"
					( Origin gPackager )
				)
				( objectStatus "C1B19.1" )
			)
			( pin "@baseboard_fab2_lib.baseboard_fab2(sch_1):page198_i64:b"
				( attribute "PN" "2"
					( Origin gPackager )
				)
				( objectStatus "C1B19.2" )
			)
			( pin "@baseboard_fab2_lib.baseboard_fab2(sch_1):page198_i67:a"
				( attribute "PN" "1"
					( Origin gPackager )
				)
				( objectStatus "C9M6.1" )
			)
			( pin "@baseboard_fab2_lib.baseboard_fab2(sch_1):page198_i67:b"
				( attribute "PN" "2"
					( Origin gPackager )
				)
				( objectStatus "C9M6.2" )
			)
			( pin "@baseboard_fab2_lib.baseboard_fab2(sch_1):page198_i69:d"
				( attribute "PN" "5"
					( Origin gPackager )
				)
				( objectStatus "EU9M1.5" )
			)
			( pin "@baseboard_fab2_lib.baseboard_fab2(sch_1):page198_i69:g"
				( attribute "PN" "7"
					( Origin gPackager )
				)
				( objectStatus "EU9M1.7" )
			)
			( pin "@baseboard_fab2_lib.baseboard_fab2(sch_1):page198_i69:gnd"
				( attribute "PN" "4"
					( Origin gPackager )
				)
				( objectStatus "EU9M1.4" )
			)
			( pin "@baseboard_fab2_lib.baseboard_fab2(sch_1):page198_i69:\on\"
				( attribute "PN" "2"
					( Origin gPackager )
				)
				( objectStatus "EU9M1.2" )
			)
			( pin "@baseboard_fab2_lib.baseboard_fab2(sch_1):page198_i69:pg"
				( attribute "PN" "8"
					( Origin gPackager )
				)
				( objectStatus "EU9M1.8" )
			)
			( pin "@baseboard_fab2_lib.baseboard_fab2(sch_1):page198_i69:s"
				( attribute "PN" "6"
					( Origin gPackager )
				)
				( objectStatus "EU9M1.6" )
			)
			( pin "@baseboard_fab2_lib.baseboard_fab2(sch_1):page198_i69:shdn_n"
				( attribute "PN" "3"
					( Origin gPackager )
				)
				( objectStatus "EU9M1.3" )
			)
			( pin "@baseboard_fab2_lib.baseboard_fab2(sch_1):page198_i69:thpad"
				( attribute "PN" "9"
					( Origin gPackager )
				)
				( objectStatus "EU9M1.9" )
			)
			( pin "@baseboard_fab2_lib.baseboard_fab2(sch_1):page198_i69:vcc"
				( attribute "PN" "1"
					( Origin gPackager )
				)
				( objectStatus "EU9M1.1" )
			)
			( pin "@baseboard_fab2_lib.baseboard_fab2(sch_1):page198_i74:a"
				( attribute "PN" "1"
					( Origin gPackager )
				)
				( objectStatus "C9M10.1" )
			)
			( pin "@baseboard_fab2_lib.baseboard_fab2(sch_1):page198_i74:b"
				( attribute "PN" "2"
					( Origin gPackager )
				)
				( objectStatus "C9M10.2" )
			)
			( pin "@baseboard_fab2_lib.baseboard_fab2(sch_1):page198_i76:a"
				( attribute "PN" "1"
					( Origin gPackager )
				)
				( objectStatus "C9M9.1" )
			)
			( pin "@baseboard_fab2_lib.baseboard_fab2(sch_1):page198_i76:b"
				( attribute "PN" "2"
					( Origin gPackager )
				)
				( objectStatus "C9M9.2" )
			)
			( pin "@baseboard_fab2_lib.baseboard_fab2(sch_1):page198_i78:a"
				( attribute "PN" "1"
					( Origin gPackager )
				)
				( objectStatus "R8E12.1" )
			)
			( pin "@baseboard_fab2_lib.baseboard_fab2(sch_1):page198_i78:b"
				( attribute "PN" "2"
					( Origin gPackager )
				)
				( objectStatus "R8E12.2" )
			)
			( pin "@baseboard_fab2_lib.baseboard_fab2(sch_1):page198_i83:a"
				( attribute "PN" "1"
					( Origin gPackager )
				)
				( objectStatus "R8B4.1" )
			)
			( pin "@baseboard_fab2_lib.baseboard_fab2(sch_1):page198_i83:b"
				( attribute "PN" "2"
					( Origin gPackager )
				)
				( objectStatus "R8B4.2" )
			)
			( pin "@baseboard_fab2_lib.baseboard_fab2(sch_1):page198_i85:drn"
				( attribute "PN" "5"
					( Origin gPackager )
				)
				( objectStatus "Q8G1.5" )
			)
			( pin "@baseboard_fab2_lib.baseboard_fab2(sch_1):page198_i85:gate"
				( attribute "PN" "4"
					( Origin gPackager )
				)
				( objectStatus "Q8G1.4" )
			)
			( pin "@baseboard_fab2_lib.baseboard_fab2(sch_1):page198_i85:src"
				( attribute "PN" "1"
					( Origin gPackager )
				)
				( objectStatus "Q8G1.1" )
			)
			( pin "@baseboard_fab2_lib.baseboard_fab2(sch_1):page198_i86:drn"
				( attribute "PN" "5"
					( Origin gPackager )
				)
				( objectStatus "Q1B1.5" )
			)
			( pin "@baseboard_fab2_lib.baseboard_fab2(sch_1):page198_i86:gate"
				( attribute "PN" "4"
					( Origin gPackager )
				)
				( objectStatus "Q1B1.4" )
			)
			( pin "@baseboard_fab2_lib.baseboard_fab2(sch_1):page198_i86:src"
				( attribute "PN" "1"
					( Origin gPackager )
				)
				( objectStatus "Q1B1.1" )
			)
			( pin "@baseboard_fab2_lib.baseboard_fab2(sch_1):page198_i87:drn"
				( attribute "PN" "5"
					( Origin gPackager )
				)
				( objectStatus "Q8B1.5" )
			)
			( pin "@baseboard_fab2_lib.baseboard_fab2(sch_1):page198_i87:gate"
				( attribute "PN" "4"
					( Origin gPackager )
				)
				( objectStatus "Q8B1.4" )
			)
			( pin "@baseboard_fab2_lib.baseboard_fab2(sch_1):page198_i87:src"
				( attribute "PN" "1"
					( Origin gPackager )
				)
				( objectStatus "Q8B1.1" )
			)
			( pin "@baseboard_fab2_lib.baseboard_fab2(sch_1):page198_i88:drn"
				( attribute "PN" "5"
					( Origin gPackager )
				)
				( objectStatus "Q7E7.5" )
			)
			( pin "@baseboard_fab2_lib.baseboard_fab2(sch_1):page198_i88:gate"
				( attribute "PN" "4"
					( Origin gPackager )
				)
				( objectStatus "Q7E7.4" )
			)
			( pin "@baseboard_fab2_lib.baseboard_fab2(sch_1):page198_i88:src"
				( attribute "PN" "1"
					( Origin gPackager )
				)
				( objectStatus "Q7E7.1" )
			)
			( pin "@baseboard_fab2_lib.baseboard_fab2(sch_1):page199_i2:a"
				( attribute "PN" "1"
					( Origin gPackager )
				)
				( objectStatus "R9P30.1" )
			)
			( pin "@baseboard_fab2_lib.baseboard_fab2(sch_1):page199_i2:b"
				( attribute "PN" "2"
					( Origin gPackager )
				)
				( objectStatus "R9P30.2" )
			)
			( pin "@baseboard_fab2_lib.baseboard_fab2(sch_1):page199_i3:a"
				( attribute "PN" "1"
					( Origin gPackager )
				)
				( objectStatus "C1D25.1" )
			)
			( pin "@baseboard_fab2_lib.baseboard_fab2(sch_1):page199_i3:b"
				( attribute "PN" "2"
					( Origin gPackager )
				)
				( objectStatus "C1D25.2" )
			)
			( pin "@baseboard_fab2_lib.baseboard_fab2(sch_1):page199_i7:a"
				( attribute "PN" "1"
					( Origin gPackager )
				)
				( objectStatus "C1D27.1" )
			)
			( pin "@baseboard_fab2_lib.baseboard_fab2(sch_1):page199_i7:b"
				( attribute "PN" "2"
					( Origin gPackager )
				)
				( objectStatus "C1D27.2" )
			)
			( pin "@baseboard_fab2_lib.baseboard_fab2(sch_1):page199_i9:a"
				( attribute "PN" "1"
					( Origin gPackager )
				)
				( objectStatus "R1D43.1" )
			)
			( pin "@baseboard_fab2_lib.baseboard_fab2(sch_1):page199_i9:b"
				( attribute "PN" "2"
					( Origin gPackager )
				)
				( objectStatus "R1D43.2" )
			)
			( pin "@baseboard_fab2_lib.baseboard_fab2(sch_1):page199_i10:adr1"
				( attribute "PN" "7"
					( Origin gPackager )
				)
				( objectStatus "EU1D2.7" )
			)
			( pin "@baseboard_fab2_lib.baseboard_fab2(sch_1):page199_i10:adr2"
				( attribute "PN" "8"
					( Origin gPackager )
				)
				( objectStatus "EU1D2.8" )
			)
			( pin "@baseboard_fab2_lib.baseboard_fab2(sch_1):page199_i10:csout"
				( attribute "PN" "19"
					( Origin gPackager )
				)
				( objectStatus "EU1D2.19" )
			)
			( pin "@baseboard_fab2_lib.baseboard_fab2(sch_1):page199_i10:enable"
				( attribute "PN" "12"
					( Origin gPackager )
				)
				( objectStatus "EU1D2.12" )
			)
			( pin "@baseboard_fab2_lib.baseboard_fab2(sch_1):page199_i10:ep"
				( attribute "PN" "33"
					( Origin gPackager )
				)
				( objectStatus "EU1D2.33" )
			)
			( pin "@baseboard_fab2_lib.baseboard_fab2(sch_1):page199_i10:fault_n"
				( attribute "PN" "6"
					( Origin gPackager )
				)
				( objectStatus "EU1D2.6" )
			)
			( pin "@baseboard_fab2_lib.baseboard_fab2(sch_1):page199_i10:gate"
				( attribute "PN" "24"
					( Origin gPackager )
				)
				( objectStatus "EU1D2.24" )
			)
			( pin "@baseboard_fab2_lib.baseboard_fab2(sch_1):page199_i10:gnd"
				( attribute "PN" "22"
					( Origin gPackager )
				)
				( objectStatus "EU1D2.22" )
			)
			( pin "@baseboard_fab2_lib.baseboard_fab2(sch_1):page199_i10:gpo1_alert1_n_conv"
				( attribute "PN" "13"
					( Origin gPackager )
				)
				( objectStatus "EU1D2.13" )
			)
			( pin "@baseboard_fab2_lib.baseboard_fab2(sch_1):page199_i10:gpo2_alert2_n"
				( attribute "PN" "14"
					( Origin gPackager )
				)
				( objectStatus "EU1D2.14" )
			)
			( pin "@baseboard_fab2_lib.baseboard_fab2(sch_1):page199_i10:hsn"
				( attribute "PN" "27"
					( Origin gPackager )
				)
				( objectStatus "EU1D2.27" )
			)
			( pin "@baseboard_fab2_lib.baseboard_fab2(sch_1):page199_i10:hsp"
				( attribute "PN" "28"
					( Origin gPackager )
				)
				( objectStatus "EU1D2.28" )
			)
			( pin "@baseboard_fab2_lib.baseboard_fab2(sch_1):page199_i10:iset"
				( attribute "PN" "3"
					( Origin gPackager )
				)
				( objectStatus "EU1D2.3" )
			)
			( pin "@baseboard_fab2_lib.baseboard_fab2(sch_1):page199_i10:istart"
				( attribute "PN" "4"
					( Origin gPackager )
				)
				( objectStatus "EU1D2.4" )
			)
			( pin "@baseboard_fab2_lib.baseboard_fab2(sch_1):page199_i10:mclk"
				( attribute "PN" "10"
					( Origin gPackager )
				)
				( objectStatus "EU1D2.10" )
			)
			( pin "@baseboard_fab2_lib.baseboard_fab2(sch_1):page199_i10:mdat"
				( attribute "PN" "11"
					( Origin gPackager )
				)
				( objectStatus "EU1D2.11" )
			)
			( pin "@baseboard_fab2_lib.baseboard_fab2(sch_1):page199_i10:mon"
				( attribute "PN" "26"
					( Origin gPackager )
				)
				( objectStatus "EU1D2.26" )
			)
			( pin "@baseboard_fab2_lib.baseboard_fab2(sch_1):page199_i10:mop"
				( attribute "PN" "29"
					( Origin gPackager )
				)
				( objectStatus "EU1D2.29" )
			)
			( pin "@baseboard_fab2_lib.baseboard_fab2(sch_1):page199_i10:ov"
				( attribute "PN" "32"
					( Origin gPackager )
				)
				( objectStatus "EU1D2.32" )
			)
			( pin "@baseboard_fab2_lib.baseboard_fab2(sch_1):page199_i10:pgnd"
				( attribute "PN" "23"
					( Origin gPackager )
				)
				( objectStatus "EU1D2.23" )
			)
			( pin "@baseboard_fab2_lib.baseboard_fab2(sch_1):page199_i10:pset"
				( attribute "PN" "1"
					( Origin gPackager )
				)
				( objectStatus "EU1D2.1" )
			)
			( pin "@baseboard_fab2_lib.baseboard_fab2(sch_1):page199_i10:pwgin"
				( attribute "PN" "21"
					( Origin gPackager )
				)
				( objectStatus "EU1D2.21" )
			)
			( pin "@baseboard_fab2_lib.baseboard_fab2(sch_1):page199_i10:pwrgd"
				( attribute "PN" "18"
					( Origin gPackager )
				)
				( objectStatus "EU1D2.18" )
			)
			( pin "@baseboard_fab2_lib.baseboard_fab2(sch_1):page199_i10:retry_n"
				( attribute "PN" "17"
					( Origin gPackager )
				)
				( objectStatus "EU1D2.17" )
			)
			( pin "@baseboard_fab2_lib.baseboard_fab2(sch_1):page199_i10:scl"
				( attribute "PN" "16"
					( Origin gPackager )
				)
				( objectStatus "EU1D2.16" )
			)
			( pin "@baseboard_fab2_lib.baseboard_fab2(sch_1):page199_i10:sda"
				( attribute "PN" "15"
					( Origin gPackager )
				)
				( objectStatus "EU1D2.15" )
			)
			( pin "@baseboard_fab2_lib.baseboard_fab2(sch_1):page199_i10:spiss_n"
				( attribute "PN" "9"
					( Origin gPackager )
				)
				( objectStatus "EU1D2.9" )
			)
			( pin "@baseboard_fab2_lib.baseboard_fab2(sch_1):page199_i10:temp"
				( attribute "PN" "25"
					( Origin gPackager )
				)
				( objectStatus "EU1D2.25" )
			)
			( pin "@baseboard_fab2_lib.baseboard_fab2(sch_1):page199_i10:timer"
				( attribute "PN" "5"
					( Origin gPackager )
				)
				( objectStatus "EU1D2.5" )
			)
			( pin "@baseboard_fab2_lib.baseboard_fab2(sch_1):page199_i10:uv"
				( attribute "PN" "31"
					( Origin gPackager )
				)
				( objectStatus "EU1D2.31" )
			)
			( pin "@baseboard_fab2_lib.baseboard_fab2(sch_1):page199_i10:vcap"
				( attribute "PN" "2"
					( Origin gPackager )
				)
				( objectStatus "EU1D2.2" )
			)
			( pin "@baseboard_fab2_lib.baseboard_fab2(sch_1):page199_i10:vcc"
				( attribute "PN" "30"
					( Origin gPackager )
				)
				( objectStatus "EU1D2.30" )
			)
			( pin "@baseboard_fab2_lib.baseboard_fab2(sch_1):page199_i10:vout"
				( attribute "PN" "20"
					( Origin gPackager )
				)
				( objectStatus "EU1D2.20" )
			)
			( pin "@baseboard_fab2_lib.baseboard_fab2(sch_1):page199_i12:a"
				( attribute "PN" "1"
					( Origin gPackager )
				)
				( objectStatus "R9P29.1" )
			)
			( pin "@baseboard_fab2_lib.baseboard_fab2(sch_1):page199_i12:b"
				( attribute "PN" "2"
					( Origin gPackager )
				)
				( objectStatus "R9P29.2" )
			)
			( pin "@baseboard_fab2_lib.baseboard_fab2(sch_1):page199_i13:a"
				( attribute "PN" "1"
					( Origin gPackager )
				)
				( objectStatus "R1D42.1" )
			)
			( pin "@baseboard_fab2_lib.baseboard_fab2(sch_1):page199_i13:b"
				( attribute "PN" "2"
					( Origin gPackager )
				)
				( objectStatus "R1D42.2" )
			)
			( pin "@baseboard_fab2_lib.baseboard_fab2(sch_1):page199_i15:a"
				( attribute "PN" "1"
					( Origin gPackager )
				)
				( objectStatus "R1D37.1" )
			)
			( pin "@baseboard_fab2_lib.baseboard_fab2(sch_1):page199_i15:b"
				( attribute "PN" "2"
					( Origin gPackager )
				)
				( objectStatus "R1D37.2" )
			)
			( pin "@baseboard_fab2_lib.baseboard_fab2(sch_1):page199_i16:a"
				( attribute "PN" "1"
					( Origin gPackager )
				)
				( objectStatus "R1D39.1" )
			)
			( pin "@baseboard_fab2_lib.baseboard_fab2(sch_1):page199_i16:b"
				( attribute "PN" "2"
					( Origin gPackager )
				)
				( objectStatus "R1D39.2" )
			)
			( pin "@baseboard_fab2_lib.baseboard_fab2(sch_1):page199_i17:a"
				( attribute "PN" "1"
					( Origin gPackager )
				)
				( objectStatus "R1D32.1" )
			)
			( pin "@baseboard_fab2_lib.baseboard_fab2(sch_1):page199_i17:b"
				( attribute "PN" "2"
					( Origin gPackager )
				)
				( objectStatus "R1D32.2" )
			)
			( pin "@baseboard_fab2_lib.baseboard_fab2(sch_1):page199_i19:a"
				( attribute "PN" "1"
					( Origin gPackager )
				)
				( objectStatus "R1D41.1" )
			)
			( pin "@baseboard_fab2_lib.baseboard_fab2(sch_1):page199_i19:b"
				( attribute "PN" "2"
					( Origin gPackager )
				)
				( objectStatus "R1D41.2" )
			)
			( pin "@baseboard_fab2_lib.baseboard_fab2(sch_1):page199_i24:a"
				( attribute "PN" "1"
					( Origin gPackager )
				)
				( objectStatus "C9P14.1" )
			)
			( pin "@baseboard_fab2_lib.baseboard_fab2(sch_1):page199_i24:b"
				( attribute "PN" "2"
					( Origin gPackager )
				)
				( objectStatus "C9P14.2" )
			)
			( pin "@baseboard_fab2_lib.baseboard_fab2(sch_1):page199_i26:a"
				( attribute "PN" "1"
					( Origin gPackager )
				)
				( objectStatus "R1D28.1" )
			)
			( pin "@baseboard_fab2_lib.baseboard_fab2(sch_1):page199_i26:b"
				( attribute "PN" "2"
					( Origin gPackager )
				)
				( objectStatus "R1D28.2" )
			)
			( pin "@baseboard_fab2_lib.baseboard_fab2(sch_1):page199_i27:a"
				( attribute "PN" "1"
					( Origin gPackager )
				)
				( objectStatus "R1D24.1" )
			)
			( pin "@baseboard_fab2_lib.baseboard_fab2(sch_1):page199_i27:b"
				( attribute "PN" "2"
					( Origin gPackager )
				)
				( objectStatus "R1D24.2" )
			)
			( pin "@baseboard_fab2_lib.baseboard_fab2(sch_1):page199_i28:a"
				( attribute "PN" "1"
					( Origin gPackager )
				)
				( objectStatus "R1D25.1" )
			)
			( pin "@baseboard_fab2_lib.baseboard_fab2(sch_1):page199_i28:b"
				( attribute "PN" "2"
					( Origin gPackager )
				)
				( objectStatus "R1D25.2" )
			)
			( pin "@baseboard_fab2_lib.baseboard_fab2(sch_1):page199_i33:a"
				( attribute "PN" "1"
					( Origin gPackager )
				)
				( objectStatus "R9P17.1" )
			)
			( pin "@baseboard_fab2_lib.baseboard_fab2(sch_1):page199_i33:b"
				( attribute "PN" "2"
					( Origin gPackager )
				)
				( objectStatus "R9P17.2" )
			)
			( pin "@baseboard_fab2_lib.baseboard_fab2(sch_1):page199_i36:a"
				( attribute "PN" "1"
					( Origin gPackager )
				)
				( objectStatus "R9P16.1" )
			)
			( pin "@baseboard_fab2_lib.baseboard_fab2(sch_1):page199_i36:b"
				( attribute "PN" "2"
					( Origin gPackager )
				)
				( objectStatus "R9P16.2" )
			)
			( pin "@baseboard_fab2_lib.baseboard_fab2(sch_1):page199_i38:a"
				( attribute "PN" "1"
					( Origin gPackager )
				)
				( objectStatus "R1D27.1" )
			)
			( pin "@baseboard_fab2_lib.baseboard_fab2(sch_1):page199_i38:b"
				( attribute "PN" "2"
					( Origin gPackager )
				)
				( objectStatus "R1D27.2" )
			)
			( pin "@baseboard_fab2_lib.baseboard_fab2(sch_1):page199_i41:a"
				( attribute "PN" "1"
					( Origin gPackager )
				)
				( objectStatus "R9P18.1" )
			)
			( pin "@baseboard_fab2_lib.baseboard_fab2(sch_1):page199_i41:b"
				( attribute "PN" "2"
					( Origin gPackager )
				)
				( objectStatus "R9P18.2" )
			)
			( pin "@baseboard_fab2_lib.baseboard_fab2(sch_1):page199_i43:a"
				( attribute "PN" "1"
					( Origin gPackager )
				)
				( objectStatus "R1D31.1" )
			)
			( pin "@baseboard_fab2_lib.baseboard_fab2(sch_1):page199_i43:b"
				( attribute "PN" "2"
					( Origin gPackager )
				)
				( objectStatus "R1D31.2" )
			)
			( pin "@baseboard_fab2_lib.baseboard_fab2(sch_1):page199_i53:a"
				( attribute "PN" "1"
					( Origin gPackager )
				)
				( objectStatus "C1D11.1" )
			)
			( pin "@baseboard_fab2_lib.baseboard_fab2(sch_1):page199_i53:b"
				( attribute "PN" "2"
					( Origin gPackager )
				)
				( objectStatus "C1D11.2" )
			)
			( pin "@baseboard_fab2_lib.baseboard_fab2(sch_1):page199_i54:a"
				( attribute "PN" "1"
					( Origin gPackager )
				)
				( objectStatus "R9P23.1" )
			)
			( pin "@baseboard_fab2_lib.baseboard_fab2(sch_1):page199_i54:b"
				( attribute "PN" "2"
					( Origin gPackager )
				)
				( objectStatus "R9P23.2" )
			)
			( pin "@baseboard_fab2_lib.baseboard_fab2(sch_1):page199_i55:a"
				( attribute "PN" "1"
					( Origin gPackager )
				)
				( objectStatus "R9P24.1" )
			)
			( pin "@baseboard_fab2_lib.baseboard_fab2(sch_1):page199_i55:b"
				( attribute "PN" "2"
					( Origin gPackager )
				)
				( objectStatus "R9P24.2" )
			)
			( pin "@baseboard_fab2_lib.baseboard_fab2(sch_1):page199_i58:b"
				( attribute "PN" "1"
					( Origin gPackager )
				)
				( objectStatus "Q1D3.1" )
			)
			( pin "@baseboard_fab2_lib.baseboard_fab2(sch_1):page199_i58:c"
				( attribute "PN" "3"
					( Origin gPackager )
				)
				( objectStatus "Q1D3.3" )
			)
			( pin "@baseboard_fab2_lib.baseboard_fab2(sch_1):page199_i58:e"
				( attribute "PN" "2"
					( Origin gPackager )
				)
				( objectStatus "Q1D3.2" )
			)
			( pin "@baseboard_fab2_lib.baseboard_fab2(sch_1):page199_i65:a"
				( attribute "PN" "1"
					( Origin gPackager )
				)
				( objectStatus "R1D36.1" )
			)
			( pin "@baseboard_fab2_lib.baseboard_fab2(sch_1):page199_i65:b"
				( attribute "PN" "2"
					( Origin gPackager )
				)
				( objectStatus "R1D36.2" )
			)
			( pin "@baseboard_fab2_lib.baseboard_fab2(sch_1):page199_i67:a"
				( attribute "PN" "1"
					( Origin gPackager )
				)
				( objectStatus "C9P12.1" )
			)
			( pin "@baseboard_fab2_lib.baseboard_fab2(sch_1):page199_i67:b"
				( attribute "PN" "2"
					( Origin gPackager )
				)
				( objectStatus "C9P12.2" )
			)
			( pin "@baseboard_fab2_lib.baseboard_fab2(sch_1):page199_i82:drain(0)"
				( attribute "PN" "3"
					( Origin gPackager )
				)
				( objectStatus "Q1D1.3" )
			)
			( pin "@baseboard_fab2_lib.baseboard_fab2(sch_1):page199_i82:gate(0)"
				( attribute "PN" "5"
					( Origin gPackager )
				)
				( objectStatus "Q1D1.5" )
			)
			( pin "@baseboard_fab2_lib.baseboard_fab2(sch_1):page199_i82:source(0)"
				( attribute "PN" "4"
					( Origin gPackager )
				)
				( objectStatus "Q1D1.4" )
			)
			( pin "@baseboard_fab2_lib.baseboard_fab2(sch_1):page199_i84:a"
				( attribute "PN" "1"
					( Origin gPackager )
				)
				( objectStatus "R1D13.1" )
			)
			( pin "@baseboard_fab2_lib.baseboard_fab2(sch_1):page199_i84:b"
				( attribute "PN" "2"
					( Origin gPackager )
				)
				( objectStatus "R1D13.2" )
			)
			( pin "@baseboard_fab2_lib.baseboard_fab2(sch_1):page199_i85:a"
				( attribute "PN" "1"
					( Origin gPackager )
				)
				( objectStatus "R1D16.1" )
			)
			( pin "@baseboard_fab2_lib.baseboard_fab2(sch_1):page199_i85:b"
				( attribute "PN" "2"
					( Origin gPackager )
				)
				( objectStatus "R1D16.2" )
			)
			( pin "@baseboard_fab2_lib.baseboard_fab2(sch_1):page199_i86:drain(0)"
				( attribute "PN" "6"
					( Origin gPackager )
				)
				( objectStatus "Q1D1.6" )
			)
			( pin "@baseboard_fab2_lib.baseboard_fab2(sch_1):page199_i86:gate(0)"
				( attribute "PN" "2"
					( Origin gPackager )
				)
				( objectStatus "Q1D1.2" )
			)
			( pin "@baseboard_fab2_lib.baseboard_fab2(sch_1):page199_i86:source(0)"
				( attribute "PN" "1"
					( Origin gPackager )
				)
				( objectStatus "Q1D1.1" )
			)
			( pin "@baseboard_fab2_lib.baseboard_fab2(sch_1):page199_i88:a"
				( attribute "PN" "1"
					( Origin gPackager )
				)
				( objectStatus "R1D11.1" )
			)
			( pin "@baseboard_fab2_lib.baseboard_fab2(sch_1):page199_i88:b"
				( attribute "PN" "2"
					( Origin gPackager )
				)
				( objectStatus "R1D11.2" )
			)
			( pin "@baseboard_fab2_lib.baseboard_fab2(sch_1):page199_i92:a"
				( attribute "PN" "1"
					( Origin gPackager )
				)
				( objectStatus "R1D15.1" )
			)
			( pin "@baseboard_fab2_lib.baseboard_fab2(sch_1):page199_i92:b"
				( attribute "PN" "2"
					( Origin gPackager )
				)
				( objectStatus "R1D15.2" )
			)
			( pin "@baseboard_fab2_lib.baseboard_fab2(sch_1):page199_i99:a"
				( attribute "PN" "2"
					( Origin gPackager )
				)
				( objectStatus "VR1D1.2" )
			)
			( pin "@baseboard_fab2_lib.baseboard_fab2(sch_1):page199_i99:c"
				( attribute "PN" "1"
					( Origin gPackager )
				)
				( objectStatus "VR1D1.1" )
			)
			( pin "@baseboard_fab2_lib.baseboard_fab2(sch_1):page199_i100:a"
				( attribute "PN" "1"
					( Origin gPackager )
				)
				( objectStatus "R1D40.1" )
			)
			( pin "@baseboard_fab2_lib.baseboard_fab2(sch_1):page199_i100:b"
				( attribute "PN" "2"
					( Origin gPackager )
				)
				( objectStatus "R1D40.2" )
			)
			( pin "@baseboard_fab2_lib.baseboard_fab2(sch_1):page199_i102:a"
				( attribute "PN" "1"
					( Origin gPackager )
				)
				( objectStatus "R1D34.1" )
			)
			( pin "@baseboard_fab2_lib.baseboard_fab2(sch_1):page199_i102:b"
				( attribute "PN" "2"
					( Origin gPackager )
				)
				( objectStatus "R1D34.2" )
			)
			( pin "@baseboard_fab2_lib.baseboard_fab2(sch_1):page199_i105:a"
				( attribute "PN" "1"
					( Origin gPackager )
				)
				( objectStatus "C9P15.1" )
			)
			( pin "@baseboard_fab2_lib.baseboard_fab2(sch_1):page199_i105:b"
				( attribute "PN" "2"
					( Origin gPackager )
				)
				( objectStatus "C9P15.2" )
			)
			( pin "@baseboard_fab2_lib.baseboard_fab2(sch_1):page199_i107:a"
				( attribute "PN" "1"
					( Origin gPackager )
				)
				( objectStatus "C1D26.1" )
			)
			( pin "@baseboard_fab2_lib.baseboard_fab2(sch_1):page199_i107:b"
				( attribute "PN" "2"
					( Origin gPackager )
				)
				( objectStatus "C1D26.2" )
			)
			( pin "@baseboard_fab2_lib.baseboard_fab2(sch_1):page199_i108:a"
				( attribute "PN" "1"
					( Origin gPackager )
				)
				( objectStatus "R1D33.1" )
			)
			( pin "@baseboard_fab2_lib.baseboard_fab2(sch_1):page199_i108:b"
				( attribute "PN" "2"
					( Origin gPackager )
				)
				( objectStatus "R1D33.2" )
			)
			( pin "@baseboard_fab2_lib.baseboard_fab2(sch_1):page199_i109:a"
				( attribute "PN" "1"
					( Origin gPackager )
				)
				( objectStatus "R1D26.1" )
			)
			( pin "@baseboard_fab2_lib.baseboard_fab2(sch_1):page199_i109:b"
				( attribute "PN" "2"
					( Origin gPackager )
				)
				( objectStatus "R1D26.2" )
			)
			( pin "@baseboard_fab2_lib.baseboard_fab2(sch_1):page199_i110:a"
				( attribute "PN" "1"
					( Origin gPackager )
				)
				( objectStatus "R1D30.1" )
			)
			( pin "@baseboard_fab2_lib.baseboard_fab2(sch_1):page199_i110:b"
				( attribute "PN" "2"
					( Origin gPackager )
				)
				( objectStatus "R1D30.2" )
			)
			( pin "@baseboard_fab2_lib.baseboard_fab2(sch_1):page199_i119:a"
				( attribute "PN" "1"
					( Origin gPackager )
				)
				( objectStatus "C1D19.1" )
			)
			( pin "@baseboard_fab2_lib.baseboard_fab2(sch_1):page199_i119:b"
				( attribute "PN" "2"
					( Origin gPackager )
				)
				( objectStatus "C1D19.2" )
			)
			( pin "@baseboard_fab2_lib.baseboard_fab2(sch_1):page199_i121:a"
				( attribute "PN" "1"
					( Origin gPackager )
				)
				( objectStatus "C1D21.1" )
			)
			( pin "@baseboard_fab2_lib.baseboard_fab2(sch_1):page199_i121:b"
				( attribute "PN" "2"
					( Origin gPackager )
				)
				( objectStatus "C1D21.2" )
			)
			( pin "@baseboard_fab2_lib.baseboard_fab2(sch_1):page200_i36:a"
				( attribute "PN" "1"
					( Origin gPackager )
				)
				( objectStatus "C9P17.1" )
			)
			( pin "@baseboard_fab2_lib.baseboard_fab2(sch_1):page200_i36:b"
				( attribute "PN" "2"
					( Origin gPackager )
				)
				( objectStatus "C9P17.2" )
			)
			( pin "@baseboard_fab2_lib.baseboard_fab2(sch_1):page200_i40:a"
				( attribute "PN" "1"
					( Origin gPackager )
				)
				( objectStatus "C9P16.1" )
			)
			( pin "@baseboard_fab2_lib.baseboard_fab2(sch_1):page200_i40:b"
				( attribute "PN" "2"
					( Origin gPackager )
				)
				( objectStatus "C9P16.2" )
			)
			( pin "@baseboard_fab2_lib.baseboard_fab2(sch_1):page200_i42:a"
				( attribute "PN" "1"
					( Origin gPackager )
				)
				( objectStatus "C1D22.1" )
			)
			( pin "@baseboard_fab2_lib.baseboard_fab2(sch_1):page200_i42:b"
				( attribute "PN" "2"
					( Origin gPackager )
				)
				( objectStatus "C1D22.2" )
			)
			( pin "@baseboard_fab2_lib.baseboard_fab2(sch_1):page200_i43:a"
				( attribute "PN" "1"
					( Origin gPackager )
				)
				( objectStatus "R1D45.1" )
			)
			( pin "@baseboard_fab2_lib.baseboard_fab2(sch_1):page200_i43:b"
				( attribute "PN" "2"
					( Origin gPackager )
				)
				( objectStatus "R1D45.2" )
			)
			( pin "@baseboard_fab2_lib.baseboard_fab2(sch_1):page200_i44:a"
				( attribute "PN" "1"
					( Origin gPackager )
				)
				( objectStatus "R1D44.1" )
			)
			( pin "@baseboard_fab2_lib.baseboard_fab2(sch_1):page200_i44:b"
				( attribute "PN" "2"
					( Origin gPackager )
				)
				( objectStatus "R1D44.2" )
			)
			( pin "@baseboard_fab2_lib.baseboard_fab2(sch_1):page200_i47:a"
				( attribute "PN" "1"
					( Origin gPackager )
				)
				( objectStatus "R9P27.1" )
			)
			( pin "@baseboard_fab2_lib.baseboard_fab2(sch_1):page200_i47:b"
				( attribute "PN" "2"
					( Origin gPackager )
				)
				( objectStatus "R9P27.2" )
			)
			( pin "@baseboard_fab2_lib.baseboard_fab2(sch_1):page200_i48:a"
				( attribute "PN" "1"
					( Origin gPackager )
				)
				( objectStatus "R1D46.1" )
			)
			( pin "@baseboard_fab2_lib.baseboard_fab2(sch_1):page200_i48:b"
				( attribute "PN" "2"
					( Origin gPackager )
				)
				( objectStatus "R1D46.2" )
			)
			( pin "@baseboard_fab2_lib.baseboard_fab2(sch_1):page200_i49:\1\"
				( attribute "PN" "1"
					( Origin gPackager )
				)
				( objectStatus "R9R1.1" )
			)
			( pin "@baseboard_fab2_lib.baseboard_fab2(sch_1):page200_i49:\2\"
				( attribute "PN" "2"
					( Origin gPackager )
				)
				( objectStatus "R9R1.2" )
			)
			( pin "@baseboard_fab2_lib.baseboard_fab2(sch_1):page200_i49:\3\"
				( attribute "PN" "3"
					( Origin gPackager )
				)
				( objectStatus "R9R1.3" )
			)
			( pin "@baseboard_fab2_lib.baseboard_fab2(sch_1):page200_i49:\4\"
				( attribute "PN" "4"
					( Origin gPackager )
				)
				( objectStatus "R9R1.4" )
			)
			( pin "@baseboard_fab2_lib.baseboard_fab2(sch_1):page200_i49:\5\"
				( attribute "PN" "5"
					( Origin gPackager )
				)
				( objectStatus "R9R1.5" )
			)
			( pin "@baseboard_fab2_lib.baseboard_fab2(sch_1):page200_i49:\6\"
				( attribute "PN" "6"
					( Origin gPackager )
				)
				( objectStatus "R9R1.6" )
			)
			( pin "@baseboard_fab2_lib.baseboard_fab2(sch_1):page200_i50:\1\"
				( attribute "PN" "1"
					( Origin gPackager )
				)
				( objectStatus "R1D49.1" )
			)
			( pin "@baseboard_fab2_lib.baseboard_fab2(sch_1):page200_i50:\2\"
				( attribute "PN" "2"
					( Origin gPackager )
				)
				( objectStatus "R1D49.2" )
			)
			( pin "@baseboard_fab2_lib.baseboard_fab2(sch_1):page200_i50:\3\"
				( attribute "PN" "3"
					( Origin gPackager )
				)
				( objectStatus "R1D49.3" )
			)
			( pin "@baseboard_fab2_lib.baseboard_fab2(sch_1):page200_i50:\4\"
				( attribute "PN" "4"
					( Origin gPackager )
				)
				( objectStatus "R1D49.4" )
			)
			( pin "@baseboard_fab2_lib.baseboard_fab2(sch_1):page200_i50:\5\"
				( attribute "PN" "5"
					( Origin gPackager )
				)
				( objectStatus "R1D49.5" )
			)
			( pin "@baseboard_fab2_lib.baseboard_fab2(sch_1):page200_i50:\6\"
				( attribute "PN" "6"
					( Origin gPackager )
				)
				( objectStatus "R1D49.6" )
			)
			( pin "@baseboard_fab2_lib.baseboard_fab2(sch_1):page200_i51:a"
				( attribute "PN" "1"
					( Origin gPackager )
				)
				( objectStatus "R9P26.1" )
			)
			( pin "@baseboard_fab2_lib.baseboard_fab2(sch_1):page200_i51:b"
				( attribute "PN" "2"
					( Origin gPackager )
				)
				( objectStatus "R9P26.2" )
			)
			( pin "@baseboard_fab2_lib.baseboard_fab2(sch_1):page200_i52:a"
				( attribute "PN" "1"
					( Origin gPackager )
				)
				( objectStatus "R1D47.1" )
			)
			( pin "@baseboard_fab2_lib.baseboard_fab2(sch_1):page200_i52:b"
				( attribute "PN" "2"
					( Origin gPackager )
				)
				( objectStatus "R1D47.2" )
			)
			( pin "@baseboard_fab2_lib.baseboard_fab2(sch_1):page200_i54:d"
				( attribute "PN" "5"
					( Origin gPackager )
				)
				( objectStatus "EU1E3.5" )
			)
			( pin "@baseboard_fab2_lib.baseboard_fab2(sch_1):page200_i54:g"
				( attribute "PN" "4"
					( Origin gPackager )
				)
				( objectStatus "EU1E3.4" )
			)
			( pin "@baseboard_fab2_lib.baseboard_fab2(sch_1):page200_i54:s1"
				( attribute "PN" "1"
					( Origin gPackager )
				)
				( objectStatus "EU1E3.1" )
			)
			( pin "@baseboard_fab2_lib.baseboard_fab2(sch_1):page200_i54:s2"
				( attribute "PN" "2"
					( Origin gPackager )
				)
				( objectStatus "EU1E3.2" )
			)
			( pin "@baseboard_fab2_lib.baseboard_fab2(sch_1):page200_i54:s3"
				( attribute "PN" "3"
					( Origin gPackager )
				)
				( objectStatus "EU1E3.3" )
			)
			( pin "@baseboard_fab2_lib.baseboard_fab2(sch_1):page200_i56:a"
				( attribute "PN" "1"
					( Origin gPackager )
				)
				( objectStatus "R1E1.1" )
			)
			( pin "@baseboard_fab2_lib.baseboard_fab2(sch_1):page200_i56:b"
				( attribute "PN" "2"
					( Origin gPackager )
				)
				( objectStatus "R1E1.2" )
			)
			( pin "@baseboard_fab2_lib.baseboard_fab2(sch_1):page200_i57:d"
				( attribute "PN" "5"
					( Origin gPackager )
				)
				( objectStatus "EU9R1.5" )
			)
			( pin "@baseboard_fab2_lib.baseboard_fab2(sch_1):page200_i57:g"
				( attribute "PN" "4"
					( Origin gPackager )
				)
				( objectStatus "EU9R1.4" )
			)
			( pin "@baseboard_fab2_lib.baseboard_fab2(sch_1):page200_i57:s1"
				( attribute "PN" "1"
					( Origin gPackager )
				)
				( objectStatus "EU9R1.1" )
			)
			( pin "@baseboard_fab2_lib.baseboard_fab2(sch_1):page200_i57:s2"
				( attribute "PN" "2"
					( Origin gPackager )
				)
				( objectStatus "EU9R1.2" )
			)
			( pin "@baseboard_fab2_lib.baseboard_fab2(sch_1):page200_i57:s3"
				( attribute "PN" "3"
					( Origin gPackager )
				)
				( objectStatus "EU9R1.3" )
			)
			( pin "@baseboard_fab2_lib.baseboard_fab2(sch_1):page200_i58:a"
				( attribute "PN" "1"
					( Origin gPackager )
				)
				( objectStatus "R9R4.1" )
			)
			( pin "@baseboard_fab2_lib.baseboard_fab2(sch_1):page200_i58:b"
				( attribute "PN" "2"
					( Origin gPackager )
				)
				( objectStatus "R9R4.2" )
			)
			( pin "@baseboard_fab2_lib.baseboard_fab2(sch_1):page200_i59:d"
				( attribute "PN" "5"
					( Origin gPackager )
				)
				( objectStatus "EU1E1.5" )
			)
			( pin "@baseboard_fab2_lib.baseboard_fab2(sch_1):page200_i59:g"
				( attribute "PN" "4"
					( Origin gPackager )
				)
				( objectStatus "EU1E1.4" )
			)
			( pin "@baseboard_fab2_lib.baseboard_fab2(sch_1):page200_i59:s1"
				( attribute "PN" "1"
					( Origin gPackager )
				)
				( objectStatus "EU1E1.1" )
			)
			( pin "@baseboard_fab2_lib.baseboard_fab2(sch_1):page200_i59:s2"
				( attribute "PN" "2"
					( Origin gPackager )
				)
				( objectStatus "EU1E1.2" )
			)
			( pin "@baseboard_fab2_lib.baseboard_fab2(sch_1):page200_i59:s3"
				( attribute "PN" "3"
					( Origin gPackager )
				)
				( objectStatus "EU1E1.3" )
			)
			( pin "@baseboard_fab2_lib.baseboard_fab2(sch_1):page200_i60:a"
				( attribute "PN" "1"
					( Origin gPackager )
				)
				( objectStatus "R1D48.1" )
			)
			( pin "@baseboard_fab2_lib.baseboard_fab2(sch_1):page200_i60:b"
				( attribute "PN" "2"
					( Origin gPackager )
				)
				( objectStatus "R1D48.2" )
			)
			( pin "@baseboard_fab2_lib.baseboard_fab2(sch_1):page200_i70:a"
				( attribute "PN" "1"
					( Origin gPackager )
				)
				( objectStatus "R9P19.1" )
			)
			( pin "@baseboard_fab2_lib.baseboard_fab2(sch_1):page200_i70:b"
				( attribute "PN" "2"
					( Origin gPackager )
				)
				( objectStatus "R9P19.2" )
			)
			( pin "@baseboard_fab2_lib.baseboard_fab2(sch_1):page200_i71:a"
				( attribute "PN" "1"
					( Origin gPackager )
				)
				( objectStatus "R9P21.1" )
			)
			( pin "@baseboard_fab2_lib.baseboard_fab2(sch_1):page200_i71:b"
				( attribute "PN" "2"
					( Origin gPackager )
				)
				( objectStatus "R9P21.2" )
			)
			( pin "@baseboard_fab2_lib.baseboard_fab2(sch_1):page200_i86:a"
				( attribute "PN" "1"
					( Origin gPackager )
				)
				( objectStatus "R9P20.1" )
			)
			( pin "@baseboard_fab2_lib.baseboard_fab2(sch_1):page200_i86:b"
				( attribute "PN" "2"
					( Origin gPackager )
				)
				( objectStatus "R9P20.2" )
			)
			( pin "@baseboard_fab2_lib.baseboard_fab2(sch_1):page200_i103:a"
				( attribute "PN" "2"
					( Origin gPackager )
				)
				( objectStatus "U1D1.2" )
			)
			( pin "@baseboard_fab2_lib.baseboard_fab2(sch_1):page200_i103:oe"
				( attribute "PN" "1"
					( Origin gPackager )
				)
				( objectStatus "U1D1.1" )
			)
			( pin "@baseboard_fab2_lib.baseboard_fab2(sch_1):page200_i103:y"
				( attribute "PN" "4"
					( Origin gPackager )
				)
				( objectStatus "U1D1.4" )
			)
			( pin "@baseboard_fab2_lib.baseboard_fab2(sch_1):page200_i108:a"
				( attribute "PN" "1"
					( Origin gPackager )
				)
				( objectStatus "R9P11.1" )
			)
			( pin "@baseboard_fab2_lib.baseboard_fab2(sch_1):page200_i108:b"
				( attribute "PN" "2"
					( Origin gPackager )
				)
				( objectStatus "R9P11.2" )
			)
			( pin "@baseboard_fab2_lib.baseboard_fab2(sch_1):page200_i149:a"
				( attribute "PN" "1"
					( Origin gPackager )
				)
				( objectStatus "R9P6.1" )
			)
			( pin "@baseboard_fab2_lib.baseboard_fab2(sch_1):page200_i149:b"
				( attribute "PN" "2"
					( Origin gPackager )
				)
				( objectStatus "R9P6.2" )
			)
			( pin "@baseboard_fab2_lib.baseboard_fab2(sch_1):page200_i154:a"
				( attribute "PN" "1"
					( Origin gPackager )
				)
				( objectStatus "R1D51.1" )
			)
			( pin "@baseboard_fab2_lib.baseboard_fab2(sch_1):page200_i154:b"
				( attribute "PN" "2"
					( Origin gPackager )
				)
				( objectStatus "R1D51.2" )
			)
			( pin "@baseboard_fab2_lib.baseboard_fab2(sch_1):page200_i155:a"
				( attribute "PN" "1"
					( Origin gPackager )
				)
				( objectStatus "C1E2.1" )
			)
			( pin "@baseboard_fab2_lib.baseboard_fab2(sch_1):page200_i155:b"
				( attribute "PN" "2"
					( Origin gPackager )
				)
				( objectStatus "C1E2.2" )
			)
			( pin "@baseboard_fab2_lib.baseboard_fab2(sch_1):page200_i158:a"
				( attribute "PN" "1"
					( Origin gPackager )
				)
				( objectStatus "R1D22.1" )
			)
			( pin "@baseboard_fab2_lib.baseboard_fab2(sch_1):page200_i158:b"
				( attribute "PN" "2"
					( Origin gPackager )
				)
				( objectStatus "R1D22.2" )
			)
			( pin "@baseboard_fab2_lib.baseboard_fab2(sch_1):page200_i163:gnd"
				( attribute "PN" "5"
					( Origin gPackager )
				)
				( objectStatus "U9P1.5" )
			)
			( pin "@baseboard_fab2_lib.baseboard_fab2(sch_1):page200_i163:inap"
				( attribute "PN" "4"
					( Origin gPackager )
				)
				( objectStatus "U9P1.4" )
			)
			( pin "@baseboard_fab2_lib.baseboard_fab2(sch_1):page200_i163:inbn"
				( attribute "PN" "3"
					( Origin gPackager )
				)
				( objectStatus "U9P1.3" )
			)
			( pin "@baseboard_fab2_lib.baseboard_fab2(sch_1):page200_i163:outa"
				( attribute "PN" "6"
					( Origin gPackager )
				)
				( objectStatus "U9P1.6" )
			)
			( pin "@baseboard_fab2_lib.baseboard_fab2(sch_1):page200_i163:outb"
				( attribute "PN" "1"
					( Origin gPackager )
				)
				( objectStatus "U9P1.1" )
			)
			( pin "@baseboard_fab2_lib.baseboard_fab2(sch_1):page200_i163:vdd"
				( attribute "PN" "2"
					( Origin gPackager )
				)
				( objectStatus "U9P1.2" )
			)
			( pin "@baseboard_fab2_lib.baseboard_fab2(sch_1):page200_i170:gnd"
				( attribute "PN" "5"
					( Origin gPackager )
				)
				( objectStatus "U1D2.5" )
			)
			( pin "@baseboard_fab2_lib.baseboard_fab2(sch_1):page200_i170:inap"
				( attribute "PN" "4"
					( Origin gPackager )
				)
				( objectStatus "U1D2.4" )
			)
			( pin "@baseboard_fab2_lib.baseboard_fab2(sch_1):page200_i170:inbn"
				( attribute "PN" "3"
					( Origin gPackager )
				)
				( objectStatus "U1D2.3" )
			)
			( pin "@baseboard_fab2_lib.baseboard_fab2(sch_1):page200_i170:outa"
				( attribute "PN" "6"
					( Origin gPackager )
				)
				( objectStatus "U1D2.6" )
			)
			( pin "@baseboard_fab2_lib.baseboard_fab2(sch_1):page200_i170:outb"
				( attribute "PN" "1"
					( Origin gPackager )
				)
				( objectStatus "U1D2.1" )
			)
			( pin "@baseboard_fab2_lib.baseboard_fab2(sch_1):page200_i170:vdd"
				( attribute "PN" "2"
					( Origin gPackager )
				)
				( objectStatus "U1D2.2" )
			)
			( pin "@baseboard_fab2_lib.baseboard_fab2(sch_1):page200_i174:a"
				( attribute "PN" "1"
					( Origin gPackager )
				)
				( objectStatus "R1D12.1" )
			)
			( pin "@baseboard_fab2_lib.baseboard_fab2(sch_1):page200_i174:b"
				( attribute "PN" "2"
					( Origin gPackager )
				)
				( objectStatus "R1D12.2" )
			)
			( pin "@baseboard_fab2_lib.baseboard_fab2(sch_1):page200_i175:a"
				( attribute "PN" "1"
					( Origin gPackager )
				)
				( objectStatus "R1D19.1" )
			)
			( pin "@baseboard_fab2_lib.baseboard_fab2(sch_1):page200_i175:b"
				( attribute "PN" "2"
					( Origin gPackager )
				)
				( objectStatus "R1D19.2" )
			)
			( pin "@baseboard_fab2_lib.baseboard_fab2(sch_1):page200_i185:a"
				( attribute "PN" "1"
					( Origin gPackager )
				)
				( objectStatus "C9P6.1" )
			)
			( pin "@baseboard_fab2_lib.baseboard_fab2(sch_1):page200_i185:b"
				( attribute "PN" "2"
					( Origin gPackager )
				)
				( objectStatus "C9P6.2" )
			)
			( pin "@baseboard_fab2_lib.baseboard_fab2(sch_1):page200_i187:a"
				( attribute "PN" "1"
					( Origin gPackager )
				)
				( objectStatus "C1D9.1" )
			)
			( pin "@baseboard_fab2_lib.baseboard_fab2(sch_1):page200_i187:b"
				( attribute "PN" "2"
					( Origin gPackager )
				)
				( objectStatus "C1D9.2" )
			)
			( pin "@baseboard_fab2_lib.baseboard_fab2(sch_1):page199_i87:a"
				( attribute "PN" "1"
					( Origin gPackager )
				)
				( objectStatus "R1D18.1" )
			)
			( pin "@baseboard_fab2_lib.baseboard_fab2(sch_1):page199_i87:b"
				( attribute "PN" "2"
					( Origin gPackager )
				)
				( objectStatus "R1D18.2" )
			)
			( pin "@baseboard_fab2_lib.baseboard_fab2(sch_1):page200_i191:a"
				( attribute "PN" "1"
					( Origin gPackager )
				)
				( objectStatus "R1D23.1" )
			)
			( pin "@baseboard_fab2_lib.baseboard_fab2(sch_1):page200_i191:b"
				( attribute "PN" "2"
					( Origin gPackager )
				)
				( objectStatus "R1D23.2" )
			)
			( pin "@baseboard_fab2_lib.baseboard_fab2(sch_1):page200_i192:a"
				( attribute "PN" "1"
					( Origin gPackager )
				)
				( objectStatus "R9P10.1" )
			)
			( pin "@baseboard_fab2_lib.baseboard_fab2(sch_1):page200_i192:b"
				( attribute "PN" "2"
					( Origin gPackager )
				)
				( objectStatus "R9P10.2" )
			)
			( pin "@baseboard_fab2_lib.baseboard_fab2(sch_1):page200_i196:drain(0)"
				( attribute "PN" "6"
					( Origin gPackager )
				)
				( objectStatus "Q9P1.6" )
			)
			( pin "@baseboard_fab2_lib.baseboard_fab2(sch_1):page200_i196:gate(0)"
				( attribute "PN" "2"
					( Origin gPackager )
				)
				( objectStatus "Q9P1.2" )
			)
			( pin "@baseboard_fab2_lib.baseboard_fab2(sch_1):page200_i196:source(0)"
				( attribute "PN" "1"
					( Origin gPackager )
				)
				( objectStatus "Q9P1.1" )
			)
			( pin "@baseboard_fab2_lib.baseboard_fab2(sch_1):page200_i199:drain(0)"
				( attribute "PN" "3"
					( Origin gPackager )
				)
				( objectStatus "Q9P1.3" )
			)
			( pin "@baseboard_fab2_lib.baseboard_fab2(sch_1):page200_i199:gate(0)"
				( attribute "PN" "5"
					( Origin gPackager )
				)
				( objectStatus "Q9P1.5" )
			)
			( pin "@baseboard_fab2_lib.baseboard_fab2(sch_1):page200_i199:source(0)"
				( attribute "PN" "4"
					( Origin gPackager )
				)
				( objectStatus "Q9P1.4" )
			)
			( pin "@baseboard_fab2_lib.baseboard_fab2(sch_1):page200_i200:gnd"
				( attribute "PN" "5"
					( Origin gPackager )
				)
				( objectStatus "U9P2.5" )
			)
			( pin "@baseboard_fab2_lib.baseboard_fab2(sch_1):page200_i200:inap"
				( attribute "PN" "4"
					( Origin gPackager )
				)
				( objectStatus "U9P2.4" )
			)
			( pin "@baseboard_fab2_lib.baseboard_fab2(sch_1):page200_i200:inbn"
				( attribute "PN" "3"
					( Origin gPackager )
				)
				( objectStatus "U9P2.3" )
			)
			( pin "@baseboard_fab2_lib.baseboard_fab2(sch_1):page200_i200:outa"
				( attribute "PN" "6"
					( Origin gPackager )
				)
				( objectStatus "U9P2.6" )
			)
			( pin "@baseboard_fab2_lib.baseboard_fab2(sch_1):page200_i200:outb"
				( attribute "PN" "1"
					( Origin gPackager )
				)
				( objectStatus "U9P2.1" )
			)
			( pin "@baseboard_fab2_lib.baseboard_fab2(sch_1):page200_i200:vdd"
				( attribute "PN" "2"
					( Origin gPackager )
				)
				( objectStatus "U9P2.2" )
			)
			( pin "@baseboard_fab2_lib.baseboard_fab2(sch_1):page200_i201:a"
				( attribute "PN" "1"
					( Origin gPackager )
				)
				( objectStatus "C9P11.1" )
			)
			( pin "@baseboard_fab2_lib.baseboard_fab2(sch_1):page200_i201:b"
				( attribute "PN" "2"
					( Origin gPackager )
				)
				( objectStatus "C9P11.2" )
			)
			( pin "@baseboard_fab2_lib.baseboard_fab2(sch_1):page200_i203:drn"
				( attribute "PN" "3"
					( Origin gPackager )
				)
				( objectStatus "Q1D2.3" )
			)
			( pin "@baseboard_fab2_lib.baseboard_fab2(sch_1):page200_i203:gate"
				( attribute "PN" "1"
					( Origin gPackager )
				)
				( objectStatus "Q1D2.1" )
			)
			( pin "@baseboard_fab2_lib.baseboard_fab2(sch_1):page200_i203:src"
				( attribute "PN" "2"
					( Origin gPackager )
				)
				( objectStatus "Q1D2.2" )
			)
			( pin "@baseboard_fab2_lib.baseboard_fab2(sch_1):page200_i204:a"
				( attribute "PN" "1"
					( Origin gPackager )
				)
				( objectStatus "R1D21.1" )
			)
			( pin "@baseboard_fab2_lib.baseboard_fab2(sch_1):page200_i204:b"
				( attribute "PN" "2"
					( Origin gPackager )
				)
				( objectStatus "R1D21.2" )
			)
			( pin "@baseboard_fab2_lib.baseboard_fab2(sch_1):page200_i210:a"
				( attribute "PN" "1"
					( Origin gPackager )
				)
				( objectStatus "R9P4.1" )
			)
			( pin "@baseboard_fab2_lib.baseboard_fab2(sch_1):page200_i210:b"
				( attribute "PN" "2"
					( Origin gPackager )
				)
				( objectStatus "R9P4.2" )
			)
			( pin "@baseboard_fab2_lib.baseboard_fab2(sch_1):page200_i213:a"
				( attribute "PN" "2"
					( Origin gPackager )
				)
				( objectStatus "CR9P2.2" )
			)
			( pin "@baseboard_fab2_lib.baseboard_fab2(sch_1):page200_i213:c"
				( attribute "PN" "1"
					( Origin gPackager )
				)
				( objectStatus "CR9P2.1" )
			)
			( pin "@baseboard_fab2_lib.baseboard_fab2(sch_1):page200_i214:a"
				( attribute "PN" "2"
					( Origin gPackager )
				)
				( objectStatus "CR9P1.2" )
			)
			( pin "@baseboard_fab2_lib.baseboard_fab2(sch_1):page200_i214:c"
				( attribute "PN" "1"
					( Origin gPackager )
				)
				( objectStatus "CR9P1.1" )
			)
			( pin "@baseboard_fab2_lib.baseboard_fab2(sch_1):page200_i215:a"
				( attribute "PN" "1"
					( Origin gPackager )
				)
				( objectStatus "R9P5.1" )
			)
			( pin "@baseboard_fab2_lib.baseboard_fab2(sch_1):page200_i215:b"
				( attribute "PN" "2"
					( Origin gPackager )
				)
				( objectStatus "R9P5.2" )
			)
			( pin "@baseboard_fab2_lib.baseboard_fab2(sch_1):page200_i218:a"
				( attribute "PN" "1"
					( Origin gPackager )
				)
				( objectStatus "R9P12.1" )
			)
			( pin "@baseboard_fab2_lib.baseboard_fab2(sch_1):page200_i218:b"
				( attribute "PN" "2"
					( Origin gPackager )
				)
				( objectStatus "R9P12.2" )
			)
			( pin "@baseboard_fab2_lib.baseboard_fab2(sch_1):page200_i220:a"
				( attribute "PN" "2"
					( Origin gPackager )
				)
				( objectStatus "CR1F5.2" )
			)
			( pin "@baseboard_fab2_lib.baseboard_fab2(sch_1):page200_i220:c"
				( attribute "PN" "1"
					( Origin gPackager )
				)
				( objectStatus "CR1F5.1" )
			)
			( pin "@baseboard_fab2_lib.baseboard_fab2(sch_1):page200_i222:a"
				( attribute "PN" "1"
					( Origin gPackager )
				)
				( objectStatus "R9P33.1" )
			)
			( pin "@baseboard_fab2_lib.baseboard_fab2(sch_1):page200_i222:b"
				( attribute "PN" "2"
					( Origin gPackager )
				)
				( objectStatus "R9P33.2" )
			)
			( pin "@baseboard_fab2_lib.baseboard_fab2(sch_1):page206_i155:a"
				( attribute "PN" "1"
					( Origin gPackager )
				)
				( objectStatus "R1D7.1" )
			)
			( pin "@baseboard_fab2_lib.baseboard_fab2(sch_1):page206_i155:b"
				( attribute "PN" "2"
					( Origin gPackager )
				)
				( objectStatus "R1D7.2" )
			)
			( pin "@baseboard_fab2_lib.baseboard_fab2(sch_1):page218_i70:a"
				( attribute "PN" "1"
					( Origin gPackager )
				)
				( objectStatus "R3L13.1" )
			)
			( pin "@baseboard_fab2_lib.baseboard_fab2(sch_1):page218_i70:b"
				( attribute "PN" "2"
					( Origin gPackager )
				)
				( objectStatus "R3L13.2" )
			)
			( pin "@baseboard_fab2_lib.baseboard_fab2(sch_1):page201_i22:a"
				( attribute "PN" "1"
					( Origin gPackager )
				)
				( objectStatus "R4D31.1" )
			)
			( pin "@baseboard_fab2_lib.baseboard_fab2(sch_1):page201_i22:b"
				( attribute "PN" "2"
					( Origin gPackager )
				)
				( objectStatus "R4D31.2" )
			)
			( pin "@baseboard_fab2_lib.baseboard_fab2(sch_1):page201_i25:a"
				( attribute "PN" "1"
					( Origin gPackager )
				)
				( objectStatus "R4D58.1" )
			)
			( pin "@baseboard_fab2_lib.baseboard_fab2(sch_1):page201_i25:b"
				( attribute "PN" "2"
					( Origin gPackager )
				)
				( objectStatus "R4D58.2" )
			)
			( pin "@baseboard_fab2_lib.baseboard_fab2(sch_1):page201_i26:a"
				( attribute "PN" "1"
					( Origin gPackager )
				)
				( objectStatus "R4D67.1" )
			)
			( pin "@baseboard_fab2_lib.baseboard_fab2(sch_1):page201_i26:b"
				( attribute "PN" "2"
					( Origin gPackager )
				)
				( objectStatus "R4D67.2" )
			)
			( pin "@baseboard_fab2_lib.baseboard_fab2(sch_1):page201_i27:a"
				( attribute "PN" "1"
					( Origin gPackager )
				)
				( objectStatus "R4E5.1" )
			)
			( pin "@baseboard_fab2_lib.baseboard_fab2(sch_1):page201_i27:b"
				( attribute "PN" "2"
					( Origin gPackager )
				)
				( objectStatus "R4E5.2" )
			)
			( pin "@baseboard_fab2_lib.baseboard_fab2(sch_1):page201_i30:a"
				( attribute "PN" "1"
					( Origin gPackager )
				)
				( objectStatus "C4D25.1" )
			)
			( pin "@baseboard_fab2_lib.baseboard_fab2(sch_1):page201_i30:b"
				( attribute "PN" "2"
					( Origin gPackager )
				)
				( objectStatus "C4D25.2" )
			)
			( pin "@baseboard_fab2_lib.baseboard_fab2(sch_1):page201_i32:a"
				( attribute "PN" "1"
					( Origin gPackager )
				)
				( objectStatus "C4D26.1" )
			)
			( pin "@baseboard_fab2_lib.baseboard_fab2(sch_1):page201_i32:b"
				( attribute "PN" "2"
					( Origin gPackager )
				)
				( objectStatus "C4D26.2" )
			)
			( pin "@baseboard_fab2_lib.baseboard_fab2(sch_1):page201_i37:a"
				( attribute "PN" "1"
					( Origin gPackager )
				)
				( objectStatus "C4D15.1" )
			)
			( pin "@baseboard_fab2_lib.baseboard_fab2(sch_1):page201_i37:b"
				( attribute "PN" "2"
					( Origin gPackager )
				)
				( objectStatus "C4D15.2" )
			)
			( pin "@baseboard_fab2_lib.baseboard_fab2(sch_1):page201_i39:a"
				( attribute "PN" "1"
					( Origin gPackager )
				)
				( objectStatus "C4D19.1" )
			)
			( pin "@baseboard_fab2_lib.baseboard_fab2(sch_1):page201_i39:b"
				( attribute "PN" "2"
					( Origin gPackager )
				)
				( objectStatus "C4D19.2" )
			)
			( pin "@baseboard_fab2_lib.baseboard_fab2(sch_1):page201_i40:a"
				( attribute "PN" "1"
					( Origin gPackager )
				)
				( objectStatus "R4D26.1" )
			)
			( pin "@baseboard_fab2_lib.baseboard_fab2(sch_1):page201_i40:b"
				( attribute "PN" "2"
					( Origin gPackager )
				)
				( objectStatus "R4D26.2" )
			)
			( pin "@baseboard_fab2_lib.baseboard_fab2(sch_1):page211_i99:a"
				( attribute "PN" "1"
					( Origin gPackager )
				)
				( objectStatus "R3P17.1" )
			)
			( pin "@baseboard_fab2_lib.baseboard_fab2(sch_1):page211_i99:b"
				( attribute "PN" "2"
					( Origin gPackager )
				)
				( objectStatus "R3P17.2" )
			)
			( pin "@baseboard_fab2_lib.baseboard_fab2(sch_1):page201_i54:a"
				( attribute "PN" "1"
					( Origin gPackager )
				)
				( objectStatus "R4D27.1" )
			)
			( pin "@baseboard_fab2_lib.baseboard_fab2(sch_1):page201_i54:b"
				( attribute "PN" "2"
					( Origin gPackager )
				)
				( objectStatus "R4D27.2" )
			)
			( pin "@baseboard_fab2_lib.baseboard_fab2(sch_1):page201_i55:a"
				( attribute "PN" "1"
					( Origin gPackager )
				)
				( objectStatus "R4D32.1" )
			)
			( pin "@baseboard_fab2_lib.baseboard_fab2(sch_1):page201_i55:b"
				( attribute "PN" "2"
					( Origin gPackager )
				)
				( objectStatus "R4D32.2" )
			)
			( pin "@baseboard_fab2_lib.baseboard_fab2(sch_1):page201_i56:a"
				( attribute "PN" "1"
					( Origin gPackager )
				)
				( objectStatus "R4E6.1" )
			)
			( pin "@baseboard_fab2_lib.baseboard_fab2(sch_1):page201_i56:b"
				( attribute "PN" "2"
					( Origin gPackager )
				)
				( objectStatus "R4E6.2" )
			)
			( pin "@baseboard_fab2_lib.baseboard_fab2(sch_1):page206_i156:a"
				( attribute "PN" "1"
					( Origin gPackager )
				)
				( objectStatus "C1C8.1" )
			)
			( pin "@baseboard_fab2_lib.baseboard_fab2(sch_1):page206_i156:b"
				( attribute "PN" "2"
					( Origin gPackager )
				)
				( objectStatus "C1C8.2" )
			)
			( pin "@baseboard_fab2_lib.baseboard_fab2(sch_1):page201_i64:a"
				( attribute "PN" "1"
					( Origin gPackager )
				)
				( objectStatus "C4D29.1" )
			)
			( pin "@baseboard_fab2_lib.baseboard_fab2(sch_1):page201_i64:b"
				( attribute "PN" "2"
					( Origin gPackager )
				)
				( objectStatus "C4D29.2" )
			)
			( pin "@baseboard_fab2_lib.baseboard_fab2(sch_1):page201_i66:a"
				( attribute "PN" "1"
					( Origin gPackager )
				)
				( objectStatus "C4D17.1" )
			)
			( pin "@baseboard_fab2_lib.baseboard_fab2(sch_1):page201_i66:b"
				( attribute "PN" "2"
					( Origin gPackager )
				)
				( objectStatus "C4D17.2" )
			)
			( pin "@baseboard_fab2_lib.baseboard_fab2(sch_1):page201_i68:a"
				( attribute "PN" "1"
					( Origin gPackager )
				)
				( objectStatus "C4D18.1" )
			)
			( pin "@baseboard_fab2_lib.baseboard_fab2(sch_1):page201_i68:b"
				( attribute "PN" "2"
					( Origin gPackager )
				)
				( objectStatus "C4D18.2" )
			)
			( pin "@baseboard_fab2_lib.baseboard_fab2(sch_1):page201_i70:a"
				( attribute "PN" "1"
					( Origin gPackager )
				)
				( objectStatus "C4D45.1" )
			)
			( pin "@baseboard_fab2_lib.baseboard_fab2(sch_1):page201_i70:b"
				( attribute "PN" "2"
					( Origin gPackager )
				)
				( objectStatus "C4D45.2" )
			)
			( pin "@baseboard_fab2_lib.baseboard_fab2(sch_1):page201_i98:a"
				( attribute "PN" "1"
					( Origin gPackager )
				)
				( objectStatus "R4D66.1" )
			)
			( pin "@baseboard_fab2_lib.baseboard_fab2(sch_1):page201_i98:b"
				( attribute "PN" "2"
					( Origin gPackager )
				)
				( objectStatus "R4D66.2" )
			)
			( pin "@baseboard_fab2_lib.baseboard_fab2(sch_1):page201_i102:a"
				( attribute "PN" "1"
					( Origin gPackager )
				)
				( objectStatus "R6P32.1" )
			)
			( pin "@baseboard_fab2_lib.baseboard_fab2(sch_1):page201_i102:b"
				( attribute "PN" "2"
					( Origin gPackager )
				)
				( objectStatus "R6P32.2" )
			)
			( pin "@baseboard_fab2_lib.baseboard_fab2(sch_1):page201_i103:a"
				( attribute "PN" "1"
					( Origin gPackager )
				)
				( objectStatus "R6P37.1" )
			)
			( pin "@baseboard_fab2_lib.baseboard_fab2(sch_1):page201_i103:b"
				( attribute "PN" "2"
					( Origin gPackager )
				)
				( objectStatus "R6P37.2" )
			)
			( pin "@baseboard_fab2_lib.baseboard_fab2(sch_1):page201_i109:a"
				( attribute "PN" "1"
					( Origin gPackager )
				)
				( objectStatus "R4E8.1" )
			)
			( pin "@baseboard_fab2_lib.baseboard_fab2(sch_1):page201_i109:b"
				( attribute "PN" "2"
					( Origin gPackager )
				)
				( objectStatus "R4E8.2" )
			)
			( pin "@baseboard_fab2_lib.baseboard_fab2(sch_1):page201_i110:a"
				( attribute "PN" "1"
					( Origin gPackager )
				)
				( objectStatus "R4D39.1" )
			)
			( pin "@baseboard_fab2_lib.baseboard_fab2(sch_1):page201_i110:b"
				( attribute "PN" "2"
					( Origin gPackager )
				)
				( objectStatus "R4D39.2" )
			)
			( pin "@baseboard_fab2_lib.baseboard_fab2(sch_1):page201_i111:a"
				( attribute "PN" "1"
					( Origin gPackager )
				)
				( objectStatus "R4E3.1" )
			)
			( pin "@baseboard_fab2_lib.baseboard_fab2(sch_1):page201_i111:b"
				( attribute "PN" "2"
					( Origin gPackager )
				)
				( objectStatus "R4E3.2" )
			)
			( pin "@baseboard_fab2_lib.baseboard_fab2(sch_1):page201_i116:a"
				( attribute "PN" "1"
					( Origin gPackager )
				)
				( objectStatus "R4E20.1" )
			)
			( pin "@baseboard_fab2_lib.baseboard_fab2(sch_1):page201_i116:b"
				( attribute "PN" "2"
					( Origin gPackager )
				)
				( objectStatus "R4E20.2" )
			)
			( pin "@baseboard_fab2_lib.baseboard_fab2(sch_1):page201_i120:a"
				( attribute "PN" "1"
					( Origin gPackager )
				)
				( objectStatus "R6P27.1" )
			)
			( pin "@baseboard_fab2_lib.baseboard_fab2(sch_1):page201_i120:b"
				( attribute "PN" "2"
					( Origin gPackager )
				)
				( objectStatus "R6P27.2" )
			)
			( pin "@baseboard_fab2_lib.baseboard_fab2(sch_1):page201_i121:a"
				( attribute "PN" "1"
					( Origin gPackager )
				)
				( objectStatus "R6P28.1" )
			)
			( pin "@baseboard_fab2_lib.baseboard_fab2(sch_1):page201_i121:b"
				( attribute "PN" "2"
					( Origin gPackager )
				)
				( objectStatus "R6P28.2" )
			)
			( pin "@baseboard_fab2_lib.baseboard_fab2(sch_1):page201_i124:a"
				( attribute "PN" "1"
					( Origin gPackager )
				)
				( objectStatus "R4D63.1" )
			)
			( pin "@baseboard_fab2_lib.baseboard_fab2(sch_1):page201_i124:b"
				( attribute "PN" "2"
					( Origin gPackager )
				)
				( objectStatus "R4D63.2" )
			)
			( pin "@baseboard_fab2_lib.baseboard_fab2(sch_1):page201_i125:a"
				( attribute "PN" "1"
					( Origin gPackager )
				)
				( objectStatus "C4D42.1" )
			)
			( pin "@baseboard_fab2_lib.baseboard_fab2(sch_1):page201_i125:b"
				( attribute "PN" "2"
					( Origin gPackager )
				)
				( objectStatus "C4D42.2" )
			)
			( pin "@baseboard_fab2_lib.baseboard_fab2(sch_1):page201_i127:a"
				( attribute "PN" "1"
					( Origin gPackager )
				)
				( objectStatus "R4D65.1" )
			)
			( pin "@baseboard_fab2_lib.baseboard_fab2(sch_1):page201_i127:b"
				( attribute "PN" "2"
					( Origin gPackager )
				)
				( objectStatus "R4D65.2" )
			)
			( pin "@baseboard_fab2_lib.baseboard_fab2(sch_1):page201_i128:a"
				( attribute "PN" "1"
					( Origin gPackager )
				)
				( objectStatus "R6P45.1" )
			)
			( pin "@baseboard_fab2_lib.baseboard_fab2(sch_1):page201_i128:b"
				( attribute "PN" "2"
					( Origin gPackager )
				)
				( objectStatus "R6P45.2" )
			)
			( pin "@baseboard_fab2_lib.baseboard_fab2(sch_1):page201_i131:a"
				( attribute "PN" "1"
					( Origin gPackager )
				)
				( objectStatus "R6P18.1" )
			)
			( pin "@baseboard_fab2_lib.baseboard_fab2(sch_1):page201_i131:b"
				( attribute "PN" "2"
					( Origin gPackager )
				)
				( objectStatus "R6P18.2" )
			)
			( pin "@baseboard_fab2_lib.baseboard_fab2(sch_1):page201_i132:a"
				( attribute "PN" "1"
					( Origin gPackager )
				)
				( objectStatus "R6P16.1" )
			)
			( pin "@baseboard_fab2_lib.baseboard_fab2(sch_1):page201_i132:b"
				( attribute "PN" "2"
					( Origin gPackager )
				)
				( objectStatus "R6P16.2" )
			)
			( pin "@baseboard_fab2_lib.baseboard_fab2(sch_1):page201_i155:airef1"
				( attribute "PN" "23"
					( Origin gPackager )
				)
				( objectStatus "EU4D4.23" )
			)
			( pin "@baseboard_fab2_lib.baseboard_fab2(sch_1):page201_i155:airef2"
				( attribute "PN" "25"
					( Origin gPackager )
				)
				( objectStatus "EU4D4.25" )
			)
			( pin "@baseboard_fab2_lib.baseboard_fab2(sch_1):page201_i155:airef3"
				( attribute "PN" "27"
					( Origin gPackager )
				)
				( objectStatus "EU4D4.27" )
			)
			( pin "@baseboard_fab2_lib.baseboard_fab2(sch_1):page201_i155:airef4"
				( attribute "PN" "29"
					( Origin gPackager )
				)
				( objectStatus "EU4D4.29" )
			)
			( pin "@baseboard_fab2_lib.baseboard_fab2(sch_1):page201_i155:airef5"
				( attribute "PN" "31"
					( Origin gPackager )
				)
				( objectStatus "EU4D4.31" )
			)
			( pin "@baseboard_fab2_lib.baseboard_fab2(sch_1):page201_i155:airef6"
				( attribute "PN" "33"
					( Origin gPackager )
				)
				( objectStatus "EU4D4.33" )
			)
			( pin "@baseboard_fab2_lib.baseboard_fab2(sch_1):page201_i155:aisen1"
				( attribute "PN" "24"
					( Origin gPackager )
				)
				( objectStatus "EU4D4.24" )
			)
			( pin "@baseboard_fab2_lib.baseboard_fab2(sch_1):page201_i155:aisen2"
				( attribute "PN" "26"
					( Origin gPackager )
				)
				( objectStatus "EU4D4.26" )
			)
			( pin "@baseboard_fab2_lib.baseboard_fab2(sch_1):page201_i155:aisen3"
				( attribute "PN" "28"
					( Origin gPackager )
				)
				( objectStatus "EU4D4.28" )
			)
			( pin "@baseboard_fab2_lib.baseboard_fab2(sch_1):page201_i155:aisen4"
				( attribute "PN" "30"
					( Origin gPackager )
				)
				( objectStatus "EU4D4.30" )
			)
			( pin "@baseboard_fab2_lib.baseboard_fab2(sch_1):page201_i155:aisen5"
				( attribute "PN" "32"
					( Origin gPackager )
				)
				( objectStatus "EU4D4.32" )
			)
			( pin "@baseboard_fab2_lib.baseboard_fab2(sch_1):page201_i155:aisen6"
				( attribute "PN" "34"
					( Origin gPackager )
				)
				( objectStatus "EU4D4.34" )
			)
			( pin "@baseboard_fab2_lib.baseboard_fab2(sch_1):page201_i155:apwm1"
				( attribute "PN" "7"
					( Origin gPackager )
				)
				( objectStatus "EU4D4.7" )
			)
			( pin "@baseboard_fab2_lib.baseboard_fab2(sch_1):page201_i155:apwm2"
				( attribute "PN" "6"
					( Origin gPackager )
				)
				( objectStatus "EU4D4.6" )
			)
			( pin "@baseboard_fab2_lib.baseboard_fab2(sch_1):page201_i155:apwm3"
				( attribute "PN" "5"
					( Origin gPackager )
				)
				( objectStatus "EU4D4.5" )
			)
			( pin "@baseboard_fab2_lib.baseboard_fab2(sch_1):page201_i155:apwm4"
				( attribute "PN" "4"
					( Origin gPackager )
				)
				( objectStatus "EU4D4.4" )
			)
			( pin "@baseboard_fab2_lib.baseboard_fab2(sch_1):page201_i155:apwm5"
				( attribute "PN" "3"
					( Origin gPackager )
				)
				( objectStatus "EU4D4.3" )
			)
			( pin "@baseboard_fab2_lib.baseboard_fab2(sch_1):page201_i155:apwm6"
				( attribute "PN" "2"
					( Origin gPackager )
				)
				( objectStatus "EU4D4.2" )
			)
			( pin "@baseboard_fab2_lib.baseboard_fab2(sch_1):page201_i155:atsen"
				( attribute "PN" "43"
					( Origin gPackager )
				)
				( objectStatus "EU4D4.43" )
			)
			( pin "@baseboard_fab2_lib.baseboard_fab2(sch_1):page201_i155:avref"
				( attribute "PN" "22"
					( Origin gPackager )
				)
				( objectStatus "EU4D4.22" )
			)
			( pin "@baseboard_fab2_lib.baseboard_fab2(sch_1):page201_i155:avren"
				( attribute "PN" "12"
					( Origin gPackager )
				)
				( objectStatus "EU4D4.12" )
			)
			( pin "@baseboard_fab2_lib.baseboard_fab2(sch_1):page201_i155:avrrdy"
				( attribute "PN" "11"
					( Origin gPackager )
				)
				( objectStatus "EU4D4.11" )
			)
			( pin "@baseboard_fab2_lib.baseboard_fab2(sch_1):page201_i155:avsen"
				( attribute "PN" "21"
					( Origin gPackager )
				)
				( objectStatus "EU4D4.21" )
			)
			( pin "@baseboard_fab2_lib.baseboard_fab2(sch_1):page201_i155:biref1"
				( attribute "PN" "37"
					( Origin gPackager )
				)
				( objectStatus "EU4D4.37" )
			)
			( pin "@baseboard_fab2_lib.baseboard_fab2(sch_1):page201_i155:bisen1"
				( attribute "PN" "38"
					( Origin gPackager )
				)
				( objectStatus "EU4D4.38" )
			)
			( pin "@baseboard_fab2_lib.baseboard_fab2(sch_1):page201_i155:bpwm1"
				( attribute "PN" "1"
					( Origin gPackager )
				)
				( objectStatus "EU4D4.1" )
			)
			( pin "@baseboard_fab2_lib.baseboard_fab2(sch_1):page201_i155:btsen"
				( attribute "PN" "42"
					( Origin gPackager )
				)
				( objectStatus "EU4D4.42" )
			)
			( pin "@baseboard_fab2_lib.baseboard_fab2(sch_1):page201_i155:bvref"
				( attribute "PN" "36"
					( Origin gPackager )
				)
				( objectStatus "EU4D4.36" )
			)
			( pin "@baseboard_fab2_lib.baseboard_fab2(sch_1):page201_i155:bvsen"
				( attribute "PN" "35"
					( Origin gPackager )
				)
				( objectStatus "EU4D4.35" )
			)
			( pin "@baseboard_fab2_lib.baseboard_fab2(sch_1):page201_i155:iinsen"
				( attribute "PN" "46"
					( Origin gPackager )
				)
				( objectStatus "EU4D4.46" )
			)
			( pin "@baseboard_fab2_lib.baseboard_fab2(sch_1):page201_i155:mp0"
				( attribute "PN" "15"
					( Origin gPackager )
				)
				( objectStatus "EU4D4.15" )
			)
			( pin "@baseboard_fab2_lib.baseboard_fab2(sch_1):page201_i155:mp1"
				( attribute "PN" "16"
					( Origin gPackager )
				)
				( objectStatus "EU4D4.16" )
			)
			( pin "@baseboard_fab2_lib.baseboard_fab2(sch_1):page201_i155:mp2"
				( attribute "PN" "20"
					( Origin gPackager )
				)
				( objectStatus "EU4D4.20" )
			)
			( pin "@baseboard_fab2_lib.baseboard_fab2(sch_1):page201_i155:mp3"
				( attribute "PN" "39"
					( Origin gPackager )
				)
				( objectStatus "EU4D4.39" )
			)
			( pin "@baseboard_fab2_lib.baseboard_fab2(sch_1):page201_i155:mp4"
				( attribute "PN" "40"
					( Origin gPackager )
				)
				( objectStatus "EU4D4.40" )
			)
			( pin "@baseboard_fab2_lib.baseboard_fab2(sch_1):page201_i155:pinalrt_n"
				( attribute "PN" "14"
					( Origin gPackager )
				)
				( objectStatus "EU4D4.14" )
			)
			( pin "@baseboard_fab2_lib.baseboard_fab2(sch_1):page201_i155:reset_n"
				( attribute "PN" "10"
					( Origin gPackager )
				)
				( objectStatus "EU4D4.10" )
			)
			( pin "@baseboard_fab2_lib.baseboard_fab2(sch_1):page201_i155:scl"
				( attribute "PN" "9"
					( Origin gPackager )
				)
				( objectStatus "EU4D4.9" )
			)
			( pin "@baseboard_fab2_lib.baseboard_fab2(sch_1):page201_i155:sda"
				( attribute "PN" "8"
					( Origin gPackager )
				)
				( objectStatus "EU4D4.8" )
			)
			( pin "@baseboard_fab2_lib.baseboard_fab2(sch_1):page201_i155:thpad"
				( attribute "PN" "49"
					( Origin gPackager )
				)
				( objectStatus "EU4D4.49" )
			)
			( pin "@baseboard_fab2_lib.baseboard_fab2(sch_1):page201_i155:valrt_n"
				( attribute "PN" "19"
					( Origin gPackager )
				)
				( objectStatus "EU4D4.19" )
			)
			( pin "@baseboard_fab2_lib.baseboard_fab2(sch_1):page201_i155:vclk"
				( attribute "PN" "17"
					( Origin gPackager )
				)
				( objectStatus "EU4D4.17" )
			)
			( pin "@baseboard_fab2_lib.baseboard_fab2(sch_1):page201_i155:vd12"
				( attribute "PN" "48"
					( Origin gPackager )
				)
				( objectStatus "EU4D4.48" )
			)
			( pin "@baseboard_fab2_lib.baseboard_fab2(sch_1):page201_i155:vdd"
				( attribute "PN" "47"
					( Origin gPackager )
				)
				( objectStatus "EU4D4.47" )
			)
			( pin "@baseboard_fab2_lib.baseboard_fab2(sch_1):page201_i155:vdio"
				( attribute "PN" "18"
					( Origin gPackager )
				)
				( objectStatus "EU4D4.18" )
			)
			( pin "@baseboard_fab2_lib.baseboard_fab2(sch_1):page201_i155:vinsen"
				( attribute "PN" "45"
					( Origin gPackager )
				)
				( objectStatus "EU4D4.45" )
			)
			( pin "@baseboard_fab2_lib.baseboard_fab2(sch_1):page201_i155:vrhot_n"
				( attribute "PN" "13"
					( Origin gPackager )
				)
				( objectStatus "EU4D4.13" )
			)
			( pin "@baseboard_fab2_lib.baseboard_fab2(sch_1):page201_i155:xaddr1"
				( attribute "PN" "44"
					( Origin gPackager )
				)
				( objectStatus "EU4D4.44" )
			)
			( pin "@baseboard_fab2_lib.baseboard_fab2(sch_1):page201_i155:xaddr2"
				( attribute "PN" "41"
					( Origin gPackager )
				)
				( objectStatus "EU4D4.41" )
			)
			( pin "@baseboard_fab2_lib.baseboard_fab2(sch_1):page202_i110:f"
				( attribute "PN" "2"
					( Origin gPackager )
				)
				( objectStatus "L4D3.2" )
			)
			( pin "@baseboard_fab2_lib.baseboard_fab2(sch_1):page202_i110:s"
				( attribute "PN" "1"
					( Origin gPackager )
				)
				( objectStatus "L4D3.1" )
			)
			( pin "@baseboard_fab2_lib.baseboard_fab2(sch_1):page202_i9:a"
				( attribute "PN" "1"
					( Origin gPackager )
				)
				( objectStatus "C6R7.1" )
			)
			( pin "@baseboard_fab2_lib.baseboard_fab2(sch_1):page202_i9:b"
				( attribute "PN" "2"
					( Origin gPackager )
				)
				( objectStatus "C6R7.2" )
			)
			( pin "@baseboard_fab2_lib.baseboard_fab2(sch_1):page202_i18:a"
				( attribute "PN" "1"
					( Origin gPackager )
				)
				( objectStatus "C4E5.1" )
			)
			( pin "@baseboard_fab2_lib.baseboard_fab2(sch_1):page202_i18:b"
				( attribute "PN" "2"
					( Origin gPackager )
				)
				( objectStatus "C4E5.2" )
			)
			( pin "@baseboard_fab2_lib.baseboard_fab2(sch_1):page219_i152:\1\"
				( attribute "PN" "1"
					( Origin gPackager )
				)
				( objectStatus "C7A26.1" )
			)
			( pin "@baseboard_fab2_lib.baseboard_fab2(sch_1):page219_i152:\2\"
				( attribute "PN" "2"
					( Origin gPackager )
				)
				( objectStatus "C7A26.2" )
			)
			( pin "@baseboard_fab2_lib.baseboard_fab2(sch_1):page202_i22:a"
				( attribute "PN" "1"
					( Origin gPackager )
				)
				( objectStatus "C4E17.1" )
			)
			( pin "@baseboard_fab2_lib.baseboard_fab2(sch_1):page202_i22:b"
				( attribute "PN" "2"
					( Origin gPackager )
				)
				( objectStatus "C4E17.2" )
			)
			( pin "@baseboard_fab2_lib.baseboard_fab2(sch_1):page202_i24:a"
				( attribute "PN" "1"
					( Origin gPackager )
				)
				( objectStatus "C4E27.1" )
			)
			( pin "@baseboard_fab2_lib.baseboard_fab2(sch_1):page202_i24:b"
				( attribute "PN" "2"
					( Origin gPackager )
				)
				( objectStatus "C4E27.2" )
			)
			( pin "@baseboard_fab2_lib.baseboard_fab2(sch_1):page214_i175:\1\"
				( attribute "PN" "1"
					( Origin gPackager )
				)
				( objectStatus "C4E28.1" )
			)
			( pin "@baseboard_fab2_lib.baseboard_fab2(sch_1):page214_i175:\2\"
				( attribute "PN" "2"
					( Origin gPackager )
				)
				( objectStatus "C4E28.2" )
			)
			( pin "@baseboard_fab2_lib.baseboard_fab2(sch_1):page202_i27:a"
				( attribute "PN" "1"
					( Origin gPackager )
				)
				( objectStatus "C4E11.1" )
			)
			( pin "@baseboard_fab2_lib.baseboard_fab2(sch_1):page202_i27:b"
				( attribute "PN" "2"
					( Origin gPackager )
				)
				( objectStatus "C4E11.2" )
			)
			( pin "@baseboard_fab2_lib.baseboard_fab2(sch_1):page203_i130:f"
				( attribute "PN" "2"
					( Origin gPackager )
				)
				( objectStatus "L4D2.2" )
			)
			( pin "@baseboard_fab2_lib.baseboard_fab2(sch_1):page203_i130:s"
				( attribute "PN" "1"
					( Origin gPackager )
				)
				( objectStatus "L4D2.1" )
			)
			( pin "@baseboard_fab2_lib.baseboard_fab2(sch_1):page202_i32:a"
				( attribute "PN" "1"
					( Origin gPackager )
				)
				( objectStatus "C4D50.1" )
			)
			( pin "@baseboard_fab2_lib.baseboard_fab2(sch_1):page202_i32:b"
				( attribute "PN" "2"
					( Origin gPackager )
				)
				( objectStatus "C4D50.2" )
			)
			( pin "@baseboard_fab2_lib.baseboard_fab2(sch_1):page207_i106:a"
				( attribute "PN" "1"
					( Origin gPackager )
				)
				( objectStatus "R9R2.1" )
			)
			( pin "@baseboard_fab2_lib.baseboard_fab2(sch_1):page207_i106:b"
				( attribute "PN" "2"
					( Origin gPackager )
				)
				( objectStatus "R9R2.2" )
			)
			( pin "@baseboard_fab2_lib.baseboard_fab2(sch_1):page202_i34:a"
				( attribute "PN" "1"
					( Origin gPackager )
				)
				( objectStatus "C4E10.1" )
			)
			( pin "@baseboard_fab2_lib.baseboard_fab2(sch_1):page202_i34:b"
				( attribute "PN" "2"
					( Origin gPackager )
				)
				( objectStatus "C4E10.2" )
			)
			( pin "@baseboard_fab2_lib.baseboard_fab2(sch_1):page202_i35:a"
				( attribute "PN" "1"
					( Origin gPackager )
				)
				( objectStatus "C4E20.1" )
			)
			( pin "@baseboard_fab2_lib.baseboard_fab2(sch_1):page202_i35:b"
				( attribute "PN" "2"
					( Origin gPackager )
				)
				( objectStatus "C4E20.2" )
			)
			( pin "@baseboard_fab2_lib.baseboard_fab2(sch_1):page202_i36:a"
				( attribute "PN" "1"
					( Origin gPackager )
				)
				( objectStatus "C4E19.1" )
			)
			( pin "@baseboard_fab2_lib.baseboard_fab2(sch_1):page202_i36:b"
				( attribute "PN" "2"
					( Origin gPackager )
				)
				( objectStatus "C4E19.2" )
			)
			( pin "@baseboard_fab2_lib.baseboard_fab2(sch_1):page202_i37:a"
				( attribute "PN" "1"
					( Origin gPackager )
				)
				( objectStatus "C6R11.1" )
			)
			( pin "@baseboard_fab2_lib.baseboard_fab2(sch_1):page202_i37:b"
				( attribute "PN" "2"
					( Origin gPackager )
				)
				( objectStatus "C6R11.2" )
			)
			( pin "@baseboard_fab2_lib.baseboard_fab2(sch_1):page202_i38:a"
				( attribute "PN" "1"
					( Origin gPackager )
				)
				( objectStatus "C6P13.1" )
			)
			( pin "@baseboard_fab2_lib.baseboard_fab2(sch_1):page202_i38:b"
				( attribute "PN" "2"
					( Origin gPackager )
				)
				( objectStatus "C6P13.2" )
			)
			( pin "@baseboard_fab2_lib.baseboard_fab2(sch_1):page205_i81:a"
				( attribute "PN" "1"
					( Origin gPackager )
				)
				( objectStatus "R6N3.1" )
			)
			( pin "@baseboard_fab2_lib.baseboard_fab2(sch_1):page205_i81:b"
				( attribute "PN" "2"
					( Origin gPackager )
				)
				( objectStatus "R6N3.2" )
			)
			( pin "@baseboard_fab2_lib.baseboard_fab2(sch_1):page202_i42:a"
				( attribute "PN" "1"
					( Origin gPackager )
				)
				( objectStatus "C6R13.1" )
			)
			( pin "@baseboard_fab2_lib.baseboard_fab2(sch_1):page202_i42:b"
				( attribute "PN" "2"
					( Origin gPackager )
				)
				( objectStatus "C6R13.2" )
			)
			( pin "@baseboard_fab2_lib.baseboard_fab2(sch_1):page202_i45:a"
				( attribute "PN" "1"
					( Origin gPackager )
				)
				( objectStatus "C4E26.1" )
			)
			( pin "@baseboard_fab2_lib.baseboard_fab2(sch_1):page202_i45:b"
				( attribute "PN" "2"
					( Origin gPackager )
				)
				( objectStatus "C4E26.2" )
			)
			( pin "@baseboard_fab2_lib.baseboard_fab2(sch_1):page202_i46:a"
				( attribute "PN" "1"
					( Origin gPackager )
				)
				( objectStatus "C4D49.1" )
			)
			( pin "@baseboard_fab2_lib.baseboard_fab2(sch_1):page202_i46:b"
				( attribute "PN" "2"
					( Origin gPackager )
				)
				( objectStatus "C4D49.2" )
			)
			( pin "@baseboard_fab2_lib.baseboard_fab2(sch_1):page202_i47:a"
				( attribute "PN" "1"
					( Origin gPackager )
				)
				( objectStatus "C4D48.1" )
			)
			( pin "@baseboard_fab2_lib.baseboard_fab2(sch_1):page202_i47:b"
				( attribute "PN" "2"
					( Origin gPackager )
				)
				( objectStatus "C4D48.2" )
			)
			( pin "@baseboard_fab2_lib.baseboard_fab2(sch_1):page202_i48:a"
				( attribute "PN" "1"
					( Origin gPackager )
				)
				( objectStatus "C6R4.1" )
			)
			( pin "@baseboard_fab2_lib.baseboard_fab2(sch_1):page202_i48:b"
				( attribute "PN" "2"
					( Origin gPackager )
				)
				( objectStatus "C6R4.2" )
			)
			( pin "@baseboard_fab2_lib.baseboard_fab2(sch_1):page202_i49:a"
				( attribute "PN" "1"
					( Origin gPackager )
				)
				( objectStatus "C6P22.1" )
			)
			( pin "@baseboard_fab2_lib.baseboard_fab2(sch_1):page202_i49:b"
				( attribute "PN" "2"
					( Origin gPackager )
				)
				( objectStatus "C6P22.2" )
			)
			( pin "@baseboard_fab2_lib.baseboard_fab2(sch_1):page202_i51:a"
				( attribute "PN" "1"
					( Origin gPackager )
				)
				( objectStatus "C6N8.1" )
			)
			( pin "@baseboard_fab2_lib.baseboard_fab2(sch_1):page202_i51:b"
				( attribute "PN" "2"
					( Origin gPackager )
				)
				( objectStatus "C6N8.2" )
			)
			( pin "@baseboard_fab2_lib.baseboard_fab2(sch_1):page202_i61:a"
				( attribute "PN" "1"
					( Origin gPackager )
				)
				( objectStatus "C4E3.1" )
			)
			( pin "@baseboard_fab2_lib.baseboard_fab2(sch_1):page202_i61:b"
				( attribute "PN" "2"
					( Origin gPackager )
				)
				( objectStatus "C4E3.2" )
			)
			( pin "@baseboard_fab2_lib.baseboard_fab2(sch_1):page202_i62:a"
				( attribute "PN" "1"
					( Origin gPackager )
				)
				( objectStatus "C6P16.1" )
			)
			( pin "@baseboard_fab2_lib.baseboard_fab2(sch_1):page202_i62:b"
				( attribute "PN" "2"
					( Origin gPackager )
				)
				( objectStatus "C6P16.2" )
			)
			( pin "@baseboard_fab2_lib.baseboard_fab2(sch_1):page202_i63:boost"
				( attribute "PN" "33"
					( Origin gPackager )
				)
				( objectStatus "EU4E1.33" )
			)
			( pin "@baseboard_fab2_lib.baseboard_fab2(sch_1):page202_i63:en"
				( attribute "PN" "35"
					( Origin gPackager )
				)
				( objectStatus "EU4E1.35" )
			)
			( pin "@baseboard_fab2_lib.baseboard_fab2(sch_1):page202_i63:gl(0)"
				( attribute "PN" "6"
					( Origin gPackager )
				)
				( objectStatus "EU4E1.6" )
			)
			( pin "@baseboard_fab2_lib.baseboard_fab2(sch_1):page202_i63:gl(1)"
				( attribute "PN" "41"
					( Origin gPackager )
				)
				( objectStatus "EU4E1.41" )
			)
			( pin "@baseboard_fab2_lib.baseboard_fab2(sch_1):page202_i63:iout"
				( attribute "PN" "38"
					( Origin gPackager )
				)
				( objectStatus "EU4E1.38" )
			)
			( pin "@baseboard_fab2_lib.baseboard_fab2(sch_1):page202_i63:lgnd"
				( attribute "PN" "2"
					( Origin gPackager )
				)
				( objectStatus "EU4E1.2" )
			)
			( pin "@baseboard_fab2_lib.baseboard_fab2(sch_1):page202_i63:nc"
				( attribute "PN" "31"
					( Origin gPackager )
				)
				( objectStatus "EU4E1.31" )
			)
			( pin "@baseboard_fab2_lib.baseboard_fab2(sch_1):page202_i63:ocset"
				( attribute "PN" "37"
					( Origin gPackager )
				)
				( objectStatus "EU4E1.37" )
			)
			( pin "@baseboard_fab2_lib.baseboard_fab2(sch_1):page202_i63:pgnd(0)"
				( attribute "PN" "5"
					( Origin gPackager )
				)
				( objectStatus "EU4E1.5" )
			)
			( pin "@baseboard_fab2_lib.baseboard_fab2(sch_1):page202_i63:pgnd(1)"
				( attribute "PN" "7"
					( Origin gPackager )
				)
				( objectStatus "EU4E1.7" )
			)
			( pin "@baseboard_fab2_lib.baseboard_fab2(sch_1):page202_i63:pgnd(2)"
				( attribute "PN" "40"
					( Origin gPackager )
				)
				( objectStatus "EU4E1.40" )
			)
			( pin "@baseboard_fab2_lib.baseboard_fab2(sch_1):page202_i63:phase"
				( attribute "PN" "32"
					( Origin gPackager )
				)
				( objectStatus "EU4E1.32" )
			)
			( pin "@baseboard_fab2_lib.baseboard_fab2(sch_1):page202_i63:pwm"
				( attribute "PN" "34"
					( Origin gPackager )
				)
				( objectStatus "EU4E1.34" )
			)
			( pin "@baseboard_fab2_lib.baseboard_fab2(sch_1):page202_i63:refin"
				( attribute "PN" "39"
					( Origin gPackager )
				)
				( objectStatus "EU4E1.39" )
			)
			( pin "@baseboard_fab2_lib.baseboard_fab2(sch_1):page202_i63:sw"
				( attribute "PN" "10"
					( Origin gPackager )
				)
				( objectStatus "EU4E1.10" )
			)
			( pin "@baseboard_fab2_lib.baseboard_fab2(sch_1):page202_i63:tout_flt"
				( attribute "PN" "36"
					( Origin gPackager )
				)
				( objectStatus "EU4E1.36" )
			)
			( pin "@baseboard_fab2_lib.baseboard_fab2(sch_1):page202_i63:vcc"
				( attribute "PN" "3"
					( Origin gPackager )
				)
				( objectStatus "EU4E1.3" )
			)
			( pin "@baseboard_fab2_lib.baseboard_fab2(sch_1):page202_i63:vdrv"
				( attribute "PN" "4"
					( Origin gPackager )
				)
				( objectStatus "EU4E1.4" )
			)
			( pin "@baseboard_fab2_lib.baseboard_fab2(sch_1):page202_i63:vin(0)"
				( attribute "PN" "25"
					( Origin gPackager )
				)
				( objectStatus "EU4E1.25" )
			)
			( pin "@baseboard_fab2_lib.baseboard_fab2(sch_1):page202_i63:vin(1)"
				( attribute "PN" "30"
					( Origin gPackager )
				)
				( objectStatus "EU4E1.30" )
			)
			( pin "@baseboard_fab2_lib.baseboard_fab2(sch_1):page202_i63:vos"
				( attribute "PN" "1"
					( Origin gPackager )
				)
				( objectStatus "EU4E1.1" )
			)
			( pin "@baseboard_fab2_lib.baseboard_fab2(sch_1):page202_i64:boost"
				( attribute "PN" "33"
					( Origin gPackager )
				)
				( objectStatus "EU4D6.33" )
			)
			( pin "@baseboard_fab2_lib.baseboard_fab2(sch_1):page202_i64:en"
				( attribute "PN" "35"
					( Origin gPackager )
				)
				( objectStatus "EU4D6.35" )
			)
			( pin "@baseboard_fab2_lib.baseboard_fab2(sch_1):page202_i64:gl(0)"
				( attribute "PN" "6"
					( Origin gPackager )
				)
				( objectStatus "EU4D6.6" )
			)
			( pin "@baseboard_fab2_lib.baseboard_fab2(sch_1):page202_i64:gl(1)"
				( attribute "PN" "41"
					( Origin gPackager )
				)
				( objectStatus "EU4D6.41" )
			)
			( pin "@baseboard_fab2_lib.baseboard_fab2(sch_1):page202_i64:iout"
				( attribute "PN" "38"
					( Origin gPackager )
				)
				( objectStatus "EU4D6.38" )
			)
			( pin "@baseboard_fab2_lib.baseboard_fab2(sch_1):page202_i64:lgnd"
				( attribute "PN" "2"
					( Origin gPackager )
				)
				( objectStatus "EU4D6.2" )
			)
			( pin "@baseboard_fab2_lib.baseboard_fab2(sch_1):page202_i64:nc"
				( attribute "PN" "31"
					( Origin gPackager )
				)
				( objectStatus "EU4D6.31" )
			)
			( pin "@baseboard_fab2_lib.baseboard_fab2(sch_1):page202_i64:ocset"
				( attribute "PN" "37"
					( Origin gPackager )
				)
				( objectStatus "EU4D6.37" )
			)
			( pin "@baseboard_fab2_lib.baseboard_fab2(sch_1):page202_i64:pgnd(0)"
				( attribute "PN" "5"
					( Origin gPackager )
				)
				( objectStatus "EU4D6.5" )
			)
			( pin "@baseboard_fab2_lib.baseboard_fab2(sch_1):page202_i64:pgnd(1)"
				( attribute "PN" "7"
					( Origin gPackager )
				)
				( objectStatus "EU4D6.7" )
			)
			( pin "@baseboard_fab2_lib.baseboard_fab2(sch_1):page202_i64:pgnd(2)"
				( attribute "PN" "40"
					( Origin gPackager )
				)
				( objectStatus "EU4D6.40" )
			)
			( pin "@baseboard_fab2_lib.baseboard_fab2(sch_1):page202_i64:phase"
				( attribute "PN" "32"
					( Origin gPackager )
				)
				( objectStatus "EU4D6.32" )
			)
			( pin "@baseboard_fab2_lib.baseboard_fab2(sch_1):page202_i64:pwm"
				( attribute "PN" "34"
					( Origin gPackager )
				)
				( objectStatus "EU4D6.34" )
			)
			( pin "@baseboard_fab2_lib.baseboard_fab2(sch_1):page202_i64:refin"
				( attribute "PN" "39"
					( Origin gPackager )
				)
				( objectStatus "EU4D6.39" )
			)
			( pin "@baseboard_fab2_lib.baseboard_fab2(sch_1):page202_i64:sw"
				( attribute "PN" "10"
					( Origin gPackager )
				)
				( objectStatus "EU4D6.10" )
			)
			( pin "@baseboard_fab2_lib.baseboard_fab2(sch_1):page202_i64:tout_flt"
				( attribute "PN" "36"
					( Origin gPackager )
				)
				( objectStatus "EU4D6.36" )
			)
			( pin "@baseboard_fab2_lib.baseboard_fab2(sch_1):page202_i64:vcc"
				( attribute "PN" "3"
					( Origin gPackager )
				)
				( objectStatus "EU4D6.3" )
			)
			( pin "@baseboard_fab2_lib.baseboard_fab2(sch_1):page202_i64:vdrv"
				( attribute "PN" "4"
					( Origin gPackager )
				)
				( objectStatus "EU4D6.4" )
			)
			( pin "@baseboard_fab2_lib.baseboard_fab2(sch_1):page202_i64:vin(0)"
				( attribute "PN" "25"
					( Origin gPackager )
				)
				( objectStatus "EU4D6.25" )
			)
			( pin "@baseboard_fab2_lib.baseboard_fab2(sch_1):page202_i64:vin(1)"
				( attribute "PN" "30"
					( Origin gPackager )
				)
				( objectStatus "EU4D6.30" )
			)
			( pin "@baseboard_fab2_lib.baseboard_fab2(sch_1):page202_i64:vos"
				( attribute "PN" "1"
					( Origin gPackager )
				)
				( objectStatus "EU4D6.1" )
			)
			( pin "@baseboard_fab2_lib.baseboard_fab2(sch_1):page202_i65:a"
				( attribute "PN" "1"
					( Origin gPackager )
				)
				( objectStatus "R4E22.1" )
			)
			( pin "@baseboard_fab2_lib.baseboard_fab2(sch_1):page202_i65:b"
				( attribute "PN" "2"
					( Origin gPackager )
				)
				( objectStatus "R4E22.2" )
			)
			( pin "@baseboard_fab2_lib.baseboard_fab2(sch_1):page202_i67:a"
				( attribute "PN" "1"
					( Origin gPackager )
				)
				( objectStatus "R4E19.1" )
			)
			( pin "@baseboard_fab2_lib.baseboard_fab2(sch_1):page202_i67:b"
				( attribute "PN" "2"
					( Origin gPackager )
				)
				( objectStatus "R4E19.2" )
			)
			( pin "@baseboard_fab2_lib.baseboard_fab2(sch_1):page203_i1:a"
				( attribute "PN" "1"
					( Origin gPackager )
				)
				( objectStatus "C6P24.1" )
			)
			( pin "@baseboard_fab2_lib.baseboard_fab2(sch_1):page203_i1:b"
				( attribute "PN" "2"
					( Origin gPackager )
				)
				( objectStatus "C6P24.2" )
			)
			( pin "@baseboard_fab2_lib.baseboard_fab2(sch_1):page203_i2:a"
				( attribute "PN" "1"
					( Origin gPackager )
				)
				( objectStatus "C6R6.1" )
			)
			( pin "@baseboard_fab2_lib.baseboard_fab2(sch_1):page203_i2:b"
				( attribute "PN" "2"
					( Origin gPackager )
				)
				( objectStatus "C6R6.2" )
			)
			( pin "@baseboard_fab2_lib.baseboard_fab2(sch_1):page203_i3:a"
				( attribute "PN" "1"
					( Origin gPackager )
				)
				( objectStatus "C4D9.1" )
			)
			( pin "@baseboard_fab2_lib.baseboard_fab2(sch_1):page203_i3:b"
				( attribute "PN" "2"
					( Origin gPackager )
				)
				( objectStatus "C4D9.2" )
			)
			( pin "@baseboard_fab2_lib.baseboard_fab2(sch_1):page207_i108:f"
				( attribute "PN" "2"
					( Origin gPackager )
				)
				( objectStatus "L1D3.2" )
			)
			( pin "@baseboard_fab2_lib.baseboard_fab2(sch_1):page207_i108:s"
				( attribute "PN" "1"
					( Origin gPackager )
				)
				( objectStatus "L1D3.1" )
			)
			( pin "@baseboard_fab2_lib.baseboard_fab2(sch_1):page203_i16:a"
				( attribute "PN" "1"
					( Origin gPackager )
				)
				( objectStatus "C6R3.1" )
			)
			( pin "@baseboard_fab2_lib.baseboard_fab2(sch_1):page203_i16:b"
				( attribute "PN" "2"
					( Origin gPackager )
				)
				( objectStatus "C6R3.2" )
			)
			( pin "@baseboard_fab2_lib.baseboard_fab2(sch_1):page203_i18:a"
				( attribute "PN" "1"
					( Origin gPackager )
				)
				( objectStatus "C6R9.1" )
			)
			( pin "@baseboard_fab2_lib.baseboard_fab2(sch_1):page203_i18:b"
				( attribute "PN" "2"
					( Origin gPackager )
				)
				( objectStatus "C6R9.2" )
			)
			( pin "@baseboard_fab2_lib.baseboard_fab2(sch_1):page204_i104:f"
				( attribute "PN" "2"
					( Origin gPackager )
				)
				( objectStatus "L4C3.2" )
			)
			( pin "@baseboard_fab2_lib.baseboard_fab2(sch_1):page204_i104:s"
				( attribute "PN" "1"
					( Origin gPackager )
				)
				( objectStatus "L4C3.1" )
			)
			( pin "@baseboard_fab2_lib.baseboard_fab2(sch_1):page203_i25:a"
				( attribute "PN" "1"
					( Origin gPackager )
				)
				( objectStatus "C6P3.1" )
			)
			( pin "@baseboard_fab2_lib.baseboard_fab2(sch_1):page203_i25:b"
				( attribute "PN" "2"
					( Origin gPackager )
				)
				( objectStatus "C6P3.2" )
			)
			( pin "@baseboard_fab2_lib.baseboard_fab2(sch_1):page203_i28:a"
				( attribute "PN" "1"
					( Origin gPackager )
				)
				( objectStatus "C6P23.1" )
			)
			( pin "@baseboard_fab2_lib.baseboard_fab2(sch_1):page203_i28:b"
				( attribute "PN" "2"
					( Origin gPackager )
				)
				( objectStatus "C6P23.2" )
			)
			( pin "@baseboard_fab2_lib.baseboard_fab2(sch_1):page203_i29:a"
				( attribute "PN" "1"
					( Origin gPackager )
				)
				( objectStatus "C6P14.1" )
			)
			( pin "@baseboard_fab2_lib.baseboard_fab2(sch_1):page203_i29:b"
				( attribute "PN" "2"
					( Origin gPackager )
				)
				( objectStatus "C6P14.2" )
			)
			( pin "@baseboard_fab2_lib.baseboard_fab2(sch_1):page203_i30:a"
				( attribute "PN" "1"
					( Origin gPackager )
				)
				( objectStatus "C6P18.1" )
			)
			( pin "@baseboard_fab2_lib.baseboard_fab2(sch_1):page203_i30:b"
				( attribute "PN" "2"
					( Origin gPackager )
				)
				( objectStatus "C6P18.2" )
			)
			( pin "@baseboard_fab2_lib.baseboard_fab2(sch_1):page203_i32:a"
				( attribute "PN" "1"
					( Origin gPackager )
				)
				( objectStatus "C6P8.1" )
			)
			( pin "@baseboard_fab2_lib.baseboard_fab2(sch_1):page203_i32:b"
				( attribute "PN" "2"
					( Origin gPackager )
				)
				( objectStatus "C6P8.2" )
			)
			( pin "@baseboard_fab2_lib.baseboard_fab2(sch_1):page203_i34:a"
				( attribute "PN" "1"
					( Origin gPackager )
				)
				( objectStatus "C6N9.1" )
			)
			( pin "@baseboard_fab2_lib.baseboard_fab2(sch_1):page203_i34:b"
				( attribute "PN" "2"
					( Origin gPackager )
				)
				( objectStatus "C6N9.2" )
			)
			( pin "@baseboard_fab2_lib.baseboard_fab2(sch_1):page202_i108:a"
				( attribute "PN" "1"
					( Origin gPackager )
				)
				( objectStatus "R6R6.1" )
			)
			( pin "@baseboard_fab2_lib.baseboard_fab2(sch_1):page202_i108:b"
				( attribute "PN" "2"
					( Origin gPackager )
				)
				( objectStatus "R6R6.2" )
			)
			( pin "@baseboard_fab2_lib.baseboard_fab2(sch_1):page203_i40:a"
				( attribute "PN" "1"
					( Origin gPackager )
				)
				( objectStatus "C4D13.1" )
			)
			( pin "@baseboard_fab2_lib.baseboard_fab2(sch_1):page203_i40:b"
				( attribute "PN" "2"
					( Origin gPackager )
				)
				( objectStatus "C4D13.2" )
			)
			( pin "@baseboard_fab2_lib.baseboard_fab2(sch_1):page202_i112:\1\"
				( attribute "PN" "1"
					( Origin gPackager )
				)
				( objectStatus "C4E6.1" )
			)
			( pin "@baseboard_fab2_lib.baseboard_fab2(sch_1):page202_i112:\2\"
				( attribute "PN" "2"
					( Origin gPackager )
				)
				( objectStatus "C4E6.2" )
			)
			( pin "@baseboard_fab2_lib.baseboard_fab2(sch_1):page203_i42:a"
				( attribute "PN" "1"
					( Origin gPackager )
				)
				( objectStatus "C4D28.1" )
			)
			( pin "@baseboard_fab2_lib.baseboard_fab2(sch_1):page203_i42:b"
				( attribute "PN" "2"
					( Origin gPackager )
				)
				( objectStatus "C4D28.2" )
			)
			( pin "@baseboard_fab2_lib.baseboard_fab2(sch_1):page203_i45:a"
				( attribute "PN" "1"
					( Origin gPackager )
				)
				( objectStatus "C4D16.1" )
			)
			( pin "@baseboard_fab2_lib.baseboard_fab2(sch_1):page203_i45:b"
				( attribute "PN" "2"
					( Origin gPackager )
				)
				( objectStatus "C4D16.2" )
			)
			( pin "@baseboard_fab2_lib.baseboard_fab2(sch_1):page203_i46:a"
				( attribute "PN" "1"
					( Origin gPackager )
				)
				( objectStatus "C4D35.1" )
			)
			( pin "@baseboard_fab2_lib.baseboard_fab2(sch_1):page203_i46:b"
				( attribute "PN" "2"
					( Origin gPackager )
				)
				( objectStatus "C4D35.2" )
			)
			( pin "@baseboard_fab2_lib.baseboard_fab2(sch_1):page203_i47:a"
				( attribute "PN" "1"
					( Origin gPackager )
				)
				( objectStatus "C4D30.1" )
			)
			( pin "@baseboard_fab2_lib.baseboard_fab2(sch_1):page203_i47:b"
				( attribute "PN" "2"
					( Origin gPackager )
				)
				( objectStatus "C4D30.2" )
			)
			( pin "@baseboard_fab2_lib.baseboard_fab2(sch_1):page203_i48:a"
				( attribute "PN" "1"
					( Origin gPackager )
				)
				( objectStatus "C4D5.1" )
			)
			( pin "@baseboard_fab2_lib.baseboard_fab2(sch_1):page203_i48:b"
				( attribute "PN" "2"
					( Origin gPackager )
				)
				( objectStatus "C4D5.2" )
			)
			( pin "@baseboard_fab2_lib.baseboard_fab2(sch_1):page202_i111:\1\"
				( attribute "PN" "1"
					( Origin gPackager )
				)
				( objectStatus "C4E25.1" )
			)
			( pin "@baseboard_fab2_lib.baseboard_fab2(sch_1):page202_i111:\2\"
				( attribute "PN" "2"
					( Origin gPackager )
				)
				( objectStatus "C4E25.2" )
			)
			( pin "@baseboard_fab2_lib.baseboard_fab2(sch_1):page202_i107:a"
				( attribute "PN" "1"
					( Origin gPackager )
				)
				( objectStatus "R6R2.1" )
			)
			( pin "@baseboard_fab2_lib.baseboard_fab2(sch_1):page202_i107:b"
				( attribute "PN" "2"
					( Origin gPackager )
				)
				( objectStatus "R6R2.2" )
			)
			( pin "@baseboard_fab2_lib.baseboard_fab2(sch_1):page203_i51:a"
				( attribute "PN" "1"
					( Origin gPackager )
				)
				( objectStatus "C4D7.1" )
			)
			( pin "@baseboard_fab2_lib.baseboard_fab2(sch_1):page203_i51:b"
				( attribute "PN" "2"
					( Origin gPackager )
				)
				( objectStatus "C4D7.2" )
			)
			( pin "@baseboard_fab2_lib.baseboard_fab2(sch_1):page203_i52:a"
				( attribute "PN" "1"
					( Origin gPackager )
				)
				( objectStatus "C4D11.1" )
			)
			( pin "@baseboard_fab2_lib.baseboard_fab2(sch_1):page203_i52:b"
				( attribute "PN" "2"
					( Origin gPackager )
				)
				( objectStatus "C4D11.2" )
			)
			( pin "@baseboard_fab2_lib.baseboard_fab2(sch_1):page203_i53:a"
				( attribute "PN" "1"
					( Origin gPackager )
				)
				( objectStatus "C4D10.1" )
			)
			( pin "@baseboard_fab2_lib.baseboard_fab2(sch_1):page203_i53:b"
				( attribute "PN" "2"
					( Origin gPackager )
				)
				( objectStatus "C4D10.2" )
			)
			( pin "@baseboard_fab2_lib.baseboard_fab2(sch_1):page203_i54:a"
				( attribute "PN" "1"
					( Origin gPackager )
				)
				( objectStatus "C6P19.1" )
			)
			( pin "@baseboard_fab2_lib.baseboard_fab2(sch_1):page203_i54:b"
				( attribute "PN" "2"
					( Origin gPackager )
				)
				( objectStatus "C6P19.2" )
			)
			( pin "@baseboard_fab2_lib.baseboard_fab2(sch_1):page203_i57:a"
				( attribute "PN" "1"
					( Origin gPackager )
				)
				( objectStatus "C6P20.1" )
			)
			( pin "@baseboard_fab2_lib.baseboard_fab2(sch_1):page203_i57:b"
				( attribute "PN" "2"
					( Origin gPackager )
				)
				( objectStatus "C6P20.2" )
			)
			( pin "@baseboard_fab2_lib.baseboard_fab2(sch_1):page203_i58:a"
				( attribute "PN" "1"
					( Origin gPackager )
				)
				( objectStatus "C6P15.1" )
			)
			( pin "@baseboard_fab2_lib.baseboard_fab2(sch_1):page203_i58:b"
				( attribute "PN" "2"
					( Origin gPackager )
				)
				( objectStatus "C6P15.2" )
			)
			( pin "@baseboard_fab2_lib.baseboard_fab2(sch_1):page203_i59:a"
				( attribute "PN" "1"
					( Origin gPackager )
				)
				( objectStatus "C6P7.1" )
			)
			( pin "@baseboard_fab2_lib.baseboard_fab2(sch_1):page203_i59:b"
				( attribute "PN" "2"
					( Origin gPackager )
				)
				( objectStatus "C6P7.2" )
			)
			( pin "@baseboard_fab2_lib.baseboard_fab2(sch_1):page203_i66:a"
				( attribute "PN" "1"
					( Origin gPackager )
				)
				( objectStatus "C6P21.1" )
			)
			( pin "@baseboard_fab2_lib.baseboard_fab2(sch_1):page203_i66:b"
				( attribute "PN" "2"
					( Origin gPackager )
				)
				( objectStatus "C6P21.2" )
			)
			( pin "@baseboard_fab2_lib.baseboard_fab2(sch_1):page203_i67:a"
				( attribute "PN" "1"
					( Origin gPackager )
				)
				( objectStatus "R4E13.1" )
			)
			( pin "@baseboard_fab2_lib.baseboard_fab2(sch_1):page203_i67:b"
				( attribute "PN" "2"
					( Origin gPackager )
				)
				( objectStatus "R4E13.2" )
			)
			( pin "@baseboard_fab2_lib.baseboard_fab2(sch_1):page203_i68:a"
				( attribute "PN" "1"
					( Origin gPackager )
				)
				( objectStatus "C4D34.1" )
			)
			( pin "@baseboard_fab2_lib.baseboard_fab2(sch_1):page203_i68:b"
				( attribute "PN" "2"
					( Origin gPackager )
				)
				( objectStatus "C4D34.2" )
			)
			( pin "@baseboard_fab2_lib.baseboard_fab2(sch_1):page203_i69:a"
				( attribute "PN" "1"
					( Origin gPackager )
				)
				( objectStatus "C4D4.1" )
			)
			( pin "@baseboard_fab2_lib.baseboard_fab2(sch_1):page203_i69:b"
				( attribute "PN" "2"
					( Origin gPackager )
				)
				( objectStatus "C4D4.2" )
			)
			( pin "@baseboard_fab2_lib.baseboard_fab2(sch_1):page203_i70:boost"
				( attribute "PN" "33"
					( Origin gPackager )
				)
				( objectStatus "EU4D3.33" )
			)
			( pin "@baseboard_fab2_lib.baseboard_fab2(sch_1):page203_i70:en"
				( attribute "PN" "35"
					( Origin gPackager )
				)
				( objectStatus "EU4D3.35" )
			)
			( pin "@baseboard_fab2_lib.baseboard_fab2(sch_1):page203_i70:gl(0)"
				( attribute "PN" "6"
					( Origin gPackager )
				)
				( objectStatus "EU4D3.6" )
			)
			( pin "@baseboard_fab2_lib.baseboard_fab2(sch_1):page203_i70:gl(1)"
				( attribute "PN" "41"
					( Origin gPackager )
				)
				( objectStatus "EU4D3.41" )
			)
			( pin "@baseboard_fab2_lib.baseboard_fab2(sch_1):page203_i70:iout"
				( attribute "PN" "38"
					( Origin gPackager )
				)
				( objectStatus "EU4D3.38" )
			)
			( pin "@baseboard_fab2_lib.baseboard_fab2(sch_1):page203_i70:lgnd"
				( attribute "PN" "2"
					( Origin gPackager )
				)
				( objectStatus "EU4D3.2" )
			)
			( pin "@baseboard_fab2_lib.baseboard_fab2(sch_1):page203_i70:nc"
				( attribute "PN" "31"
					( Origin gPackager )
				)
				( objectStatus "EU4D3.31" )
			)
			( pin "@baseboard_fab2_lib.baseboard_fab2(sch_1):page203_i70:ocset"
				( attribute "PN" "37"
					( Origin gPackager )
				)
				( objectStatus "EU4D3.37" )
			)
			( pin "@baseboard_fab2_lib.baseboard_fab2(sch_1):page203_i70:pgnd(0)"
				( attribute "PN" "5"
					( Origin gPackager )
				)
				( objectStatus "EU4D3.5" )
			)
			( pin "@baseboard_fab2_lib.baseboard_fab2(sch_1):page203_i70:pgnd(1)"
				( attribute "PN" "7"
					( Origin gPackager )
				)
				( objectStatus "EU4D3.7" )
			)
			( pin "@baseboard_fab2_lib.baseboard_fab2(sch_1):page203_i70:pgnd(2)"
				( attribute "PN" "40"
					( Origin gPackager )
				)
				( objectStatus "EU4D3.40" )
			)
			( pin "@baseboard_fab2_lib.baseboard_fab2(sch_1):page203_i70:phase"
				( attribute "PN" "32"
					( Origin gPackager )
				)
				( objectStatus "EU4D3.32" )
			)
			( pin "@baseboard_fab2_lib.baseboard_fab2(sch_1):page203_i70:pwm"
				( attribute "PN" "34"
					( Origin gPackager )
				)
				( objectStatus "EU4D3.34" )
			)
			( pin "@baseboard_fab2_lib.baseboard_fab2(sch_1):page203_i70:refin"
				( attribute "PN" "39"
					( Origin gPackager )
				)
				( objectStatus "EU4D3.39" )
			)
			( pin "@baseboard_fab2_lib.baseboard_fab2(sch_1):page203_i70:sw"
				( attribute "PN" "10"
					( Origin gPackager )
				)
				( objectStatus "EU4D3.10" )
			)
			( pin "@baseboard_fab2_lib.baseboard_fab2(sch_1):page203_i70:tout_flt"
				( attribute "PN" "36"
					( Origin gPackager )
				)
				( objectStatus "EU4D3.36" )
			)
			( pin "@baseboard_fab2_lib.baseboard_fab2(sch_1):page203_i70:vcc"
				( attribute "PN" "3"
					( Origin gPackager )
				)
				( objectStatus "EU4D3.3" )
			)
			( pin "@baseboard_fab2_lib.baseboard_fab2(sch_1):page203_i70:vdrv"
				( attribute "PN" "4"
					( Origin gPackager )
				)
				( objectStatus "EU4D3.4" )
			)
			( pin "@baseboard_fab2_lib.baseboard_fab2(sch_1):page203_i70:vin(0)"
				( attribute "PN" "25"
					( Origin gPackager )
				)
				( objectStatus "EU4D3.25" )
			)
			( pin "@baseboard_fab2_lib.baseboard_fab2(sch_1):page203_i70:vin(1)"
				( attribute "PN" "30"
					( Origin gPackager )
				)
				( objectStatus "EU4D3.30" )
			)
			( pin "@baseboard_fab2_lib.baseboard_fab2(sch_1):page203_i70:vos"
				( attribute "PN" "1"
					( Origin gPackager )
				)
				( objectStatus "EU4D3.1" )
			)
			( pin "@baseboard_fab2_lib.baseboard_fab2(sch_1):page203_i71:boost"
				( attribute "PN" "33"
					( Origin gPackager )
				)
				( objectStatus "EU4D1.33" )
			)
			( pin "@baseboard_fab2_lib.baseboard_fab2(sch_1):page203_i71:en"
				( attribute "PN" "35"
					( Origin gPackager )
				)
				( objectStatus "EU4D1.35" )
			)
			( pin "@baseboard_fab2_lib.baseboard_fab2(sch_1):page203_i71:gl(0)"
				( attribute "PN" "6"
					( Origin gPackager )
				)
				( objectStatus "EU4D1.6" )
			)
			( pin "@baseboard_fab2_lib.baseboard_fab2(sch_1):page203_i71:gl(1)"
				( attribute "PN" "41"
					( Origin gPackager )
				)
				( objectStatus "EU4D1.41" )
			)
			( pin "@baseboard_fab2_lib.baseboard_fab2(sch_1):page203_i71:iout"
				( attribute "PN" "38"
					( Origin gPackager )
				)
				( objectStatus "EU4D1.38" )
			)
			( pin "@baseboard_fab2_lib.baseboard_fab2(sch_1):page203_i71:lgnd"
				( attribute "PN" "2"
					( Origin gPackager )
				)
				( objectStatus "EU4D1.2" )
			)
			( pin "@baseboard_fab2_lib.baseboard_fab2(sch_1):page203_i71:nc"
				( attribute "PN" "31"
					( Origin gPackager )
				)
				( objectStatus "EU4D1.31" )
			)
			( pin "@baseboard_fab2_lib.baseboard_fab2(sch_1):page203_i71:ocset"
				( attribute "PN" "37"
					( Origin gPackager )
				)
				( objectStatus "EU4D1.37" )
			)
			( pin "@baseboard_fab2_lib.baseboard_fab2(sch_1):page203_i71:pgnd(0)"
				( attribute "PN" "5"
					( Origin gPackager )
				)
				( objectStatus "EU4D1.5" )
			)
			( pin "@baseboard_fab2_lib.baseboard_fab2(sch_1):page203_i71:pgnd(1)"
				( attribute "PN" "7"
					( Origin gPackager )
				)
				( objectStatus "EU4D1.7" )
			)
			( pin "@baseboard_fab2_lib.baseboard_fab2(sch_1):page203_i71:pgnd(2)"
				( attribute "PN" "40"
					( Origin gPackager )
				)
				( objectStatus "EU4D1.40" )
			)
			( pin "@baseboard_fab2_lib.baseboard_fab2(sch_1):page203_i71:phase"
				( attribute "PN" "32"
					( Origin gPackager )
				)
				( objectStatus "EU4D1.32" )
			)
			( pin "@baseboard_fab2_lib.baseboard_fab2(sch_1):page203_i71:pwm"
				( attribute "PN" "34"
					( Origin gPackager )
				)
				( objectStatus "EU4D1.34" )
			)
			( pin "@baseboard_fab2_lib.baseboard_fab2(sch_1):page203_i71:refin"
				( attribute "PN" "39"
					( Origin gPackager )
				)
				( objectStatus "EU4D1.39" )
			)
			( pin "@baseboard_fab2_lib.baseboard_fab2(sch_1):page203_i71:sw"
				( attribute "PN" "10"
					( Origin gPackager )
				)
				( objectStatus "EU4D1.10" )
			)
			( pin "@baseboard_fab2_lib.baseboard_fab2(sch_1):page203_i71:tout_flt"
				( attribute "PN" "36"
					( Origin gPackager )
				)
				( objectStatus "EU4D1.36" )
			)
			( pin "@baseboard_fab2_lib.baseboard_fab2(sch_1):page203_i71:vcc"
				( attribute "PN" "3"
					( Origin gPackager )
				)
				( objectStatus "EU4D1.3" )
			)
			( pin "@baseboard_fab2_lib.baseboard_fab2(sch_1):page203_i71:vdrv"
				( attribute "PN" "4"
					( Origin gPackager )
				)
				( objectStatus "EU4D1.4" )
			)
			( pin "@baseboard_fab2_lib.baseboard_fab2(sch_1):page203_i71:vin(0)"
				( attribute "PN" "25"
					( Origin gPackager )
				)
				( objectStatus "EU4D1.25" )
			)
			( pin "@baseboard_fab2_lib.baseboard_fab2(sch_1):page203_i71:vin(1)"
				( attribute "PN" "30"
					( Origin gPackager )
				)
				( objectStatus "EU4D1.30" )
			)
			( pin "@baseboard_fab2_lib.baseboard_fab2(sch_1):page203_i71:vos"
				( attribute "PN" "1"
					( Origin gPackager )
				)
				( objectStatus "EU4D1.1" )
			)
			( pin "@baseboard_fab2_lib.baseboard_fab2(sch_1):page203_i89:a"
				( attribute "PN" "1"
					( Origin gPackager )
				)
				( objectStatus "R4D72.1" )
			)
			( pin "@baseboard_fab2_lib.baseboard_fab2(sch_1):page203_i89:b"
				( attribute "PN" "2"
					( Origin gPackager )
				)
				( objectStatus "R4D72.2" )
			)
			( pin "@baseboard_fab2_lib.baseboard_fab2(sch_1):page203_i91:a"
				( attribute "PN" "1"
					( Origin gPackager )
				)
				( objectStatus "R4D71.1" )
			)
			( pin "@baseboard_fab2_lib.baseboard_fab2(sch_1):page203_i91:b"
				( attribute "PN" "2"
					( Origin gPackager )
				)
				( objectStatus "R4D71.2" )
			)
			( pin "@baseboard_fab2_lib.baseboard_fab2(sch_1):page207_i107:f"
				( attribute "PN" "2"
					( Origin gPackager )
				)
				( objectStatus "L1E1.2" )
			)
			( pin "@baseboard_fab2_lib.baseboard_fab2(sch_1):page207_i107:s"
				( attribute "PN" "1"
					( Origin gPackager )
				)
				( objectStatus "L1E1.1" )
			)
			( pin "@baseboard_fab2_lib.baseboard_fab2(sch_1):page204_i9:a"
				( attribute "PN" "1"
					( Origin gPackager )
				)
				( objectStatus "C4D12.1" )
			)
			( pin "@baseboard_fab2_lib.baseboard_fab2(sch_1):page204_i9:b"
				( attribute "PN" "2"
					( Origin gPackager )
				)
				( objectStatus "C4D12.2" )
			)
			( pin "@baseboard_fab2_lib.baseboard_fab2(sch_1):page204_i18:a"
				( attribute "PN" "1"
					( Origin gPackager )
				)
				( objectStatus "C4D47.1" )
			)
			( pin "@baseboard_fab2_lib.baseboard_fab2(sch_1):page204_i18:b"
				( attribute "PN" "2"
					( Origin gPackager )
				)
				( objectStatus "C4D47.2" )
			)
			( pin "@baseboard_fab2_lib.baseboard_fab2(sch_1):page203_i132:\1\"
				( attribute "PN" "1"
					( Origin gPackager )
				)
				( objectStatus "C4D14.1" )
			)
			( pin "@baseboard_fab2_lib.baseboard_fab2(sch_1):page203_i132:\2\"
				( attribute "PN" "2"
					( Origin gPackager )
				)
				( objectStatus "C4D14.2" )
			)
			( pin "@baseboard_fab2_lib.baseboard_fab2(sch_1):page204_i22:a"
				( attribute "PN" "1"
					( Origin gPackager )
				)
				( objectStatus "C4C17.1" )
			)
			( pin "@baseboard_fab2_lib.baseboard_fab2(sch_1):page204_i22:b"
				( attribute "PN" "2"
					( Origin gPackager )
				)
				( objectStatus "C4C17.2" )
			)
			( pin "@baseboard_fab2_lib.baseboard_fab2(sch_1):page207_i105:a"
				( attribute "PN" "1"
					( Origin gPackager )
				)
				( objectStatus "R9R11.1" )
			)
			( pin "@baseboard_fab2_lib.baseboard_fab2(sch_1):page207_i105:b"
				( attribute "PN" "2"
					( Origin gPackager )
				)
				( objectStatus "R9R11.2" )
			)
			( pin "@baseboard_fab2_lib.baseboard_fab2(sch_1):page204_i34:a"
				( attribute "PN" "1"
					( Origin gPackager )
				)
				( objectStatus "C4D46.1" )
			)
			( pin "@baseboard_fab2_lib.baseboard_fab2(sch_1):page204_i34:b"
				( attribute "PN" "2"
					( Origin gPackager )
				)
				( objectStatus "C4D46.2" )
			)
			( pin "@baseboard_fab2_lib.baseboard_fab2(sch_1):page204_i35:a"
				( attribute "PN" "1"
					( Origin gPackager )
				)
				( objectStatus "C4C19.1" )
			)
			( pin "@baseboard_fab2_lib.baseboard_fab2(sch_1):page204_i35:b"
				( attribute "PN" "2"
					( Origin gPackager )
				)
				( objectStatus "C4C19.2" )
			)
			( pin "@baseboard_fab2_lib.baseboard_fab2(sch_1):page204_i36:a"
				( attribute "PN" "1"
					( Origin gPackager )
				)
				( objectStatus "C4C18.1" )
			)
			( pin "@baseboard_fab2_lib.baseboard_fab2(sch_1):page204_i36:b"
				( attribute "PN" "2"
					( Origin gPackager )
				)
				( objectStatus "C4C18.2" )
			)
			( pin "@baseboard_fab2_lib.baseboard_fab2(sch_1):page204_i37:a"
				( attribute "PN" "1"
					( Origin gPackager )
				)
				( objectStatus "C6N10.1" )
			)
			( pin "@baseboard_fab2_lib.baseboard_fab2(sch_1):page204_i37:b"
				( attribute "PN" "2"
					( Origin gPackager )
				)
				( objectStatus "C6N10.2" )
			)
			( pin "@baseboard_fab2_lib.baseboard_fab2(sch_1):page204_i38:a"
				( attribute "PN" "1"
					( Origin gPackager )
				)
				( objectStatus "C6P17.1" )
			)
			( pin "@baseboard_fab2_lib.baseboard_fab2(sch_1):page204_i38:b"
				( attribute "PN" "2"
					( Origin gPackager )
				)
				( objectStatus "C6P17.2" )
			)
			( pin "@baseboard_fab2_lib.baseboard_fab2(sch_1):page204_i42:a"
				( attribute "PN" "1"
					( Origin gPackager )
				)
				( objectStatus "C6N11.1" )
			)
			( pin "@baseboard_fab2_lib.baseboard_fab2(sch_1):page204_i42:b"
				( attribute "PN" "2"
					( Origin gPackager )
				)
				( objectStatus "C6N11.2" )
			)
			( pin "@baseboard_fab2_lib.baseboard_fab2(sch_1):page209_i81:f"
				( attribute "PN" "2"
					( Origin gPackager )
				)
				( objectStatus "L1B2.2" )
			)
			( pin "@baseboard_fab2_lib.baseboard_fab2(sch_1):page209_i81:s"
				( attribute "PN" "1"
					( Origin gPackager )
				)
				( objectStatus "L1B2.1" )
			)
			( pin "@baseboard_fab2_lib.baseboard_fab2(sch_1):page204_i48:a"
				( attribute "PN" "1"
					( Origin gPackager )
				)
				( objectStatus "C4D2.1" )
			)
			( pin "@baseboard_fab2_lib.baseboard_fab2(sch_1):page204_i48:b"
				( attribute "PN" "2"
					( Origin gPackager )
				)
				( objectStatus "C4D2.2" )
			)
			( pin "@baseboard_fab2_lib.baseboard_fab2(sch_1):page204_i50:a"
				( attribute "PN" "1"
					( Origin gPackager )
				)
				( objectStatus "C4E16.1" )
			)
			( pin "@baseboard_fab2_lib.baseboard_fab2(sch_1):page204_i50:b"
				( attribute "PN" "2"
					( Origin gPackager )
				)
				( objectStatus "C4E16.2" )
			)
			( pin "@baseboard_fab2_lib.baseboard_fab2(sch_1):page138_i194:a"
				( attribute "PN" "1"
					( Origin gPackager )
				)
				( objectStatus "R8W5.1" )
			)
			( pin "@baseboard_fab2_lib.baseboard_fab2(sch_1):page138_i194:b"
				( attribute "PN" "2"
					( Origin gPackager )
				)
				( objectStatus "R8W5.2" )
			)
			( pin "@baseboard_fab2_lib.baseboard_fab2(sch_1):page138_i195:a"
				( attribute "PN" "1"
					( Origin gPackager )
				)
				( objectStatus "R8W4.1" )
			)
			( pin "@baseboard_fab2_lib.baseboard_fab2(sch_1):page138_i195:b"
				( attribute "PN" "2"
					( Origin gPackager )
				)
				( objectStatus "R8W4.2" )
			)
			( pin "@baseboard_fab2_lib.baseboard_fab2(sch_1):page204_i60:a"
				( attribute "PN" "1"
					( Origin gPackager )
				)
				( objectStatus "R4E14.1" )
			)
			( pin "@baseboard_fab2_lib.baseboard_fab2(sch_1):page204_i60:b"
				( attribute "PN" "2"
					( Origin gPackager )
				)
				( objectStatus "R4E14.2" )
			)
			( pin "@baseboard_fab2_lib.baseboard_fab2(sch_1):page204_i61:a"
				( attribute "PN" "1"
					( Origin gPackager )
				)
				( objectStatus "R4E16.1" )
			)
			( pin "@baseboard_fab2_lib.baseboard_fab2(sch_1):page204_i61:b"
				( attribute "PN" "2"
					( Origin gPackager )
				)
				( objectStatus "R4E16.2" )
			)
			( pin "@baseboard_fab2_lib.baseboard_fab2(sch_1):page204_i62:a"
				( attribute "PN" "1"
					( Origin gPackager )
				)
				( objectStatus "R4E17.1" )
			)
			( pin "@baseboard_fab2_lib.baseboard_fab2(sch_1):page204_i62:b"
				( attribute "PN" "2"
					( Origin gPackager )
				)
				( objectStatus "R4E17.2" )
			)
			( pin "@baseboard_fab2_lib.baseboard_fab2(sch_1):page204_i63:a"
				( attribute "PN" "1"
					( Origin gPackager )
				)
				( objectStatus "R4E15.1" )
			)
			( pin "@baseboard_fab2_lib.baseboard_fab2(sch_1):page204_i63:b"
				( attribute "PN" "2"
					( Origin gPackager )
				)
				( objectStatus "R4E15.2" )
			)
			( pin "@baseboard_fab2_lib.baseboard_fab2(sch_1):page204_i64:a"
				( attribute "PN" "1"
					( Origin gPackager )
				)
				( objectStatus "R4E18.1" )
			)
			( pin "@baseboard_fab2_lib.baseboard_fab2(sch_1):page204_i64:b"
				( attribute "PN" "2"
					( Origin gPackager )
				)
				( objectStatus "R4E18.2" )
			)
			( pin "@baseboard_fab2_lib.baseboard_fab2(sch_1):page204_i67:a"
				( attribute "PN" "1"
					( Origin gPackager )
				)
				( objectStatus "C4C12.1" )
			)
			( pin "@baseboard_fab2_lib.baseboard_fab2(sch_1):page204_i67:b"
				( attribute "PN" "2"
					( Origin gPackager )
				)
				( objectStatus "C4C12.2" )
			)
			( pin "@baseboard_fab2_lib.baseboard_fab2(sch_1):page204_i70:a"
				( attribute "PN" "1"
					( Origin gPackager )
				)
				( objectStatus "C6R2.1" )
			)
			( pin "@baseboard_fab2_lib.baseboard_fab2(sch_1):page204_i70:b"
				( attribute "PN" "2"
					( Origin gPackager )
				)
				( objectStatus "C6R2.2" )
			)
			( pin "@baseboard_fab2_lib.baseboard_fab2(sch_1):page204_i71:boost"
				( attribute "PN" "33"
					( Origin gPackager )
				)
				( objectStatus "EU4C2.33" )
			)
			( pin "@baseboard_fab2_lib.baseboard_fab2(sch_1):page204_i71:en"
				( attribute "PN" "35"
					( Origin gPackager )
				)
				( objectStatus "EU4C2.35" )
			)
			( pin "@baseboard_fab2_lib.baseboard_fab2(sch_1):page204_i71:gl(0)"
				( attribute "PN" "6"
					( Origin gPackager )
				)
				( objectStatus "EU4C2.6" )
			)
			( pin "@baseboard_fab2_lib.baseboard_fab2(sch_1):page204_i71:gl(1)"
				( attribute "PN" "41"
					( Origin gPackager )
				)
				( objectStatus "EU4C2.41" )
			)
			( pin "@baseboard_fab2_lib.baseboard_fab2(sch_1):page204_i71:iout"
				( attribute "PN" "38"
					( Origin gPackager )
				)
				( objectStatus "EU4C2.38" )
			)
			( pin "@baseboard_fab2_lib.baseboard_fab2(sch_1):page204_i71:lgnd"
				( attribute "PN" "2"
					( Origin gPackager )
				)
				( objectStatus "EU4C2.2" )
			)
			( pin "@baseboard_fab2_lib.baseboard_fab2(sch_1):page204_i71:nc"
				( attribute "PN" "31"
					( Origin gPackager )
				)
				( objectStatus "EU4C2.31" )
			)
			( pin "@baseboard_fab2_lib.baseboard_fab2(sch_1):page204_i71:ocset"
				( attribute "PN" "37"
					( Origin gPackager )
				)
				( objectStatus "EU4C2.37" )
			)
			( pin "@baseboard_fab2_lib.baseboard_fab2(sch_1):page204_i71:pgnd(0)"
				( attribute "PN" "5"
					( Origin gPackager )
				)
				( objectStatus "EU4C2.5" )
			)
			( pin "@baseboard_fab2_lib.baseboard_fab2(sch_1):page204_i71:pgnd(1)"
				( attribute "PN" "7"
					( Origin gPackager )
				)
				( objectStatus "EU4C2.7" )
			)
			( pin "@baseboard_fab2_lib.baseboard_fab2(sch_1):page204_i71:pgnd(2)"
				( attribute "PN" "40"
					( Origin gPackager )
				)
				( objectStatus "EU4C2.40" )
			)
			( pin "@baseboard_fab2_lib.baseboard_fab2(sch_1):page204_i71:phase"
				( attribute "PN" "32"
					( Origin gPackager )
				)
				( objectStatus "EU4C2.32" )
			)
			( pin "@baseboard_fab2_lib.baseboard_fab2(sch_1):page204_i71:pwm"
				( attribute "PN" "34"
					( Origin gPackager )
				)
				( objectStatus "EU4C2.34" )
			)
			( pin "@baseboard_fab2_lib.baseboard_fab2(sch_1):page204_i71:refin"
				( attribute "PN" "39"
					( Origin gPackager )
				)
				( objectStatus "EU4C2.39" )
			)
			( pin "@baseboard_fab2_lib.baseboard_fab2(sch_1):page204_i71:sw"
				( attribute "PN" "10"
					( Origin gPackager )
				)
				( objectStatus "EU4C2.10" )
			)
			( pin "@baseboard_fab2_lib.baseboard_fab2(sch_1):page204_i71:tout_flt"
				( attribute "PN" "36"
					( Origin gPackager )
				)
				( objectStatus "EU4C2.36" )
			)
			( pin "@baseboard_fab2_lib.baseboard_fab2(sch_1):page204_i71:vcc"
				( attribute "PN" "3"
					( Origin gPackager )
				)
				( objectStatus "EU4C2.3" )
			)
			( pin "@baseboard_fab2_lib.baseboard_fab2(sch_1):page204_i71:vdrv"
				( attribute "PN" "4"
					( Origin gPackager )
				)
				( objectStatus "EU4C2.4" )
			)
			( pin "@baseboard_fab2_lib.baseboard_fab2(sch_1):page204_i71:vin(0)"
				( attribute "PN" "25"
					( Origin gPackager )
				)
				( objectStatus "EU4C2.25" )
			)
			( pin "@baseboard_fab2_lib.baseboard_fab2(sch_1):page204_i71:vin(1)"
				( attribute "PN" "30"
					( Origin gPackager )
				)
				( objectStatus "EU4C2.30" )
			)
			( pin "@baseboard_fab2_lib.baseboard_fab2(sch_1):page204_i71:vos"
				( attribute "PN" "1"
					( Origin gPackager )
				)
				( objectStatus "EU4C2.1" )
			)
			( pin "@baseboard_fab2_lib.baseboard_fab2(sch_1):page204_i83:a"
				( attribute "PN" "1"
					( Origin gPackager )
				)
				( objectStatus "R4D68.1" )
			)
			( pin "@baseboard_fab2_lib.baseboard_fab2(sch_1):page204_i83:b"
				( attribute "PN" "2"
					( Origin gPackager )
				)
				( objectStatus "R4D68.2" )
			)
			( pin "@baseboard_fab2_lib.baseboard_fab2(sch_1):page205_i5:a"
				( attribute "PN" "1"
					( Origin gPackager )
				)
				( objectStatus "C6N7.1" )
			)
			( pin "@baseboard_fab2_lib.baseboard_fab2(sch_1):page205_i5:b"
				( attribute "PN" "2"
					( Origin gPackager )
				)
				( objectStatus "C6N7.2" )
			)
			( pin "@baseboard_fab2_lib.baseboard_fab2(sch_1):page210_i72:f"
				( attribute "PN" "2"
					( Origin gPackager )
				)
				( objectStatus "L1C1.2" )
			)
			( pin "@baseboard_fab2_lib.baseboard_fab2(sch_1):page210_i72:s"
				( attribute "PN" "1"
					( Origin gPackager )
				)
				( objectStatus "L1C1.1" )
			)
			( pin "@baseboard_fab2_lib.baseboard_fab2(sch_1):page205_i12:a"
				( attribute "PN" "1"
					( Origin gPackager )
				)
				( objectStatus "C6N1.1" )
			)
			( pin "@baseboard_fab2_lib.baseboard_fab2(sch_1):page205_i12:b"
				( attribute "PN" "2"
					( Origin gPackager )
				)
				( objectStatus "C6N1.2" )
			)
			( pin "@baseboard_fab2_lib.baseboard_fab2(sch_1):page205_i14:a"
				( attribute "PN" "1"
					( Origin gPackager )
				)
				( objectStatus "C6N4.1" )
			)
			( pin "@baseboard_fab2_lib.baseboard_fab2(sch_1):page205_i14:b"
				( attribute "PN" "2"
					( Origin gPackager )
				)
				( objectStatus "C6N4.2" )
			)
			( pin "@baseboard_fab2_lib.baseboard_fab2(sch_1):page205_i16:a"
				( attribute "PN" "1"
					( Origin gPackager )
				)
				( objectStatus "C4C5.1" )
			)
			( pin "@baseboard_fab2_lib.baseboard_fab2(sch_1):page205_i16:b"
				( attribute "PN" "2"
					( Origin gPackager )
				)
				( objectStatus "C4C5.2" )
			)
			( pin "@baseboard_fab2_lib.baseboard_fab2(sch_1):page204_i113:\1\"
				( attribute "PN" "1"
					( Origin gPackager )
				)
				( objectStatus "C4C14.1" )
			)
			( pin "@baseboard_fab2_lib.baseboard_fab2(sch_1):page204_i113:\2\"
				( attribute "PN" "2"
					( Origin gPackager )
				)
				( objectStatus "C4C14.2" )
			)
			( pin "@baseboard_fab2_lib.baseboard_fab2(sch_1):page204_i103:a"
				( attribute "PN" "1"
					( Origin gPackager )
				)
				( objectStatus "R6P47.1" )
			)
			( pin "@baseboard_fab2_lib.baseboard_fab2(sch_1):page204_i103:b"
				( attribute "PN" "2"
					( Origin gPackager )
				)
				( objectStatus "R6P47.2" )
			)
			( pin "@baseboard_fab2_lib.baseboard_fab2(sch_1):page205_i20:a"
				( attribute "PN" "1"
					( Origin gPackager )
				)
				( objectStatus "C4C6.1" )
			)
			( pin "@baseboard_fab2_lib.baseboard_fab2(sch_1):page205_i20:b"
				( attribute "PN" "2"
					( Origin gPackager )
				)
				( objectStatus "C4C6.2" )
			)
			( pin "@baseboard_fab2_lib.baseboard_fab2(sch_1):page205_i24:a"
				( attribute "PN" "1"
					( Origin gPackager )
				)
				( objectStatus "R4C5.1" )
			)
			( pin "@baseboard_fab2_lib.baseboard_fab2(sch_1):page205_i24:b"
				( attribute "PN" "2"
					( Origin gPackager )
				)
				( objectStatus "R4C5.2" )
			)
			( pin "@baseboard_fab2_lib.baseboard_fab2(sch_1):page205_i25:a"
				( attribute "PN" "1"
					( Origin gPackager )
				)
				( objectStatus "C4C8.1" )
			)
			( pin "@baseboard_fab2_lib.baseboard_fab2(sch_1):page205_i25:b"
				( attribute "PN" "2"
					( Origin gPackager )
				)
				( objectStatus "C4C8.2" )
			)
			( pin "@baseboard_fab2_lib.baseboard_fab2(sch_1):page205_i26:a"
				( attribute "PN" "1"
					( Origin gPackager )
				)
				( objectStatus "R4C4.1" )
			)
			( pin "@baseboard_fab2_lib.baseboard_fab2(sch_1):page205_i26:b"
				( attribute "PN" "2"
					( Origin gPackager )
				)
				( objectStatus "R4C4.2" )
			)
			( pin "@baseboard_fab2_lib.baseboard_fab2(sch_1):page205_i29:a"
				( attribute "PN" "1"
					( Origin gPackager )
				)
				( objectStatus "R4C1.1" )
			)
			( pin "@baseboard_fab2_lib.baseboard_fab2(sch_1):page205_i29:b"
				( attribute "PN" "2"
					( Origin gPackager )
				)
				( objectStatus "R4C1.2" )
			)
			( pin "@baseboard_fab2_lib.baseboard_fab2(sch_1):page205_i30:a"
				( attribute "PN" "1"
					( Origin gPackager )
				)
				( objectStatus "R4C2.1" )
			)
			( pin "@baseboard_fab2_lib.baseboard_fab2(sch_1):page205_i30:b"
				( attribute "PN" "2"
					( Origin gPackager )
				)
				( objectStatus "R4C2.2" )
			)
			( pin "@baseboard_fab2_lib.baseboard_fab2(sch_1):page205_i31:a"
				( attribute "PN" "1"
					( Origin gPackager )
				)
				( objectStatus "C4C10.1" )
			)
			( pin "@baseboard_fab2_lib.baseboard_fab2(sch_1):page205_i31:b"
				( attribute "PN" "2"
					( Origin gPackager )
				)
				( objectStatus "C4C10.2" )
			)
			( pin "@baseboard_fab2_lib.baseboard_fab2(sch_1):page205_i32:a"
				( attribute "PN" "1"
					( Origin gPackager )
				)
				( objectStatus "C4C9.1" )
			)
			( pin "@baseboard_fab2_lib.baseboard_fab2(sch_1):page205_i32:b"
				( attribute "PN" "2"
					( Origin gPackager )
				)
				( objectStatus "C4C9.2" )
			)
			( pin "@baseboard_fab2_lib.baseboard_fab2(sch_1):page205_i33:a"
				( attribute "PN" "1"
					( Origin gPackager )
				)
				( objectStatus "C6N2.1" )
			)
			( pin "@baseboard_fab2_lib.baseboard_fab2(sch_1):page205_i33:b"
				( attribute "PN" "2"
					( Origin gPackager )
				)
				( objectStatus "C6N2.2" )
			)
			( pin "@baseboard_fab2_lib.baseboard_fab2(sch_1):page205_i34:a"
				( attribute "PN" "1"
					( Origin gPackager )
				)
				( objectStatus "C6N3.1" )
			)
			( pin "@baseboard_fab2_lib.baseboard_fab2(sch_1):page205_i34:b"
				( attribute "PN" "2"
					( Origin gPackager )
				)
				( objectStatus "C6N3.2" )
			)
			( pin "@baseboard_fab2_lib.baseboard_fab2(sch_1):page205_i35:a"
				( attribute "PN" "1"
					( Origin gPackager )
				)
				( objectStatus "C6N6.1" )
			)
			( pin "@baseboard_fab2_lib.baseboard_fab2(sch_1):page205_i35:b"
				( attribute "PN" "2"
					( Origin gPackager )
				)
				( objectStatus "C6N6.2" )
			)
			( pin "@baseboard_fab2_lib.baseboard_fab2(sch_1):page205_i37:a"
				( attribute "PN" "1"
					( Origin gPackager )
				)
				( objectStatus "R4C3.1" )
			)
			( pin "@baseboard_fab2_lib.baseboard_fab2(sch_1):page205_i37:b"
				( attribute "PN" "2"
					( Origin gPackager )
				)
				( objectStatus "R4C3.2" )
			)
			( pin "@baseboard_fab2_lib.baseboard_fab2(sch_1):page205_i43:a"
				( attribute "PN" "1"
					( Origin gPackager )
				)
				( objectStatus "C4C11.1" )
			)
			( pin "@baseboard_fab2_lib.baseboard_fab2(sch_1):page205_i43:b"
				( attribute "PN" "2"
					( Origin gPackager )
				)
				( objectStatus "C4C11.2" )
			)
			( pin "@baseboard_fab2_lib.baseboard_fab2(sch_1):page205_i45:a"
				( attribute "PN" "1"
					( Origin gPackager )
				)
				( objectStatus "R6N4.1" )
			)
			( pin "@baseboard_fab2_lib.baseboard_fab2(sch_1):page205_i45:b"
				( attribute "PN" "2"
					( Origin gPackager )
				)
				( objectStatus "R6N4.2" )
			)
			( pin "@baseboard_fab2_lib.baseboard_fab2(sch_1):page205_i46:boost"
				( attribute "PN" "33"
					( Origin gPackager )
				)
				( objectStatus "EU4C1.33" )
			)
			( pin "@baseboard_fab2_lib.baseboard_fab2(sch_1):page205_i46:en"
				( attribute "PN" "35"
					( Origin gPackager )
				)
				( objectStatus "EU4C1.35" )
			)
			( pin "@baseboard_fab2_lib.baseboard_fab2(sch_1):page205_i46:gl(0)"
				( attribute "PN" "6"
					( Origin gPackager )
				)
				( objectStatus "EU4C1.6" )
			)
			( pin "@baseboard_fab2_lib.baseboard_fab2(sch_1):page205_i46:gl(1)"
				( attribute "PN" "41"
					( Origin gPackager )
				)
				( objectStatus "EU4C1.41" )
			)
			( pin "@baseboard_fab2_lib.baseboard_fab2(sch_1):page205_i46:iout"
				( attribute "PN" "38"
					( Origin gPackager )
				)
				( objectStatus "EU4C1.38" )
			)
			( pin "@baseboard_fab2_lib.baseboard_fab2(sch_1):page205_i46:lgnd"
				( attribute "PN" "2"
					( Origin gPackager )
				)
				( objectStatus "EU4C1.2" )
			)
			( pin "@baseboard_fab2_lib.baseboard_fab2(sch_1):page205_i46:nc"
				( attribute "PN" "31"
					( Origin gPackager )
				)
				( objectStatus "EU4C1.31" )
			)
			( pin "@baseboard_fab2_lib.baseboard_fab2(sch_1):page205_i46:ocset"
				( attribute "PN" "37"
					( Origin gPackager )
				)
				( objectStatus "EU4C1.37" )
			)
			( pin "@baseboard_fab2_lib.baseboard_fab2(sch_1):page205_i46:pgnd(0)"
				( attribute "PN" "5"
					( Origin gPackager )
				)
				( objectStatus "EU4C1.5" )
			)
			( pin "@baseboard_fab2_lib.baseboard_fab2(sch_1):page205_i46:pgnd(1)"
				( attribute "PN" "7"
					( Origin gPackager )
				)
				( objectStatus "EU4C1.7" )
			)
			( pin "@baseboard_fab2_lib.baseboard_fab2(sch_1):page205_i46:pgnd(2)"
				( attribute "PN" "40"
					( Origin gPackager )
				)
				( objectStatus "EU4C1.40" )
			)
			( pin "@baseboard_fab2_lib.baseboard_fab2(sch_1):page205_i46:phase"
				( attribute "PN" "32"
					( Origin gPackager )
				)
				( objectStatus "EU4C1.32" )
			)
			( pin "@baseboard_fab2_lib.baseboard_fab2(sch_1):page205_i46:pwm"
				( attribute "PN" "34"
					( Origin gPackager )
				)
				( objectStatus "EU4C1.34" )
			)
			( pin "@baseboard_fab2_lib.baseboard_fab2(sch_1):page205_i46:refin"
				( attribute "PN" "39"
					( Origin gPackager )
				)
				( objectStatus "EU4C1.39" )
			)
			( pin "@baseboard_fab2_lib.baseboard_fab2(sch_1):page205_i46:sw"
				( attribute "PN" "10"
					( Origin gPackager )
				)
				( objectStatus "EU4C1.10" )
			)
			( pin "@baseboard_fab2_lib.baseboard_fab2(sch_1):page205_i46:tout_flt"
				( attribute "PN" "36"
					( Origin gPackager )
				)
				( objectStatus "EU4C1.36" )
			)
			( pin "@baseboard_fab2_lib.baseboard_fab2(sch_1):page205_i46:vcc"
				( attribute "PN" "3"
					( Origin gPackager )
				)
				( objectStatus "EU4C1.3" )
			)
			( pin "@baseboard_fab2_lib.baseboard_fab2(sch_1):page205_i46:vdrv"
				( attribute "PN" "4"
					( Origin gPackager )
				)
				( objectStatus "EU4C1.4" )
			)
			( pin "@baseboard_fab2_lib.baseboard_fab2(sch_1):page205_i46:vin(0)"
				( attribute "PN" "25"
					( Origin gPackager )
				)
				( objectStatus "EU4C1.25" )
			)
			( pin "@baseboard_fab2_lib.baseboard_fab2(sch_1):page205_i46:vin(1)"
				( attribute "PN" "30"
					( Origin gPackager )
				)
				( objectStatus "EU4C1.30" )
			)
			( pin "@baseboard_fab2_lib.baseboard_fab2(sch_1):page205_i46:vos"
				( attribute "PN" "1"
					( Origin gPackager )
				)
				( objectStatus "EU4C1.1" )
			)
			( pin "@baseboard_fab2_lib.baseboard_fab2(sch_1):page205_i62:a"
				( attribute "PN" "1"
					( Origin gPackager )
				)
				( objectStatus "R4C13.1" )
			)
			( pin "@baseboard_fab2_lib.baseboard_fab2(sch_1):page205_i62:b"
				( attribute "PN" "2"
					( Origin gPackager )
				)
				( objectStatus "R4C13.2" )
			)
			( pin "@baseboard_fab2_lib.baseboard_fab2(sch_1):page206_i4:a"
				( attribute "PN" "1"
					( Origin gPackager )
				)
				( objectStatus "R9P1.1" )
			)
			( pin "@baseboard_fab2_lib.baseboard_fab2(sch_1):page206_i4:b"
				( attribute "PN" "2"
					( Origin gPackager )
				)
				( objectStatus "R9P1.2" )
			)
			( pin "@baseboard_fab2_lib.baseboard_fab2(sch_1):page206_i6:a"
				( attribute "PN" "1"
					( Origin gPackager )
				)
				( objectStatus "R1D6.1" )
			)
			( pin "@baseboard_fab2_lib.baseboard_fab2(sch_1):page206_i6:b"
				( attribute "PN" "2"
					( Origin gPackager )
				)
				( objectStatus "R1D6.2" )
			)
			( pin "@baseboard_fab2_lib.baseboard_fab2(sch_1):page235_i246:a"
				( attribute "PN" "1"
					( Origin gPackager )
				)
				( objectStatus "C4W4.1" )
			)
			( pin "@baseboard_fab2_lib.baseboard_fab2(sch_1):page235_i246:b"
				( attribute "PN" "2"
					( Origin gPackager )
				)
				( objectStatus "C4W4.2" )
			)
			( pin "@baseboard_fab2_lib.baseboard_fab2(sch_1):page206_i29:a"
				( attribute "PN" "1"
					( Origin gPackager )
				)
				( objectStatus "C1C13.1" )
			)
			( pin "@baseboard_fab2_lib.baseboard_fab2(sch_1):page206_i29:b"
				( attribute "PN" "2"
					( Origin gPackager )
				)
				( objectStatus "C1C13.2" )
			)
			( pin "@baseboard_fab2_lib.baseboard_fab2(sch_1):page206_i31:a"
				( attribute "PN" "1"
					( Origin gPackager )
				)
				( objectStatus "C1C14.1" )
			)
			( pin "@baseboard_fab2_lib.baseboard_fab2(sch_1):page206_i31:b"
				( attribute "PN" "2"
					( Origin gPackager )
				)
				( objectStatus "C1C14.2" )
			)
			( pin "@baseboard_fab2_lib.baseboard_fab2(sch_1):page206_i33:a"
				( attribute "PN" "1"
					( Origin gPackager )
				)
				( objectStatus "R1D53.1" )
			)
			( pin "@baseboard_fab2_lib.baseboard_fab2(sch_1):page206_i33:b"
				( attribute "PN" "2"
					( Origin gPackager )
				)
				( objectStatus "R1D53.2" )
			)
			( pin "@baseboard_fab2_lib.baseboard_fab2(sch_1):page206_i34:a"
				( attribute "PN" "1"
					( Origin gPackager )
				)
				( objectStatus "R1C18.1" )
			)
			( pin "@baseboard_fab2_lib.baseboard_fab2(sch_1):page206_i34:b"
				( attribute "PN" "2"
					( Origin gPackager )
				)
				( objectStatus "R1C18.2" )
			)
			( pin "@baseboard_fab2_lib.baseboard_fab2(sch_1):page206_i35:a"
				( attribute "PN" "1"
					( Origin gPackager )
				)
				( objectStatus "R1C28.1" )
			)
			( pin "@baseboard_fab2_lib.baseboard_fab2(sch_1):page206_i35:b"
				( attribute "PN" "2"
					( Origin gPackager )
				)
				( objectStatus "R1C28.2" )
			)
			( pin "@baseboard_fab2_lib.baseboard_fab2(sch_1):page206_i36:a"
				( attribute "PN" "1"
					( Origin gPackager )
				)
				( objectStatus "R1D8.1" )
			)
			( pin "@baseboard_fab2_lib.baseboard_fab2(sch_1):page206_i36:b"
				( attribute "PN" "2"
					( Origin gPackager )
				)
				( objectStatus "R1D8.2" )
			)
			( pin "@baseboard_fab2_lib.baseboard_fab2(sch_1):page206_i37:a"
				( attribute "PN" "1"
					( Origin gPackager )
				)
				( objectStatus "R1D3.1" )
			)
			( pin "@baseboard_fab2_lib.baseboard_fab2(sch_1):page206_i37:b"
				( attribute "PN" "2"
					( Origin gPackager )
				)
				( objectStatus "R1D3.2" )
			)
			( pin "@baseboard_fab2_lib.baseboard_fab2(sch_1):page206_i38:a"
				( attribute "PN" "1"
					( Origin gPackager )
				)
				( objectStatus "R1D2.1" )
			)
			( pin "@baseboard_fab2_lib.baseboard_fab2(sch_1):page206_i38:b"
				( attribute "PN" "2"
					( Origin gPackager )
				)
				( objectStatus "R1D2.2" )
			)
			( pin "@baseboard_fab2_lib.baseboard_fab2(sch_1):page206_i41:a"
				( attribute "PN" "1"
					( Origin gPackager )
				)
				( objectStatus "C1C7.1" )
			)
			( pin "@baseboard_fab2_lib.baseboard_fab2(sch_1):page206_i41:b"
				( attribute "PN" "2"
					( Origin gPackager )
				)
				( objectStatus "C1C7.2" )
			)
			( pin "@baseboard_fab2_lib.baseboard_fab2(sch_1):page206_i42:a"
				( attribute "PN" "1"
					( Origin gPackager )
				)
				( objectStatus "C1C9.1" )
			)
			( pin "@baseboard_fab2_lib.baseboard_fab2(sch_1):page206_i42:b"
				( attribute "PN" "2"
					( Origin gPackager )
				)
				( objectStatus "C1C9.2" )
			)
			( pin "@baseboard_fab2_lib.baseboard_fab2(sch_1):page206_i46:a"
				( attribute "PN" "1"
					( Origin gPackager )
				)
				( objectStatus "R1C14.1" )
			)
			( pin "@baseboard_fab2_lib.baseboard_fab2(sch_1):page206_i46:b"
				( attribute "PN" "2"
					( Origin gPackager )
				)
				( objectStatus "R1C14.2" )
			)
			( pin "@baseboard_fab2_lib.baseboard_fab2(sch_1):page206_i49:a"
				( attribute "PN" "1"
					( Origin gPackager )
				)
				( objectStatus "R1C13.1" )
			)
			( pin "@baseboard_fab2_lib.baseboard_fab2(sch_1):page206_i49:b"
				( attribute "PN" "2"
					( Origin gPackager )
				)
				( objectStatus "R1C13.2" )
			)
			( pin "@baseboard_fab2_lib.baseboard_fab2(sch_1):page206_i53:a"
				( attribute "PN" "1"
					( Origin gPackager )
				)
				( objectStatus "R9P2.1" )
			)
			( pin "@baseboard_fab2_lib.baseboard_fab2(sch_1):page206_i53:b"
				( attribute "PN" "2"
					( Origin gPackager )
				)
				( objectStatus "R9P2.2" )
			)
			( pin "@baseboard_fab2_lib.baseboard_fab2(sch_1):page206_i54:a"
				( attribute "PN" "1"
					( Origin gPackager )
				)
				( objectStatus "R1D9.1" )
			)
			( pin "@baseboard_fab2_lib.baseboard_fab2(sch_1):page206_i54:b"
				( attribute "PN" "2"
					( Origin gPackager )
				)
				( objectStatus "R1D9.2" )
			)
			( pin "@baseboard_fab2_lib.baseboard_fab2(sch_1):page206_i56:a"
				( attribute "PN" "1"
					( Origin gPackager )
				)
				( objectStatus "R1C16.1" )
			)
			( pin "@baseboard_fab2_lib.baseboard_fab2(sch_1):page206_i56:b"
				( attribute "PN" "2"
					( Origin gPackager )
				)
				( objectStatus "R1C16.2" )
			)
			( pin "@baseboard_fab2_lib.baseboard_fab2(sch_1):page206_i68:a"
				( attribute "PN" "1"
					( Origin gPackager )
				)
				( objectStatus "C1C16.1" )
			)
			( pin "@baseboard_fab2_lib.baseboard_fab2(sch_1):page206_i68:b"
				( attribute "PN" "2"
					( Origin gPackager )
				)
				( objectStatus "C1C16.2" )
			)
			( pin "@baseboard_fab2_lib.baseboard_fab2(sch_1):page206_i69:a"
				( attribute "PN" "1"
					( Origin gPackager )
				)
				( objectStatus "C1C10.1" )
			)
			( pin "@baseboard_fab2_lib.baseboard_fab2(sch_1):page206_i69:b"
				( attribute "PN" "2"
					( Origin gPackager )
				)
				( objectStatus "C1C10.2" )
			)
			( pin "@baseboard_fab2_lib.baseboard_fab2(sch_1):page206_i71:a"
				( attribute "PN" "1"
					( Origin gPackager )
				)
				( objectStatus "C1C11.1" )
			)
			( pin "@baseboard_fab2_lib.baseboard_fab2(sch_1):page206_i71:b"
				( attribute "PN" "2"
					( Origin gPackager )
				)
				( objectStatus "C1C11.2" )
			)
			( pin "@baseboard_fab2_lib.baseboard_fab2(sch_1):page211_i103:a"
				( attribute "PN" "1"
					( Origin gPackager )
				)
				( objectStatus "C3P2.1" )
			)
			( pin "@baseboard_fab2_lib.baseboard_fab2(sch_1):page211_i103:b"
				( attribute "PN" "2"
					( Origin gPackager )
				)
				( objectStatus "C3P2.2" )
			)
			( pin "@baseboard_fab2_lib.baseboard_fab2(sch_1):page206_i77:a"
				( attribute "PN" "1"
					( Origin gPackager )
				)
				( objectStatus "R1C21.1" )
			)
			( pin "@baseboard_fab2_lib.baseboard_fab2(sch_1):page206_i77:b"
				( attribute "PN" "2"
					( Origin gPackager )
				)
				( objectStatus "R1C21.2" )
			)
			( pin "@baseboard_fab2_lib.baseboard_fab2(sch_1):page206_i78:a"
				( attribute "PN" "1"
					( Origin gPackager )
				)
				( objectStatus "C1D1.1" )
			)
			( pin "@baseboard_fab2_lib.baseboard_fab2(sch_1):page206_i78:b"
				( attribute "PN" "2"
					( Origin gPackager )
				)
				( objectStatus "C1D1.2" )
			)
			( pin "@baseboard_fab2_lib.baseboard_fab2(sch_1):page206_i79:a"
				( attribute "PN" "1"
					( Origin gPackager )
				)
				( objectStatus "R1D4.1" )
			)
			( pin "@baseboard_fab2_lib.baseboard_fab2(sch_1):page206_i79:b"
				( attribute "PN" "2"
					( Origin gPackager )
				)
				( objectStatus "R1D4.2" )
			)
			( pin "@baseboard_fab2_lib.baseboard_fab2(sch_1):page206_i111:a"
				( attribute "PN" "1"
					( Origin gPackager )
				)
				( objectStatus "R9N7.1" )
			)
			( pin "@baseboard_fab2_lib.baseboard_fab2(sch_1):page206_i111:b"
				( attribute "PN" "2"
					( Origin gPackager )
				)
				( objectStatus "R9N7.2" )
			)
			( pin "@baseboard_fab2_lib.baseboard_fab2(sch_1):page206_i112:a"
				( attribute "PN" "1"
					( Origin gPackager )
				)
				( objectStatus "R9N8.1" )
			)
			( pin "@baseboard_fab2_lib.baseboard_fab2(sch_1):page206_i112:b"
				( attribute "PN" "2"
					( Origin gPackager )
				)
				( objectStatus "R9N8.2" )
			)
			( pin "@baseboard_fab2_lib.baseboard_fab2(sch_1):page206_i113:a"
				( attribute "PN" "1"
					( Origin gPackager )
				)
				( objectStatus "R1C30.1" )
			)
			( pin "@baseboard_fab2_lib.baseboard_fab2(sch_1):page206_i113:b"
				( attribute "PN" "2"
					( Origin gPackager )
				)
				( objectStatus "R1C30.2" )
			)
			( pin "@baseboard_fab2_lib.baseboard_fab2(sch_1):page206_i114:a"
				( attribute "PN" "1"
					( Origin gPackager )
				)
				( objectStatus "C1C23.1" )
			)
			( pin "@baseboard_fab2_lib.baseboard_fab2(sch_1):page206_i114:b"
				( attribute "PN" "2"
					( Origin gPackager )
				)
				( objectStatus "C1C23.2" )
			)
			( pin "@baseboard_fab2_lib.baseboard_fab2(sch_1):page206_i116:a"
				( attribute "PN" "1"
					( Origin gPackager )
				)
				( objectStatus "R1D1.1" )
			)
			( pin "@baseboard_fab2_lib.baseboard_fab2(sch_1):page206_i116:b"
				( attribute "PN" "2"
					( Origin gPackager )
				)
				( objectStatus "R1D1.2" )
			)
			( pin "@baseboard_fab2_lib.baseboard_fab2(sch_1):page206_i117:a"
				( attribute "PN" "1"
					( Origin gPackager )
				)
				( objectStatus "R9P3.1" )
			)
			( pin "@baseboard_fab2_lib.baseboard_fab2(sch_1):page206_i117:b"
				( attribute "PN" "2"
					( Origin gPackager )
				)
				( objectStatus "R9P3.2" )
			)
			( pin "@baseboard_fab2_lib.baseboard_fab2(sch_1):page206_i119:a"
				( attribute "PN" "1"
					( Origin gPackager )
				)
				( objectStatus "R9N16.1" )
			)
			( pin "@baseboard_fab2_lib.baseboard_fab2(sch_1):page206_i119:b"
				( attribute "PN" "2"
					( Origin gPackager )
				)
				( objectStatus "R9N16.2" )
			)
			( pin "@baseboard_fab2_lib.baseboard_fab2(sch_1):page206_i120:a"
				( attribute "PN" "1"
					( Origin gPackager )
				)
				( objectStatus "R9N14.1" )
			)
			( pin "@baseboard_fab2_lib.baseboard_fab2(sch_1):page206_i120:b"
				( attribute "PN" "2"
					( Origin gPackager )
				)
				( objectStatus "R9N14.2" )
			)
			( pin "@baseboard_fab2_lib.baseboard_fab2(sch_1):page206_i130:airef1"
				( attribute "PN" "23"
					( Origin gPackager )
				)
				( objectStatus "EU1C2.23" )
			)
			( pin "@baseboard_fab2_lib.baseboard_fab2(sch_1):page206_i130:airef2"
				( attribute "PN" "25"
					( Origin gPackager )
				)
				( objectStatus "EU1C2.25" )
			)
			( pin "@baseboard_fab2_lib.baseboard_fab2(sch_1):page206_i130:airef3"
				( attribute "PN" "27"
					( Origin gPackager )
				)
				( objectStatus "EU1C2.27" )
			)
			( pin "@baseboard_fab2_lib.baseboard_fab2(sch_1):page206_i130:airef4"
				( attribute "PN" "29"
					( Origin gPackager )
				)
				( objectStatus "EU1C2.29" )
			)
			( pin "@baseboard_fab2_lib.baseboard_fab2(sch_1):page206_i130:airef5"
				( attribute "PN" "31"
					( Origin gPackager )
				)
				( objectStatus "EU1C2.31" )
			)
			( pin "@baseboard_fab2_lib.baseboard_fab2(sch_1):page206_i130:airef6"
				( attribute "PN" "33"
					( Origin gPackager )
				)
				( objectStatus "EU1C2.33" )
			)
			( pin "@baseboard_fab2_lib.baseboard_fab2(sch_1):page206_i130:aisen1"
				( attribute "PN" "24"
					( Origin gPackager )
				)
				( objectStatus "EU1C2.24" )
			)
			( pin "@baseboard_fab2_lib.baseboard_fab2(sch_1):page206_i130:aisen2"
				( attribute "PN" "26"
					( Origin gPackager )
				)
				( objectStatus "EU1C2.26" )
			)
			( pin "@baseboard_fab2_lib.baseboard_fab2(sch_1):page206_i130:aisen3"
				( attribute "PN" "28"
					( Origin gPackager )
				)
				( objectStatus "EU1C2.28" )
			)
			( pin "@baseboard_fab2_lib.baseboard_fab2(sch_1):page206_i130:aisen4"
				( attribute "PN" "30"
					( Origin gPackager )
				)
				( objectStatus "EU1C2.30" )
			)
			( pin "@baseboard_fab2_lib.baseboard_fab2(sch_1):page206_i130:aisen5"
				( attribute "PN" "32"
					( Origin gPackager )
				)
				( objectStatus "EU1C2.32" )
			)
			( pin "@baseboard_fab2_lib.baseboard_fab2(sch_1):page206_i130:aisen6"
				( attribute "PN" "34"
					( Origin gPackager )
				)
				( objectStatus "EU1C2.34" )
			)
			( pin "@baseboard_fab2_lib.baseboard_fab2(sch_1):page206_i130:apwm1"
				( attribute "PN" "7"
					( Origin gPackager )
				)
				( objectStatus "EU1C2.7" )
			)
			( pin "@baseboard_fab2_lib.baseboard_fab2(sch_1):page206_i130:apwm2"
				( attribute "PN" "6"
					( Origin gPackager )
				)
				( objectStatus "EU1C2.6" )
			)
			( pin "@baseboard_fab2_lib.baseboard_fab2(sch_1):page206_i130:apwm3"
				( attribute "PN" "5"
					( Origin gPackager )
				)
				( objectStatus "EU1C2.5" )
			)
			( pin "@baseboard_fab2_lib.baseboard_fab2(sch_1):page206_i130:apwm4"
				( attribute "PN" "4"
					( Origin gPackager )
				)
				( objectStatus "EU1C2.4" )
			)
			( pin "@baseboard_fab2_lib.baseboard_fab2(sch_1):page206_i130:apwm5"
				( attribute "PN" "3"
					( Origin gPackager )
				)
				( objectStatus "EU1C2.3" )
			)
			( pin "@baseboard_fab2_lib.baseboard_fab2(sch_1):page206_i130:apwm6"
				( attribute "PN" "2"
					( Origin gPackager )
				)
				( objectStatus "EU1C2.2" )
			)
			( pin "@baseboard_fab2_lib.baseboard_fab2(sch_1):page206_i130:atsen"
				( attribute "PN" "43"
					( Origin gPackager )
				)
				( objectStatus "EU1C2.43" )
			)
			( pin "@baseboard_fab2_lib.baseboard_fab2(sch_1):page206_i130:avref"
				( attribute "PN" "22"
					( Origin gPackager )
				)
				( objectStatus "EU1C2.22" )
			)
			( pin "@baseboard_fab2_lib.baseboard_fab2(sch_1):page206_i130:avren"
				( attribute "PN" "12"
					( Origin gPackager )
				)
				( objectStatus "EU1C2.12" )
			)
			( pin "@baseboard_fab2_lib.baseboard_fab2(sch_1):page206_i130:avrrdy"
				( attribute "PN" "11"
					( Origin gPackager )
				)
				( objectStatus "EU1C2.11" )
			)
			( pin "@baseboard_fab2_lib.baseboard_fab2(sch_1):page206_i130:avsen"
				( attribute "PN" "21"
					( Origin gPackager )
				)
				( objectStatus "EU1C2.21" )
			)
			( pin "@baseboard_fab2_lib.baseboard_fab2(sch_1):page206_i130:biref1"
				( attribute "PN" "37"
					( Origin gPackager )
				)
				( objectStatus "EU1C2.37" )
			)
			( pin "@baseboard_fab2_lib.baseboard_fab2(sch_1):page206_i130:bisen1"
				( attribute "PN" "38"
					( Origin gPackager )
				)
				( objectStatus "EU1C2.38" )
			)
			( pin "@baseboard_fab2_lib.baseboard_fab2(sch_1):page206_i130:bpwm1"
				( attribute "PN" "1"
					( Origin gPackager )
				)
				( objectStatus "EU1C2.1" )
			)
			( pin "@baseboard_fab2_lib.baseboard_fab2(sch_1):page206_i130:btsen"
				( attribute "PN" "42"
					( Origin gPackager )
				)
				( objectStatus "EU1C2.42" )
			)
			( pin "@baseboard_fab2_lib.baseboard_fab2(sch_1):page206_i130:bvref"
				( attribute "PN" "36"
					( Origin gPackager )
				)
				( objectStatus "EU1C2.36" )
			)
			( pin "@baseboard_fab2_lib.baseboard_fab2(sch_1):page206_i130:bvsen"
				( attribute "PN" "35"
					( Origin gPackager )
				)
				( objectStatus "EU1C2.35" )
			)
			( pin "@baseboard_fab2_lib.baseboard_fab2(sch_1):page206_i130:iinsen"
				( attribute "PN" "46"
					( Origin gPackager )
				)
				( objectStatus "EU1C2.46" )
			)
			( pin "@baseboard_fab2_lib.baseboard_fab2(sch_1):page206_i130:mp0"
				( attribute "PN" "15"
					( Origin gPackager )
				)
				( objectStatus "EU1C2.15" )
			)
			( pin "@baseboard_fab2_lib.baseboard_fab2(sch_1):page206_i130:mp1"
				( attribute "PN" "16"
					( Origin gPackager )
				)
				( objectStatus "EU1C2.16" )
			)
			( pin "@baseboard_fab2_lib.baseboard_fab2(sch_1):page206_i130:mp2"
				( attribute "PN" "20"
					( Origin gPackager )
				)
				( objectStatus "EU1C2.20" )
			)
			( pin "@baseboard_fab2_lib.baseboard_fab2(sch_1):page206_i130:mp3"
				( attribute "PN" "39"
					( Origin gPackager )
				)
				( objectStatus "EU1C2.39" )
			)
			( pin "@baseboard_fab2_lib.baseboard_fab2(sch_1):page206_i130:mp4"
				( attribute "PN" "40"
					( Origin gPackager )
				)
				( objectStatus "EU1C2.40" )
			)
			( pin "@baseboard_fab2_lib.baseboard_fab2(sch_1):page206_i130:pinalrt_n"
				( attribute "PN" "14"
					( Origin gPackager )
				)
				( objectStatus "EU1C2.14" )
			)
			( pin "@baseboard_fab2_lib.baseboard_fab2(sch_1):page206_i130:reset_n"
				( attribute "PN" "10"
					( Origin gPackager )
				)
				( objectStatus "EU1C2.10" )
			)
			( pin "@baseboard_fab2_lib.baseboard_fab2(sch_1):page206_i130:scl"
				( attribute "PN" "9"
					( Origin gPackager )
				)
				( objectStatus "EU1C2.9" )
			)
			( pin "@baseboard_fab2_lib.baseboard_fab2(sch_1):page206_i130:sda"
				( attribute "PN" "8"
					( Origin gPackager )
				)
				( objectStatus "EU1C2.8" )
			)
			( pin "@baseboard_fab2_lib.baseboard_fab2(sch_1):page206_i130:thpad"
				( attribute "PN" "49"
					( Origin gPackager )
				)
				( objectStatus "EU1C2.49" )
			)
			( pin "@baseboard_fab2_lib.baseboard_fab2(sch_1):page206_i130:valrt_n"
				( attribute "PN" "19"
					( Origin gPackager )
				)
				( objectStatus "EU1C2.19" )
			)
			( pin "@baseboard_fab2_lib.baseboard_fab2(sch_1):page206_i130:vclk"
				( attribute "PN" "17"
					( Origin gPackager )
				)
				( objectStatus "EU1C2.17" )
			)
			( pin "@baseboard_fab2_lib.baseboard_fab2(sch_1):page206_i130:vd12"
				( attribute "PN" "48"
					( Origin gPackager )
				)
				( objectStatus "EU1C2.48" )
			)
			( pin "@baseboard_fab2_lib.baseboard_fab2(sch_1):page206_i130:vdd"
				( attribute "PN" "47"
					( Origin gPackager )
				)
				( objectStatus "EU1C2.47" )
			)
			( pin "@baseboard_fab2_lib.baseboard_fab2(sch_1):page206_i130:vdio"
				( attribute "PN" "18"
					( Origin gPackager )
				)
				( objectStatus "EU1C2.18" )
			)
			( pin "@baseboard_fab2_lib.baseboard_fab2(sch_1):page206_i130:vinsen"
				( attribute "PN" "45"
					( Origin gPackager )
				)
				( objectStatus "EU1C2.45" )
			)
			( pin "@baseboard_fab2_lib.baseboard_fab2(sch_1):page206_i130:vrhot_n"
				( attribute "PN" "13"
					( Origin gPackager )
				)
				( objectStatus "EU1C2.13" )
			)
			( pin "@baseboard_fab2_lib.baseboard_fab2(sch_1):page206_i130:xaddr1"
				( attribute "PN" "44"
					( Origin gPackager )
				)
				( objectStatus "EU1C2.44" )
			)
			( pin "@baseboard_fab2_lib.baseboard_fab2(sch_1):page206_i130:xaddr2"
				( attribute "PN" "41"
					( Origin gPackager )
				)
				( objectStatus "EU1C2.41" )
			)
			( pin "@baseboard_fab2_lib.baseboard_fab2(sch_1):page207_i8:a"
				( attribute "PN" "1"
					( Origin gPackager )
				)
				( objectStatus "C9R8.1" )
			)
			( pin "@baseboard_fab2_lib.baseboard_fab2(sch_1):page207_i8:b"
				( attribute "PN" "2"
					( Origin gPackager )
				)
				( objectStatus "C9R8.2" )
			)
			( pin "@baseboard_fab2_lib.baseboard_fab2(sch_1):page207_i18:a"
				( attribute "PN" "1"
					( Origin gPackager )
				)
				( objectStatus "C1E3.1" )
			)
			( pin "@baseboard_fab2_lib.baseboard_fab2(sch_1):page207_i18:b"
				( attribute "PN" "2"
					( Origin gPackager )
				)
				( objectStatus "C1E3.2" )
			)
			( pin "@baseboard_fab2_lib.baseboard_fab2(sch_1):page207_i20:boost"
				( attribute "PN" "33"
					( Origin gPackager )
				)
				( objectStatus "EU1E2.33" )
			)
			( pin "@baseboard_fab2_lib.baseboard_fab2(sch_1):page207_i20:en"
				( attribute "PN" "35"
					( Origin gPackager )
				)
				( objectStatus "EU1E2.35" )
			)
			( pin "@baseboard_fab2_lib.baseboard_fab2(sch_1):page207_i20:gl(0)"
				( attribute "PN" "6"
					( Origin gPackager )
				)
				( objectStatus "EU1E2.6" )
			)
			( pin "@baseboard_fab2_lib.baseboard_fab2(sch_1):page207_i20:gl(1)"
				( attribute "PN" "41"
					( Origin gPackager )
				)
				( objectStatus "EU1E2.41" )
			)
			( pin "@baseboard_fab2_lib.baseboard_fab2(sch_1):page207_i20:iout"
				( attribute "PN" "38"
					( Origin gPackager )
				)
				( objectStatus "EU1E2.38" )
			)
			( pin "@baseboard_fab2_lib.baseboard_fab2(sch_1):page207_i20:lgnd"
				( attribute "PN" "2"
					( Origin gPackager )
				)
				( objectStatus "EU1E2.2" )
			)
			( pin "@baseboard_fab2_lib.baseboard_fab2(sch_1):page207_i20:nc"
				( attribute "PN" "31"
					( Origin gPackager )
				)
				( objectStatus "EU1E2.31" )
			)
			( pin "@baseboard_fab2_lib.baseboard_fab2(sch_1):page207_i20:ocset"
				( attribute "PN" "37"
					( Origin gPackager )
				)
				( objectStatus "EU1E2.37" )
			)
			( pin "@baseboard_fab2_lib.baseboard_fab2(sch_1):page207_i20:pgnd(0)"
				( attribute "PN" "5"
					( Origin gPackager )
				)
				( objectStatus "EU1E2.5" )
			)
			( pin "@baseboard_fab2_lib.baseboard_fab2(sch_1):page207_i20:pgnd(1)"
				( attribute "PN" "7"
					( Origin gPackager )
				)
				( objectStatus "EU1E2.7" )
			)
			( pin "@baseboard_fab2_lib.baseboard_fab2(sch_1):page207_i20:pgnd(2)"
				( attribute "PN" "40"
					( Origin gPackager )
				)
				( objectStatus "EU1E2.40" )
			)
			( pin "@baseboard_fab2_lib.baseboard_fab2(sch_1):page207_i20:phase"
				( attribute "PN" "32"
					( Origin gPackager )
				)
				( objectStatus "EU1E2.32" )
			)
			( pin "@baseboard_fab2_lib.baseboard_fab2(sch_1):page207_i20:pwm"
				( attribute "PN" "34"
					( Origin gPackager )
				)
				( objectStatus "EU1E2.34" )
			)
			( pin "@baseboard_fab2_lib.baseboard_fab2(sch_1):page207_i20:refin"
				( attribute "PN" "39"
					( Origin gPackager )
				)
				( objectStatus "EU1E2.39" )
			)
			( pin "@baseboard_fab2_lib.baseboard_fab2(sch_1):page207_i20:sw"
				( attribute "PN" "10"
					( Origin gPackager )
				)
				( objectStatus "EU1E2.10" )
			)
			( pin "@baseboard_fab2_lib.baseboard_fab2(sch_1):page207_i20:tout_flt"
				( attribute "PN" "36"
					( Origin gPackager )
				)
				( objectStatus "EU1E2.36" )
			)
			( pin "@baseboard_fab2_lib.baseboard_fab2(sch_1):page207_i20:vcc"
				( attribute "PN" "3"
					( Origin gPackager )
				)
				( objectStatus "EU1E2.3" )
			)
			( pin "@baseboard_fab2_lib.baseboard_fab2(sch_1):page207_i20:vdrv"
				( attribute "PN" "4"
					( Origin gPackager )
				)
				( objectStatus "EU1E2.4" )
			)
			( pin "@baseboard_fab2_lib.baseboard_fab2(sch_1):page207_i20:vin(0)"
				( attribute "PN" "25"
					( Origin gPackager )
				)
				( objectStatus "EU1E2.25" )
			)
			( pin "@baseboard_fab2_lib.baseboard_fab2(sch_1):page207_i20:vin(1)"
				( attribute "PN" "30"
					( Origin gPackager )
				)
				( objectStatus "EU1E2.30" )
			)
			( pin "@baseboard_fab2_lib.baseboard_fab2(sch_1):page207_i20:vos"
				( attribute "PN" "1"
					( Origin gPackager )
				)
				( objectStatus "EU1E2.1" )
			)
			( pin "@baseboard_fab2_lib.baseboard_fab2(sch_1):page208_i115:a"
				( attribute "PN" "1"
					( Origin gPackager )
				)
				( objectStatus "R9P8.1" )
			)
			( pin "@baseboard_fab2_lib.baseboard_fab2(sch_1):page208_i115:b"
				( attribute "PN" "2"
					( Origin gPackager )
				)
				( objectStatus "R9P8.2" )
			)
			( pin "@baseboard_fab2_lib.baseboard_fab2(sch_1):page207_i28:a"
				( attribute "PN" "1"
					( Origin gPackager )
				)
				( objectStatus "C1E7.1" )
			)
			( pin "@baseboard_fab2_lib.baseboard_fab2(sch_1):page207_i28:b"
				( attribute "PN" "2"
					( Origin gPackager )
				)
				( objectStatus "C1E7.2" )
			)
			( pin "@baseboard_fab2_lib.baseboard_fab2(sch_1):page224_i155:\1\"
				( attribute "PN" "1"
					( Origin gPackager )
				)
				( objectStatus "C1G4.1" )
			)
			( pin "@baseboard_fab2_lib.baseboard_fab2(sch_1):page224_i155:\2\"
				( attribute "PN" "2"
					( Origin gPackager )
				)
				( objectStatus "C1G4.2" )
			)
			( pin "@baseboard_fab2_lib.baseboard_fab2(sch_1):page207_i30:a"
				( attribute "PN" "1"
					( Origin gPackager )
				)
				( objectStatus "C1E11.1" )
			)
			( pin "@baseboard_fab2_lib.baseboard_fab2(sch_1):page207_i30:b"
				( attribute "PN" "2"
					( Origin gPackager )
				)
				( objectStatus "C1E11.2" )
			)
			( pin "@baseboard_fab2_lib.baseboard_fab2(sch_1):page207_i32:a"
				( attribute "PN" "1"
					( Origin gPackager )
				)
				( objectStatus "C1E8.1" )
			)
			( pin "@baseboard_fab2_lib.baseboard_fab2(sch_1):page207_i32:b"
				( attribute "PN" "2"
					( Origin gPackager )
				)
				( objectStatus "C1E8.2" )
			)
			( pin "@baseboard_fab2_lib.baseboard_fab2(sch_1):page207_i33:a"
				( attribute "PN" "1"
					( Origin gPackager )
				)
				( objectStatus "C1E14.1" )
			)
			( pin "@baseboard_fab2_lib.baseboard_fab2(sch_1):page207_i33:b"
				( attribute "PN" "2"
					( Origin gPackager )
				)
				( objectStatus "C1E14.2" )
			)
			( pin "@baseboard_fab2_lib.baseboard_fab2(sch_1):page207_i34:a"
				( attribute "PN" "1"
					( Origin gPackager )
				)
				( objectStatus "C1E13.1" )
			)
			( pin "@baseboard_fab2_lib.baseboard_fab2(sch_1):page207_i34:b"
				( attribute "PN" "2"
					( Origin gPackager )
				)
				( objectStatus "C1E13.2" )
			)
			( pin "@baseboard_fab2_lib.baseboard_fab2(sch_1):page207_i36:a"
				( attribute "PN" "1"
					( Origin gPackager )
				)
				( objectStatus "C1E25.1" )
			)
			( pin "@baseboard_fab2_lib.baseboard_fab2(sch_1):page207_i36:b"
				( attribute "PN" "2"
					( Origin gPackager )
				)
				( objectStatus "C1E25.2" )
			)
			( pin "@baseboard_fab2_lib.baseboard_fab2(sch_1):page224_i154:\1\"
				( attribute "PN" "1"
					( Origin gPackager )
				)
				( objectStatus "C1F21.1" )
			)
			( pin "@baseboard_fab2_lib.baseboard_fab2(sch_1):page224_i154:\2\"
				( attribute "PN" "2"
					( Origin gPackager )
				)
				( objectStatus "C1F21.2" )
			)
			( pin "@baseboard_fab2_lib.baseboard_fab2(sch_1):page207_i38:a"
				( attribute "PN" "1"
					( Origin gPackager )
				)
				( objectStatus "C1D36.1" )
			)
			( pin "@baseboard_fab2_lib.baseboard_fab2(sch_1):page207_i38:b"
				( attribute "PN" "2"
					( Origin gPackager )
				)
				( objectStatus "C1D36.2" )
			)
			( pin "@baseboard_fab2_lib.baseboard_fab2(sch_1):page208_i114:a"
				( attribute "PN" "1"
					( Origin gPackager )
				)
				( objectStatus "R9P22.1" )
			)
			( pin "@baseboard_fab2_lib.baseboard_fab2(sch_1):page208_i114:b"
				( attribute "PN" "2"
					( Origin gPackager )
				)
				( objectStatus "R9P22.2" )
			)
			( pin "@baseboard_fab2_lib.baseboard_fab2(sch_1):page207_i40:a"
				( attribute "PN" "1"
					( Origin gPackager )
				)
				( objectStatus "C1E24.1" )
			)
			( pin "@baseboard_fab2_lib.baseboard_fab2(sch_1):page207_i40:b"
				( attribute "PN" "2"
					( Origin gPackager )
				)
				( objectStatus "C1E24.2" )
			)
			( pin "@baseboard_fab2_lib.baseboard_fab2(sch_1):page207_i41:a"
				( attribute "PN" "1"
					( Origin gPackager )
				)
				( objectStatus "C1D34.1" )
			)
			( pin "@baseboard_fab2_lib.baseboard_fab2(sch_1):page207_i41:b"
				( attribute "PN" "2"
					( Origin gPackager )
				)
				( objectStatus "C1D34.2" )
			)
			( pin "@baseboard_fab2_lib.baseboard_fab2(sch_1):page207_i42:a"
				( attribute "PN" "1"
					( Origin gPackager )
				)
				( objectStatus "C1D35.1" )
			)
			( pin "@baseboard_fab2_lib.baseboard_fab2(sch_1):page207_i42:b"
				( attribute "PN" "2"
					( Origin gPackager )
				)
				( objectStatus "C1D35.2" )
			)
			( pin "@baseboard_fab2_lib.baseboard_fab2(sch_1):page207_i43:a"
				( attribute "PN" "1"
					( Origin gPackager )
				)
				( objectStatus "C9R7.1" )
			)
			( pin "@baseboard_fab2_lib.baseboard_fab2(sch_1):page207_i43:b"
				( attribute "PN" "2"
					( Origin gPackager )
				)
				( objectStatus "C9R7.2" )
			)
			( pin "@baseboard_fab2_lib.baseboard_fab2(sch_1):page207_i44:a"
				( attribute "PN" "1"
					( Origin gPackager )
				)
				( objectStatus "C9R10.1" )
			)
			( pin "@baseboard_fab2_lib.baseboard_fab2(sch_1):page207_i44:b"
				( attribute "PN" "2"
					( Origin gPackager )
				)
				( objectStatus "C9R10.2" )
			)
			( pin "@baseboard_fab2_lib.baseboard_fab2(sch_1):page207_i48:a"
				( attribute "PN" "1"
					( Origin gPackager )
				)
				( objectStatus "C9R11.1" )
			)
			( pin "@baseboard_fab2_lib.baseboard_fab2(sch_1):page207_i48:b"
				( attribute "PN" "2"
					( Origin gPackager )
				)
				( objectStatus "C9R11.2" )
			)
			( pin "@baseboard_fab2_lib.baseboard_fab2(sch_1):page207_i50:a"
				( attribute "PN" "1"
					( Origin gPackager )
				)
				( objectStatus "C9P22.1" )
			)
			( pin "@baseboard_fab2_lib.baseboard_fab2(sch_1):page207_i50:b"
				( attribute "PN" "2"
					( Origin gPackager )
				)
				( objectStatus "C9P22.2" )
			)
			( pin "@baseboard_fab2_lib.baseboard_fab2(sch_1):page207_i51:a"
				( attribute "PN" "1"
					( Origin gPackager )
				)
				( objectStatus "C9P25.1" )
			)
			( pin "@baseboard_fab2_lib.baseboard_fab2(sch_1):page207_i51:b"
				( attribute "PN" "2"
					( Origin gPackager )
				)
				( objectStatus "C9P25.2" )
			)
			( pin "@baseboard_fab2_lib.baseboard_fab2(sch_1):page207_i54:a"
				( attribute "PN" "1"
					( Origin gPackager )
				)
				( objectStatus "C9P26.1" )
			)
			( pin "@baseboard_fab2_lib.baseboard_fab2(sch_1):page207_i54:b"
				( attribute "PN" "2"
					( Origin gPackager )
				)
				( objectStatus "C9P26.2" )
			)
			( pin "@baseboard_fab2_lib.baseboard_fab2(sch_1):page207_i58:a"
				( attribute "PN" "1"
					( Origin gPackager )
				)
				( objectStatus "C1E9.1" )
			)
			( pin "@baseboard_fab2_lib.baseboard_fab2(sch_1):page207_i58:b"
				( attribute "PN" "2"
					( Origin gPackager )
				)
				( objectStatus "C1E9.2" )
			)
			( pin "@baseboard_fab2_lib.baseboard_fab2(sch_1):page207_i59:a"
				( attribute "PN" "1"
					( Origin gPackager )
				)
				( objectStatus "C9P3.1" )
			)
			( pin "@baseboard_fab2_lib.baseboard_fab2(sch_1):page207_i59:b"
				( attribute "PN" "2"
					( Origin gPackager )
				)
				( objectStatus "C9P3.2" )
			)
			( pin "@baseboard_fab2_lib.baseboard_fab2(sch_1):page207_i67:a"
				( attribute "PN" "1"
					( Origin gPackager )
				)
				( objectStatus "R1E13.1" )
			)
			( pin "@baseboard_fab2_lib.baseboard_fab2(sch_1):page207_i67:b"
				( attribute "PN" "2"
					( Origin gPackager )
				)
				( objectStatus "R1E13.2" )
			)
			( pin "@baseboard_fab2_lib.baseboard_fab2(sch_1):page207_i68:a"
				( attribute "PN" "1"
					( Origin gPackager )
				)
				( objectStatus "R1E14.1" )
			)
			( pin "@baseboard_fab2_lib.baseboard_fab2(sch_1):page207_i68:b"
				( attribute "PN" "2"
					( Origin gPackager )
				)
				( objectStatus "R1E14.2" )
			)
			( pin "@baseboard_fab2_lib.baseboard_fab2(sch_1):page208_i7:a"
				( attribute "PN" "1"
					( Origin gPackager )
				)
				( objectStatus "R1E3.1" )
			)
			( pin "@baseboard_fab2_lib.baseboard_fab2(sch_1):page208_i7:b"
				( attribute "PN" "2"
					( Origin gPackager )
				)
				( objectStatus "R1E3.2" )
			)
			( pin "@baseboard_fab2_lib.baseboard_fab2(sch_1):page208_i9:a"
				( attribute "PN" "1"
					( Origin gPackager )
				)
				( objectStatus "C1D14.1" )
			)
			( pin "@baseboard_fab2_lib.baseboard_fab2(sch_1):page208_i9:b"
				( attribute "PN" "2"
					( Origin gPackager )
				)
				( objectStatus "C1D14.2" )
			)
			( pin "@baseboard_fab2_lib.baseboard_fab2(sch_1):page161_i139:\1\"
				( attribute "PN" "1"
					( Origin gPackager )
				)
				( objectStatus "J1F2.1" )
			)
			( pin "@baseboard_fab2_lib.baseboard_fab2(sch_1):page161_i139:\2\"
				( attribute "PN" "2"
					( Origin gPackager )
				)
				( objectStatus "J1F2.2" )
			)
			( pin "@baseboard_fab2_lib.baseboard_fab2(sch_1):page161_i139:\3\"
				( attribute "PN" "3"
					( Origin gPackager )
				)
				( objectStatus "J1F2.3" )
			)
			( pin "@baseboard_fab2_lib.baseboard_fab2(sch_1):page161_i139:\4\"
				( attribute "PN" "4"
					( Origin gPackager )
				)
				( objectStatus "J1F2.4" )
			)
			( pin "@baseboard_fab2_lib.baseboard_fab2(sch_1):page161_i139:np1"
				( attribute "PN" "NP1"
					( Origin gPackager )
				)
				( objectStatus "J1F2.NP1" )
			)
			( pin "@baseboard_fab2_lib.baseboard_fab2(sch_1):page208_i12:a"
				( attribute "PN" "1"
					( Origin gPackager )
				)
				( objectStatus "C9P8.1" )
			)
			( pin "@baseboard_fab2_lib.baseboard_fab2(sch_1):page208_i12:b"
				( attribute "PN" "2"
					( Origin gPackager )
				)
				( objectStatus "C9P8.2" )
			)
			( pin "@baseboard_fab2_lib.baseboard_fab2(sch_1):page208_i14:a"
				( attribute "PN" "1"
					( Origin gPackager )
				)
				( objectStatus "C9P5.1" )
			)
			( pin "@baseboard_fab2_lib.baseboard_fab2(sch_1):page208_i14:b"
				( attribute "PN" "2"
					( Origin gPackager )
				)
				( objectStatus "C9P5.2" )
			)
			( pin "@baseboard_fab2_lib.baseboard_fab2(sch_1):page209_i80:f"
				( attribute "PN" "2"
					( Origin gPackager )
				)
				( objectStatus "L1C2.2" )
			)
			( pin "@baseboard_fab2_lib.baseboard_fab2(sch_1):page209_i80:s"
				( attribute "PN" "1"
					( Origin gPackager )
				)
				( objectStatus "L1C2.1" )
			)
			( pin "@baseboard_fab2_lib.baseboard_fab2(sch_1):page208_i22:a"
				( attribute "PN" "1"
					( Origin gPackager )
				)
				( objectStatus "C1D3.1" )
			)
			( pin "@baseboard_fab2_lib.baseboard_fab2(sch_1):page208_i22:b"
				( attribute "PN" "2"
					( Origin gPackager )
				)
				( objectStatus "C1D3.2" )
			)
			( pin "@baseboard_fab2_lib.baseboard_fab2(sch_1):page208_i24:a"
				( attribute "PN" "1"
					( Origin gPackager )
				)
				( objectStatus "C9N24.1" )
			)
			( pin "@baseboard_fab2_lib.baseboard_fab2(sch_1):page208_i24:b"
				( attribute "PN" "2"
					( Origin gPackager )
				)
				( objectStatus "C9N24.2" )
			)
			( pin "@baseboard_fab2_lib.baseboard_fab2(sch_1):page208_i25:a"
				( attribute "PN" "1"
					( Origin gPackager )
				)
				( objectStatus "C9R9.1" )
			)
			( pin "@baseboard_fab2_lib.baseboard_fab2(sch_1):page208_i25:b"
				( attribute "PN" "2"
					( Origin gPackager )
				)
				( objectStatus "C9R9.2" )
			)
			( pin "@baseboard_fab2_lib.baseboard_fab2(sch_1):page208_i26:a"
				( attribute "PN" "1"
					( Origin gPackager )
				)
				( objectStatus "C9R3.1" )
			)
			( pin "@baseboard_fab2_lib.baseboard_fab2(sch_1):page208_i26:b"
				( attribute "PN" "2"
					( Origin gPackager )
				)
				( objectStatus "C9R3.2" )
			)
			( pin "@baseboard_fab2_lib.baseboard_fab2(sch_1):page208_i27:boost"
				( attribute "PN" "33"
					( Origin gPackager )
				)
				( objectStatus "EU1D3.33" )
			)
			( pin "@baseboard_fab2_lib.baseboard_fab2(sch_1):page208_i27:en"
				( attribute "PN" "35"
					( Origin gPackager )
				)
				( objectStatus "EU1D3.35" )
			)
			( pin "@baseboard_fab2_lib.baseboard_fab2(sch_1):page208_i27:gl(0)"
				( attribute "PN" "6"
					( Origin gPackager )
				)
				( objectStatus "EU1D3.6" )
			)
			( pin "@baseboard_fab2_lib.baseboard_fab2(sch_1):page208_i27:gl(1)"
				( attribute "PN" "41"
					( Origin gPackager )
				)
				( objectStatus "EU1D3.41" )
			)
			( pin "@baseboard_fab2_lib.baseboard_fab2(sch_1):page208_i27:iout"
				( attribute "PN" "38"
					( Origin gPackager )
				)
				( objectStatus "EU1D3.38" )
			)
			( pin "@baseboard_fab2_lib.baseboard_fab2(sch_1):page208_i27:lgnd"
				( attribute "PN" "2"
					( Origin gPackager )
				)
				( objectStatus "EU1D3.2" )
			)
			( pin "@baseboard_fab2_lib.baseboard_fab2(sch_1):page208_i27:nc"
				( attribute "PN" "31"
					( Origin gPackager )
				)
				( objectStatus "EU1D3.31" )
			)
			( pin "@baseboard_fab2_lib.baseboard_fab2(sch_1):page208_i27:ocset"
				( attribute "PN" "37"
					( Origin gPackager )
				)
				( objectStatus "EU1D3.37" )
			)
			( pin "@baseboard_fab2_lib.baseboard_fab2(sch_1):page208_i27:pgnd(0)"
				( attribute "PN" "5"
					( Origin gPackager )
				)
				( objectStatus "EU1D3.5" )
			)
			( pin "@baseboard_fab2_lib.baseboard_fab2(sch_1):page208_i27:pgnd(1)"
				( attribute "PN" "7"
					( Origin gPackager )
				)
				( objectStatus "EU1D3.7" )
			)
			( pin "@baseboard_fab2_lib.baseboard_fab2(sch_1):page208_i27:pgnd(2)"
				( attribute "PN" "40"
					( Origin gPackager )
				)
				( objectStatus "EU1D3.40" )
			)
			( pin "@baseboard_fab2_lib.baseboard_fab2(sch_1):page208_i27:phase"
				( attribute "PN" "32"
					( Origin gPackager )
				)
				( objectStatus "EU1D3.32" )
			)
			( pin "@baseboard_fab2_lib.baseboard_fab2(sch_1):page208_i27:pwm"
				( attribute "PN" "34"
					( Origin gPackager )
				)
				( objectStatus "EU1D3.34" )
			)
			( pin "@baseboard_fab2_lib.baseboard_fab2(sch_1):page208_i27:refin"
				( attribute "PN" "39"
					( Origin gPackager )
				)
				( objectStatus "EU1D3.39" )
			)
			( pin "@baseboard_fab2_lib.baseboard_fab2(sch_1):page208_i27:sw"
				( attribute "PN" "10"
					( Origin gPackager )
				)
				( objectStatus "EU1D3.10" )
			)
			( pin "@baseboard_fab2_lib.baseboard_fab2(sch_1):page208_i27:tout_flt"
				( attribute "PN" "36"
					( Origin gPackager )
				)
				( objectStatus "EU1D3.36" )
			)
			( pin "@baseboard_fab2_lib.baseboard_fab2(sch_1):page208_i27:vcc"
				( attribute "PN" "3"
					( Origin gPackager )
				)
				( objectStatus "EU1D3.3" )
			)
			( pin "@baseboard_fab2_lib.baseboard_fab2(sch_1):page208_i27:vdrv"
				( attribute "PN" "4"
					( Origin gPackager )
				)
				( objectStatus "EU1D3.4" )
			)
			( pin "@baseboard_fab2_lib.baseboard_fab2(sch_1):page208_i27:vin(0)"
				( attribute "PN" "25"
					( Origin gPackager )
				)
				( objectStatus "EU1D3.25" )
			)
			( pin "@baseboard_fab2_lib.baseboard_fab2(sch_1):page208_i27:vin(1)"
				( attribute "PN" "30"
					( Origin gPackager )
				)
				( objectStatus "EU1D3.30" )
			)
			( pin "@baseboard_fab2_lib.baseboard_fab2(sch_1):page208_i27:vos"
				( attribute "PN" "1"
					( Origin gPackager )
				)
				( objectStatus "EU1D3.1" )
			)
			( pin "@baseboard_fab2_lib.baseboard_fab2(sch_1):page208_i28:a"
				( attribute "PN" "1"
					( Origin gPackager )
				)
				( objectStatus "C9P23.1" )
			)
			( pin "@baseboard_fab2_lib.baseboard_fab2(sch_1):page208_i28:b"
				( attribute "PN" "2"
					( Origin gPackager )
				)
				( objectStatus "C9P23.2" )
			)
			( pin "@baseboard_fab2_lib.baseboard_fab2(sch_1):page208_i30:a"
				( attribute "PN" "1"
					( Origin gPackager )
				)
				( objectStatus "C9P18.1" )
			)
			( pin "@baseboard_fab2_lib.baseboard_fab2(sch_1):page208_i30:b"
				( attribute "PN" "2"
					( Origin gPackager )
				)
				( objectStatus "C9P18.2" )
			)
			( pin "@baseboard_fab2_lib.baseboard_fab2(sch_1):page216_i146:a"
				( attribute "PN" "1"
					( Origin gPackager )
				)
				( objectStatus "R3U9.1" )
			)
			( pin "@baseboard_fab2_lib.baseboard_fab2(sch_1):page216_i146:b"
				( attribute "PN" "2"
					( Origin gPackager )
				)
				( objectStatus "R3U9.2" )
			)
			( pin "@baseboard_fab2_lib.baseboard_fab2(sch_1):page208_i38:a"
				( attribute "PN" "1"
					( Origin gPackager )
				)
				( objectStatus "C1D16.1" )
			)
			( pin "@baseboard_fab2_lib.baseboard_fab2(sch_1):page208_i38:b"
				( attribute "PN" "2"
					( Origin gPackager )
				)
				( objectStatus "C1D16.2" )
			)
			( pin "@baseboard_fab2_lib.baseboard_fab2(sch_1):page207_i110:\1\"
				( attribute "PN" "1"
					( Origin gPackager )
				)
				( objectStatus "C1E6.1" )
			)
			( pin "@baseboard_fab2_lib.baseboard_fab2(sch_1):page207_i110:\2\"
				( attribute "PN" "2"
					( Origin gPackager )
				)
				( objectStatus "C1E6.2" )
			)
			( pin "@baseboard_fab2_lib.baseboard_fab2(sch_1):page208_i40:a"
				( attribute "PN" "1"
					( Origin gPackager )
				)
				( objectStatus "C1D20.1" )
			)
			( pin "@baseboard_fab2_lib.baseboard_fab2(sch_1):page208_i40:b"
				( attribute "PN" "2"
					( Origin gPackager )
				)
				( objectStatus "C1D20.2" )
			)
			( pin "@baseboard_fab2_lib.baseboard_fab2(sch_1):page208_i43:a"
				( attribute "PN" "1"
					( Origin gPackager )
				)
				( objectStatus "C1D17.1" )
			)
			( pin "@baseboard_fab2_lib.baseboard_fab2(sch_1):page208_i43:b"
				( attribute "PN" "2"
					( Origin gPackager )
				)
				( objectStatus "C1D17.2" )
			)
			( pin "@baseboard_fab2_lib.baseboard_fab2(sch_1):page208_i44:a"
				( attribute "PN" "1"
					( Origin gPackager )
				)
				( objectStatus "C1D28.1" )
			)
			( pin "@baseboard_fab2_lib.baseboard_fab2(sch_1):page208_i44:b"
				( attribute "PN" "2"
					( Origin gPackager )
				)
				( objectStatus "C1D28.2" )
			)
			( pin "@baseboard_fab2_lib.baseboard_fab2(sch_1):page208_i45:a"
				( attribute "PN" "1"
					( Origin gPackager )
				)
				( objectStatus "C1D23.1" )
			)
			( pin "@baseboard_fab2_lib.baseboard_fab2(sch_1):page208_i45:b"
				( attribute "PN" "2"
					( Origin gPackager )
				)
				( objectStatus "C1D23.2" )
			)
			( pin "@baseboard_fab2_lib.baseboard_fab2(sch_1):page208_i46:a"
				( attribute "PN" "1"
					( Origin gPackager )
				)
				( objectStatus "C1D6.1" )
			)
			( pin "@baseboard_fab2_lib.baseboard_fab2(sch_1):page208_i46:b"
				( attribute "PN" "2"
					( Origin gPackager )
				)
				( objectStatus "C1D6.2" )
			)
			( pin "@baseboard_fab2_lib.baseboard_fab2(sch_1):page207_i109:\1\"
				( attribute "PN" "1"
					( Origin gPackager )
				)
				( objectStatus "C1E23.1" )
			)
			( pin "@baseboard_fab2_lib.baseboard_fab2(sch_1):page207_i109:\2\"
				( attribute "PN" "2"
					( Origin gPackager )
				)
				( objectStatus "C1E23.2" )
			)
			( pin "@baseboard_fab2_lib.baseboard_fab2(sch_1):page208_i48:a"
				( attribute "PN" "1"
					( Origin gPackager )
				)
				( objectStatus "C1D10.1" )
			)
			( pin "@baseboard_fab2_lib.baseboard_fab2(sch_1):page208_i48:b"
				( attribute "PN" "2"
					( Origin gPackager )
				)
				( objectStatus "C1D10.2" )
			)
			( pin "@baseboard_fab2_lib.baseboard_fab2(sch_1):page209_i79:a"
				( attribute "PN" "1"
					( Origin gPackager )
				)
				( objectStatus "R9P32.1" )
			)
			( pin "@baseboard_fab2_lib.baseboard_fab2(sch_1):page209_i79:b"
				( attribute "PN" "2"
					( Origin gPackager )
				)
				( objectStatus "R9P32.2" )
			)
			( pin "@baseboard_fab2_lib.baseboard_fab2(sch_1):page208_i50:a"
				( attribute "PN" "1"
					( Origin gPackager )
				)
				( objectStatus "C1D7.1" )
			)
			( pin "@baseboard_fab2_lib.baseboard_fab2(sch_1):page208_i50:b"
				( attribute "PN" "2"
					( Origin gPackager )
				)
				( objectStatus "C1D7.2" )
			)
			( pin "@baseboard_fab2_lib.baseboard_fab2(sch_1):page208_i51:a"
				( attribute "PN" "1"
					( Origin gPackager )
				)
				( objectStatus "C1D13.1" )
			)
			( pin "@baseboard_fab2_lib.baseboard_fab2(sch_1):page208_i51:b"
				( attribute "PN" "2"
					( Origin gPackager )
				)
				( objectStatus "C1D13.2" )
			)
			( pin "@baseboard_fab2_lib.baseboard_fab2(sch_1):page208_i52:a"
				( attribute "PN" "1"
					( Origin gPackager )
				)
				( objectStatus "C1D12.1" )
			)
			( pin "@baseboard_fab2_lib.baseboard_fab2(sch_1):page208_i52:b"
				( attribute "PN" "2"
					( Origin gPackager )
				)
				( objectStatus "C1D12.2" )
			)
			( pin "@baseboard_fab2_lib.baseboard_fab2(sch_1):page208_i53:a"
				( attribute "PN" "1"
					( Origin gPackager )
				)
				( objectStatus "C9P4.1" )
			)
			( pin "@baseboard_fab2_lib.baseboard_fab2(sch_1):page208_i53:b"
				( attribute "PN" "2"
					( Origin gPackager )
				)
				( objectStatus "C9P4.2" )
			)
			( pin "@baseboard_fab2_lib.baseboard_fab2(sch_1):page208_i54:a"
				( attribute "PN" "1"
					( Origin gPackager )
				)
				( objectStatus "C9P7.1" )
			)
			( pin "@baseboard_fab2_lib.baseboard_fab2(sch_1):page208_i54:b"
				( attribute "PN" "2"
					( Origin gPackager )
				)
				( objectStatus "C9P7.2" )
			)
			( pin "@baseboard_fab2_lib.baseboard_fab2(sch_1):page208_i55:a"
				( attribute "PN" "1"
					( Origin gPackager )
				)
				( objectStatus "C9P9.1" )
			)
			( pin "@baseboard_fab2_lib.baseboard_fab2(sch_1):page208_i55:b"
				( attribute "PN" "2"
					( Origin gPackager )
				)
				( objectStatus "C9P9.2" )
			)
			( pin "@baseboard_fab2_lib.baseboard_fab2(sch_1):page208_i58:a"
				( attribute "PN" "1"
					( Origin gPackager )
				)
				( objectStatus "C9P24.1" )
			)
			( pin "@baseboard_fab2_lib.baseboard_fab2(sch_1):page208_i58:b"
				( attribute "PN" "2"
					( Origin gPackager )
				)
				( objectStatus "C9P24.2" )
			)
			( pin "@baseboard_fab2_lib.baseboard_fab2(sch_1):page208_i59:a"
				( attribute "PN" "1"
					( Origin gPackager )
				)
				( objectStatus "C9P1.1" )
			)
			( pin "@baseboard_fab2_lib.baseboard_fab2(sch_1):page208_i59:b"
				( attribute "PN" "2"
					( Origin gPackager )
				)
				( objectStatus "C9P1.2" )
			)
			( pin "@baseboard_fab2_lib.baseboard_fab2(sch_1):page208_i60:a"
				( attribute "PN" "1"
					( Origin gPackager )
				)
				( objectStatus "C9P2.1" )
			)
			( pin "@baseboard_fab2_lib.baseboard_fab2(sch_1):page208_i60:b"
				( attribute "PN" "2"
					( Origin gPackager )
				)
				( objectStatus "C9P2.2" )
			)
			( pin "@baseboard_fab2_lib.baseboard_fab2(sch_1):page208_i66:a"
				( attribute "PN" "1"
					( Origin gPackager )
				)
				( objectStatus "C9P10.1" )
			)
			( pin "@baseboard_fab2_lib.baseboard_fab2(sch_1):page208_i66:b"
				( attribute "PN" "2"
					( Origin gPackager )
				)
				( objectStatus "C9P10.2" )
			)
			( pin "@baseboard_fab2_lib.baseboard_fab2(sch_1):page208_i67:a"
				( attribute "PN" "1"
					( Origin gPackager )
				)
				( objectStatus "C9R2.1" )
			)
			( pin "@baseboard_fab2_lib.baseboard_fab2(sch_1):page208_i67:b"
				( attribute "PN" "2"
					( Origin gPackager )
				)
				( objectStatus "C9R2.2" )
			)
			( pin "@baseboard_fab2_lib.baseboard_fab2(sch_1):page208_i71:boost"
				( attribute "PN" "33"
					( Origin gPackager )
				)
				( objectStatus "EU1D1.33" )
			)
			( pin "@baseboard_fab2_lib.baseboard_fab2(sch_1):page208_i71:en"
				( attribute "PN" "35"
					( Origin gPackager )
				)
				( objectStatus "EU1D1.35" )
			)
			( pin "@baseboard_fab2_lib.baseboard_fab2(sch_1):page208_i71:gl(0)"
				( attribute "PN" "6"
					( Origin gPackager )
				)
				( objectStatus "EU1D1.6" )
			)
			( pin "@baseboard_fab2_lib.baseboard_fab2(sch_1):page208_i71:gl(1)"
				( attribute "PN" "41"
					( Origin gPackager )
				)
				( objectStatus "EU1D1.41" )
			)
			( pin "@baseboard_fab2_lib.baseboard_fab2(sch_1):page208_i71:iout"
				( attribute "PN" "38"
					( Origin gPackager )
				)
				( objectStatus "EU1D1.38" )
			)
			( pin "@baseboard_fab2_lib.baseboard_fab2(sch_1):page208_i71:lgnd"
				( attribute "PN" "2"
					( Origin gPackager )
				)
				( objectStatus "EU1D1.2" )
			)
			( pin "@baseboard_fab2_lib.baseboard_fab2(sch_1):page208_i71:nc"
				( attribute "PN" "31"
					( Origin gPackager )
				)
				( objectStatus "EU1D1.31" )
			)
			( pin "@baseboard_fab2_lib.baseboard_fab2(sch_1):page208_i71:ocset"
				( attribute "PN" "37"
					( Origin gPackager )
				)
				( objectStatus "EU1D1.37" )
			)
			( pin "@baseboard_fab2_lib.baseboard_fab2(sch_1):page208_i71:pgnd(0)"
				( attribute "PN" "5"
					( Origin gPackager )
				)
				( objectStatus "EU1D1.5" )
			)
			( pin "@baseboard_fab2_lib.baseboard_fab2(sch_1):page208_i71:pgnd(1)"
				( attribute "PN" "7"
					( Origin gPackager )
				)
				( objectStatus "EU1D1.7" )
			)
			( pin "@baseboard_fab2_lib.baseboard_fab2(sch_1):page208_i71:pgnd(2)"
				( attribute "PN" "40"
					( Origin gPackager )
				)
				( objectStatus "EU1D1.40" )
			)
			( pin "@baseboard_fab2_lib.baseboard_fab2(sch_1):page208_i71:phase"
				( attribute "PN" "32"
					( Origin gPackager )
				)
				( objectStatus "EU1D1.32" )
			)
			( pin "@baseboard_fab2_lib.baseboard_fab2(sch_1):page208_i71:pwm"
				( attribute "PN" "34"
					( Origin gPackager )
				)
				( objectStatus "EU1D1.34" )
			)
			( pin "@baseboard_fab2_lib.baseboard_fab2(sch_1):page208_i71:refin"
				( attribute "PN" "39"
					( Origin gPackager )
				)
				( objectStatus "EU1D1.39" )
			)
			( pin "@baseboard_fab2_lib.baseboard_fab2(sch_1):page208_i71:sw"
				( attribute "PN" "10"
					( Origin gPackager )
				)
				( objectStatus "EU1D1.10" )
			)
			( pin "@baseboard_fab2_lib.baseboard_fab2(sch_1):page208_i71:tout_flt"
				( attribute "PN" "36"
					( Origin gPackager )
				)
				( objectStatus "EU1D1.36" )
			)
			( pin "@baseboard_fab2_lib.baseboard_fab2(sch_1):page208_i71:vcc"
				( attribute "PN" "3"
					( Origin gPackager )
				)
				( objectStatus "EU1D1.3" )
			)
			( pin "@baseboard_fab2_lib.baseboard_fab2(sch_1):page208_i71:vdrv"
				( attribute "PN" "4"
					( Origin gPackager )
				)
				( objectStatus "EU1D1.4" )
			)
			( pin "@baseboard_fab2_lib.baseboard_fab2(sch_1):page208_i71:vin(0)"
				( attribute "PN" "25"
					( Origin gPackager )
				)
				( objectStatus "EU1D1.25" )
			)
			( pin "@baseboard_fab2_lib.baseboard_fab2(sch_1):page208_i71:vin(1)"
				( attribute "PN" "30"
					( Origin gPackager )
				)
				( objectStatus "EU1D1.30" )
			)
			( pin "@baseboard_fab2_lib.baseboard_fab2(sch_1):page208_i71:vos"
				( attribute "PN" "1"
					( Origin gPackager )
				)
				( objectStatus "EU1D1.1" )
			)
			( pin "@baseboard_fab2_lib.baseboard_fab2(sch_1):page208_i75:a"
				( attribute "PN" "1"
					( Origin gPackager )
				)
				( objectStatus "R1D54.1" )
			)
			( pin "@baseboard_fab2_lib.baseboard_fab2(sch_1):page208_i75:b"
				( attribute "PN" "2"
					( Origin gPackager )
				)
				( objectStatus "R1D54.2" )
			)
			( pin "@baseboard_fab2_lib.baseboard_fab2(sch_1):page208_i76:a"
				( attribute "PN" "1"
					( Origin gPackager )
				)
				( objectStatus "R1D55.1" )
			)
			( pin "@baseboard_fab2_lib.baseboard_fab2(sch_1):page208_i76:b"
				( attribute "PN" "2"
					( Origin gPackager )
				)
				( objectStatus "R1D55.2" )
			)
			( pin "@baseboard_fab2_lib.baseboard_fab2(sch_1):page209_i3:a"
				( attribute "PN" "1"
					( Origin gPackager )
				)
				( objectStatus "R1E5.1" )
			)
			( pin "@baseboard_fab2_lib.baseboard_fab2(sch_1):page209_i3:b"
				( attribute "PN" "2"
					( Origin gPackager )
				)
				( objectStatus "R1E5.2" )
			)
			( pin "@baseboard_fab2_lib.baseboard_fab2(sch_1):page209_i5:a"
				( attribute "PN" "1"
					( Origin gPackager )
				)
				( objectStatus "C9N27.1" )
			)
			( pin "@baseboard_fab2_lib.baseboard_fab2(sch_1):page209_i5:b"
				( attribute "PN" "2"
					( Origin gPackager )
				)
				( objectStatus "C9N27.2" )
			)
			( pin "@baseboard_fab2_lib.baseboard_fab2(sch_1):page209_i7:a"
				( attribute "PN" "1"
					( Origin gPackager )
				)
				( objectStatus "C9N26.1" )
			)
			( pin "@baseboard_fab2_lib.baseboard_fab2(sch_1):page209_i7:b"
				( attribute "PN" "2"
					( Origin gPackager )
				)
				( objectStatus "C9N26.2" )
			)
			( pin "@baseboard_fab2_lib.baseboard_fab2(sch_1):page209_i8:a"
				( attribute "PN" "1"
					( Origin gPackager )
				)
				( objectStatus "C9N25.1" )
			)
			( pin "@baseboard_fab2_lib.baseboard_fab2(sch_1):page209_i8:b"
				( attribute "PN" "2"
					( Origin gPackager )
				)
				( objectStatus "C9N25.2" )
			)
			( pin "@baseboard_fab2_lib.baseboard_fab2(sch_1):page209_i9:a"
				( attribute "PN" "1"
					( Origin gPackager )
				)
				( objectStatus "R1E8.1" )
			)
			( pin "@baseboard_fab2_lib.baseboard_fab2(sch_1):page209_i9:b"
				( attribute "PN" "2"
					( Origin gPackager )
				)
				( objectStatus "R1E8.2" )
			)
			( pin "@baseboard_fab2_lib.baseboard_fab2(sch_1):page209_i10:a"
				( attribute "PN" "1"
					( Origin gPackager )
				)
				( objectStatus "R1E7.1" )
			)
			( pin "@baseboard_fab2_lib.baseboard_fab2(sch_1):page209_i10:b"
				( attribute "PN" "2"
					( Origin gPackager )
				)
				( objectStatus "R1E7.2" )
			)
			( pin "@baseboard_fab2_lib.baseboard_fab2(sch_1):page209_i11:a"
				( attribute "PN" "1"
					( Origin gPackager )
				)
				( objectStatus "R1E6.1" )
			)
			( pin "@baseboard_fab2_lib.baseboard_fab2(sch_1):page209_i11:b"
				( attribute "PN" "2"
					( Origin gPackager )
				)
				( objectStatus "R1E6.2" )
			)
			( pin "@baseboard_fab2_lib.baseboard_fab2(sch_1):page209_i15:a"
				( attribute "PN" "1"
					( Origin gPackager )
				)
				( objectStatus "R1E4.1" )
			)
			( pin "@baseboard_fab2_lib.baseboard_fab2(sch_1):page209_i15:b"
				( attribute "PN" "2"
					( Origin gPackager )
				)
				( objectStatus "R1E4.2" )
			)
			( pin "@baseboard_fab2_lib.baseboard_fab2(sch_1):page209_i16:a"
				( attribute "PN" "1"
					( Origin gPackager )
				)
				( objectStatus "C1C26.1" )
			)
			( pin "@baseboard_fab2_lib.baseboard_fab2(sch_1):page209_i16:b"
				( attribute "PN" "2"
					( Origin gPackager )
				)
				( objectStatus "C1C26.2" )
			)
			( pin "@baseboard_fab2_lib.baseboard_fab2(sch_1):page209_i17:a"
				( attribute "PN" "1"
					( Origin gPackager )
				)
				( objectStatus "C1C25.1" )
			)
			( pin "@baseboard_fab2_lib.baseboard_fab2(sch_1):page209_i17:b"
				( attribute "PN" "2"
					( Origin gPackager )
				)
				( objectStatus "C1C25.2" )
			)
			( pin "@baseboard_fab2_lib.baseboard_fab2(sch_1):page209_i18:a"
				( attribute "PN" "1"
					( Origin gPackager )
				)
				( objectStatus "C1D32.1" )
			)
			( pin "@baseboard_fab2_lib.baseboard_fab2(sch_1):page209_i18:b"
				( attribute "PN" "2"
					( Origin gPackager )
				)
				( objectStatus "C1D32.2" )
			)
			( pin "@baseboard_fab2_lib.baseboard_fab2(sch_1):page209_i20:a"
				( attribute "PN" "1"
					( Origin gPackager )
				)
				( objectStatus "C1C24.1" )
			)
			( pin "@baseboard_fab2_lib.baseboard_fab2(sch_1):page209_i20:b"
				( attribute "PN" "2"
					( Origin gPackager )
				)
				( objectStatus "C1C24.2" )
			)
			( pin "@baseboard_fab2_lib.baseboard_fab2(sch_1):page227_i147:\1\"
				( attribute "PN" "1"
					( Origin gPackager )
				)
				( objectStatus "C1A11.1" )
			)
			( pin "@baseboard_fab2_lib.baseboard_fab2(sch_1):page227_i147:\2\"
				( attribute "PN" "2"
					( Origin gPackager )
				)
				( objectStatus "C1A11.2" )
			)
			( pin "@baseboard_fab2_lib.baseboard_fab2(sch_1):page209_i22:a"
				( attribute "PN" "1"
					( Origin gPackager )
				)
				( objectStatus "C1D33.1" )
			)
			( pin "@baseboard_fab2_lib.baseboard_fab2(sch_1):page209_i22:b"
				( attribute "PN" "2"
					( Origin gPackager )
				)
				( objectStatus "C1D33.2" )
			)
			( pin "@baseboard_fab2_lib.baseboard_fab2(sch_1):page210_i71:a"
				( attribute "PN" "1"
					( Origin gPackager )
				)
				( objectStatus "R9N3.1" )
			)
			( pin "@baseboard_fab2_lib.baseboard_fab2(sch_1):page210_i71:b"
				( attribute "PN" "2"
					( Origin gPackager )
				)
				( objectStatus "R9N3.2" )
			)
			( pin "@baseboard_fab2_lib.baseboard_fab2(sch_1):page133_i370:a"
				( attribute "PN" "1"
					( Origin gPackager )
				)
				( objectStatus "R3P7.1" )
			)
			( pin "@baseboard_fab2_lib.baseboard_fab2(sch_1):page133_i370:b"
				( attribute "PN" "2"
					( Origin gPackager )
				)
				( objectStatus "R3P7.2" )
			)
			( pin "@baseboard_fab2_lib.baseboard_fab2(sch_1):page217_i261:f"
				( attribute "PN" "2"
					( Origin gPackager )
				)
				( objectStatus "L7F2.2" )
			)
			( pin "@baseboard_fab2_lib.baseboard_fab2(sch_1):page217_i261:s"
				( attribute "PN" "1"
					( Origin gPackager )
				)
				( objectStatus "L7F2.1" )
			)
			( pin "@baseboard_fab2_lib.baseboard_fab2(sch_1):page209_i35:a"
				( attribute "PN" "1"
					( Origin gPackager )
				)
				( objectStatus "C1C1.1" )
			)
			( pin "@baseboard_fab2_lib.baseboard_fab2(sch_1):page209_i35:b"
				( attribute "PN" "2"
					( Origin gPackager )
				)
				( objectStatus "C1C1.2" )
			)
			( pin "@baseboard_fab2_lib.baseboard_fab2(sch_1):page209_i37:a"
				( attribute "PN" "1"
					( Origin gPackager )
				)
				( objectStatus "C1E18.1" )
			)
			( pin "@baseboard_fab2_lib.baseboard_fab2(sch_1):page209_i37:b"
				( attribute "PN" "2"
					( Origin gPackager )
				)
				( objectStatus "C1E18.2" )
			)
			( pin "@baseboard_fab2_lib.baseboard_fab2(sch_1):page209_i38:a"
				( attribute "PN" "1"
					( Origin gPackager )
				)
				( objectStatus "C1C2.1" )
			)
			( pin "@baseboard_fab2_lib.baseboard_fab2(sch_1):page209_i38:b"
				( attribute "PN" "2"
					( Origin gPackager )
				)
				( objectStatus "C1C2.2" )
			)
			( pin "@baseboard_fab2_lib.baseboard_fab2(sch_1):page219_i157:f"
				( attribute "PN" "2"
					( Origin gPackager )
				)
				( objectStatus "L7A1.2" )
			)
			( pin "@baseboard_fab2_lib.baseboard_fab2(sch_1):page219_i157:s"
				( attribute "PN" "1"
					( Origin gPackager )
				)
				( objectStatus "L7A1.1" )
			)
			( pin "@baseboard_fab2_lib.baseboard_fab2(sch_1):page209_i42:a"
				( attribute "PN" "1"
					( Origin gPackager )
				)
				( objectStatus "C1D24.1" )
			)
			( pin "@baseboard_fab2_lib.baseboard_fab2(sch_1):page209_i42:b"
				( attribute "PN" "2"
					( Origin gPackager )
				)
				( objectStatus "C1D24.2" )
			)
			( pin "@baseboard_fab2_lib.baseboard_fab2(sch_1):page209_i55:a"
				( attribute "PN" "1"
					( Origin gPackager )
				)
				( objectStatus "C9P20.1" )
			)
			( pin "@baseboard_fab2_lib.baseboard_fab2(sch_1):page209_i55:b"
				( attribute "PN" "2"
					( Origin gPackager )
				)
				( objectStatus "C9P20.2" )
			)
			( pin "@baseboard_fab2_lib.baseboard_fab2(sch_1):page209_i56:boost"
				( attribute "PN" "33"
					( Origin gPackager )
				)
				( objectStatus "EU1C3.33" )
			)
			( pin "@baseboard_fab2_lib.baseboard_fab2(sch_1):page209_i56:en"
				( attribute "PN" "35"
					( Origin gPackager )
				)
				( objectStatus "EU1C3.35" )
			)
			( pin "@baseboard_fab2_lib.baseboard_fab2(sch_1):page209_i56:gl(0)"
				( attribute "PN" "6"
					( Origin gPackager )
				)
				( objectStatus "EU1C3.6" )
			)
			( pin "@baseboard_fab2_lib.baseboard_fab2(sch_1):page209_i56:gl(1)"
				( attribute "PN" "41"
					( Origin gPackager )
				)
				( objectStatus "EU1C3.41" )
			)
			( pin "@baseboard_fab2_lib.baseboard_fab2(sch_1):page209_i56:iout"
				( attribute "PN" "38"
					( Origin gPackager )
				)
				( objectStatus "EU1C3.38" )
			)
			( pin "@baseboard_fab2_lib.baseboard_fab2(sch_1):page209_i56:lgnd"
				( attribute "PN" "2"
					( Origin gPackager )
				)
				( objectStatus "EU1C3.2" )
			)
			( pin "@baseboard_fab2_lib.baseboard_fab2(sch_1):page209_i56:nc"
				( attribute "PN" "31"
					( Origin gPackager )
				)
				( objectStatus "EU1C3.31" )
			)
			( pin "@baseboard_fab2_lib.baseboard_fab2(sch_1):page209_i56:ocset"
				( attribute "PN" "37"
					( Origin gPackager )
				)
				( objectStatus "EU1C3.37" )
			)
			( pin "@baseboard_fab2_lib.baseboard_fab2(sch_1):page209_i56:pgnd(0)"
				( attribute "PN" "5"
					( Origin gPackager )
				)
				( objectStatus "EU1C3.5" )
			)
			( pin "@baseboard_fab2_lib.baseboard_fab2(sch_1):page209_i56:pgnd(1)"
				( attribute "PN" "7"
					( Origin gPackager )
				)
				( objectStatus "EU1C3.7" )
			)
			( pin "@baseboard_fab2_lib.baseboard_fab2(sch_1):page209_i56:pgnd(2)"
				( attribute "PN" "40"
					( Origin gPackager )
				)
				( objectStatus "EU1C3.40" )
			)
			( pin "@baseboard_fab2_lib.baseboard_fab2(sch_1):page209_i56:phase"
				( attribute "PN" "32"
					( Origin gPackager )
				)
				( objectStatus "EU1C3.32" )
			)
			( pin "@baseboard_fab2_lib.baseboard_fab2(sch_1):page209_i56:pwm"
				( attribute "PN" "34"
					( Origin gPackager )
				)
				( objectStatus "EU1C3.34" )
			)
			( pin "@baseboard_fab2_lib.baseboard_fab2(sch_1):page209_i56:refin"
				( attribute "PN" "39"
					( Origin gPackager )
				)
				( objectStatus "EU1C3.39" )
			)
			( pin "@baseboard_fab2_lib.baseboard_fab2(sch_1):page209_i56:sw"
				( attribute "PN" "10"
					( Origin gPackager )
				)
				( objectStatus "EU1C3.10" )
			)
			( pin "@baseboard_fab2_lib.baseboard_fab2(sch_1):page209_i56:tout_flt"
				( attribute "PN" "36"
					( Origin gPackager )
				)
				( objectStatus "EU1C3.36" )
			)
			( pin "@baseboard_fab2_lib.baseboard_fab2(sch_1):page209_i56:vcc"
				( attribute "PN" "3"
					( Origin gPackager )
				)
				( objectStatus "EU1C3.3" )
			)
			( pin "@baseboard_fab2_lib.baseboard_fab2(sch_1):page209_i56:vdrv"
				( attribute "PN" "4"
					( Origin gPackager )
				)
				( objectStatus "EU1C3.4" )
			)
			( pin "@baseboard_fab2_lib.baseboard_fab2(sch_1):page209_i56:vin(0)"
				( attribute "PN" "25"
					( Origin gPackager )
				)
				( objectStatus "EU1C3.25" )
			)
			( pin "@baseboard_fab2_lib.baseboard_fab2(sch_1):page209_i56:vin(1)"
				( attribute "PN" "30"
					( Origin gPackager )
				)
				( objectStatus "EU1C3.30" )
			)
			( pin "@baseboard_fab2_lib.baseboard_fab2(sch_1):page209_i56:vos"
				( attribute "PN" "1"
					( Origin gPackager )
				)
				( objectStatus "EU1C3.1" )
			)
			( pin "@baseboard_fab2_lib.baseboard_fab2(sch_1):page209_i59:a"
				( attribute "PN" "1"
					( Origin gPackager )
				)
				( objectStatus "R1D52.1" )
			)
			( pin "@baseboard_fab2_lib.baseboard_fab2(sch_1):page209_i59:b"
				( attribute "PN" "2"
					( Origin gPackager )
				)
				( objectStatus "R1D52.2" )
			)
			( pin "@baseboard_fab2_lib.baseboard_fab2(sch_1):page210_i8:a"
				( attribute "PN" "1"
					( Origin gPackager )
				)
				( objectStatus "C1C19.1" )
			)
			( pin "@baseboard_fab2_lib.baseboard_fab2(sch_1):page210_i8:b"
				( attribute "PN" "2"
					( Origin gPackager )
				)
				( objectStatus "C1C19.2" )
			)
			( pin "@baseboard_fab2_lib.baseboard_fab2(sch_1):page236_i178:f"
				( attribute "PN" "2"
					( Origin gPackager )
				)
				( objectStatus "L7A2.2" )
			)
			( pin "@baseboard_fab2_lib.baseboard_fab2(sch_1):page236_i178:s"
				( attribute "PN" "1"
					( Origin gPackager )
				)
				( objectStatus "L7A2.1" )
			)
			( pin "@baseboard_fab2_lib.baseboard_fab2(sch_1):page210_i12:a"
				( attribute "PN" "1"
					( Origin gPackager )
				)
				( objectStatus "C9N11.1" )
			)
			( pin "@baseboard_fab2_lib.baseboard_fab2(sch_1):page210_i12:b"
				( attribute "PN" "2"
					( Origin gPackager )
				)
				( objectStatus "C9N11.2" )
			)
			( pin "@baseboard_fab2_lib.baseboard_fab2(sch_1):page210_i14:a"
				( attribute "PN" "1"
					( Origin gPackager )
				)
				( objectStatus "C9N20.1" )
			)
			( pin "@baseboard_fab2_lib.baseboard_fab2(sch_1):page210_i14:b"
				( attribute "PN" "2"
					( Origin gPackager )
				)
				( objectStatus "C9N20.2" )
			)
			( pin "@baseboard_fab2_lib.baseboard_fab2(sch_1):page212_i140:a"
				( attribute "PN" "1"
					( Origin gPackager )
				)
				( objectStatus "R3N7.1" )
			)
			( pin "@baseboard_fab2_lib.baseboard_fab2(sch_1):page212_i140:b"
				( attribute "PN" "2"
					( Origin gPackager )
				)
				( objectStatus "R3N7.2" )
			)
			( pin "@baseboard_fab2_lib.baseboard_fab2(sch_1):page210_i22:a"
				( attribute "PN" "1"
					( Origin gPackager )
				)
				( objectStatus "C1C4.1" )
			)
			( pin "@baseboard_fab2_lib.baseboard_fab2(sch_1):page210_i22:b"
				( attribute "PN" "2"
					( Origin gPackager )
				)
				( objectStatus "C1C4.2" )
			)
			( pin "@baseboard_fab2_lib.baseboard_fab2(sch_1):page208_i118:\1\"
				( attribute "PN" "1"
					( Origin gPackager )
				)
				( objectStatus "C1D15.1" )
			)
			( pin "@baseboard_fab2_lib.baseboard_fab2(sch_1):page208_i118:\2\"
				( attribute "PN" "2"
					( Origin gPackager )
				)
				( objectStatus "C1D15.2" )
			)
			( pin "@baseboard_fab2_lib.baseboard_fab2(sch_1):page210_i24:a"
				( attribute "PN" "1"
					( Origin gPackager )
				)
				( objectStatus "C1C12.1" )
			)
			( pin "@baseboard_fab2_lib.baseboard_fab2(sch_1):page210_i24:b"
				( attribute "PN" "2"
					( Origin gPackager )
				)
				( objectStatus "C1C12.2" )
			)
			( pin "@baseboard_fab2_lib.baseboard_fab2(sch_1):page210_i26:a"
				( attribute "PN" "1"
					( Origin gPackager )
				)
				( objectStatus "C1C5.1" )
			)
			( pin "@baseboard_fab2_lib.baseboard_fab2(sch_1):page210_i26:b"
				( attribute "PN" "2"
					( Origin gPackager )
				)
				( objectStatus "C1C5.2" )
			)
			( pin "@baseboard_fab2_lib.baseboard_fab2(sch_1):page210_i27:a"
				( attribute "PN" "1"
					( Origin gPackager )
				)
				( objectStatus "C1C17.1" )
			)
			( pin "@baseboard_fab2_lib.baseboard_fab2(sch_1):page210_i27:b"
				( attribute "PN" "2"
					( Origin gPackager )
				)
				( objectStatus "C1C17.2" )
			)
			( pin "@baseboard_fab2_lib.baseboard_fab2(sch_1):page210_i28:a"
				( attribute "PN" "1"
					( Origin gPackager )
				)
				( objectStatus "C1C15.1" )
			)
			( pin "@baseboard_fab2_lib.baseboard_fab2(sch_1):page210_i28:b"
				( attribute "PN" "2"
					( Origin gPackager )
				)
				( objectStatus "C1C15.2" )
			)
			( pin "@baseboard_fab2_lib.baseboard_fab2(sch_1):page210_i29:a"
				( attribute "PN" "1"
					( Origin gPackager )
				)
				( objectStatus "R1C12.1" )
			)
			( pin "@baseboard_fab2_lib.baseboard_fab2(sch_1):page210_i29:b"
				( attribute "PN" "2"
					( Origin gPackager )
				)
				( objectStatus "R1C12.2" )
			)
			( pin "@baseboard_fab2_lib.baseboard_fab2(sch_1):page210_i31:a"
				( attribute "PN" "1"
					( Origin gPackager )
				)
				( objectStatus "R1C7.1" )
			)
			( pin "@baseboard_fab2_lib.baseboard_fab2(sch_1):page210_i31:b"
				( attribute "PN" "2"
					( Origin gPackager )
				)
				( objectStatus "R1C7.2" )
			)
			( pin "@baseboard_fab2_lib.baseboard_fab2(sch_1):page210_i32:a"
				( attribute "PN" "1"
					( Origin gPackager )
				)
				( objectStatus "R1C5.1" )
			)
			( pin "@baseboard_fab2_lib.baseboard_fab2(sch_1):page210_i32:b"
				( attribute "PN" "2"
					( Origin gPackager )
				)
				( objectStatus "R1C5.2" )
			)
			( pin "@baseboard_fab2_lib.baseboard_fab2(sch_1):page210_i33:a"
				( attribute "PN" "1"
					( Origin gPackager )
				)
				( objectStatus "R1C4.1" )
			)
			( pin "@baseboard_fab2_lib.baseboard_fab2(sch_1):page210_i33:b"
				( attribute "PN" "2"
					( Origin gPackager )
				)
				( objectStatus "R1C4.2" )
			)
			( pin "@baseboard_fab2_lib.baseboard_fab2(sch_1):page210_i34:a"
				( attribute "PN" "1"
					( Origin gPackager )
				)
				( objectStatus "R1C6.1" )
			)
			( pin "@baseboard_fab2_lib.baseboard_fab2(sch_1):page210_i34:b"
				( attribute "PN" "2"
					( Origin gPackager )
				)
				( objectStatus "R1C6.2" )
			)
			( pin "@baseboard_fab2_lib.baseboard_fab2(sch_1):page210_i35:a"
				( attribute "PN" "1"
					( Origin gPackager )
				)
				( objectStatus "C9N13.1" )
			)
			( pin "@baseboard_fab2_lib.baseboard_fab2(sch_1):page210_i35:b"
				( attribute "PN" "2"
					( Origin gPackager )
				)
				( objectStatus "C9N13.2" )
			)
			( pin "@baseboard_fab2_lib.baseboard_fab2(sch_1):page210_i36:a"
				( attribute "PN" "1"
					( Origin gPackager )
				)
				( objectStatus "C9N19.1" )
			)
			( pin "@baseboard_fab2_lib.baseboard_fab2(sch_1):page210_i36:b"
				( attribute "PN" "2"
					( Origin gPackager )
				)
				( objectStatus "C9N19.2" )
			)
			( pin "@baseboard_fab2_lib.baseboard_fab2(sch_1):page210_i38:a"
				( attribute "PN" "1"
					( Origin gPackager )
				)
				( objectStatus "C9N21.1" )
			)
			( pin "@baseboard_fab2_lib.baseboard_fab2(sch_1):page210_i38:b"
				( attribute "PN" "2"
					( Origin gPackager )
				)
				( objectStatus "C9N21.2" )
			)
			( pin "@baseboard_fab2_lib.baseboard_fab2(sch_1):page210_i44:a"
				( attribute "PN" "1"
					( Origin gPackager )
				)
				( objectStatus "C9N22.1" )
			)
			( pin "@baseboard_fab2_lib.baseboard_fab2(sch_1):page210_i44:b"
				( attribute "PN" "2"
					( Origin gPackager )
				)
				( objectStatus "C9N22.2" )
			)
			( pin "@baseboard_fab2_lib.baseboard_fab2(sch_1):page210_i45:a"
				( attribute "PN" "1"
					( Origin gPackager )
				)
				( objectStatus "R9N4.1" )
			)
			( pin "@baseboard_fab2_lib.baseboard_fab2(sch_1):page210_i45:b"
				( attribute "PN" "2"
					( Origin gPackager )
				)
				( objectStatus "R9N4.2" )
			)
			( pin "@baseboard_fab2_lib.baseboard_fab2(sch_1):page210_i51:boost"
				( attribute "PN" "33"
					( Origin gPackager )
				)
				( objectStatus "EU1C1.33" )
			)
			( pin "@baseboard_fab2_lib.baseboard_fab2(sch_1):page210_i51:en"
				( attribute "PN" "35"
					( Origin gPackager )
				)
				( objectStatus "EU1C1.35" )
			)
			( pin "@baseboard_fab2_lib.baseboard_fab2(sch_1):page210_i51:gl(0)"
				( attribute "PN" "6"
					( Origin gPackager )
				)
				( objectStatus "EU1C1.6" )
			)
			( pin "@baseboard_fab2_lib.baseboard_fab2(sch_1):page210_i51:gl(1)"
				( attribute "PN" "41"
					( Origin gPackager )
				)
				( objectStatus "EU1C1.41" )
			)
			( pin "@baseboard_fab2_lib.baseboard_fab2(sch_1):page210_i51:iout"
				( attribute "PN" "38"
					( Origin gPackager )
				)
				( objectStatus "EU1C1.38" )
			)
			( pin "@baseboard_fab2_lib.baseboard_fab2(sch_1):page210_i51:lgnd"
				( attribute "PN" "2"
					( Origin gPackager )
				)
				( objectStatus "EU1C1.2" )
			)
			( pin "@baseboard_fab2_lib.baseboard_fab2(sch_1):page210_i51:nc"
				( attribute "PN" "31"
					( Origin gPackager )
				)
				( objectStatus "EU1C1.31" )
			)
			( pin "@baseboard_fab2_lib.baseboard_fab2(sch_1):page210_i51:ocset"
				( attribute "PN" "37"
					( Origin gPackager )
				)
				( objectStatus "EU1C1.37" )
			)
			( pin "@baseboard_fab2_lib.baseboard_fab2(sch_1):page210_i51:pgnd(0)"
				( attribute "PN" "5"
					( Origin gPackager )
				)
				( objectStatus "EU1C1.5" )
			)
			( pin "@baseboard_fab2_lib.baseboard_fab2(sch_1):page210_i51:pgnd(1)"
				( attribute "PN" "7"
					( Origin gPackager )
				)
				( objectStatus "EU1C1.7" )
			)
			( pin "@baseboard_fab2_lib.baseboard_fab2(sch_1):page210_i51:pgnd(2)"
				( attribute "PN" "40"
					( Origin gPackager )
				)
				( objectStatus "EU1C1.40" )
			)
			( pin "@baseboard_fab2_lib.baseboard_fab2(sch_1):page210_i51:phase"
				( attribute "PN" "32"
					( Origin gPackager )
				)
				( objectStatus "EU1C1.32" )
			)
			( pin "@baseboard_fab2_lib.baseboard_fab2(sch_1):page210_i51:pwm"
				( attribute "PN" "34"
					( Origin gPackager )
				)
				( objectStatus "EU1C1.34" )
			)
			( pin "@baseboard_fab2_lib.baseboard_fab2(sch_1):page210_i51:refin"
				( attribute "PN" "39"
					( Origin gPackager )
				)
				( objectStatus "EU1C1.39" )
			)
			( pin "@baseboard_fab2_lib.baseboard_fab2(sch_1):page210_i51:sw"
				( attribute "PN" "10"
					( Origin gPackager )
				)
				( objectStatus "EU1C1.10" )
			)
			( pin "@baseboard_fab2_lib.baseboard_fab2(sch_1):page210_i51:tout_flt"
				( attribute "PN" "36"
					( Origin gPackager )
				)
				( objectStatus "EU1C1.36" )
			)
			( pin "@baseboard_fab2_lib.baseboard_fab2(sch_1):page210_i51:vcc"
				( attribute "PN" "3"
					( Origin gPackager )
				)
				( objectStatus "EU1C1.3" )
			)
			( pin "@baseboard_fab2_lib.baseboard_fab2(sch_1):page210_i51:vdrv"
				( attribute "PN" "4"
					( Origin gPackager )
				)
				( objectStatus "EU1C1.4" )
			)
			( pin "@baseboard_fab2_lib.baseboard_fab2(sch_1):page210_i51:vin(0)"
				( attribute "PN" "25"
					( Origin gPackager )
				)
				( objectStatus "EU1C1.25" )
			)
			( pin "@baseboard_fab2_lib.baseboard_fab2(sch_1):page210_i51:vin(1)"
				( attribute "PN" "30"
					( Origin gPackager )
				)
				( objectStatus "EU1C1.30" )
			)
			( pin "@baseboard_fab2_lib.baseboard_fab2(sch_1):page210_i51:vos"
				( attribute "PN" "1"
					( Origin gPackager )
				)
				( objectStatus "EU1C1.1" )
			)
			( pin "@baseboard_fab2_lib.baseboard_fab2(sch_1):page210_i52:a"
				( attribute "PN" "1"
					( Origin gPackager )
				)
				( objectStatus "R1C37.1" )
			)
			( pin "@baseboard_fab2_lib.baseboard_fab2(sch_1):page210_i52:b"
				( attribute "PN" "2"
					( Origin gPackager )
				)
				( objectStatus "R1C37.2" )
			)
			( pin "@baseboard_fab2_lib.baseboard_fab2(sch_1):page211_i11:a"
				( attribute "PN" "1"
					( Origin gPackager )
				)
				( objectStatus "C3P4.1" )
			)
			( pin "@baseboard_fab2_lib.baseboard_fab2(sch_1):page211_i11:b"
				( attribute "PN" "2"
					( Origin gPackager )
				)
				( objectStatus "C3P4.2" )
			)
			( pin "@baseboard_fab2_lib.baseboard_fab2(sch_1):page211_i13:a"
				( attribute "PN" "1"
					( Origin gPackager )
				)
				( objectStatus "C3P5.1" )
			)
			( pin "@baseboard_fab2_lib.baseboard_fab2(sch_1):page211_i13:b"
				( attribute "PN" "2"
					( Origin gPackager )
				)
				( objectStatus "C3P5.2" )
			)
			( pin "@baseboard_fab2_lib.baseboard_fab2(sch_1):page211_i16:a"
				( attribute "PN" "1"
					( Origin gPackager )
				)
				( objectStatus "R3P11.1" )
			)
			( pin "@baseboard_fab2_lib.baseboard_fab2(sch_1):page211_i16:b"
				( attribute "PN" "2"
					( Origin gPackager )
				)
				( objectStatus "R3P11.2" )
			)
			( pin "@baseboard_fab2_lib.baseboard_fab2(sch_1):page215_i70:a"
				( attribute "PN" "1"
					( Origin gPackager )
				)
				( objectStatus "R3T11.1" )
			)
			( pin "@baseboard_fab2_lib.baseboard_fab2(sch_1):page215_i70:b"
				( attribute "PN" "2"
					( Origin gPackager )
				)
				( objectStatus "R3T11.2" )
			)
			( pin "@baseboard_fab2_lib.baseboard_fab2(sch_1):page211_i20:a"
				( attribute "PN" "1"
					( Origin gPackager )
				)
				( objectStatus "C3P3.1" )
			)
			( pin "@baseboard_fab2_lib.baseboard_fab2(sch_1):page211_i20:b"
				( attribute "PN" "2"
					( Origin gPackager )
				)
				( objectStatus "C3P3.2" )
			)
			( pin "@baseboard_fab2_lib.baseboard_fab2(sch_1):page211_i22:a"
				( attribute "PN" "1"
					( Origin gPackager )
				)
				( objectStatus "C3P7.1" )
			)
			( pin "@baseboard_fab2_lib.baseboard_fab2(sch_1):page211_i22:b"
				( attribute "PN" "2"
					( Origin gPackager )
				)
				( objectStatus "C3P7.2" )
			)
			( pin "@baseboard_fab2_lib.baseboard_fab2(sch_1):page211_i24:a"
				( attribute "PN" "1"
					( Origin gPackager )
				)
				( objectStatus "R3P22.1" )
			)
			( pin "@baseboard_fab2_lib.baseboard_fab2(sch_1):page211_i24:b"
				( attribute "PN" "2"
					( Origin gPackager )
				)
				( objectStatus "R3P22.2" )
			)
			( pin "@baseboard_fab2_lib.baseboard_fab2(sch_1):page211_i100:a"
				( attribute "PN" "1"
					( Origin gPackager )
				)
				( objectStatus "R3P13.1" )
			)
			( pin "@baseboard_fab2_lib.baseboard_fab2(sch_1):page211_i100:b"
				( attribute "PN" "2"
					( Origin gPackager )
				)
				( objectStatus "R3P13.2" )
			)
			( pin "@baseboard_fab2_lib.baseboard_fab2(sch_1):page211_i29:a"
				( attribute "PN" "1"
					( Origin gPackager )
				)
				( objectStatus "R3P15.1" )
			)
			( pin "@baseboard_fab2_lib.baseboard_fab2(sch_1):page211_i29:b"
				( attribute "PN" "2"
					( Origin gPackager )
				)
				( objectStatus "R3P15.2" )
			)
			( pin "@baseboard_fab2_lib.baseboard_fab2(sch_1):page211_i31:a"
				( attribute "PN" "1"
					( Origin gPackager )
				)
				( objectStatus "R3P12.1" )
			)
			( pin "@baseboard_fab2_lib.baseboard_fab2(sch_1):page211_i31:b"
				( attribute "PN" "2"
					( Origin gPackager )
				)
				( objectStatus "R3P12.2" )
			)
			( pin "@baseboard_fab2_lib.baseboard_fab2(sch_1):page211_i32:a"
				( attribute "PN" "1"
					( Origin gPackager )
				)
				( objectStatus "R3P16.1" )
			)
			( pin "@baseboard_fab2_lib.baseboard_fab2(sch_1):page211_i32:b"
				( attribute "PN" "2"
					( Origin gPackager )
				)
				( objectStatus "R3P16.2" )
			)
			( pin "@baseboard_fab2_lib.baseboard_fab2(sch_1):page213_i105:a"
				( attribute "PN" "1"
					( Origin gPackager )
				)
				( objectStatus "C4D40.1" )
			)
			( pin "@baseboard_fab2_lib.baseboard_fab2(sch_1):page213_i105:b"
				( attribute "PN" "2"
					( Origin gPackager )
				)
				( objectStatus "C4D40.2" )
			)
			( pin "@baseboard_fab2_lib.baseboard_fab2(sch_1):page211_i52:a"
				( attribute "PN" "1"
					( Origin gPackager )
				)
				( objectStatus "R3N31.1" )
			)
			( pin "@baseboard_fab2_lib.baseboard_fab2(sch_1):page211_i52:b"
				( attribute "PN" "2"
					( Origin gPackager )
				)
				( objectStatus "R3N31.2" )
			)
			( pin "@baseboard_fab2_lib.baseboard_fab2(sch_1):page211_i56:a"
				( attribute "PN" "1"
					( Origin gPackager )
				)
				( objectStatus "R3P25.1" )
			)
			( pin "@baseboard_fab2_lib.baseboard_fab2(sch_1):page211_i56:b"
				( attribute "PN" "2"
					( Origin gPackager )
				)
				( objectStatus "R3P25.2" )
			)
			( pin "@baseboard_fab2_lib.baseboard_fab2(sch_1):page211_i58:a"
				( attribute "PN" "1"
					( Origin gPackager )
				)
				( objectStatus "R3P20.1" )
			)
			( pin "@baseboard_fab2_lib.baseboard_fab2(sch_1):page211_i58:b"
				( attribute "PN" "2"
					( Origin gPackager )
				)
				( objectStatus "R3P20.2" )
			)
			( pin "@baseboard_fab2_lib.baseboard_fab2(sch_1):page211_i60:a"
				( attribute "PN" "1"
					( Origin gPackager )
				)
				( objectStatus "R3N23.1" )
			)
			( pin "@baseboard_fab2_lib.baseboard_fab2(sch_1):page211_i60:b"
				( attribute "PN" "2"
					( Origin gPackager )
				)
				( objectStatus "R3N23.2" )
			)
			( pin "@baseboard_fab2_lib.baseboard_fab2(sch_1):page211_i61:a"
				( attribute "PN" "1"
					( Origin gPackager )
				)
				( objectStatus "R3P1.1" )
			)
			( pin "@baseboard_fab2_lib.baseboard_fab2(sch_1):page211_i61:b"
				( attribute "PN" "2"
					( Origin gPackager )
				)
				( objectStatus "R3P1.2" )
			)
			( pin "@baseboard_fab2_lib.baseboard_fab2(sch_1):page211_i64:a"
				( attribute "PN" "1"
					( Origin gPackager )
				)
				( objectStatus "R3P18.1" )
			)
			( pin "@baseboard_fab2_lib.baseboard_fab2(sch_1):page211_i64:b"
				( attribute "PN" "2"
					( Origin gPackager )
				)
				( objectStatus "R3P18.2" )
			)
			( pin "@baseboard_fab2_lib.baseboard_fab2(sch_1):page215_i73:a"
				( attribute "PN" "1"
					( Origin gPackager )
				)
				( objectStatus "R7G10.1" )
			)
			( pin "@baseboard_fab2_lib.baseboard_fab2(sch_1):page215_i73:b"
				( attribute "PN" "2"
					( Origin gPackager )
				)
				( objectStatus "R7G10.2" )
			)
			( pin "@baseboard_fab2_lib.baseboard_fab2(sch_1):page211_i71:a"
				( attribute "PN" "1"
					( Origin gPackager )
				)
				( objectStatus "C3P6.1" )
			)
			( pin "@baseboard_fab2_lib.baseboard_fab2(sch_1):page211_i71:b"
				( attribute "PN" "2"
					( Origin gPackager )
				)
				( objectStatus "C3P6.2" )
			)
			( pin "@baseboard_fab2_lib.baseboard_fab2(sch_1):page211_i81:a"
				( attribute "PN" "1"
					( Origin gPackager )
				)
				( objectStatus "R3N19.1" )
			)
			( pin "@baseboard_fab2_lib.baseboard_fab2(sch_1):page211_i81:b"
				( attribute "PN" "2"
					( Origin gPackager )
				)
				( objectStatus "R3N19.2" )
			)
			( pin "@baseboard_fab2_lib.baseboard_fab2(sch_1):page211_i83:a"
				( attribute "PN" "1"
					( Origin gPackager )
				)
				( objectStatus "C3N39.1" )
			)
			( pin "@baseboard_fab2_lib.baseboard_fab2(sch_1):page211_i83:b"
				( attribute "PN" "2"
					( Origin gPackager )
				)
				( objectStatus "C3N39.2" )
			)
			( pin "@baseboard_fab2_lib.baseboard_fab2(sch_1):page211_i87:a"
				( attribute "PN" "1"
					( Origin gPackager )
				)
				( objectStatus "R3P26.1" )
			)
			( pin "@baseboard_fab2_lib.baseboard_fab2(sch_1):page211_i87:b"
				( attribute "PN" "2"
					( Origin gPackager )
				)
				( objectStatus "R3P26.2" )
			)
			( pin "@baseboard_fab2_lib.baseboard_fab2(sch_1):page211_i88:a"
				( attribute "PN" "1"
					( Origin gPackager )
				)
				( objectStatus "R3P21.1" )
			)
			( pin "@baseboard_fab2_lib.baseboard_fab2(sch_1):page211_i88:b"
				( attribute "PN" "2"
					( Origin gPackager )
				)
				( objectStatus "R3P21.2" )
			)
			( pin "@baseboard_fab2_lib.baseboard_fab2(sch_1):page211_i93:airef1"
				( attribute "PN" "21"
					( Origin gPackager )
				)
				( objectStatus "EU3P1.21" )
			)
			( pin "@baseboard_fab2_lib.baseboard_fab2(sch_1):page211_i93:aisen1"
				( attribute "PN" "22"
					( Origin gPackager )
				)
				( objectStatus "EU3P1.22" )
			)
			( pin "@baseboard_fab2_lib.baseboard_fab2(sch_1):page211_i93:apwm1"
				( attribute "PN" "5"
					( Origin gPackager )
				)
				( objectStatus "EU3P1.5" )
			)
			( pin "@baseboard_fab2_lib.baseboard_fab2(sch_1):page211_i93:atsen"
				( attribute "PN" "35"
					( Origin gPackager )
				)
				( objectStatus "EU3P1.35" )
			)
			( pin "@baseboard_fab2_lib.baseboard_fab2(sch_1):page211_i93:avref"
				( attribute "PN" "20"
					( Origin gPackager )
				)
				( objectStatus "EU3P1.20" )
			)
			( pin "@baseboard_fab2_lib.baseboard_fab2(sch_1):page211_i93:avren"
				( attribute "PN" "10"
					( Origin gPackager )
				)
				( objectStatus "EU3P1.10" )
			)
			( pin "@baseboard_fab2_lib.baseboard_fab2(sch_1):page211_i93:avrrdy"
				( attribute "PN" "9"
					( Origin gPackager )
				)
				( objectStatus "EU3P1.9" )
			)
			( pin "@baseboard_fab2_lib.baseboard_fab2(sch_1):page211_i93:avsen"
				( attribute "PN" "19"
					( Origin gPackager )
				)
				( objectStatus "EU3P1.19" )
			)
			( pin "@baseboard_fab2_lib.baseboard_fab2(sch_1):page211_i93:biref1"
				( attribute "PN" "25"
					( Origin gPackager )
				)
				( objectStatus "EU3P1.25" )
			)
			( pin "@baseboard_fab2_lib.baseboard_fab2(sch_1):page211_i93:bisen1"
				( attribute "PN" "26"
					( Origin gPackager )
				)
				( objectStatus "EU3P1.26" )
			)
			( pin "@baseboard_fab2_lib.baseboard_fab2(sch_1):page211_i93:bpwm1"
				( attribute "PN" "3"
					( Origin gPackager )
				)
				( objectStatus "EU3P1.3" )
			)
			( pin "@baseboard_fab2_lib.baseboard_fab2(sch_1):page211_i93:btsen"
				( attribute "PN" "34"
					( Origin gPackager )
				)
				( objectStatus "EU3P1.34" )
			)
			( pin "@baseboard_fab2_lib.baseboard_fab2(sch_1):page211_i93:bvref"
				( attribute "PN" "30"
					( Origin gPackager )
				)
				( objectStatus "EU3P1.30" )
			)
			( pin "@baseboard_fab2_lib.baseboard_fab2(sch_1):page211_i93:bvsen"
				( attribute "PN" "29"
					( Origin gPackager )
				)
				( objectStatus "EU3P1.29" )
			)
			( pin "@baseboard_fab2_lib.baseboard_fab2(sch_1):page211_i93:dnc(0)"
				( attribute "PN" "1"
					( Origin gPackager )
				)
				( objectStatus "EU3P1.1" )
			)
			( pin "@baseboard_fab2_lib.baseboard_fab2(sch_1):page211_i93:dnc(1)"
				( attribute "PN" "2"
					( Origin gPackager )
				)
				( objectStatus "EU3P1.2" )
			)
			( pin "@baseboard_fab2_lib.baseboard_fab2(sch_1):page211_i93:dnc(2)"
				( attribute "PN" "4"
					( Origin gPackager )
				)
				( objectStatus "EU3P1.4" )
			)
			( pin "@baseboard_fab2_lib.baseboard_fab2(sch_1):page211_i93:dnc(3)"
				( attribute "PN" "24"
					( Origin gPackager )
				)
				( objectStatus "EU3P1.24" )
			)
			( pin "@baseboard_fab2_lib.baseboard_fab2(sch_1):page211_i93:dnc(4)"
				( attribute "PN" "28"
					( Origin gPackager )
				)
				( objectStatus "EU3P1.28" )
			)
			( pin "@baseboard_fab2_lib.baseboard_fab2(sch_1):page211_i93:gnd(0)"
				( attribute "PN" "27"
					( Origin gPackager )
				)
				( objectStatus "EU3P1.27" )
			)
			( pin "@baseboard_fab2_lib.baseboard_fab2(sch_1):page211_i93:gnd(1)"
				( attribute "PN" "23"
					( Origin gPackager )
				)
				( objectStatus "EU3P1.23" )
			)
			( pin "@baseboard_fab2_lib.baseboard_fab2(sch_1):page211_i93:iinsen"
				( attribute "PN" "38"
					( Origin gPackager )
				)
				( objectStatus "EU3P1.38" )
			)
			( pin "@baseboard_fab2_lib.baseboard_fab2(sch_1):page211_i93:mp0"
				( attribute "PN" "13"
					( Origin gPackager )
				)
				( objectStatus "EU3P1.13" )
			)
			( pin "@baseboard_fab2_lib.baseboard_fab2(sch_1):page211_i93:mp1"
				( attribute "PN" "14"
					( Origin gPackager )
				)
				( objectStatus "EU3P1.14" )
			)
			( pin "@baseboard_fab2_lib.baseboard_fab2(sch_1):page211_i93:mp2"
				( attribute "PN" "18"
					( Origin gPackager )
				)
				( objectStatus "EU3P1.18" )
			)
			( pin "@baseboard_fab2_lib.baseboard_fab2(sch_1):page211_i93:mp3"
				( attribute "PN" "31"
					( Origin gPackager )
				)
				( objectStatus "EU3P1.31" )
			)
			( pin "@baseboard_fab2_lib.baseboard_fab2(sch_1):page211_i93:mp4"
				( attribute "PN" "32"
					( Origin gPackager )
				)
				( objectStatus "EU3P1.32" )
			)
			( pin "@baseboard_fab2_lib.baseboard_fab2(sch_1):page211_i93:pinalrt_n"
				( attribute "PN" "12"
					( Origin gPackager )
				)
				( objectStatus "EU3P1.12" )
			)
			( pin "@baseboard_fab2_lib.baseboard_fab2(sch_1):page211_i93:reset_n"
				( attribute "PN" "8"
					( Origin gPackager )
				)
				( objectStatus "EU3P1.8" )
			)
			( pin "@baseboard_fab2_lib.baseboard_fab2(sch_1):page211_i93:scl"
				( attribute "PN" "7"
					( Origin gPackager )
				)
				( objectStatus "EU3P1.7" )
			)
			( pin "@baseboard_fab2_lib.baseboard_fab2(sch_1):page211_i93:sda"
				( attribute "PN" "6"
					( Origin gPackager )
				)
				( objectStatus "EU3P1.6" )
			)
			( pin "@baseboard_fab2_lib.baseboard_fab2(sch_1):page211_i93:thpad"
				( attribute "PN" "41"
					( Origin gPackager )
				)
				( objectStatus "EU3P1.41" )
			)
			( pin "@baseboard_fab2_lib.baseboard_fab2(sch_1):page211_i93:valrt_n"
				( attribute "PN" "17"
					( Origin gPackager )
				)
				( objectStatus "EU3P1.17" )
			)
			( pin "@baseboard_fab2_lib.baseboard_fab2(sch_1):page211_i93:vclk"
				( attribute "PN" "15"
					( Origin gPackager )
				)
				( objectStatus "EU3P1.15" )
			)
			( pin "@baseboard_fab2_lib.baseboard_fab2(sch_1):page211_i93:vd12"
				( attribute "PN" "40"
					( Origin gPackager )
				)
				( objectStatus "EU3P1.40" )
			)
			( pin "@baseboard_fab2_lib.baseboard_fab2(sch_1):page211_i93:vdd"
				( attribute "PN" "39"
					( Origin gPackager )
				)
				( objectStatus "EU3P1.39" )
			)
			( pin "@baseboard_fab2_lib.baseboard_fab2(sch_1):page211_i93:vdio"
				( attribute "PN" "16"
					( Origin gPackager )
				)
				( objectStatus "EU3P1.16" )
			)
			( pin "@baseboard_fab2_lib.baseboard_fab2(sch_1):page211_i93:vinsen"
				( attribute "PN" "37"
					( Origin gPackager )
				)
				( objectStatus "EU3P1.37" )
			)
			( pin "@baseboard_fab2_lib.baseboard_fab2(sch_1):page211_i93:vrhot_n"
				( attribute "PN" "11"
					( Origin gPackager )
				)
				( objectStatus "EU3P1.11" )
			)
			( pin "@baseboard_fab2_lib.baseboard_fab2(sch_1):page211_i93:xaddr1"
				( attribute "PN" "36"
					( Origin gPackager )
				)
				( objectStatus "EU3P1.36" )
			)
			( pin "@baseboard_fab2_lib.baseboard_fab2(sch_1):page211_i93:xaddr2"
				( attribute "PN" "33"
					( Origin gPackager )
				)
				( objectStatus "EU3P1.33" )
			)
			( pin "@baseboard_fab2_lib.baseboard_fab2(sch_1):page214_i178:a"
				( attribute "PN" "1"
					( Origin gPackager )
				)
				( objectStatus "C4E7.1" )
			)
			( pin "@baseboard_fab2_lib.baseboard_fab2(sch_1):page214_i178:b"
				( attribute "PN" "2"
					( Origin gPackager )
				)
				( objectStatus "C4E7.2" )
			)
			( pin "@baseboard_fab2_lib.baseboard_fab2(sch_1):page214_i177:a"
				( attribute "PN" "1"
					( Origin gPackager )
				)
				( objectStatus "C6R12.1" )
			)
			( pin "@baseboard_fab2_lib.baseboard_fab2(sch_1):page214_i177:b"
				( attribute "PN" "2"
					( Origin gPackager )
				)
				( objectStatus "C6R12.2" )
			)
			( pin "@baseboard_fab2_lib.baseboard_fab2(sch_1):page212_i18:a"
				( attribute "PN" "1"
					( Origin gPackager )
				)
				( objectStatus "C3N35.1" )
			)
			( pin "@baseboard_fab2_lib.baseboard_fab2(sch_1):page212_i18:b"
				( attribute "PN" "2"
					( Origin gPackager )
				)
				( objectStatus "C3N35.2" )
			)
			( pin "@baseboard_fab2_lib.baseboard_fab2(sch_1):page212_i23:a"
				( attribute "PN" "1"
					( Origin gPackager )
				)
				( objectStatus "C7C6.1" )
			)
			( pin "@baseboard_fab2_lib.baseboard_fab2(sch_1):page212_i23:b"
				( attribute "PN" "2"
					( Origin gPackager )
				)
				( objectStatus "C7C6.2" )
			)
			( pin "@baseboard_fab2_lib.baseboard_fab2(sch_1):page236_i179:f"
				( attribute "PN" "2"
					( Origin gPackager )
				)
				( objectStatus "L7A4.2" )
			)
			( pin "@baseboard_fab2_lib.baseboard_fab2(sch_1):page236_i179:s"
				( attribute "PN" "1"
					( Origin gPackager )
				)
				( objectStatus "L7A4.1" )
			)
			( pin "@baseboard_fab2_lib.baseboard_fab2(sch_1):page214_i173:a"
				( attribute "PN" "1"
					( Origin gPackager )
				)
				( objectStatus "R6R5.1" )
			)
			( pin "@baseboard_fab2_lib.baseboard_fab2(sch_1):page214_i173:b"
				( attribute "PN" "2"
					( Origin gPackager )
				)
				( objectStatus "R6R5.2" )
			)
			( pin "@baseboard_fab2_lib.baseboard_fab2(sch_1):page212_i33:a"
				( attribute "PN" "1"
					( Origin gPackager )
				)
				( objectStatus "C7C18.1" )
			)
			( pin "@baseboard_fab2_lib.baseboard_fab2(sch_1):page212_i33:b"
				( attribute "PN" "2"
					( Origin gPackager )
				)
				( objectStatus "C7C18.2" )
			)
			( pin "@baseboard_fab2_lib.baseboard_fab2(sch_1):page216_i149:\1\"
				( attribute "PN" "1"
					( Origin gPackager )
				)
				( objectStatus "C7G35.1" )
			)
			( pin "@baseboard_fab2_lib.baseboard_fab2(sch_1):page216_i149:\2\"
				( attribute "PN" "2"
					( Origin gPackager )
				)
				( objectStatus "C7G35.2" )
			)
			( pin "@baseboard_fab2_lib.baseboard_fab2(sch_1):page212_i36:a"
				( attribute "PN" "1"
					( Origin gPackager )
				)
				( objectStatus "C7C17.1" )
			)
			( pin "@baseboard_fab2_lib.baseboard_fab2(sch_1):page212_i36:b"
				( attribute "PN" "2"
					( Origin gPackager )
				)
				( objectStatus "C7C17.2" )
			)
			( pin "@baseboard_fab2_lib.baseboard_fab2(sch_1):page212_i37:a"
				( attribute "PN" "1"
					( Origin gPackager )
				)
				( objectStatus "C7C14.1" )
			)
			( pin "@baseboard_fab2_lib.baseboard_fab2(sch_1):page212_i37:b"
				( attribute "PN" "2"
					( Origin gPackager )
				)
				( objectStatus "C7C14.2" )
			)
			( pin "@baseboard_fab2_lib.baseboard_fab2(sch_1):page212_i38:a"
				( attribute "PN" "1"
					( Origin gPackager )
				)
				( objectStatus "C7C11.1" )
			)
			( pin "@baseboard_fab2_lib.baseboard_fab2(sch_1):page212_i38:b"
				( attribute "PN" "2"
					( Origin gPackager )
				)
				( objectStatus "C7C11.2" )
			)
			( pin "@baseboard_fab2_lib.baseboard_fab2(sch_1):page212_i39:a"
				( attribute "PN" "1"
					( Origin gPackager )
				)
				( objectStatus "C7C12.1" )
			)
			( pin "@baseboard_fab2_lib.baseboard_fab2(sch_1):page212_i39:b"
				( attribute "PN" "2"
					( Origin gPackager )
				)
				( objectStatus "C7C12.2" )
			)
			( pin "@baseboard_fab2_lib.baseboard_fab2(sch_1):page212_i40:a"
				( attribute "PN" "1"
					( Origin gPackager )
				)
				( objectStatus "C3N36.1" )
			)
			( pin "@baseboard_fab2_lib.baseboard_fab2(sch_1):page212_i40:b"
				( attribute "PN" "2"
					( Origin gPackager )
				)
				( objectStatus "C3N36.2" )
			)
			( pin "@baseboard_fab2_lib.baseboard_fab2(sch_1):page212_i41:a"
				( attribute "PN" "1"
					( Origin gPackager )
				)
				( objectStatus "C3N33.1" )
			)
			( pin "@baseboard_fab2_lib.baseboard_fab2(sch_1):page212_i41:b"
				( attribute "PN" "2"
					( Origin gPackager )
				)
				( objectStatus "C3N33.2" )
			)
			( pin "@baseboard_fab2_lib.baseboard_fab2(sch_1):page212_i43:a"
				( attribute "PN" "1"
					( Origin gPackager )
				)
				( objectStatus "C3N34.1" )
			)
			( pin "@baseboard_fab2_lib.baseboard_fab2(sch_1):page212_i43:b"
				( attribute "PN" "2"
					( Origin gPackager )
				)
				( objectStatus "C3N34.2" )
			)
			( pin "@baseboard_fab2_lib.baseboard_fab2(sch_1):page203_i129:a"
				( attribute "PN" "1"
					( Origin gPackager )
				)
				( objectStatus "R6P10.1" )
			)
			( pin "@baseboard_fab2_lib.baseboard_fab2(sch_1):page203_i129:b"
				( attribute "PN" "2"
					( Origin gPackager )
				)
				( objectStatus "R6P10.2" )
			)
			( pin "@baseboard_fab2_lib.baseboard_fab2(sch_1):page203_i128:a"
				( attribute "PN" "1"
					( Origin gPackager )
				)
				( objectStatus "R6P19.1" )
			)
			( pin "@baseboard_fab2_lib.baseboard_fab2(sch_1):page203_i128:b"
				( attribute "PN" "2"
					( Origin gPackager )
				)
				( objectStatus "R6P19.2" )
			)
			( pin "@baseboard_fab2_lib.baseboard_fab2(sch_1):page214_i174:f"
				( attribute "PN" "2"
					( Origin gPackager )
				)
				( objectStatus "L4E2.2" )
			)
			( pin "@baseboard_fab2_lib.baseboard_fab2(sch_1):page214_i174:s"
				( attribute "PN" "1"
					( Origin gPackager )
				)
				( objectStatus "L4E2.1" )
			)
			( pin "@baseboard_fab2_lib.baseboard_fab2(sch_1):page212_i60:a"
				( attribute "PN" "1"
					( Origin gPackager )
				)
				( objectStatus "C3P1.1" )
			)
			( pin "@baseboard_fab2_lib.baseboard_fab2(sch_1):page212_i60:b"
				( attribute "PN" "2"
					( Origin gPackager )
				)
				( objectStatus "C3P1.2" )
			)
			( pin "@baseboard_fab2_lib.baseboard_fab2(sch_1):page212_i68:a"
				( attribute "PN" "1"
					( Origin gPackager )
				)
				( objectStatus "R3N20.1" )
			)
			( pin "@baseboard_fab2_lib.baseboard_fab2(sch_1):page212_i68:b"
				( attribute "PN" "2"
					( Origin gPackager )
				)
				( objectStatus "R3N20.2" )
			)
			( pin "@baseboard_fab2_lib.baseboard_fab2(sch_1):page212_i74:a"
				( attribute "PN" "1"
					( Origin gPackager )
				)
				( objectStatus "R3N21.1" )
			)
			( pin "@baseboard_fab2_lib.baseboard_fab2(sch_1):page212_i74:b"
				( attribute "PN" "2"
					( Origin gPackager )
				)
				( objectStatus "R3N21.2" )
			)
			( pin "@baseboard_fab2_lib.baseboard_fab2(sch_1):page212_i77:a"
				( attribute "PN" "1"
					( Origin gPackager )
				)
				( objectStatus "C7C10.1" )
			)
			( pin "@baseboard_fab2_lib.baseboard_fab2(sch_1):page212_i77:b"
				( attribute "PN" "2"
					( Origin gPackager )
				)
				( objectStatus "C7C10.2" )
			)
			( pin "@baseboard_fab2_lib.baseboard_fab2(sch_1):page212_i78:a"
				( attribute "PN" "1"
					( Origin gPackager )
				)
				( objectStatus "R7C3.1" )
			)
			( pin "@baseboard_fab2_lib.baseboard_fab2(sch_1):page212_i78:b"
				( attribute "PN" "2"
					( Origin gPackager )
				)
				( objectStatus "R7C3.2" )
			)
			( pin "@baseboard_fab2_lib.baseboard_fab2(sch_1):page212_i101:boost"
				( attribute "PN" "33"
					( Origin gPackager )
				)
				( objectStatus "EU7C1.33" )
			)
			( pin "@baseboard_fab2_lib.baseboard_fab2(sch_1):page212_i101:en"
				( attribute "PN" "35"
					( Origin gPackager )
				)
				( objectStatus "EU7C1.35" )
			)
			( pin "@baseboard_fab2_lib.baseboard_fab2(sch_1):page212_i101:gl(0)"
				( attribute "PN" "6"
					( Origin gPackager )
				)
				( objectStatus "EU7C1.6" )
			)
			( pin "@baseboard_fab2_lib.baseboard_fab2(sch_1):page212_i101:gl(1)"
				( attribute "PN" "41"
					( Origin gPackager )
				)
				( objectStatus "EU7C1.41" )
			)
			( pin "@baseboard_fab2_lib.baseboard_fab2(sch_1):page212_i101:iout"
				( attribute "PN" "38"
					( Origin gPackager )
				)
				( objectStatus "EU7C1.38" )
			)
			( pin "@baseboard_fab2_lib.baseboard_fab2(sch_1):page212_i101:lgnd"
				( attribute "PN" "2"
					( Origin gPackager )
				)
				( objectStatus "EU7C1.2" )
			)
			( pin "@baseboard_fab2_lib.baseboard_fab2(sch_1):page212_i101:nc"
				( attribute "PN" "31"
					( Origin gPackager )
				)
				( objectStatus "EU7C1.31" )
			)
			( pin "@baseboard_fab2_lib.baseboard_fab2(sch_1):page212_i101:ocset"
				( attribute "PN" "37"
					( Origin gPackager )
				)
				( objectStatus "EU7C1.37" )
			)
			( pin "@baseboard_fab2_lib.baseboard_fab2(sch_1):page212_i101:pgnd(0)"
				( attribute "PN" "5"
					( Origin gPackager )
				)
				( objectStatus "EU7C1.5" )
			)
			( pin "@baseboard_fab2_lib.baseboard_fab2(sch_1):page212_i101:pgnd(1)"
				( attribute "PN" "7"
					( Origin gPackager )
				)
				( objectStatus "EU7C1.7" )
			)
			( pin "@baseboard_fab2_lib.baseboard_fab2(sch_1):page212_i101:pgnd(2)"
				( attribute "PN" "40"
					( Origin gPackager )
				)
				( objectStatus "EU7C1.40" )
			)
			( pin "@baseboard_fab2_lib.baseboard_fab2(sch_1):page212_i101:phase"
				( attribute "PN" "32"
					( Origin gPackager )
				)
				( objectStatus "EU7C1.32" )
			)
			( pin "@baseboard_fab2_lib.baseboard_fab2(sch_1):page212_i101:pwm"
				( attribute "PN" "34"
					( Origin gPackager )
				)
				( objectStatus "EU7C1.34" )
			)
			( pin "@baseboard_fab2_lib.baseboard_fab2(sch_1):page212_i101:refin"
				( attribute "PN" "39"
					( Origin gPackager )
				)
				( objectStatus "EU7C1.39" )
			)
			( pin "@baseboard_fab2_lib.baseboard_fab2(sch_1):page212_i101:sw"
				( attribute "PN" "10"
					( Origin gPackager )
				)
				( objectStatus "EU7C1.10" )
			)
			( pin "@baseboard_fab2_lib.baseboard_fab2(sch_1):page212_i101:tout_flt"
				( attribute "PN" "36"
					( Origin gPackager )
				)
				( objectStatus "EU7C1.36" )
			)
			( pin "@baseboard_fab2_lib.baseboard_fab2(sch_1):page212_i101:vcc"
				( attribute "PN" "3"
					( Origin gPackager )
				)
				( objectStatus "EU7C1.3" )
			)
			( pin "@baseboard_fab2_lib.baseboard_fab2(sch_1):page212_i101:vdrv"
				( attribute "PN" "4"
					( Origin gPackager )
				)
				( objectStatus "EU7C1.4" )
			)
			( pin "@baseboard_fab2_lib.baseboard_fab2(sch_1):page212_i101:vin(0)"
				( attribute "PN" "25"
					( Origin gPackager )
				)
				( objectStatus "EU7C1.25" )
			)
			( pin "@baseboard_fab2_lib.baseboard_fab2(sch_1):page212_i101:vin(1)"
				( attribute "PN" "30"
					( Origin gPackager )
				)
				( objectStatus "EU7C1.30" )
			)
			( pin "@baseboard_fab2_lib.baseboard_fab2(sch_1):page212_i101:vos"
				( attribute "PN" "1"
					( Origin gPackager )
				)
				( objectStatus "EU7C1.1" )
			)
			( pin "@baseboard_fab2_lib.baseboard_fab2(sch_1):page212_i103:a"
				( attribute "PN" "1"
					( Origin gPackager )
				)
				( objectStatus "R7C25.1" )
			)
			( pin "@baseboard_fab2_lib.baseboard_fab2(sch_1):page212_i103:b"
				( attribute "PN" "2"
					( Origin gPackager )
				)
				( objectStatus "R7C25.2" )
			)
			( pin "@baseboard_fab2_lib.baseboard_fab2(sch_1):page212_i104:a"
				( attribute "PN" "1"
					( Origin gPackager )
				)
				( objectStatus "SH3P1.1" )
			)
			( pin "@baseboard_fab2_lib.baseboard_fab2(sch_1):page212_i104:b"
				( attribute "PN" "2"
					( Origin gPackager )
				)
				( objectStatus "SH3P1.2" )
			)
			( pin "@baseboard_fab2_lib.baseboard_fab2(sch_1):page212_i105:a"
				( attribute "PN" "1"
					( Origin gPackager )
				)
				( objectStatus "SH3P2.1" )
			)
			( pin "@baseboard_fab2_lib.baseboard_fab2(sch_1):page212_i105:b"
				( attribute "PN" "2"
					( Origin gPackager )
				)
				( objectStatus "SH3P2.2" )
			)
			( pin "@baseboard_fab2_lib.baseboard_fab2(sch_1):page213_i9:a"
				( attribute "PN" "1"
					( Origin gPackager )
				)
				( objectStatus "C4D31.1" )
			)
			( pin "@baseboard_fab2_lib.baseboard_fab2(sch_1):page213_i9:b"
				( attribute "PN" "2"
					( Origin gPackager )
				)
				( objectStatus "C4D31.2" )
			)
			( pin "@baseboard_fab2_lib.baseboard_fab2(sch_1):page213_i11:a"
				( attribute "PN" "1"
					( Origin gPackager )
				)
				( objectStatus "C4D32.1" )
			)
			( pin "@baseboard_fab2_lib.baseboard_fab2(sch_1):page213_i11:b"
				( attribute "PN" "2"
					( Origin gPackager )
				)
				( objectStatus "C4D32.2" )
			)
			( pin "@baseboard_fab2_lib.baseboard_fab2(sch_1):page213_i13:a"
				( attribute "PN" "1"
					( Origin gPackager )
				)
				( objectStatus "R4D46.1" )
			)
			( pin "@baseboard_fab2_lib.baseboard_fab2(sch_1):page213_i13:b"
				( attribute "PN" "2"
					( Origin gPackager )
				)
				( objectStatus "R4D46.2" )
			)
			( pin "@baseboard_fab2_lib.baseboard_fab2(sch_1):page213_i14:a"
				( attribute "PN" "1"
					( Origin gPackager )
				)
				( objectStatus "R6P49.1" )
			)
			( pin "@baseboard_fab2_lib.baseboard_fab2(sch_1):page213_i14:b"
				( attribute "PN" "2"
					( Origin gPackager )
				)
				( objectStatus "R6P49.2" )
			)
			( pin "@baseboard_fab2_lib.baseboard_fab2(sch_1):page213_i15:a"
				( attribute "PN" "1"
					( Origin gPackager )
				)
				( objectStatus "R4D42.1" )
			)
			( pin "@baseboard_fab2_lib.baseboard_fab2(sch_1):page213_i15:b"
				( attribute "PN" "2"
					( Origin gPackager )
				)
				( objectStatus "R4D42.2" )
			)
			( pin "@baseboard_fab2_lib.baseboard_fab2(sch_1):page213_i16:a"
				( attribute "PN" "1"
					( Origin gPackager )
				)
				( objectStatus "R4D56.1" )
			)
			( pin "@baseboard_fab2_lib.baseboard_fab2(sch_1):page213_i16:b"
				( attribute "PN" "2"
					( Origin gPackager )
				)
				( objectStatus "R4D56.2" )
			)
			( pin "@baseboard_fab2_lib.baseboard_fab2(sch_1):page213_i17:a"
				( attribute "PN" "1"
					( Origin gPackager )
				)
				( objectStatus "C4D36.1" )
			)
			( pin "@baseboard_fab2_lib.baseboard_fab2(sch_1):page213_i17:b"
				( attribute "PN" "2"
					( Origin gPackager )
				)
				( objectStatus "C4D36.2" )
			)
			( pin "@baseboard_fab2_lib.baseboard_fab2(sch_1):page213_i25:a"
				( attribute "PN" "1"
					( Origin gPackager )
				)
				( objectStatus "R4D47.1" )
			)
			( pin "@baseboard_fab2_lib.baseboard_fab2(sch_1):page213_i25:b"
				( attribute "PN" "2"
					( Origin gPackager )
				)
				( objectStatus "R4D47.2" )
			)
			( pin "@baseboard_fab2_lib.baseboard_fab2(sch_1):page213_i27:a"
				( attribute "PN" "1"
					( Origin gPackager )
				)
				( objectStatus "R6P35.1" )
			)
			( pin "@baseboard_fab2_lib.baseboard_fab2(sch_1):page213_i27:b"
				( attribute "PN" "2"
					( Origin gPackager )
				)
				( objectStatus "R6P35.2" )
			)
			( pin "@baseboard_fab2_lib.baseboard_fab2(sch_1):page213_i30:a"
				( attribute "PN" "1"
					( Origin gPackager )
				)
				( objectStatus "R6P33.1" )
			)
			( pin "@baseboard_fab2_lib.baseboard_fab2(sch_1):page213_i30:b"
				( attribute "PN" "2"
					( Origin gPackager )
				)
				( objectStatus "R6P33.2" )
			)
			( pin "@baseboard_fab2_lib.baseboard_fab2(sch_1):page213_i31:a"
				( attribute "PN" "1"
					( Origin gPackager )
				)
				( objectStatus "R4D60.1" )
			)
			( pin "@baseboard_fab2_lib.baseboard_fab2(sch_1):page213_i31:b"
				( attribute "PN" "2"
					( Origin gPackager )
				)
				( objectStatus "R4D60.2" )
			)
			( pin "@baseboard_fab2_lib.baseboard_fab2(sch_1):page213_i32:a"
				( attribute "PN" "1"
					( Origin gPackager )
				)
				( objectStatus "R4D57.1" )
			)
			( pin "@baseboard_fab2_lib.baseboard_fab2(sch_1):page213_i32:b"
				( attribute "PN" "2"
					( Origin gPackager )
				)
				( objectStatus "R4D57.2" )
			)
			( pin "@baseboard_fab2_lib.baseboard_fab2(sch_1):page235_i255:a"
				( attribute "PN" "1"
					( Origin gPackager )
				)
				( objectStatus "C8A3.1" )
			)
			( pin "@baseboard_fab2_lib.baseboard_fab2(sch_1):page235_i255:b"
				( attribute "PN" "2"
					( Origin gPackager )
				)
				( objectStatus "C8A3.2" )
			)
			( pin "@baseboard_fab2_lib.baseboard_fab2(sch_1):page213_i35:a"
				( attribute "PN" "1"
					( Origin gPackager )
				)
				( objectStatus "C4D38.1" )
			)
			( pin "@baseboard_fab2_lib.baseboard_fab2(sch_1):page213_i35:b"
				( attribute "PN" "2"
					( Origin gPackager )
				)
				( objectStatus "C4D38.2" )
			)
			( pin "@baseboard_fab2_lib.baseboard_fab2(sch_1):page213_i37:a"
				( attribute "PN" "1"
					( Origin gPackager )
				)
				( objectStatus "R4D54.1" )
			)
			( pin "@baseboard_fab2_lib.baseboard_fab2(sch_1):page213_i37:b"
				( attribute "PN" "2"
					( Origin gPackager )
				)
				( objectStatus "R4D54.2" )
			)
			( pin "@baseboard_fab2_lib.baseboard_fab2(sch_1):page223_i73:a"
				( attribute "PN" "1"
					( Origin gPackager )
				)
				( objectStatus "R1G23.1" )
			)
			( pin "@baseboard_fab2_lib.baseboard_fab2(sch_1):page223_i73:b"
				( attribute "PN" "2"
					( Origin gPackager )
				)
				( objectStatus "R1G23.2" )
			)
			( pin "@baseboard_fab2_lib.baseboard_fab2(sch_1):page213_i46:a"
				( attribute "PN" "1"
					( Origin gPackager )
				)
				( objectStatus "R4D51.1" )
			)
			( pin "@baseboard_fab2_lib.baseboard_fab2(sch_1):page213_i46:b"
				( attribute "PN" "2"
					( Origin gPackager )
				)
				( objectStatus "R4D51.2" )
			)
			( pin "@baseboard_fab2_lib.baseboard_fab2(sch_1):page213_i63:a"
				( attribute "PN" "1"
					( Origin gPackager )
				)
				( objectStatus "R4D49.1" )
			)
			( pin "@baseboard_fab2_lib.baseboard_fab2(sch_1):page213_i63:b"
				( attribute "PN" "2"
					( Origin gPackager )
				)
				( objectStatus "R4D49.2" )
			)
			( pin "@baseboard_fab2_lib.baseboard_fab2(sch_1):page218_i74:a"
				( attribute "PN" "1"
					( Origin gPackager )
				)
				( objectStatus "R7A8.1" )
			)
			( pin "@baseboard_fab2_lib.baseboard_fab2(sch_1):page218_i74:b"
				( attribute "PN" "2"
					( Origin gPackager )
				)
				( objectStatus "R7A8.2" )
			)
			( pin "@baseboard_fab2_lib.baseboard_fab2(sch_1):page213_i73:a"
				( attribute "PN" "1"
					( Origin gPackager )
				)
				( objectStatus "C4D33.1" )
			)
			( pin "@baseboard_fab2_lib.baseboard_fab2(sch_1):page213_i73:b"
				( attribute "PN" "2"
					( Origin gPackager )
				)
				( objectStatus "C4D33.2" )
			)
			( pin "@baseboard_fab2_lib.baseboard_fab2(sch_1):page213_i83:a"
				( attribute "PN" "1"
					( Origin gPackager )
				)
				( objectStatus "C4D44.1" )
			)
			( pin "@baseboard_fab2_lib.baseboard_fab2(sch_1):page213_i83:b"
				( attribute "PN" "2"
					( Origin gPackager )
				)
				( objectStatus "C4D44.2" )
			)
			( pin "@baseboard_fab2_lib.baseboard_fab2(sch_1):page213_i84:a"
				( attribute "PN" "1"
					( Origin gPackager )
				)
				( objectStatus "R4E7.1" )
			)
			( pin "@baseboard_fab2_lib.baseboard_fab2(sch_1):page213_i84:b"
				( attribute "PN" "2"
					( Origin gPackager )
				)
				( objectStatus "R4E7.2" )
			)
			( pin "@baseboard_fab2_lib.baseboard_fab2(sch_1):page213_i90:a"
				( attribute "PN" "1"
					( Origin gPackager )
				)
				( objectStatus "R6P41.1" )
			)
			( pin "@baseboard_fab2_lib.baseboard_fab2(sch_1):page213_i90:b"
				( attribute "PN" "2"
					( Origin gPackager )
				)
				( objectStatus "R6P41.2" )
			)
			( pin "@baseboard_fab2_lib.baseboard_fab2(sch_1):page213_i91:a"
				( attribute "PN" "1"
					( Origin gPackager )
				)
				( objectStatus "R6P40.1" )
			)
			( pin "@baseboard_fab2_lib.baseboard_fab2(sch_1):page213_i91:b"
				( attribute "PN" "2"
					( Origin gPackager )
				)
				( objectStatus "R6P40.2" )
			)
			( pin "@baseboard_fab2_lib.baseboard_fab2(sch_1):page213_i96:airef1"
				( attribute "PN" "21"
					( Origin gPackager )
				)
				( objectStatus "EU4D5.21" )
			)
			( pin "@baseboard_fab2_lib.baseboard_fab2(sch_1):page213_i96:aisen1"
				( attribute "PN" "22"
					( Origin gPackager )
				)
				( objectStatus "EU4D5.22" )
			)
			( pin "@baseboard_fab2_lib.baseboard_fab2(sch_1):page213_i96:apwm1"
				( attribute "PN" "5"
					( Origin gPackager )
				)
				( objectStatus "EU4D5.5" )
			)
			( pin "@baseboard_fab2_lib.baseboard_fab2(sch_1):page213_i96:atsen"
				( attribute "PN" "35"
					( Origin gPackager )
				)
				( objectStatus "EU4D5.35" )
			)
			( pin "@baseboard_fab2_lib.baseboard_fab2(sch_1):page213_i96:avref"
				( attribute "PN" "20"
					( Origin gPackager )
				)
				( objectStatus "EU4D5.20" )
			)
			( pin "@baseboard_fab2_lib.baseboard_fab2(sch_1):page213_i96:avren"
				( attribute "PN" "10"
					( Origin gPackager )
				)
				( objectStatus "EU4D5.10" )
			)
			( pin "@baseboard_fab2_lib.baseboard_fab2(sch_1):page213_i96:avrrdy"
				( attribute "PN" "9"
					( Origin gPackager )
				)
				( objectStatus "EU4D5.9" )
			)
			( pin "@baseboard_fab2_lib.baseboard_fab2(sch_1):page213_i96:avsen"
				( attribute "PN" "19"
					( Origin gPackager )
				)
				( objectStatus "EU4D5.19" )
			)
			( pin "@baseboard_fab2_lib.baseboard_fab2(sch_1):page213_i96:biref1"
				( attribute "PN" "25"
					( Origin gPackager )
				)
				( objectStatus "EU4D5.25" )
			)
			( pin "@baseboard_fab2_lib.baseboard_fab2(sch_1):page213_i96:bisen1"
				( attribute "PN" "26"
					( Origin gPackager )
				)
				( objectStatus "EU4D5.26" )
			)
			( pin "@baseboard_fab2_lib.baseboard_fab2(sch_1):page213_i96:bpwm1"
				( attribute "PN" "3"
					( Origin gPackager )
				)
				( objectStatus "EU4D5.3" )
			)
			( pin "@baseboard_fab2_lib.baseboard_fab2(sch_1):page213_i96:btsen"
				( attribute "PN" "34"
					( Origin gPackager )
				)
				( objectStatus "EU4D5.34" )
			)
			( pin "@baseboard_fab2_lib.baseboard_fab2(sch_1):page213_i96:bvref"
				( attribute "PN" "30"
					( Origin gPackager )
				)
				( objectStatus "EU4D5.30" )
			)
			( pin "@baseboard_fab2_lib.baseboard_fab2(sch_1):page213_i96:bvsen"
				( attribute "PN" "29"
					( Origin gPackager )
				)
				( objectStatus "EU4D5.29" )
			)
			( pin "@baseboard_fab2_lib.baseboard_fab2(sch_1):page213_i96:dnc(0)"
				( attribute "PN" "1"
					( Origin gPackager )
				)
				( objectStatus "EU4D5.1" )
			)
			( pin "@baseboard_fab2_lib.baseboard_fab2(sch_1):page213_i96:dnc(1)"
				( attribute "PN" "2"
					( Origin gPackager )
				)
				( objectStatus "EU4D5.2" )
			)
			( pin "@baseboard_fab2_lib.baseboard_fab2(sch_1):page213_i96:dnc(2)"
				( attribute "PN" "4"
					( Origin gPackager )
				)
				( objectStatus "EU4D5.4" )
			)
			( pin "@baseboard_fab2_lib.baseboard_fab2(sch_1):page213_i96:dnc(3)"
				( attribute "PN" "24"
					( Origin gPackager )
				)
				( objectStatus "EU4D5.24" )
			)
			( pin "@baseboard_fab2_lib.baseboard_fab2(sch_1):page213_i96:dnc(4)"
				( attribute "PN" "28"
					( Origin gPackager )
				)
				( objectStatus "EU4D5.28" )
			)
			( pin "@baseboard_fab2_lib.baseboard_fab2(sch_1):page213_i96:gnd(0)"
				( attribute "PN" "27"
					( Origin gPackager )
				)
				( objectStatus "EU4D5.27" )
			)
			( pin "@baseboard_fab2_lib.baseboard_fab2(sch_1):page213_i96:gnd(1)"
				( attribute "PN" "23"
					( Origin gPackager )
				)
				( objectStatus "EU4D5.23" )
			)
			( pin "@baseboard_fab2_lib.baseboard_fab2(sch_1):page213_i96:iinsen"
				( attribute "PN" "38"
					( Origin gPackager )
				)
				( objectStatus "EU4D5.38" )
			)
			( pin "@baseboard_fab2_lib.baseboard_fab2(sch_1):page213_i96:mp0"
				( attribute "PN" "13"
					( Origin gPackager )
				)
				( objectStatus "EU4D5.13" )
			)
			( pin "@baseboard_fab2_lib.baseboard_fab2(sch_1):page213_i96:mp1"
				( attribute "PN" "14"
					( Origin gPackager )
				)
				( objectStatus "EU4D5.14" )
			)
			( pin "@baseboard_fab2_lib.baseboard_fab2(sch_1):page213_i96:mp2"
				( attribute "PN" "18"
					( Origin gPackager )
				)
				( objectStatus "EU4D5.18" )
			)
			( pin "@baseboard_fab2_lib.baseboard_fab2(sch_1):page213_i96:mp3"
				( attribute "PN" "31"
					( Origin gPackager )
				)
				( objectStatus "EU4D5.31" )
			)
			( pin "@baseboard_fab2_lib.baseboard_fab2(sch_1):page213_i96:mp4"
				( attribute "PN" "32"
					( Origin gPackager )
				)
				( objectStatus "EU4D5.32" )
			)
			( pin "@baseboard_fab2_lib.baseboard_fab2(sch_1):page213_i96:pinalrt_n"
				( attribute "PN" "12"
					( Origin gPackager )
				)
				( objectStatus "EU4D5.12" )
			)
			( pin "@baseboard_fab2_lib.baseboard_fab2(sch_1):page213_i96:reset_n"
				( attribute "PN" "8"
					( Origin gPackager )
				)
				( objectStatus "EU4D5.8" )
			)
			( pin "@baseboard_fab2_lib.baseboard_fab2(sch_1):page213_i96:scl"
				( attribute "PN" "7"
					( Origin gPackager )
				)
				( objectStatus "EU4D5.7" )
			)
			( pin "@baseboard_fab2_lib.baseboard_fab2(sch_1):page213_i96:sda"
				( attribute "PN" "6"
					( Origin gPackager )
				)
				( objectStatus "EU4D5.6" )
			)
			( pin "@baseboard_fab2_lib.baseboard_fab2(sch_1):page213_i96:thpad"
				( attribute "PN" "41"
					( Origin gPackager )
				)
				( objectStatus "EU4D5.41" )
			)
			( pin "@baseboard_fab2_lib.baseboard_fab2(sch_1):page213_i96:valrt_n"
				( attribute "PN" "17"
					( Origin gPackager )
				)
				( objectStatus "EU4D5.17" )
			)
			( pin "@baseboard_fab2_lib.baseboard_fab2(sch_1):page213_i96:vclk"
				( attribute "PN" "15"
					( Origin gPackager )
				)
				( objectStatus "EU4D5.15" )
			)
			( pin "@baseboard_fab2_lib.baseboard_fab2(sch_1):page213_i96:vd12"
				( attribute "PN" "40"
					( Origin gPackager )
				)
				( objectStatus "EU4D5.40" )
			)
			( pin "@baseboard_fab2_lib.baseboard_fab2(sch_1):page213_i96:vdd"
				( attribute "PN" "39"
					( Origin gPackager )
				)
				( objectStatus "EU4D5.39" )
			)
			( pin "@baseboard_fab2_lib.baseboard_fab2(sch_1):page213_i96:vdio"
				( attribute "PN" "16"
					( Origin gPackager )
				)
				( objectStatus "EU4D5.16" )
			)
			( pin "@baseboard_fab2_lib.baseboard_fab2(sch_1):page213_i96:vinsen"
				( attribute "PN" "37"
					( Origin gPackager )
				)
				( objectStatus "EU4D5.37" )
			)
			( pin "@baseboard_fab2_lib.baseboard_fab2(sch_1):page213_i96:vrhot_n"
				( attribute "PN" "11"
					( Origin gPackager )
				)
				( objectStatus "EU4D5.11" )
			)
			( pin "@baseboard_fab2_lib.baseboard_fab2(sch_1):page213_i96:xaddr1"
				( attribute "PN" "36"
					( Origin gPackager )
				)
				( objectStatus "EU4D5.36" )
			)
			( pin "@baseboard_fab2_lib.baseboard_fab2(sch_1):page213_i96:xaddr2"
				( attribute "PN" "33"
					( Origin gPackager )
				)
				( objectStatus "EU4D5.33" )
			)
			( pin "@baseboard_fab2_lib.baseboard_fab2(sch_1):page236_i161:\1\"
				( attribute "PN" "1"
					( Origin gPackager )
				)
				( objectStatus "C7A13.1" )
			)
			( pin "@baseboard_fab2_lib.baseboard_fab2(sch_1):page236_i161:\2\"
				( attribute "PN" "2"
					( Origin gPackager )
				)
				( objectStatus "C7A13.2" )
			)
			( pin "@baseboard_fab2_lib.baseboard_fab2(sch_1):page214_i24:a"
				( attribute "PN" "1"
					( Origin gPackager )
				)
				( objectStatus "C6R5.1" )
			)
			( pin "@baseboard_fab2_lib.baseboard_fab2(sch_1):page214_i24:b"
				( attribute "PN" "2"
					( Origin gPackager )
				)
				( objectStatus "C6R5.2" )
			)
			( pin "@baseboard_fab2_lib.baseboard_fab2(sch_1):page236_i160:\1\"
				( attribute "PN" "1"
					( Origin gPackager )
				)
				( objectStatus "C22W24.1" )
			)
			( pin "@baseboard_fab2_lib.baseboard_fab2(sch_1):page236_i160:\2\"
				( attribute "PN" "2"
					( Origin gPackager )
				)
				( objectStatus "C22W24.2" )
			)
			( pin "@baseboard_fab2_lib.baseboard_fab2(sch_1):page236_i159:\1\"
				( attribute "PN" "1"
					( Origin gPackager )
				)
				( objectStatus "C22W23.1" )
			)
			( pin "@baseboard_fab2_lib.baseboard_fab2(sch_1):page236_i159:\2\"
				( attribute "PN" "2"
					( Origin gPackager )
				)
				( objectStatus "C22W23.2" )
			)
			( pin "@baseboard_fab2_lib.baseboard_fab2(sch_1):page214_i65:a"
				( attribute "PN" "1"
					( Origin gPackager )
				)
				( objectStatus "C7R1.1" )
			)
			( pin "@baseboard_fab2_lib.baseboard_fab2(sch_1):page214_i65:b"
				( attribute "PN" "2"
					( Origin gPackager )
				)
				( objectStatus "C7R1.2" )
			)
			( pin "@baseboard_fab2_lib.baseboard_fab2(sch_1):page205_i82:f"
				( attribute "PN" "2"
					( Origin gPackager )
				)
				( objectStatus "L4C2.2" )
			)
			( pin "@baseboard_fab2_lib.baseboard_fab2(sch_1):page205_i82:s"
				( attribute "PN" "1"
					( Origin gPackager )
				)
				( objectStatus "L4C2.1" )
			)
			( pin "@baseboard_fab2_lib.baseboard_fab2(sch_1):page216_i145:a"
				( attribute "PN" "1"
					( Origin gPackager )
				)
				( objectStatus "R3U6.1" )
			)
			( pin "@baseboard_fab2_lib.baseboard_fab2(sch_1):page216_i145:b"
				( attribute "PN" "2"
					( Origin gPackager )
				)
				( objectStatus "R3U6.2" )
			)
			( pin "@baseboard_fab2_lib.baseboard_fab2(sch_1):page214_i73:a"
				( attribute "PN" "1"
					( Origin gPackager )
				)
				( objectStatus "C4E23.1" )
			)
			( pin "@baseboard_fab2_lib.baseboard_fab2(sch_1):page214_i73:b"
				( attribute "PN" "2"
					( Origin gPackager )
				)
				( objectStatus "C4E23.2" )
			)
			( pin "@baseboard_fab2_lib.baseboard_fab2(sch_1):page219_i151:\1\"
				( attribute "PN" "1"
					( Origin gPackager )
				)
				( objectStatus "C7A18.1" )
			)
			( pin "@baseboard_fab2_lib.baseboard_fab2(sch_1):page219_i151:\2\"
				( attribute "PN" "2"
					( Origin gPackager )
				)
				( objectStatus "C7A18.2" )
			)
			( pin "@baseboard_fab2_lib.baseboard_fab2(sch_1):page214_i76:a"
				( attribute "PN" "1"
					( Origin gPackager )
				)
				( objectStatus "C4E22.1" )
			)
			( pin "@baseboard_fab2_lib.baseboard_fab2(sch_1):page214_i76:b"
				( attribute "PN" "2"
					( Origin gPackager )
				)
				( objectStatus "C4E22.2" )
			)
			( pin "@baseboard_fab2_lib.baseboard_fab2(sch_1):page214_i77:a"
				( attribute "PN" "1"
					( Origin gPackager )
				)
				( objectStatus "C4E13.1" )
			)
			( pin "@baseboard_fab2_lib.baseboard_fab2(sch_1):page214_i77:b"
				( attribute "PN" "2"
					( Origin gPackager )
				)
				( objectStatus "C4E13.2" )
			)
			( pin "@baseboard_fab2_lib.baseboard_fab2(sch_1):page214_i78:a"
				( attribute "PN" "1"
					( Origin gPackager )
				)
				( objectStatus "C4E18.1" )
			)
			( pin "@baseboard_fab2_lib.baseboard_fab2(sch_1):page214_i78:b"
				( attribute "PN" "2"
					( Origin gPackager )
				)
				( objectStatus "C4E18.2" )
			)
			( pin "@baseboard_fab2_lib.baseboard_fab2(sch_1):page214_i79:a"
				( attribute "PN" "1"
					( Origin gPackager )
				)
				( objectStatus "C4E15.1" )
			)
			( pin "@baseboard_fab2_lib.baseboard_fab2(sch_1):page214_i79:b"
				( attribute "PN" "2"
					( Origin gPackager )
				)
				( objectStatus "C4E15.2" )
			)
			( pin "@baseboard_fab2_lib.baseboard_fab2(sch_1):page214_i80:a"
				( attribute "PN" "1"
					( Origin gPackager )
				)
				( objectStatus "C6R14.1" )
			)
			( pin "@baseboard_fab2_lib.baseboard_fab2(sch_1):page214_i80:b"
				( attribute "PN" "2"
					( Origin gPackager )
				)
				( objectStatus "C6R14.2" )
			)
			( pin "@baseboard_fab2_lib.baseboard_fab2(sch_1):page214_i81:a"
				( attribute "PN" "1"
					( Origin gPackager )
				)
				( objectStatus "C6R10.1" )
			)
			( pin "@baseboard_fab2_lib.baseboard_fab2(sch_1):page214_i81:b"
				( attribute "PN" "2"
					( Origin gPackager )
				)
				( objectStatus "C6R10.2" )
			)
			( pin "@baseboard_fab2_lib.baseboard_fab2(sch_1):page214_i83:a"
				( attribute "PN" "1"
					( Origin gPackager )
				)
				( objectStatus "C6R8.1" )
			)
			( pin "@baseboard_fab2_lib.baseboard_fab2(sch_1):page214_i83:b"
				( attribute "PN" "2"
					( Origin gPackager )
				)
				( objectStatus "C6R8.2" )
			)
			( pin "@baseboard_fab2_lib.baseboard_fab2(sch_1):page214_i96:a"
				( attribute "PN" "1"
					( Origin gPackager )
				)
				( objectStatus "C3D27.1" )
			)
			( pin "@baseboard_fab2_lib.baseboard_fab2(sch_1):page214_i96:b"
				( attribute "PN" "2"
					( Origin gPackager )
				)
				( objectStatus "C3D27.2" )
			)
			( pin "@baseboard_fab2_lib.baseboard_fab2(sch_1):page214_i101:a"
				( attribute "PN" "1"
					( Origin gPackager )
				)
				( objectStatus "R3D28.1" )
			)
			( pin "@baseboard_fab2_lib.baseboard_fab2(sch_1):page214_i101:b"
				( attribute "PN" "2"
					( Origin gPackager )
				)
				( objectStatus "R3D28.2" )
			)
			( pin "@baseboard_fab2_lib.baseboard_fab2(sch_1):page214_i105:a"
				( attribute "PN" "1"
					( Origin gPackager )
				)
				( objectStatus "R3E1.1" )
			)
			( pin "@baseboard_fab2_lib.baseboard_fab2(sch_1):page214_i105:b"
				( attribute "PN" "2"
					( Origin gPackager )
				)
				( objectStatus "R3E1.2" )
			)
			( pin "@baseboard_fab2_lib.baseboard_fab2(sch_1):page214_i108:a"
				( attribute "PN" "1"
					( Origin gPackager )
				)
				( objectStatus "C3E1.1" )
			)
			( pin "@baseboard_fab2_lib.baseboard_fab2(sch_1):page214_i108:b"
				( attribute "PN" "2"
					( Origin gPackager )
				)
				( objectStatus "C3E1.2" )
			)
			( pin "@baseboard_fab2_lib.baseboard_fab2(sch_1):page214_i109:a"
				( attribute "PN" "1"
					( Origin gPackager )
				)
				( objectStatus "R7R1.1" )
			)
			( pin "@baseboard_fab2_lib.baseboard_fab2(sch_1):page214_i109:b"
				( attribute "PN" "2"
					( Origin gPackager )
				)
				( objectStatus "R7R1.2" )
			)
			( pin "@baseboard_fab2_lib.baseboard_fab2(sch_1):page214_i126:boost"
				( attribute "PN" "33"
					( Origin gPackager )
				)
				( objectStatus "EU4E2.33" )
			)
			( pin "@baseboard_fab2_lib.baseboard_fab2(sch_1):page214_i126:en"
				( attribute "PN" "35"
					( Origin gPackager )
				)
				( objectStatus "EU4E2.35" )
			)
			( pin "@baseboard_fab2_lib.baseboard_fab2(sch_1):page214_i126:gl(0)"
				( attribute "PN" "6"
					( Origin gPackager )
				)
				( objectStatus "EU4E2.6" )
			)
			( pin "@baseboard_fab2_lib.baseboard_fab2(sch_1):page214_i126:gl(1)"
				( attribute "PN" "41"
					( Origin gPackager )
				)
				( objectStatus "EU4E2.41" )
			)
			( pin "@baseboard_fab2_lib.baseboard_fab2(sch_1):page214_i126:iout"
				( attribute "PN" "38"
					( Origin gPackager )
				)
				( objectStatus "EU4E2.38" )
			)
			( pin "@baseboard_fab2_lib.baseboard_fab2(sch_1):page214_i126:lgnd"
				( attribute "PN" "2"
					( Origin gPackager )
				)
				( objectStatus "EU4E2.2" )
			)
			( pin "@baseboard_fab2_lib.baseboard_fab2(sch_1):page214_i126:nc"
				( attribute "PN" "31"
					( Origin gPackager )
				)
				( objectStatus "EU4E2.31" )
			)
			( pin "@baseboard_fab2_lib.baseboard_fab2(sch_1):page214_i126:ocset"
				( attribute "PN" "37"
					( Origin gPackager )
				)
				( objectStatus "EU4E2.37" )
			)
			( pin "@baseboard_fab2_lib.baseboard_fab2(sch_1):page214_i126:pgnd(0)"
				( attribute "PN" "5"
					( Origin gPackager )
				)
				( objectStatus "EU4E2.5" )
			)
			( pin "@baseboard_fab2_lib.baseboard_fab2(sch_1):page214_i126:pgnd(1)"
				( attribute "PN" "7"
					( Origin gPackager )
				)
				( objectStatus "EU4E2.7" )
			)
			( pin "@baseboard_fab2_lib.baseboard_fab2(sch_1):page214_i126:pgnd(2)"
				( attribute "PN" "40"
					( Origin gPackager )
				)
				( objectStatus "EU4E2.40" )
			)
			( pin "@baseboard_fab2_lib.baseboard_fab2(sch_1):page214_i126:phase"
				( attribute "PN" "32"
					( Origin gPackager )
				)
				( objectStatus "EU4E2.32" )
			)
			( pin "@baseboard_fab2_lib.baseboard_fab2(sch_1):page214_i126:pwm"
				( attribute "PN" "34"
					( Origin gPackager )
				)
				( objectStatus "EU4E2.34" )
			)
			( pin "@baseboard_fab2_lib.baseboard_fab2(sch_1):page214_i126:refin"
				( attribute "PN" "39"
					( Origin gPackager )
				)
				( objectStatus "EU4E2.39" )
			)
			( pin "@baseboard_fab2_lib.baseboard_fab2(sch_1):page214_i126:sw"
				( attribute "PN" "10"
					( Origin gPackager )
				)
				( objectStatus "EU4E2.10" )
			)
			( pin "@baseboard_fab2_lib.baseboard_fab2(sch_1):page214_i126:tout_flt"
				( attribute "PN" "36"
					( Origin gPackager )
				)
				( objectStatus "EU4E2.36" )
			)
			( pin "@baseboard_fab2_lib.baseboard_fab2(sch_1):page214_i126:vcc"
				( attribute "PN" "3"
					( Origin gPackager )
				)
				( objectStatus "EU4E2.3" )
			)
			( pin "@baseboard_fab2_lib.baseboard_fab2(sch_1):page214_i126:vdrv"
				( attribute "PN" "4"
					( Origin gPackager )
				)
				( objectStatus "EU4E2.4" )
			)
			( pin "@baseboard_fab2_lib.baseboard_fab2(sch_1):page214_i126:vin(0)"
				( attribute "PN" "25"
					( Origin gPackager )
				)
				( objectStatus "EU4E2.25" )
			)
			( pin "@baseboard_fab2_lib.baseboard_fab2(sch_1):page214_i126:vin(1)"
				( attribute "PN" "30"
					( Origin gPackager )
				)
				( objectStatus "EU4E2.30" )
			)
			( pin "@baseboard_fab2_lib.baseboard_fab2(sch_1):page214_i126:vos"
				( attribute "PN" "1"
					( Origin gPackager )
				)
				( objectStatus "EU4E2.1" )
			)
			( pin "@baseboard_fab2_lib.baseboard_fab2(sch_1):page214_i127:a"
				( attribute "PN" "1"
					( Origin gPackager )
				)
				( objectStatus "R4E21.1" )
			)
			( pin "@baseboard_fab2_lib.baseboard_fab2(sch_1):page214_i127:b"
				( attribute "PN" "2"
					( Origin gPackager )
				)
				( objectStatus "R4E21.2" )
			)
			( pin "@baseboard_fab2_lib.baseboard_fab2(sch_1):page214_i129:a"
				( attribute "PN" "1"
					( Origin gPackager )
				)
				( objectStatus "SH3D2.1" )
			)
			( pin "@baseboard_fab2_lib.baseboard_fab2(sch_1):page214_i129:b"
				( attribute "PN" "2"
					( Origin gPackager )
				)
				( objectStatus "SH3D2.2" )
			)
			( pin "@baseboard_fab2_lib.baseboard_fab2(sch_1):page214_i130:a"
				( attribute "PN" "1"
					( Origin gPackager )
				)
				( objectStatus "SH3D1.1" )
			)
			( pin "@baseboard_fab2_lib.baseboard_fab2(sch_1):page214_i130:b"
				( attribute "PN" "2"
					( Origin gPackager )
				)
				( objectStatus "SH3D1.2" )
			)
			( pin "@baseboard_fab2_lib.baseboard_fab2(sch_1):page197_i35:\drain#4\"
				( attribute "PN" "4"
					( Origin gPackager )
				)
				( objectStatus "Q12W4.4" )
			)
			( pin "@baseboard_fab2_lib.baseboard_fab2(sch_1):page197_i35:\drain#6\"
				( attribute "PN" "6"
					( Origin gPackager )
				)
				( objectStatus "Q12W4.6" )
			)
			( pin "@baseboard_fab2_lib.baseboard_fab2(sch_1):page197_i35:\gate#1\"
				( attribute "PN" "1"
					( Origin gPackager )
				)
				( objectStatus "Q12W4.1" )
			)
			( pin "@baseboard_fab2_lib.baseboard_fab2(sch_1):page197_i35:\gate#3\"
				( attribute "PN" "3"
					( Origin gPackager )
				)
				( objectStatus "Q12W4.3" )
			)
			( pin "@baseboard_fab2_lib.baseboard_fab2(sch_1):page197_i35:\source#2\"
				( attribute "PN" "2"
					( Origin gPackager )
				)
				( objectStatus "Q12W4.2" )
			)
			( pin "@baseboard_fab2_lib.baseboard_fab2(sch_1):page197_i35:\source#5\"
				( attribute "PN" "5"
					( Origin gPackager )
				)
				( objectStatus "Q12W4.5" )
			)
			( pin "@baseboard_fab2_lib.baseboard_fab2(sch_1):page197_i29:a"
				( attribute "PN" "1"
					( Origin gPackager )
				)
				( objectStatus "R9M4.1" )
			)
			( pin "@baseboard_fab2_lib.baseboard_fab2(sch_1):page197_i29:b"
				( attribute "PN" "2"
					( Origin gPackager )
				)
				( objectStatus "R9M4.2" )
			)
			( pin "@baseboard_fab2_lib.baseboard_fab2(sch_1):page101_i146:a"
				( attribute "PN" "1"
					( Origin gPackager )
				)
				( objectStatus "C8F19.1" )
			)
			( pin "@baseboard_fab2_lib.baseboard_fab2(sch_1):page101_i146:b"
				( attribute "PN" "2"
					( Origin gPackager )
				)
				( objectStatus "C8F19.2" )
			)
			( pin "@baseboard_fab2_lib.baseboard_fab2(sch_1):page226_i69:airef1"
				( attribute "PN" "21"
					( Origin gPackager )
				)
				( objectStatus "EU1B1.21" )
			)
			( pin "@baseboard_fab2_lib.baseboard_fab2(sch_1):page226_i69:airef2"
				( attribute "PN" "23"
					( Origin gPackager )
				)
				( objectStatus "EU1B1.23" )
			)
			( pin "@baseboard_fab2_lib.baseboard_fab2(sch_1):page226_i69:airef3"
				( attribute "PN" "25"
					( Origin gPackager )
				)
				( objectStatus "EU1B1.25" )
			)
			( pin "@baseboard_fab2_lib.baseboard_fab2(sch_1):page226_i69:aisen1"
				( attribute "PN" "22"
					( Origin gPackager )
				)
				( objectStatus "EU1B1.22" )
			)
			( pin "@baseboard_fab2_lib.baseboard_fab2(sch_1):page226_i69:aisen2"
				( attribute "PN" "24"
					( Origin gPackager )
				)
				( objectStatus "EU1B1.24" )
			)
			( pin "@baseboard_fab2_lib.baseboard_fab2(sch_1):page226_i69:aisen3"
				( attribute "PN" "26"
					( Origin gPackager )
				)
				( objectStatus "EU1B1.26" )
			)
			( pin "@baseboard_fab2_lib.baseboard_fab2(sch_1):page226_i69:apwm1"
				( attribute "PN" "5"
					( Origin gPackager )
				)
				( objectStatus "EU1B1.5" )
			)
			( pin "@baseboard_fab2_lib.baseboard_fab2(sch_1):page226_i69:apwm2"
				( attribute "PN" "4"
					( Origin gPackager )
				)
				( objectStatus "EU1B1.4" )
			)
			( pin "@baseboard_fab2_lib.baseboard_fab2(sch_1):page226_i69:apwm3"
				( attribute "PN" "3"
					( Origin gPackager )
				)
				( objectStatus "EU1B1.3" )
			)
			( pin "@baseboard_fab2_lib.baseboard_fab2(sch_1):page226_i69:atsen"
				( attribute "PN" "35"
					( Origin gPackager )
				)
				( objectStatus "EU1B1.35" )
			)
			( pin "@baseboard_fab2_lib.baseboard_fab2(sch_1):page226_i69:avref"
				( attribute "PN" "20"
					( Origin gPackager )
				)
				( objectStatus "EU1B1.20" )
			)
			( pin "@baseboard_fab2_lib.baseboard_fab2(sch_1):page226_i69:avren"
				( attribute "PN" "10"
					( Origin gPackager )
				)
				( objectStatus "EU1B1.10" )
			)
			( pin "@baseboard_fab2_lib.baseboard_fab2(sch_1):page226_i69:avrrdy"
				( attribute "PN" "9"
					( Origin gPackager )
				)
				( objectStatus "EU1B1.9" )
			)
			( pin "@baseboard_fab2_lib.baseboard_fab2(sch_1):page226_i69:avsen"
				( attribute "PN" "19"
					( Origin gPackager )
				)
				( objectStatus "EU1B1.19" )
			)
			( pin "@baseboard_fab2_lib.baseboard_fab2(sch_1):page226_i69:biref1"
				( attribute "PN" "31"
					( Origin gPackager )
				)
				( objectStatus "EU1B1.31" )
			)
			( pin "@baseboard_fab2_lib.baseboard_fab2(sch_1):page226_i69:bisen1"
				( attribute "PN" "32"
					( Origin gPackager )
				)
				( objectStatus "EU1B1.32" )
			)
			( pin "@baseboard_fab2_lib.baseboard_fab2(sch_1):page226_i69:bpwm1"
				( attribute "PN" "1"
					( Origin gPackager )
				)
				( objectStatus "EU1B1.1" )
			)
			( pin "@baseboard_fab2_lib.baseboard_fab2(sch_1):page226_i69:btsen"
				( attribute "PN" "34"
					( Origin gPackager )
				)
				( objectStatus "EU1B1.34" )
			)
			( pin "@baseboard_fab2_lib.baseboard_fab2(sch_1):page226_i69:bvref"
				( attribute "PN" "30"
					( Origin gPackager )
				)
				( objectStatus "EU1B1.30" )
			)
			( pin "@baseboard_fab2_lib.baseboard_fab2(sch_1):page226_i69:bvsen"
				( attribute "PN" "29"
					( Origin gPackager )
				)
				( objectStatus "EU1B1.29" )
			)
			( pin "@baseboard_fab2_lib.baseboard_fab2(sch_1):page226_i69:dnc(0)"
				( attribute "PN" "2"
					( Origin gPackager )
				)
				( objectStatus "EU1B1.2" )
			)
			( pin "@baseboard_fab2_lib.baseboard_fab2(sch_1):page226_i69:dnc(1)"
				( attribute "PN" "28"
					( Origin gPackager )
				)
				( objectStatus "EU1B1.28" )
			)
			( pin "@baseboard_fab2_lib.baseboard_fab2(sch_1):page226_i69:gnd"
				( attribute "PN" "27"
					( Origin gPackager )
				)
				( objectStatus "EU1B1.27" )
			)
			( pin "@baseboard_fab2_lib.baseboard_fab2(sch_1):page226_i69:iinsen"
				( attribute "PN" "38"
					( Origin gPackager )
				)
				( objectStatus "EU1B1.38" )
			)
			( pin "@baseboard_fab2_lib.baseboard_fab2(sch_1):page226_i69:mp0"
				( attribute "PN" "13"
					( Origin gPackager )
				)
				( objectStatus "EU1B1.13" )
			)
			( pin "@baseboard_fab2_lib.baseboard_fab2(sch_1):page226_i69:mp1"
				( attribute "PN" "14"
					( Origin gPackager )
				)
				( objectStatus "EU1B1.14" )
			)
			( pin "@baseboard_fab2_lib.baseboard_fab2(sch_1):page226_i69:mp2"
				( attribute "PN" "18"
					( Origin gPackager )
				)
				( objectStatus "EU1B1.18" )
			)
			( pin "@baseboard_fab2_lib.baseboard_fab2(sch_1):page226_i69:pinalrt_n"
				( attribute "PN" "12"
					( Origin gPackager )
				)
				( objectStatus "EU1B1.12" )
			)
			( pin "@baseboard_fab2_lib.baseboard_fab2(sch_1):page226_i69:reset_n"
				( attribute "PN" "8"
					( Origin gPackager )
				)
				( objectStatus "EU1B1.8" )
			)
			( pin "@baseboard_fab2_lib.baseboard_fab2(sch_1):page226_i69:scl"
				( attribute "PN" "7"
					( Origin gPackager )
				)
				( objectStatus "EU1B1.7" )
			)
			( pin "@baseboard_fab2_lib.baseboard_fab2(sch_1):page226_i69:sda"
				( attribute "PN" "6"
					( Origin gPackager )
				)
				( objectStatus "EU1B1.6" )
			)
			( pin "@baseboard_fab2_lib.baseboard_fab2(sch_1):page226_i69:thpad"
				( attribute "PN" "41"
					( Origin gPackager )
				)
				( objectStatus "EU1B1.41" )
			)
			( pin "@baseboard_fab2_lib.baseboard_fab2(sch_1):page226_i69:valrt_n"
				( attribute "PN" "17"
					( Origin gPackager )
				)
				( objectStatus "EU1B1.17" )
			)
			( pin "@baseboard_fab2_lib.baseboard_fab2(sch_1):page226_i69:vclk"
				( attribute "PN" "15"
					( Origin gPackager )
				)
				( objectStatus "EU1B1.15" )
			)
			( pin "@baseboard_fab2_lib.baseboard_fab2(sch_1):page226_i69:vd12"
				( attribute "PN" "40"
					( Origin gPackager )
				)
				( objectStatus "EU1B1.40" )
			)
			( pin "@baseboard_fab2_lib.baseboard_fab2(sch_1):page226_i69:vdd"
				( attribute "PN" "39"
					( Origin gPackager )
				)
				( objectStatus "EU1B1.39" )
			)
			( pin "@baseboard_fab2_lib.baseboard_fab2(sch_1):page226_i69:vdio"
				( attribute "PN" "16"
					( Origin gPackager )
				)
				( objectStatus "EU1B1.16" )
			)
			( pin "@baseboard_fab2_lib.baseboard_fab2(sch_1):page226_i69:vinsen"
				( attribute "PN" "37"
					( Origin gPackager )
				)
				( objectStatus "EU1B1.37" )
			)
			( pin "@baseboard_fab2_lib.baseboard_fab2(sch_1):page226_i69:vrhot_n"
				( attribute "PN" "11"
					( Origin gPackager )
				)
				( objectStatus "EU1B1.11" )
			)
			( pin "@baseboard_fab2_lib.baseboard_fab2(sch_1):page226_i69:xaddr1"
				( attribute "PN" "36"
					( Origin gPackager )
				)
				( objectStatus "EU1B1.36" )
			)
			( pin "@baseboard_fab2_lib.baseboard_fab2(sch_1):page226_i69:xaddr2"
				( attribute "PN" "33"
					( Origin gPackager )
				)
				( objectStatus "EU1B1.33" )
			)
			( pin "@baseboard_fab2_lib.baseboard_fab2(sch_1):page226_i57:a"
				( attribute "PN" "1"
					( Origin gPackager )
				)
				( objectStatus "R9M7.1" )
			)
			( pin "@baseboard_fab2_lib.baseboard_fab2(sch_1):page226_i57:b"
				( attribute "PN" "2"
					( Origin gPackager )
				)
				( objectStatus "R9M7.2" )
			)
			( pin "@baseboard_fab2_lib.baseboard_fab2(sch_1):page223_i69:airef1"
				( attribute "PN" "21"
					( Origin gPackager )
				)
				( objectStatus "EU1G2.21" )
			)
			( pin "@baseboard_fab2_lib.baseboard_fab2(sch_1):page223_i69:airef2"
				( attribute "PN" "23"
					( Origin gPackager )
				)
				( objectStatus "EU1G2.23" )
			)
			( pin "@baseboard_fab2_lib.baseboard_fab2(sch_1):page223_i69:airef3"
				( attribute "PN" "25"
					( Origin gPackager )
				)
				( objectStatus "EU1G2.25" )
			)
			( pin "@baseboard_fab2_lib.baseboard_fab2(sch_1):page223_i69:aisen1"
				( attribute "PN" "22"
					( Origin gPackager )
				)
				( objectStatus "EU1G2.22" )
			)
			( pin "@baseboard_fab2_lib.baseboard_fab2(sch_1):page223_i69:aisen2"
				( attribute "PN" "24"
					( Origin gPackager )
				)
				( objectStatus "EU1G2.24" )
			)
			( pin "@baseboard_fab2_lib.baseboard_fab2(sch_1):page223_i69:aisen3"
				( attribute "PN" "26"
					( Origin gPackager )
				)
				( objectStatus "EU1G2.26" )
			)
			( pin "@baseboard_fab2_lib.baseboard_fab2(sch_1):page223_i69:apwm1"
				( attribute "PN" "5"
					( Origin gPackager )
				)
				( objectStatus "EU1G2.5" )
			)
			( pin "@baseboard_fab2_lib.baseboard_fab2(sch_1):page223_i69:apwm2"
				( attribute "PN" "4"
					( Origin gPackager )
				)
				( objectStatus "EU1G2.4" )
			)
			( pin "@baseboard_fab2_lib.baseboard_fab2(sch_1):page223_i69:apwm3"
				( attribute "PN" "3"
					( Origin gPackager )
				)
				( objectStatus "EU1G2.3" )
			)
			( pin "@baseboard_fab2_lib.baseboard_fab2(sch_1):page223_i69:atsen"
				( attribute "PN" "35"
					( Origin gPackager )
				)
				( objectStatus "EU1G2.35" )
			)
			( pin "@baseboard_fab2_lib.baseboard_fab2(sch_1):page223_i69:avref"
				( attribute "PN" "20"
					( Origin gPackager )
				)
				( objectStatus "EU1G2.20" )
			)
			( pin "@baseboard_fab2_lib.baseboard_fab2(sch_1):page223_i69:avren"
				( attribute "PN" "10"
					( Origin gPackager )
				)
				( objectStatus "EU1G2.10" )
			)
			( pin "@baseboard_fab2_lib.baseboard_fab2(sch_1):page223_i69:avrrdy"
				( attribute "PN" "9"
					( Origin gPackager )
				)
				( objectStatus "EU1G2.9" )
			)
			( pin "@baseboard_fab2_lib.baseboard_fab2(sch_1):page223_i69:avsen"
				( attribute "PN" "19"
					( Origin gPackager )
				)
				( objectStatus "EU1G2.19" )
			)
			( pin "@baseboard_fab2_lib.baseboard_fab2(sch_1):page223_i69:biref1"
				( attribute "PN" "31"
					( Origin gPackager )
				)
				( objectStatus "EU1G2.31" )
			)
			( pin "@baseboard_fab2_lib.baseboard_fab2(sch_1):page223_i69:bisen1"
				( attribute "PN" "32"
					( Origin gPackager )
				)
				( objectStatus "EU1G2.32" )
			)
			( pin "@baseboard_fab2_lib.baseboard_fab2(sch_1):page223_i69:bpwm1"
				( attribute "PN" "1"
					( Origin gPackager )
				)
				( objectStatus "EU1G2.1" )
			)
			( pin "@baseboard_fab2_lib.baseboard_fab2(sch_1):page223_i69:btsen"
				( attribute "PN" "34"
					( Origin gPackager )
				)
				( objectStatus "EU1G2.34" )
			)
			( pin "@baseboard_fab2_lib.baseboard_fab2(sch_1):page223_i69:bvref"
				( attribute "PN" "30"
					( Origin gPackager )
				)
				( objectStatus "EU1G2.30" )
			)
			( pin "@baseboard_fab2_lib.baseboard_fab2(sch_1):page223_i69:bvsen"
				( attribute "PN" "29"
					( Origin gPackager )
				)
				( objectStatus "EU1G2.29" )
			)
			( pin "@baseboard_fab2_lib.baseboard_fab2(sch_1):page223_i69:dnc(0)"
				( attribute "PN" "2"
					( Origin gPackager )
				)
				( objectStatus "EU1G2.2" )
			)
			( pin "@baseboard_fab2_lib.baseboard_fab2(sch_1):page223_i69:dnc(1)"
				( attribute "PN" "28"
					( Origin gPackager )
				)
				( objectStatus "EU1G2.28" )
			)
			( pin "@baseboard_fab2_lib.baseboard_fab2(sch_1):page223_i69:gnd"
				( attribute "PN" "27"
					( Origin gPackager )
				)
				( objectStatus "EU1G2.27" )
			)
			( pin "@baseboard_fab2_lib.baseboard_fab2(sch_1):page223_i69:iinsen"
				( attribute "PN" "38"
					( Origin gPackager )
				)
				( objectStatus "EU1G2.38" )
			)
			( pin "@baseboard_fab2_lib.baseboard_fab2(sch_1):page223_i69:mp0"
				( attribute "PN" "13"
					( Origin gPackager )
				)
				( objectStatus "EU1G2.13" )
			)
			( pin "@baseboard_fab2_lib.baseboard_fab2(sch_1):page223_i69:mp1"
				( attribute "PN" "14"
					( Origin gPackager )
				)
				( objectStatus "EU1G2.14" )
			)
			( pin "@baseboard_fab2_lib.baseboard_fab2(sch_1):page223_i69:mp2"
				( attribute "PN" "18"
					( Origin gPackager )
				)
				( objectStatus "EU1G2.18" )
			)
			( pin "@baseboard_fab2_lib.baseboard_fab2(sch_1):page223_i69:pinalrt_n"
				( attribute "PN" "12"
					( Origin gPackager )
				)
				( objectStatus "EU1G2.12" )
			)
			( pin "@baseboard_fab2_lib.baseboard_fab2(sch_1):page223_i69:reset_n"
				( attribute "PN" "8"
					( Origin gPackager )
				)
				( objectStatus "EU1G2.8" )
			)
			( pin "@baseboard_fab2_lib.baseboard_fab2(sch_1):page223_i69:scl"
				( attribute "PN" "7"
					( Origin gPackager )
				)
				( objectStatus "EU1G2.7" )
			)
			( pin "@baseboard_fab2_lib.baseboard_fab2(sch_1):page223_i69:sda"
				( attribute "PN" "6"
					( Origin gPackager )
				)
				( objectStatus "EU1G2.6" )
			)
			( pin "@baseboard_fab2_lib.baseboard_fab2(sch_1):page223_i69:thpad"
				( attribute "PN" "41"
					( Origin gPackager )
				)
				( objectStatus "EU1G2.41" )
			)
			( pin "@baseboard_fab2_lib.baseboard_fab2(sch_1):page223_i69:valrt_n"
				( attribute "PN" "17"
					( Origin gPackager )
				)
				( objectStatus "EU1G2.17" )
			)
			( pin "@baseboard_fab2_lib.baseboard_fab2(sch_1):page223_i69:vclk"
				( attribute "PN" "15"
					( Origin gPackager )
				)
				( objectStatus "EU1G2.15" )
			)
			( pin "@baseboard_fab2_lib.baseboard_fab2(sch_1):page223_i69:vd12"
				( attribute "PN" "40"
					( Origin gPackager )
				)
				( objectStatus "EU1G2.40" )
			)
			( pin "@baseboard_fab2_lib.baseboard_fab2(sch_1):page223_i69:vdd"
				( attribute "PN" "39"
					( Origin gPackager )
				)
				( objectStatus "EU1G2.39" )
			)
			( pin "@baseboard_fab2_lib.baseboard_fab2(sch_1):page223_i69:vdio"
				( attribute "PN" "16"
					( Origin gPackager )
				)
				( objectStatus "EU1G2.16" )
			)
			( pin "@baseboard_fab2_lib.baseboard_fab2(sch_1):page223_i69:vinsen"
				( attribute "PN" "37"
					( Origin gPackager )
				)
				( objectStatus "EU1G2.37" )
			)
			( pin "@baseboard_fab2_lib.baseboard_fab2(sch_1):page223_i69:vrhot_n"
				( attribute "PN" "11"
					( Origin gPackager )
				)
				( objectStatus "EU1G2.11" )
			)
			( pin "@baseboard_fab2_lib.baseboard_fab2(sch_1):page223_i69:xaddr1"
				( attribute "PN" "36"
					( Origin gPackager )
				)
				( objectStatus "EU1G2.36" )
			)
			( pin "@baseboard_fab2_lib.baseboard_fab2(sch_1):page223_i69:xaddr2"
				( attribute "PN" "33"
					( Origin gPackager )
				)
				( objectStatus "EU1G2.33" )
			)
			( pin "@baseboard_fab2_lib.baseboard_fab2(sch_1):page223_i57:a"
				( attribute "PN" "1"
					( Origin gPackager )
				)
				( objectStatus "R9U3.1" )
			)
			( pin "@baseboard_fab2_lib.baseboard_fab2(sch_1):page223_i57:b"
				( attribute "PN" "2"
					( Origin gPackager )
				)
				( objectStatus "R9U3.2" )
			)
			( pin "@baseboard_fab2_lib.baseboard_fab2(sch_1):page226_i75:a"
				( attribute "PN" "1"
					( Origin gPackager )
				)
				( objectStatus "R1B13.1" )
			)
			( pin "@baseboard_fab2_lib.baseboard_fab2(sch_1):page226_i75:b"
				( attribute "PN" "2"
					( Origin gPackager )
				)
				( objectStatus "R1B13.2" )
			)
			( pin "@baseboard_fab2_lib.baseboard_fab2(sch_1):page223_i55:a"
				( attribute "PN" "1"
					( Origin gPackager )
				)
				( objectStatus "R1G8.1" )
			)
			( pin "@baseboard_fab2_lib.baseboard_fab2(sch_1):page223_i55:b"
				( attribute "PN" "2"
					( Origin gPackager )
				)
				( objectStatus "R1G8.2" )
			)
			( pin "@baseboard_fab2_lib.baseboard_fab2(sch_1):page218_i69:airef1"
				( attribute "PN" "21"
					( Origin gPackager )
				)
				( objectStatus "EU7A5.21" )
			)
			( pin "@baseboard_fab2_lib.baseboard_fab2(sch_1):page218_i69:airef2"
				( attribute "PN" "23"
					( Origin gPackager )
				)
				( objectStatus "EU7A5.23" )
			)
			( pin "@baseboard_fab2_lib.baseboard_fab2(sch_1):page218_i69:airef3"
				( attribute "PN" "25"
					( Origin gPackager )
				)
				( objectStatus "EU7A5.25" )
			)
			( pin "@baseboard_fab2_lib.baseboard_fab2(sch_1):page218_i69:aisen1"
				( attribute "PN" "22"
					( Origin gPackager )
				)
				( objectStatus "EU7A5.22" )
			)
			( pin "@baseboard_fab2_lib.baseboard_fab2(sch_1):page218_i69:aisen2"
				( attribute "PN" "24"
					( Origin gPackager )
				)
				( objectStatus "EU7A5.24" )
			)
			( pin "@baseboard_fab2_lib.baseboard_fab2(sch_1):page218_i69:aisen3"
				( attribute "PN" "26"
					( Origin gPackager )
				)
				( objectStatus "EU7A5.26" )
			)
			( pin "@baseboard_fab2_lib.baseboard_fab2(sch_1):page218_i69:apwm1"
				( attribute "PN" "5"
					( Origin gPackager )
				)
				( objectStatus "EU7A5.5" )
			)
			( pin "@baseboard_fab2_lib.baseboard_fab2(sch_1):page218_i69:apwm2"
				( attribute "PN" "4"
					( Origin gPackager )
				)
				( objectStatus "EU7A5.4" )
			)
			( pin "@baseboard_fab2_lib.baseboard_fab2(sch_1):page218_i69:apwm3"
				( attribute "PN" "3"
					( Origin gPackager )
				)
				( objectStatus "EU7A5.3" )
			)
			( pin "@baseboard_fab2_lib.baseboard_fab2(sch_1):page218_i69:atsen"
				( attribute "PN" "35"
					( Origin gPackager )
				)
				( objectStatus "EU7A5.35" )
			)
			( pin "@baseboard_fab2_lib.baseboard_fab2(sch_1):page218_i69:avref"
				( attribute "PN" "20"
					( Origin gPackager )
				)
				( objectStatus "EU7A5.20" )
			)
			( pin "@baseboard_fab2_lib.baseboard_fab2(sch_1):page218_i69:avren"
				( attribute "PN" "10"
					( Origin gPackager )
				)
				( objectStatus "EU7A5.10" )
			)
			( pin "@baseboard_fab2_lib.baseboard_fab2(sch_1):page218_i69:avrrdy"
				( attribute "PN" "9"
					( Origin gPackager )
				)
				( objectStatus "EU7A5.9" )
			)
			( pin "@baseboard_fab2_lib.baseboard_fab2(sch_1):page218_i69:avsen"
				( attribute "PN" "19"
					( Origin gPackager )
				)
				( objectStatus "EU7A5.19" )
			)
			( pin "@baseboard_fab2_lib.baseboard_fab2(sch_1):page218_i69:biref1"
				( attribute "PN" "31"
					( Origin gPackager )
				)
				( objectStatus "EU7A5.31" )
			)
			( pin "@baseboard_fab2_lib.baseboard_fab2(sch_1):page218_i69:bisen1"
				( attribute "PN" "32"
					( Origin gPackager )
				)
				( objectStatus "EU7A5.32" )
			)
			( pin "@baseboard_fab2_lib.baseboard_fab2(sch_1):page218_i69:bpwm1"
				( attribute "PN" "1"
					( Origin gPackager )
				)
				( objectStatus "EU7A5.1" )
			)
			( pin "@baseboard_fab2_lib.baseboard_fab2(sch_1):page218_i69:btsen"
				( attribute "PN" "34"
					( Origin gPackager )
				)
				( objectStatus "EU7A5.34" )
			)
			( pin "@baseboard_fab2_lib.baseboard_fab2(sch_1):page218_i69:bvref"
				( attribute "PN" "30"
					( Origin gPackager )
				)
				( objectStatus "EU7A5.30" )
			)
			( pin "@baseboard_fab2_lib.baseboard_fab2(sch_1):page218_i69:bvsen"
				( attribute "PN" "29"
					( Origin gPackager )
				)
				( objectStatus "EU7A5.29" )
			)
			( pin "@baseboard_fab2_lib.baseboard_fab2(sch_1):page218_i69:dnc(0)"
				( attribute "PN" "2"
					( Origin gPackager )
				)
				( objectStatus "EU7A5.2" )
			)
			( pin "@baseboard_fab2_lib.baseboard_fab2(sch_1):page218_i69:dnc(1)"
				( attribute "PN" "28"
					( Origin gPackager )
				)
				( objectStatus "EU7A5.28" )
			)
			( pin "@baseboard_fab2_lib.baseboard_fab2(sch_1):page218_i69:gnd"
				( attribute "PN" "27"
					( Origin gPackager )
				)
				( objectStatus "EU7A5.27" )
			)
			( pin "@baseboard_fab2_lib.baseboard_fab2(sch_1):page218_i69:iinsen"
				( attribute "PN" "38"
					( Origin gPackager )
				)
				( objectStatus "EU7A5.38" )
			)
			( pin "@baseboard_fab2_lib.baseboard_fab2(sch_1):page218_i69:mp0"
				( attribute "PN" "13"
					( Origin gPackager )
				)
				( objectStatus "EU7A5.13" )
			)
			( pin "@baseboard_fab2_lib.baseboard_fab2(sch_1):page218_i69:mp1"
				( attribute "PN" "14"
					( Origin gPackager )
				)
				( objectStatus "EU7A5.14" )
			)
			( pin "@baseboard_fab2_lib.baseboard_fab2(sch_1):page218_i69:mp2"
				( attribute "PN" "18"
					( Origin gPackager )
				)
				( objectStatus "EU7A5.18" )
			)
			( pin "@baseboard_fab2_lib.baseboard_fab2(sch_1):page218_i69:pinalrt_n"
				( attribute "PN" "12"
					( Origin gPackager )
				)
				( objectStatus "EU7A5.12" )
			)
			( pin "@baseboard_fab2_lib.baseboard_fab2(sch_1):page218_i69:reset_n"
				( attribute "PN" "8"
					( Origin gPackager )
				)
				( objectStatus "EU7A5.8" )
			)
			( pin "@baseboard_fab2_lib.baseboard_fab2(sch_1):page218_i69:scl"
				( attribute "PN" "7"
					( Origin gPackager )
				)
				( objectStatus "EU7A5.7" )
			)
			( pin "@baseboard_fab2_lib.baseboard_fab2(sch_1):page218_i69:sda"
				( attribute "PN" "6"
					( Origin gPackager )
				)
				( objectStatus "EU7A5.6" )
			)
			( pin "@baseboard_fab2_lib.baseboard_fab2(sch_1):page218_i69:thpad"
				( attribute "PN" "41"
					( Origin gPackager )
				)
				( objectStatus "EU7A5.41" )
			)
			( pin "@baseboard_fab2_lib.baseboard_fab2(sch_1):page218_i69:valrt_n"
				( attribute "PN" "17"
					( Origin gPackager )
				)
				( objectStatus "EU7A5.17" )
			)
			( pin "@baseboard_fab2_lib.baseboard_fab2(sch_1):page218_i69:vclk"
				( attribute "PN" "15"
					( Origin gPackager )
				)
				( objectStatus "EU7A5.15" )
			)
			( pin "@baseboard_fab2_lib.baseboard_fab2(sch_1):page218_i69:vd12"
				( attribute "PN" "40"
					( Origin gPackager )
				)
				( objectStatus "EU7A5.40" )
			)
			( pin "@baseboard_fab2_lib.baseboard_fab2(sch_1):page218_i69:vdd"
				( attribute "PN" "39"
					( Origin gPackager )
				)
				( objectStatus "EU7A5.39" )
			)
			( pin "@baseboard_fab2_lib.baseboard_fab2(sch_1):page218_i69:vdio"
				( attribute "PN" "16"
					( Origin gPackager )
				)
				( objectStatus "EU7A5.16" )
			)
			( pin "@baseboard_fab2_lib.baseboard_fab2(sch_1):page218_i69:vinsen"
				( attribute "PN" "37"
					( Origin gPackager )
				)
				( objectStatus "EU7A5.37" )
			)
			( pin "@baseboard_fab2_lib.baseboard_fab2(sch_1):page218_i69:vrhot_n"
				( attribute "PN" "11"
					( Origin gPackager )
				)
				( objectStatus "EU7A5.11" )
			)
			( pin "@baseboard_fab2_lib.baseboard_fab2(sch_1):page218_i69:xaddr1"
				( attribute "PN" "36"
					( Origin gPackager )
				)
				( objectStatus "EU7A5.36" )
			)
			( pin "@baseboard_fab2_lib.baseboard_fab2(sch_1):page218_i69:xaddr2"
				( attribute "PN" "33"
					( Origin gPackager )
				)
				( objectStatus "EU7A5.33" )
			)
			( pin "@baseboard_fab2_lib.baseboard_fab2(sch_1):page218_i67:a"
				( attribute "PN" "1"
					( Origin gPackager )
				)
				( objectStatus "R3L11.1" )
			)
			( pin "@baseboard_fab2_lib.baseboard_fab2(sch_1):page218_i67:b"
				( attribute "PN" "2"
					( Origin gPackager )
				)
				( objectStatus "R3L11.2" )
			)
			( pin "@baseboard_fab2_lib.baseboard_fab2(sch_1):page223_i76:a"
				( attribute "PN" "1"
					( Origin gPackager )
				)
				( objectStatus "R1G6.1" )
			)
			( pin "@baseboard_fab2_lib.baseboard_fab2(sch_1):page223_i76:b"
				( attribute "PN" "2"
					( Origin gPackager )
				)
				( objectStatus "R1G6.2" )
			)
			( pin "@baseboard_fab2_lib.baseboard_fab2(sch_1):page218_i58:a"
				( attribute "PN" "1"
					( Origin gPackager )
				)
				( objectStatus "R7B5.1" )
			)
			( pin "@baseboard_fab2_lib.baseboard_fab2(sch_1):page218_i58:b"
				( attribute "PN" "2"
					( Origin gPackager )
				)
				( objectStatus "R7B5.2" )
			)
			( pin "@baseboard_fab2_lib.baseboard_fab2(sch_1):page221_i33:a"
				( attribute "PN" "1"
					( Origin gPackager )
				)
				( objectStatus "R4G19.1" )
			)
			( pin "@baseboard_fab2_lib.baseboard_fab2(sch_1):page221_i33:b"
				( attribute "PN" "2"
					( Origin gPackager )
				)
				( objectStatus "R4G19.2" )
			)
			( pin "@baseboard_fab2_lib.baseboard_fab2(sch_1):page221_i30:a"
				( attribute "PN" "1"
					( Origin gPackager )
				)
				( objectStatus "C4G14.1" )
			)
			( pin "@baseboard_fab2_lib.baseboard_fab2(sch_1):page221_i30:b"
				( attribute "PN" "2"
					( Origin gPackager )
				)
				( objectStatus "C4G14.2" )
			)
			( pin "@baseboard_fab2_lib.baseboard_fab2(sch_1):page222_i46:a"
				( attribute "PN" "1"
					( Origin gPackager )
				)
				( objectStatus "C4W5.1" )
			)
			( pin "@baseboard_fab2_lib.baseboard_fab2(sch_1):page222_i46:b"
				( attribute "PN" "2"
					( Origin gPackager )
				)
				( objectStatus "C4W5.2" )
			)
			( pin "@baseboard_fab2_lib.baseboard_fab2(sch_1):page221_i25:a"
				( attribute "PN" "1"
					( Origin gPackager )
				)
				( objectStatus "R4G18.1" )
			)
			( pin "@baseboard_fab2_lib.baseboard_fab2(sch_1):page221_i25:b"
				( attribute "PN" "2"
					( Origin gPackager )
				)
				( objectStatus "R4G18.2" )
			)
			( pin "@baseboard_fab2_lib.baseboard_fab2(sch_1):page221_i19:a"
				( attribute "PN" "1"
					( Origin gPackager )
				)
				( objectStatus "C6U16.1" )
			)
			( pin "@baseboard_fab2_lib.baseboard_fab2(sch_1):page221_i19:b"
				( attribute "PN" "2"
					( Origin gPackager )
				)
				( objectStatus "C6U16.2" )
			)
			( pin "@baseboard_fab2_lib.baseboard_fab2(sch_1):page221_i18:a"
				( attribute "PN" "1"
					( Origin gPackager )
				)
				( objectStatus "C6U15.1" )
			)
			( pin "@baseboard_fab2_lib.baseboard_fab2(sch_1):page221_i18:b"
				( attribute "PN" "2"
					( Origin gPackager )
				)
				( objectStatus "C6U15.2" )
			)
			( pin "@baseboard_fab2_lib.baseboard_fab2(sch_1):page221_i14:a"
				( attribute "PN" "1"
					( Origin gPackager )
				)
				( objectStatus "R6U4.1" )
			)
			( pin "@baseboard_fab2_lib.baseboard_fab2(sch_1):page221_i14:b"
				( attribute "PN" "2"
					( Origin gPackager )
				)
				( objectStatus "R6U4.2" )
			)
			( pin "@baseboard_fab2_lib.baseboard_fab2(sch_1):page221_i13:a"
				( attribute "PN" "1"
					( Origin gPackager )
				)
				( objectStatus "C4G15.1" )
			)
			( pin "@baseboard_fab2_lib.baseboard_fab2(sch_1):page221_i13:b"
				( attribute "PN" "2"
					( Origin gPackager )
				)
				( objectStatus "C4G15.2" )
			)
			( pin "@baseboard_fab2_lib.baseboard_fab2(sch_1):page221_i11:a"
				( attribute "PN" "1"
					( Origin gPackager )
				)
				( objectStatus "C6U12.1" )
			)
			( pin "@baseboard_fab2_lib.baseboard_fab2(sch_1):page221_i11:b"
				( attribute "PN" "2"
					( Origin gPackager )
				)
				( objectStatus "C6U12.2" )
			)
			( pin "@baseboard_fab2_lib.baseboard_fab2(sch_1):page221_i9:a"
				( attribute "PN" "1"
					( Origin gPackager )
				)
				( objectStatus "SH5U1.1" )
			)
			( pin "@baseboard_fab2_lib.baseboard_fab2(sch_1):page221_i9:b"
				( attribute "PN" "2"
					( Origin gPackager )
				)
				( objectStatus "SH5U1.2" )
			)
			( pin "@baseboard_fab2_lib.baseboard_fab2(sch_1):page235_i244:a"
				( attribute "PN" "1"
					( Origin gPackager )
				)
				( objectStatus "C4W3.1" )
			)
			( pin "@baseboard_fab2_lib.baseboard_fab2(sch_1):page235_i244:b"
				( attribute "PN" "2"
					( Origin gPackager )
				)
				( objectStatus "C4W3.2" )
			)
			( pin "@baseboard_fab2_lib.baseboard_fab2(sch_1):page216_i6:a"
				( attribute "PN" "1"
					( Origin gPackager )
				)
				( objectStatus "C6G3.1" )
			)
			( pin "@baseboard_fab2_lib.baseboard_fab2(sch_1):page216_i6:b"
				( attribute "PN" "2"
					( Origin gPackager )
				)
				( objectStatus "C6G3.2" )
			)
			( pin "@baseboard_fab2_lib.baseboard_fab2(sch_1):page216_i44:a"
				( attribute "PN" "1"
					( Origin gPackager )
				)
				( objectStatus "C7G31.1" )
			)
			( pin "@baseboard_fab2_lib.baseboard_fab2(sch_1):page216_i44:b"
				( attribute "PN" "2"
					( Origin gPackager )
				)
				( objectStatus "C7G31.2" )
			)
			( pin "@baseboard_fab2_lib.baseboard_fab2(sch_1):page216_i45:a"
				( attribute "PN" "1"
					( Origin gPackager )
				)
				( objectStatus "C3U2.1" )
			)
			( pin "@baseboard_fab2_lib.baseboard_fab2(sch_1):page216_i45:b"
				( attribute "PN" "2"
					( Origin gPackager )
				)
				( objectStatus "C3U2.2" )
			)
			( pin "@baseboard_fab2_lib.baseboard_fab2(sch_1):page216_i46:a"
				( attribute "PN" "1"
					( Origin gPackager )
				)
				( objectStatus "C3U3.1" )
			)
			( pin "@baseboard_fab2_lib.baseboard_fab2(sch_1):page216_i46:b"
				( attribute "PN" "2"
					( Origin gPackager )
				)
				( objectStatus "C3U3.2" )
			)
			( pin "@baseboard_fab2_lib.baseboard_fab2(sch_1):page216_i47:a"
				( attribute "PN" "1"
					( Origin gPackager )
				)
				( objectStatus "C3U4.1" )
			)
			( pin "@baseboard_fab2_lib.baseboard_fab2(sch_1):page216_i47:b"
				( attribute "PN" "2"
					( Origin gPackager )
				)
				( objectStatus "C3U4.2" )
			)
			( pin "@baseboard_fab2_lib.baseboard_fab2(sch_1):page216_i48:a"
				( attribute "PN" "1"
					( Origin gPackager )
				)
				( objectStatus "C7G37.1" )
			)
			( pin "@baseboard_fab2_lib.baseboard_fab2(sch_1):page216_i48:b"
				( attribute "PN" "2"
					( Origin gPackager )
				)
				( objectStatus "C7G37.2" )
			)
			( pin "@baseboard_fab2_lib.baseboard_fab2(sch_1):page216_i50:a"
				( attribute "PN" "1"
					( Origin gPackager )
				)
				( objectStatus "C7G33.1" )
			)
			( pin "@baseboard_fab2_lib.baseboard_fab2(sch_1):page216_i50:b"
				( attribute "PN" "2"
					( Origin gPackager )
				)
				( objectStatus "C7G33.2" )
			)
			( pin "@baseboard_fab2_lib.baseboard_fab2(sch_1):page216_i51:a"
				( attribute "PN" "1"
					( Origin gPackager )
				)
				( objectStatus "C7G29.1" )
			)
			( pin "@baseboard_fab2_lib.baseboard_fab2(sch_1):page216_i51:b"
				( attribute "PN" "2"
					( Origin gPackager )
				)
				( objectStatus "C7G29.2" )
			)
			( pin "@baseboard_fab2_lib.baseboard_fab2(sch_1):page219_i148:a"
				( attribute "PN" "1"
					( Origin gPackager )
				)
				( objectStatus "R3L8.1" )
			)
			( pin "@baseboard_fab2_lib.baseboard_fab2(sch_1):page219_i148:b"
				( attribute "PN" "2"
					( Origin gPackager )
				)
				( objectStatus "R3L8.2" )
			)
			( pin "@baseboard_fab2_lib.baseboard_fab2(sch_1):page216_i54:a"
				( attribute "PN" "1"
					( Origin gPackager )
				)
				( objectStatus "C7G34.1" )
			)
			( pin "@baseboard_fab2_lib.baseboard_fab2(sch_1):page216_i54:b"
				( attribute "PN" "2"
					( Origin gPackager )
				)
				( objectStatus "C7G34.2" )
			)
			( pin "@baseboard_fab2_lib.baseboard_fab2(sch_1):page210_i55:a"
				( attribute "PN" "1"
					( Origin gPackager )
				)
				( objectStatus "CT57.1" )
			)
			( pin "@baseboard_fab2_lib.baseboard_fab2(sch_1):page210_i55:b"
				( attribute "PN" "2"
					( Origin gPackager )
				)
				( objectStatus "CT57.2" )
			)
			( pin "@baseboard_fab2_lib.baseboard_fab2(sch_1):page224_i161:f"
				( attribute "PN" "2"
					( Origin gPackager )
				)
				( objectStatus "L1F2.2" )
			)
			( pin "@baseboard_fab2_lib.baseboard_fab2(sch_1):page224_i161:s"
				( attribute "PN" "1"
					( Origin gPackager )
				)
				( objectStatus "L1F2.1" )
			)
			( pin "@baseboard_fab2_lib.baseboard_fab2(sch_1):page216_i68:a"
				( attribute "PN" "1"
					( Origin gPackager )
				)
				( objectStatus "C7G27.1" )
			)
			( pin "@baseboard_fab2_lib.baseboard_fab2(sch_1):page216_i68:b"
				( attribute "PN" "2"
					( Origin gPackager )
				)
				( objectStatus "C7G27.2" )
			)
			( pin "@baseboard_fab2_lib.baseboard_fab2(sch_1):page216_i72:a"
				( attribute "PN" "1"
					( Origin gPackager )
				)
				( objectStatus "C7G41.1" )
			)
			( pin "@baseboard_fab2_lib.baseboard_fab2(sch_1):page216_i72:b"
				( attribute "PN" "2"
					( Origin gPackager )
				)
				( objectStatus "C7G41.2" )
			)
			( pin "@baseboard_fab2_lib.baseboard_fab2(sch_1):page209_i73:a"
				( attribute "PN" "1"
					( Origin gPackager )
				)
				( objectStatus "CT14.1" )
			)
			( pin "@baseboard_fab2_lib.baseboard_fab2(sch_1):page209_i73:b"
				( attribute "PN" "2"
					( Origin gPackager )
				)
				( objectStatus "CT14.2" )
			)
			( pin "@baseboard_fab2_lib.baseboard_fab2(sch_1):page219_i147:a"
				( attribute "PN" "1"
					( Origin gPackager )
				)
				( objectStatus "R3L6.1" )
			)
			( pin "@baseboard_fab2_lib.baseboard_fab2(sch_1):page219_i147:b"
				( attribute "PN" "2"
					( Origin gPackager )
				)
				( objectStatus "R3L6.2" )
			)
			( pin "@baseboard_fab2_lib.baseboard_fab2(sch_1):page216_i77:a"
				( attribute "PN" "1"
					( Origin gPackager )
				)
				( objectStatus "C7G40.1" )
			)
			( pin "@baseboard_fab2_lib.baseboard_fab2(sch_1):page216_i77:b"
				( attribute "PN" "2"
					( Origin gPackager )
				)
				( objectStatus "C7G40.2" )
			)
			( pin "@baseboard_fab2_lib.baseboard_fab2(sch_1):page216_i78:a"
				( attribute "PN" "1"
					( Origin gPackager )
				)
				( objectStatus "C7G36.1" )
			)
			( pin "@baseboard_fab2_lib.baseboard_fab2(sch_1):page216_i78:b"
				( attribute "PN" "2"
					( Origin gPackager )
				)
				( objectStatus "C7G36.2" )
			)
			( pin "@baseboard_fab2_lib.baseboard_fab2(sch_1):page216_i79:a"
				( attribute "PN" "1"
					( Origin gPackager )
				)
				( objectStatus "C7G30.1" )
			)
			( pin "@baseboard_fab2_lib.baseboard_fab2(sch_1):page216_i79:b"
				( attribute "PN" "2"
					( Origin gPackager )
				)
				( objectStatus "C7G30.2" )
			)
			( pin "@baseboard_fab2_lib.baseboard_fab2(sch_1):page216_i80:a"
				( attribute "PN" "1"
					( Origin gPackager )
				)
				( objectStatus "C3U9.1" )
			)
			( pin "@baseboard_fab2_lib.baseboard_fab2(sch_1):page216_i80:b"
				( attribute "PN" "2"
					( Origin gPackager )
				)
				( objectStatus "C3U9.2" )
			)
			( pin "@baseboard_fab2_lib.baseboard_fab2(sch_1):page216_i81:a"
				( attribute "PN" "1"
					( Origin gPackager )
				)
				( objectStatus "C3U7.1" )
			)
			( pin "@baseboard_fab2_lib.baseboard_fab2(sch_1):page216_i81:b"
				( attribute "PN" "2"
					( Origin gPackager )
				)
				( objectStatus "C3U7.2" )
			)
			( pin "@baseboard_fab2_lib.baseboard_fab2(sch_1):page216_i84:a"
				( attribute "PN" "1"
					( Origin gPackager )
				)
				( objectStatus "C3U6.1" )
			)
			( pin "@baseboard_fab2_lib.baseboard_fab2(sch_1):page216_i84:b"
				( attribute "PN" "2"
					( Origin gPackager )
				)
				( objectStatus "C3U6.2" )
			)
			( pin "@baseboard_fab2_lib.baseboard_fab2(sch_1):page216_i102:boost"
				( attribute "PN" "33"
					( Origin gPackager )
				)
				( objectStatus "EU7G2.33" )
			)
			( pin "@baseboard_fab2_lib.baseboard_fab2(sch_1):page216_i102:en"
				( attribute "PN" "35"
					( Origin gPackager )
				)
				( objectStatus "EU7G2.35" )
			)
			( pin "@baseboard_fab2_lib.baseboard_fab2(sch_1):page216_i102:gl(0)"
				( attribute "PN" "6"
					( Origin gPackager )
				)
				( objectStatus "EU7G2.6" )
			)
			( pin "@baseboard_fab2_lib.baseboard_fab2(sch_1):page216_i102:gl(1)"
				( attribute "PN" "41"
					( Origin gPackager )
				)
				( objectStatus "EU7G2.41" )
			)
			( pin "@baseboard_fab2_lib.baseboard_fab2(sch_1):page216_i102:iout"
				( attribute "PN" "38"
					( Origin gPackager )
				)
				( objectStatus "EU7G2.38" )
			)
			( pin "@baseboard_fab2_lib.baseboard_fab2(sch_1):page216_i102:lgnd"
				( attribute "PN" "2"
					( Origin gPackager )
				)
				( objectStatus "EU7G2.2" )
			)
			( pin "@baseboard_fab2_lib.baseboard_fab2(sch_1):page216_i102:nc"
				( attribute "PN" "31"
					( Origin gPackager )
				)
				( objectStatus "EU7G2.31" )
			)
			( pin "@baseboard_fab2_lib.baseboard_fab2(sch_1):page216_i102:ocset"
				( attribute "PN" "37"
					( Origin gPackager )
				)
				( objectStatus "EU7G2.37" )
			)
			( pin "@baseboard_fab2_lib.baseboard_fab2(sch_1):page216_i102:pgnd(0)"
				( attribute "PN" "5"
					( Origin gPackager )
				)
				( objectStatus "EU7G2.5" )
			)
			( pin "@baseboard_fab2_lib.baseboard_fab2(sch_1):page216_i102:pgnd(1)"
				( attribute "PN" "7"
					( Origin gPackager )
				)
				( objectStatus "EU7G2.7" )
			)
			( pin "@baseboard_fab2_lib.baseboard_fab2(sch_1):page216_i102:pgnd(2)"
				( attribute "PN" "40"
					( Origin gPackager )
				)
				( objectStatus "EU7G2.40" )
			)
			( pin "@baseboard_fab2_lib.baseboard_fab2(sch_1):page216_i102:phase"
				( attribute "PN" "32"
					( Origin gPackager )
				)
				( objectStatus "EU7G2.32" )
			)
			( pin "@baseboard_fab2_lib.baseboard_fab2(sch_1):page216_i102:pwm"
				( attribute "PN" "34"
					( Origin gPackager )
				)
				( objectStatus "EU7G2.34" )
			)
			( pin "@baseboard_fab2_lib.baseboard_fab2(sch_1):page216_i102:refin"
				( attribute "PN" "39"
					( Origin gPackager )
				)
				( objectStatus "EU7G2.39" )
			)
			( pin "@baseboard_fab2_lib.baseboard_fab2(sch_1):page216_i102:sw"
				( attribute "PN" "10"
					( Origin gPackager )
				)
				( objectStatus "EU7G2.10" )
			)
			( pin "@baseboard_fab2_lib.baseboard_fab2(sch_1):page216_i102:tout_flt"
				( attribute "PN" "36"
					( Origin gPackager )
				)
				( objectStatus "EU7G2.36" )
			)
			( pin "@baseboard_fab2_lib.baseboard_fab2(sch_1):page216_i102:vcc"
				( attribute "PN" "3"
					( Origin gPackager )
				)
				( objectStatus "EU7G2.3" )
			)
			( pin "@baseboard_fab2_lib.baseboard_fab2(sch_1):page216_i102:vdrv"
				( attribute "PN" "4"
					( Origin gPackager )
				)
				( objectStatus "EU7G2.4" )
			)
			( pin "@baseboard_fab2_lib.baseboard_fab2(sch_1):page216_i102:vin(0)"
				( attribute "PN" "25"
					( Origin gPackager )
				)
				( objectStatus "EU7G2.25" )
			)
			( pin "@baseboard_fab2_lib.baseboard_fab2(sch_1):page216_i102:vin(1)"
				( attribute "PN" "30"
					( Origin gPackager )
				)
				( objectStatus "EU7G2.30" )
			)
			( pin "@baseboard_fab2_lib.baseboard_fab2(sch_1):page216_i102:vos"
				( attribute "PN" "1"
					( Origin gPackager )
				)
				( objectStatus "EU7G2.1" )
			)
			( pin "@baseboard_fab2_lib.baseboard_fab2(sch_1):page216_i103:boost"
				( attribute "PN" "33"
					( Origin gPackager )
				)
				( objectStatus "EU7G3.33" )
			)
			( pin "@baseboard_fab2_lib.baseboard_fab2(sch_1):page216_i103:en"
				( attribute "PN" "35"
					( Origin gPackager )
				)
				( objectStatus "EU7G3.35" )
			)
			( pin "@baseboard_fab2_lib.baseboard_fab2(sch_1):page216_i103:gl(0)"
				( attribute "PN" "6"
					( Origin gPackager )
				)
				( objectStatus "EU7G3.6" )
			)
			( pin "@baseboard_fab2_lib.baseboard_fab2(sch_1):page216_i103:gl(1)"
				( attribute "PN" "41"
					( Origin gPackager )
				)
				( objectStatus "EU7G3.41" )
			)
			( pin "@baseboard_fab2_lib.baseboard_fab2(sch_1):page216_i103:iout"
				( attribute "PN" "38"
					( Origin gPackager )
				)
				( objectStatus "EU7G3.38" )
			)
			( pin "@baseboard_fab2_lib.baseboard_fab2(sch_1):page216_i103:lgnd"
				( attribute "PN" "2"
					( Origin gPackager )
				)
				( objectStatus "EU7G3.2" )
			)
			( pin "@baseboard_fab2_lib.baseboard_fab2(sch_1):page216_i103:nc"
				( attribute "PN" "31"
					( Origin gPackager )
				)
				( objectStatus "EU7G3.31" )
			)
			( pin "@baseboard_fab2_lib.baseboard_fab2(sch_1):page216_i103:ocset"
				( attribute "PN" "37"
					( Origin gPackager )
				)
				( objectStatus "EU7G3.37" )
			)
			( pin "@baseboard_fab2_lib.baseboard_fab2(sch_1):page216_i103:pgnd(0)"
				( attribute "PN" "5"
					( Origin gPackager )
				)
				( objectStatus "EU7G3.5" )
			)
			( pin "@baseboard_fab2_lib.baseboard_fab2(sch_1):page216_i103:pgnd(1)"
				( attribute "PN" "7"
					( Origin gPackager )
				)
				( objectStatus "EU7G3.7" )
			)
			( pin "@baseboard_fab2_lib.baseboard_fab2(sch_1):page216_i103:pgnd(2)"
				( attribute "PN" "40"
					( Origin gPackager )
				)
				( objectStatus "EU7G3.40" )
			)
			( pin "@baseboard_fab2_lib.baseboard_fab2(sch_1):page216_i103:phase"
				( attribute "PN" "32"
					( Origin gPackager )
				)
				( objectStatus "EU7G3.32" )
			)
			( pin "@baseboard_fab2_lib.baseboard_fab2(sch_1):page216_i103:pwm"
				( attribute "PN" "34"
					( Origin gPackager )
				)
				( objectStatus "EU7G3.34" )
			)
			( pin "@baseboard_fab2_lib.baseboard_fab2(sch_1):page216_i103:refin"
				( attribute "PN" "39"
					( Origin gPackager )
				)
				( objectStatus "EU7G3.39" )
			)
			( pin "@baseboard_fab2_lib.baseboard_fab2(sch_1):page216_i103:sw"
				( attribute "PN" "10"
					( Origin gPackager )
				)
				( objectStatus "EU7G3.10" )
			)
			( pin "@baseboard_fab2_lib.baseboard_fab2(sch_1):page216_i103:tout_flt"
				( attribute "PN" "36"
					( Origin gPackager )
				)
				( objectStatus "EU7G3.36" )
			)
			( pin "@baseboard_fab2_lib.baseboard_fab2(sch_1):page216_i103:vcc"
				( attribute "PN" "3"
					( Origin gPackager )
				)
				( objectStatus "EU7G3.3" )
			)
			( pin "@baseboard_fab2_lib.baseboard_fab2(sch_1):page216_i103:vdrv"
				( attribute "PN" "4"
					( Origin gPackager )
				)
				( objectStatus "EU7G3.4" )
			)
			( pin "@baseboard_fab2_lib.baseboard_fab2(sch_1):page216_i103:vin(0)"
				( attribute "PN" "25"
					( Origin gPackager )
				)
				( objectStatus "EU7G3.25" )
			)
			( pin "@baseboard_fab2_lib.baseboard_fab2(sch_1):page216_i103:vin(1)"
				( attribute "PN" "30"
					( Origin gPackager )
				)
				( objectStatus "EU7G3.30" )
			)
			( pin "@baseboard_fab2_lib.baseboard_fab2(sch_1):page216_i103:vos"
				( attribute "PN" "1"
					( Origin gPackager )
				)
				( objectStatus "EU7G3.1" )
			)
			( pin "@baseboard_fab2_lib.baseboard_fab2(sch_1):page216_i104:a"
				( attribute "PN" "1"
					( Origin gPackager )
				)
				( objectStatus "R7G25.1" )
			)
			( pin "@baseboard_fab2_lib.baseboard_fab2(sch_1):page216_i104:b"
				( attribute "PN" "2"
					( Origin gPackager )
				)
				( objectStatus "R7G25.2" )
			)
			( pin "@baseboard_fab2_lib.baseboard_fab2(sch_1):page216_i106:a"
				( attribute "PN" "1"
					( Origin gPackager )
				)
				( objectStatus "R7G30.1" )
			)
			( pin "@baseboard_fab2_lib.baseboard_fab2(sch_1):page216_i106:b"
				( attribute "PN" "2"
					( Origin gPackager )
				)
				( objectStatus "R7G30.2" )
			)
			( pin "@baseboard_fab2_lib.baseboard_fab2(sch_1):page217_i58:a"
				( attribute "PN" "1"
					( Origin gPackager )
				)
				( objectStatus "R3U4.1" )
			)
			( pin "@baseboard_fab2_lib.baseboard_fab2(sch_1):page217_i58:b"
				( attribute "PN" "2"
					( Origin gPackager )
				)
				( objectStatus "R3U4.2" )
			)
			( pin "@baseboard_fab2_lib.baseboard_fab2(sch_1):page217_i74:a"
				( attribute "PN" "1"
					( Origin gPackager )
				)
				( objectStatus "R4U6.1" )
			)
			( pin "@baseboard_fab2_lib.baseboard_fab2(sch_1):page217_i74:b"
				( attribute "PN" "2"
					( Origin gPackager )
				)
				( objectStatus "R4U6.2" )
			)
			( pin "@baseboard_fab2_lib.baseboard_fab2(sch_1):page217_i75:a"
				( attribute "PN" "1"
					( Origin gPackager )
				)
				( objectStatus "C7G28.1" )
			)
			( pin "@baseboard_fab2_lib.baseboard_fab2(sch_1):page217_i75:b"
				( attribute "PN" "2"
					( Origin gPackager )
				)
				( objectStatus "C7G28.2" )
			)
			( pin "@baseboard_fab2_lib.baseboard_fab2(sch_1):page217_i76:a"
				( attribute "PN" "1"
					( Origin gPackager )
				)
				( objectStatus "C3U1.1" )
			)
			( pin "@baseboard_fab2_lib.baseboard_fab2(sch_1):page217_i76:b"
				( attribute "PN" "2"
					( Origin gPackager )
				)
				( objectStatus "C3U1.2" )
			)
			( pin "@baseboard_fab2_lib.baseboard_fab2(sch_1):page217_i77:a"
				( attribute "PN" "1"
					( Origin gPackager )
				)
				( objectStatus "C3U5.1" )
			)
			( pin "@baseboard_fab2_lib.baseboard_fab2(sch_1):page217_i77:b"
				( attribute "PN" "2"
					( Origin gPackager )
				)
				( objectStatus "C3U5.2" )
			)
			( pin "@baseboard_fab2_lib.baseboard_fab2(sch_1):page217_i78:a"
				( attribute "PN" "1"
					( Origin gPackager )
				)
				( objectStatus "C3U8.1" )
			)
			( pin "@baseboard_fab2_lib.baseboard_fab2(sch_1):page217_i78:b"
				( attribute "PN" "2"
					( Origin gPackager )
				)
				( objectStatus "C3U8.2" )
			)
			( pin "@baseboard_fab2_lib.baseboard_fab2(sch_1):page217_i322:a"
				( attribute "PN" "1"
					( Origin gPackager )
				)
				( objectStatus "C5U14.1" )
			)
			( pin "@baseboard_fab2_lib.baseboard_fab2(sch_1):page217_i322:b"
				( attribute "PN" "2"
					( Origin gPackager )
				)
				( objectStatus "C5U14.2" )
			)
			( pin "@baseboard_fab2_lib.baseboard_fab2(sch_1):page217_i319:a"
				( attribute "PN" "1"
					( Origin gPackager )
				)
				( objectStatus "C4T4.1" )
			)
			( pin "@baseboard_fab2_lib.baseboard_fab2(sch_1):page217_i319:b"
				( attribute "PN" "2"
					( Origin gPackager )
				)
				( objectStatus "C4T4.2" )
			)
			( pin "@baseboard_fab2_lib.baseboard_fab2(sch_1):page217_i318:a"
				( attribute "PN" "1"
					( Origin gPackager )
				)
				( objectStatus "C5G9.1" )
			)
			( pin "@baseboard_fab2_lib.baseboard_fab2(sch_1):page217_i318:b"
				( attribute "PN" "2"
					( Origin gPackager )
				)
				( objectStatus "C5G9.2" )
			)
			( pin "@baseboard_fab2_lib.baseboard_fab2(sch_1):page217_i323:a"
				( attribute "PN" "1"
					( Origin gPackager )
				)
				( objectStatus "C5P41.1" )
			)
			( pin "@baseboard_fab2_lib.baseboard_fab2(sch_1):page217_i323:b"
				( attribute "PN" "2"
					( Origin gPackager )
				)
				( objectStatus "C5P41.2" )
			)
			( pin "@baseboard_fab2_lib.baseboard_fab2(sch_1):page217_i326:a"
				( attribute "PN" "1"
					( Origin gPackager )
				)
				( objectStatus "C5P43.1" )
			)
			( pin "@baseboard_fab2_lib.baseboard_fab2(sch_1):page217_i326:b"
				( attribute "PN" "2"
					( Origin gPackager )
				)
				( objectStatus "C5P43.2" )
			)
			( pin "@baseboard_fab2_lib.baseboard_fab2(sch_1):page217_i325:a"
				( attribute "PN" "1"
					( Origin gPackager )
				)
				( objectStatus "C5P42.1" )
			)
			( pin "@baseboard_fab2_lib.baseboard_fab2(sch_1):page217_i325:b"
				( attribute "PN" "2"
					( Origin gPackager )
				)
				( objectStatus "C5P42.2" )
			)
			( pin "@baseboard_fab2_lib.baseboard_fab2(sch_1):page217_i321:a"
				( attribute "PN" "1"
					( Origin gPackager )
				)
				( objectStatus "C5U13.1" )
			)
			( pin "@baseboard_fab2_lib.baseboard_fab2(sch_1):page217_i321:b"
				( attribute "PN" "2"
					( Origin gPackager )
				)
				( objectStatus "C5U13.2" )
			)
			( pin "@baseboard_fab2_lib.baseboard_fab2(sch_1):page220_i308:a"
				( attribute "PN" "1"
					( Origin gPackager )
				)
				( objectStatus "C5A20.1" )
			)
			( pin "@baseboard_fab2_lib.baseboard_fab2(sch_1):page220_i308:b"
				( attribute "PN" "2"
					( Origin gPackager )
				)
				( objectStatus "C5A20.2" )
			)
			( pin "@baseboard_fab2_lib.baseboard_fab2(sch_1):page220_i241:f"
				( attribute "PN" "2"
					( Origin gPackager )
				)
				( objectStatus "L7A5.2" )
			)
			( pin "@baseboard_fab2_lib.baseboard_fab2(sch_1):page220_i241:s"
				( attribute "PN" "1"
					( Origin gPackager )
				)
				( objectStatus "L7A5.1" )
			)
			( pin "@baseboard_fab2_lib.baseboard_fab2(sch_1):page217_i175:a"
				( attribute "PN" "1"
					( Origin gPackager )
				)
				( objectStatus "C7G2.1" )
			)
			( pin "@baseboard_fab2_lib.baseboard_fab2(sch_1):page217_i175:b"
				( attribute "PN" "2"
					( Origin gPackager )
				)
				( objectStatus "C7G2.2" )
			)
			( pin "@baseboard_fab2_lib.baseboard_fab2(sch_1):page220_i321:a"
				( attribute "PN" "1"
					( Origin gPackager )
				)
				( objectStatus "C5A10.1" )
			)
			( pin "@baseboard_fab2_lib.baseboard_fab2(sch_1):page220_i321:b"
				( attribute "PN" "2"
					( Origin gPackager )
				)
				( objectStatus "C5A10.2" )
			)
			( pin "@baseboard_fab2_lib.baseboard_fab2(sch_1):page217_i286:a"
				( attribute "PN" "1"
					( Origin gPackager )
				)
				( objectStatus "C5U5.1" )
			)
			( pin "@baseboard_fab2_lib.baseboard_fab2(sch_1):page217_i286:b"
				( attribute "PN" "2"
					( Origin gPackager )
				)
				( objectStatus "C5U5.2" )
			)
			( pin "@baseboard_fab2_lib.baseboard_fab2(sch_1):page217_i285:a"
				( attribute "PN" "1"
					( Origin gPackager )
				)
				( objectStatus "C5U4.1" )
			)
			( pin "@baseboard_fab2_lib.baseboard_fab2(sch_1):page217_i285:b"
				( attribute "PN" "2"
					( Origin gPackager )
				)
				( objectStatus "C5U4.2" )
			)
			( pin "@baseboard_fab2_lib.baseboard_fab2(sch_1):page217_i284:a"
				( attribute "PN" "1"
					( Origin gPackager )
				)
				( objectStatus "C5U3.1" )
			)
			( pin "@baseboard_fab2_lib.baseboard_fab2(sch_1):page217_i284:b"
				( attribute "PN" "2"
					( Origin gPackager )
				)
				( objectStatus "C5U3.2" )
			)
			( pin "@baseboard_fab2_lib.baseboard_fab2(sch_1):page217_i283:a"
				( attribute "PN" "1"
					( Origin gPackager )
				)
				( objectStatus "C5U2.1" )
			)
			( pin "@baseboard_fab2_lib.baseboard_fab2(sch_1):page217_i283:b"
				( attribute "PN" "2"
					( Origin gPackager )
				)
				( objectStatus "C5U2.2" )
			)
			( pin "@baseboard_fab2_lib.baseboard_fab2(sch_1):page221_i46:a"
				( attribute "PN" "1"
					( Origin gPackager )
				)
				( objectStatus "C5U16.1" )
			)
			( pin "@baseboard_fab2_lib.baseboard_fab2(sch_1):page221_i46:b"
				( attribute "PN" "2"
					( Origin gPackager )
				)
				( objectStatus "C5U16.2" )
			)
			( pin "@baseboard_fab2_lib.baseboard_fab2(sch_1):page217_i205:a"
				( attribute "PN" "1"
					( Origin gPackager )
				)
				( objectStatus "C5F2.1" )
			)
			( pin "@baseboard_fab2_lib.baseboard_fab2(sch_1):page217_i205:b"
				( attribute "PN" "2"
					( Origin gPackager )
				)
				( objectStatus "C5F2.2" )
			)
			( pin "@baseboard_fab2_lib.baseboard_fab2(sch_1):page217_i206:a"
				( attribute "PN" "1"
					( Origin gPackager )
				)
				( objectStatus "C5F1.1" )
			)
			( pin "@baseboard_fab2_lib.baseboard_fab2(sch_1):page217_i206:b"
				( attribute "PN" "2"
					( Origin gPackager )
				)
				( objectStatus "C5F1.2" )
			)
			( pin "@baseboard_fab2_lib.baseboard_fab2(sch_1):page217_i207:a"
				( attribute "PN" "1"
					( Origin gPackager )
				)
				( objectStatus "C5G10.1" )
			)
			( pin "@baseboard_fab2_lib.baseboard_fab2(sch_1):page217_i207:b"
				( attribute "PN" "2"
					( Origin gPackager )
				)
				( objectStatus "C5G10.2" )
			)
			( pin "@baseboard_fab2_lib.baseboard_fab2(sch_1):page217_i208:a"
				( attribute "PN" "1"
					( Origin gPackager )
				)
				( objectStatus "C5T2.1" )
			)
			( pin "@baseboard_fab2_lib.baseboard_fab2(sch_1):page217_i208:b"
				( attribute "PN" "2"
					( Origin gPackager )
				)
				( objectStatus "C5T2.2" )
			)
			( pin "@baseboard_fab2_lib.baseboard_fab2(sch_1):page217_i209:a"
				( attribute "PN" "1"
					( Origin gPackager )
				)
				( objectStatus "C5U11.1" )
			)
			( pin "@baseboard_fab2_lib.baseboard_fab2(sch_1):page217_i209:b"
				( attribute "PN" "2"
					( Origin gPackager )
				)
				( objectStatus "C5U11.2" )
			)
			( pin "@baseboard_fab2_lib.baseboard_fab2(sch_1):page217_i210:a"
				( attribute "PN" "1"
					( Origin gPackager )
				)
				( objectStatus "C5T13.1" )
			)
			( pin "@baseboard_fab2_lib.baseboard_fab2(sch_1):page217_i210:b"
				( attribute "PN" "2"
					( Origin gPackager )
				)
				( objectStatus "C5T13.2" )
			)
			( pin "@baseboard_fab2_lib.baseboard_fab2(sch_1):page217_i211:a"
				( attribute "PN" "1"
					( Origin gPackager )
				)
				( objectStatus "C5T4.1" )
			)
			( pin "@baseboard_fab2_lib.baseboard_fab2(sch_1):page217_i211:b"
				( attribute "PN" "2"
					( Origin gPackager )
				)
				( objectStatus "C5T4.2" )
			)
			( pin "@baseboard_fab2_lib.baseboard_fab2(sch_1):page217_i212:a"
				( attribute "PN" "1"
					( Origin gPackager )
				)
				( objectStatus "C5T1.1" )
			)
			( pin "@baseboard_fab2_lib.baseboard_fab2(sch_1):page217_i212:b"
				( attribute "PN" "2"
					( Origin gPackager )
				)
				( objectStatus "C5T1.2" )
			)
			( pin "@baseboard_fab2_lib.baseboard_fab2(sch_1):page217_i213:a"
				( attribute "PN" "1"
					( Origin gPackager )
				)
				( objectStatus "C5G19.1" )
			)
			( pin "@baseboard_fab2_lib.baseboard_fab2(sch_1):page217_i213:b"
				( attribute "PN" "2"
					( Origin gPackager )
				)
				( objectStatus "C5G19.2" )
			)
			( pin "@baseboard_fab2_lib.baseboard_fab2(sch_1):page217_i314:a"
				( attribute "PN" "1"
					( Origin gPackager )
				)
				( objectStatus "C5G3.1" )
			)
			( pin "@baseboard_fab2_lib.baseboard_fab2(sch_1):page217_i314:b"
				( attribute "PN" "2"
					( Origin gPackager )
				)
				( objectStatus "C5G3.2" )
			)
			( pin "@baseboard_fab2_lib.baseboard_fab2(sch_1):page220_i277:a"
				( attribute "PN" "1"
					( Origin gPackager )
				)
				( objectStatus "C5A19.1" )
			)
			( pin "@baseboard_fab2_lib.baseboard_fab2(sch_1):page220_i277:b"
				( attribute "PN" "2"
					( Origin gPackager )
				)
				( objectStatus "C5A19.2" )
			)
			( pin "@baseboard_fab2_lib.baseboard_fab2(sch_1):page217_i313:a"
				( attribute "PN" "1"
					( Origin gPackager )
				)
				( objectStatus "C5G15.1" )
			)
			( pin "@baseboard_fab2_lib.baseboard_fab2(sch_1):page217_i313:b"
				( attribute "PN" "2"
					( Origin gPackager )
				)
				( objectStatus "C5G15.2" )
			)
			( pin "@baseboard_fab2_lib.baseboard_fab2(sch_1):page217_i312:a"
				( attribute "PN" "1"
					( Origin gPackager )
				)
				( objectStatus "C5G16.1" )
			)
			( pin "@baseboard_fab2_lib.baseboard_fab2(sch_1):page217_i312:b"
				( attribute "PN" "2"
					( Origin gPackager )
				)
				( objectStatus "C5G16.2" )
			)
			( pin "@baseboard_fab2_lib.baseboard_fab2(sch_1):page220_i276:a"
				( attribute "PN" "1"
					( Origin gPackager )
				)
				( objectStatus "C5A18.1" )
			)
			( pin "@baseboard_fab2_lib.baseboard_fab2(sch_1):page220_i276:b"
				( attribute "PN" "2"
					( Origin gPackager )
				)
				( objectStatus "C5A18.2" )
			)
			( pin "@baseboard_fab2_lib.baseboard_fab2(sch_1):page220_i275:a"
				( attribute "PN" "1"
					( Origin gPackager )
				)
				( objectStatus "C5A17.1" )
			)
			( pin "@baseboard_fab2_lib.baseboard_fab2(sch_1):page220_i275:b"
				( attribute "PN" "2"
					( Origin gPackager )
				)
				( objectStatus "C5A17.2" )
			)
			( pin "@baseboard_fab2_lib.baseboard_fab2(sch_1):page217_i311:a"
				( attribute "PN" "1"
					( Origin gPackager )
				)
				( objectStatus "C5G14.1" )
			)
			( pin "@baseboard_fab2_lib.baseboard_fab2(sch_1):page217_i311:b"
				( attribute "PN" "2"
					( Origin gPackager )
				)
				( objectStatus "C5G14.2" )
			)
			( pin "@baseboard_fab2_lib.baseboard_fab2(sch_1):page220_i274:a"
				( attribute "PN" "1"
					( Origin gPackager )
				)
				( objectStatus "C5A4.1" )
			)
			( pin "@baseboard_fab2_lib.baseboard_fab2(sch_1):page220_i274:b"
				( attribute "PN" "2"
					( Origin gPackager )
				)
				( objectStatus "C5A4.2" )
			)
			( pin "@baseboard_fab2_lib.baseboard_fab2(sch_1):page217_i310:a"
				( attribute "PN" "1"
					( Origin gPackager )
				)
				( objectStatus "C5G17.1" )
			)
			( pin "@baseboard_fab2_lib.baseboard_fab2(sch_1):page217_i310:b"
				( attribute "PN" "2"
					( Origin gPackager )
				)
				( objectStatus "C5G17.2" )
			)
			( pin "@baseboard_fab2_lib.baseboard_fab2(sch_1):page217_i309:a"
				( attribute "PN" "1"
					( Origin gPackager )
				)
				( objectStatus "C5G18.1" )
			)
			( pin "@baseboard_fab2_lib.baseboard_fab2(sch_1):page217_i309:b"
				( attribute "PN" "2"
					( Origin gPackager )
				)
				( objectStatus "C5G18.2" )
			)
			( pin "@baseboard_fab2_lib.baseboard_fab2(sch_1):page220_i273:a"
				( attribute "PN" "1"
					( Origin gPackager )
				)
				( objectStatus "C5A16.1" )
			)
			( pin "@baseboard_fab2_lib.baseboard_fab2(sch_1):page220_i273:b"
				( attribute "PN" "2"
					( Origin gPackager )
				)
				( objectStatus "C5A16.2" )
			)
			( pin "@baseboard_fab2_lib.baseboard_fab2(sch_1):page220_i272:a"
				( attribute "PN" "1"
					( Origin gPackager )
				)
				( objectStatus "C5A9.1" )
			)
			( pin "@baseboard_fab2_lib.baseboard_fab2(sch_1):page220_i272:b"
				( attribute "PN" "2"
					( Origin gPackager )
				)
				( objectStatus "C5A9.2" )
			)
			( pin "@baseboard_fab2_lib.baseboard_fab2(sch_1):page217_i308:a"
				( attribute "PN" "1"
					( Origin gPackager )
				)
				( objectStatus "C5G8.1" )
			)
			( pin "@baseboard_fab2_lib.baseboard_fab2(sch_1):page217_i308:b"
				( attribute "PN" "2"
					( Origin gPackager )
				)
				( objectStatus "C5G8.2" )
			)
			( pin "@baseboard_fab2_lib.baseboard_fab2(sch_1):page217_i307:a"
				( attribute "PN" "1"
					( Origin gPackager )
				)
				( objectStatus "C5G1.1" )
			)
			( pin "@baseboard_fab2_lib.baseboard_fab2(sch_1):page217_i307:b"
				( attribute "PN" "2"
					( Origin gPackager )
				)
				( objectStatus "C5G1.2" )
			)
			( pin "@baseboard_fab2_lib.baseboard_fab2(sch_1):page220_i271:a"
				( attribute "PN" "1"
					( Origin gPackager )
				)
				( objectStatus "C5A8.1" )
			)
			( pin "@baseboard_fab2_lib.baseboard_fab2(sch_1):page220_i271:b"
				( attribute "PN" "2"
					( Origin gPackager )
				)
				( objectStatus "C5A8.2" )
			)
			( pin "@baseboard_fab2_lib.baseboard_fab2(sch_1):page220_i270:a"
				( attribute "PN" "1"
					( Origin gPackager )
				)
				( objectStatus "C5A3.1" )
			)
			( pin "@baseboard_fab2_lib.baseboard_fab2(sch_1):page220_i270:b"
				( attribute "PN" "2"
					( Origin gPackager )
				)
				( objectStatus "C5A3.2" )
			)
			( pin "@baseboard_fab2_lib.baseboard_fab2(sch_1):page217_i306:a"
				( attribute "PN" "1"
					( Origin gPackager )
				)
				( objectStatus "C5G7.1" )
			)
			( pin "@baseboard_fab2_lib.baseboard_fab2(sch_1):page217_i306:b"
				( attribute "PN" "2"
					( Origin gPackager )
				)
				( objectStatus "C5G7.2" )
			)
			( pin "@baseboard_fab2_lib.baseboard_fab2(sch_1):page217_i305:a"
				( attribute "PN" "1"
					( Origin gPackager )
				)
				( objectStatus "C5G5.1" )
			)
			( pin "@baseboard_fab2_lib.baseboard_fab2(sch_1):page217_i305:b"
				( attribute "PN" "2"
					( Origin gPackager )
				)
				( objectStatus "C5G5.2" )
			)
			( pin "@baseboard_fab2_lib.baseboard_fab2(sch_1):page220_i269:a"
				( attribute "PN" "1"
					( Origin gPackager )
				)
				( objectStatus "C5A7.1" )
			)
			( pin "@baseboard_fab2_lib.baseboard_fab2(sch_1):page220_i269:b"
				( attribute "PN" "2"
					( Origin gPackager )
				)
				( objectStatus "C5A7.2" )
			)
			( pin "@baseboard_fab2_lib.baseboard_fab2(sch_1):page220_i268:a"
				( attribute "PN" "1"
					( Origin gPackager )
				)
				( objectStatus "C5A6.1" )
			)
			( pin "@baseboard_fab2_lib.baseboard_fab2(sch_1):page220_i268:b"
				( attribute "PN" "2"
					( Origin gPackager )
				)
				( objectStatus "C5A6.2" )
			)
			( pin "@baseboard_fab2_lib.baseboard_fab2(sch_1):page217_i304:a"
				( attribute "PN" "1"
					( Origin gPackager )
				)
				( objectStatus "C5G6.1" )
			)
			( pin "@baseboard_fab2_lib.baseboard_fab2(sch_1):page217_i304:b"
				( attribute "PN" "2"
					( Origin gPackager )
				)
				( objectStatus "C5G6.2" )
			)
			( pin "@baseboard_fab2_lib.baseboard_fab2(sch_1):page220_i267:a"
				( attribute "PN" "1"
					( Origin gPackager )
				)
				( objectStatus "C5A14.1" )
			)
			( pin "@baseboard_fab2_lib.baseboard_fab2(sch_1):page220_i267:b"
				( attribute "PN" "2"
					( Origin gPackager )
				)
				( objectStatus "C5A14.2" )
			)
			( pin "@baseboard_fab2_lib.baseboard_fab2(sch_1):page217_i303:a"
				( attribute "PN" "1"
					( Origin gPackager )
				)
				( objectStatus "C5G13.1" )
			)
			( pin "@baseboard_fab2_lib.baseboard_fab2(sch_1):page217_i303:b"
				( attribute "PN" "2"
					( Origin gPackager )
				)
				( objectStatus "C5G13.2" )
			)
			( pin "@baseboard_fab2_lib.baseboard_fab2(sch_1):page217_i302:a"
				( attribute "PN" "1"
					( Origin gPackager )
				)
				( objectStatus "C5G4.1" )
			)
			( pin "@baseboard_fab2_lib.baseboard_fab2(sch_1):page217_i302:b"
				( attribute "PN" "2"
					( Origin gPackager )
				)
				( objectStatus "C5G4.2" )
			)
			( pin "@baseboard_fab2_lib.baseboard_fab2(sch_1):page220_i266:a"
				( attribute "PN" "1"
					( Origin gPackager )
				)
				( objectStatus "C5A2.1" )
			)
			( pin "@baseboard_fab2_lib.baseboard_fab2(sch_1):page220_i266:b"
				( attribute "PN" "2"
					( Origin gPackager )
				)
				( objectStatus "C5A2.2" )
			)
			( pin "@baseboard_fab2_lib.baseboard_fab2(sch_1):page220_i261:a"
				( attribute "PN" "1"
					( Origin gPackager )
				)
				( objectStatus "C5D8.1" )
			)
			( pin "@baseboard_fab2_lib.baseboard_fab2(sch_1):page220_i261:b"
				( attribute "PN" "2"
					( Origin gPackager )
				)
				( objectStatus "C5D8.2" )
			)
			( pin "@baseboard_fab2_lib.baseboard_fab2(sch_1):page217_i301:a"
				( attribute "PN" "1"
					( Origin gPackager )
				)
				( objectStatus "C5G2.1" )
			)
			( pin "@baseboard_fab2_lib.baseboard_fab2(sch_1):page217_i301:b"
				( attribute "PN" "2"
					( Origin gPackager )
				)
				( objectStatus "C5G2.2" )
			)
			( pin "@baseboard_fab2_lib.baseboard_fab2(sch_1):page217_i300:a"
				( attribute "PN" "1"
					( Origin gPackager )
				)
				( objectStatus "C5G12.1" )
			)
			( pin "@baseboard_fab2_lib.baseboard_fab2(sch_1):page217_i300:b"
				( attribute "PN" "2"
					( Origin gPackager )
				)
				( objectStatus "C5G12.2" )
			)
			( pin "@baseboard_fab2_lib.baseboard_fab2(sch_1):page220_i260:a"
				( attribute "PN" "1"
					( Origin gPackager )
				)
				( objectStatus "C5D7.1" )
			)
			( pin "@baseboard_fab2_lib.baseboard_fab2(sch_1):page220_i260:b"
				( attribute "PN" "2"
					( Origin gPackager )
				)
				( objectStatus "C5D7.2" )
			)
			( pin "@baseboard_fab2_lib.baseboard_fab2(sch_1):page220_i259:a"
				( attribute "PN" "1"
					( Origin gPackager )
				)
				( objectStatus "C5D6.1" )
			)
			( pin "@baseboard_fab2_lib.baseboard_fab2(sch_1):page220_i259:b"
				( attribute "PN" "2"
					( Origin gPackager )
				)
				( objectStatus "C5D6.2" )
			)
			( pin "@baseboard_fab2_lib.baseboard_fab2(sch_1):page217_i299:a"
				( attribute "PN" "1"
					( Origin gPackager )
				)
				( objectStatus "C5G11.1" )
			)
			( pin "@baseboard_fab2_lib.baseboard_fab2(sch_1):page217_i299:b"
				( attribute "PN" "2"
					( Origin gPackager )
				)
				( objectStatus "C5G11.2" )
			)
			( pin "@baseboard_fab2_lib.baseboard_fab2(sch_1):page220_i258:a"
				( attribute "PN" "1"
					( Origin gPackager )
				)
				( objectStatus "C5D9.1" )
			)
			( pin "@baseboard_fab2_lib.baseboard_fab2(sch_1):page220_i258:b"
				( attribute "PN" "2"
					( Origin gPackager )
				)
				( objectStatus "C5D9.2" )
			)
			( pin "@baseboard_fab2_lib.baseboard_fab2(sch_1):page217_i259:a"
				( attribute "PN" "1"
					( Origin gPackager )
				)
				( objectStatus "SH4U1.1" )
			)
			( pin "@baseboard_fab2_lib.baseboard_fab2(sch_1):page217_i259:b"
				( attribute "PN" "2"
					( Origin gPackager )
				)
				( objectStatus "SH4U1.2" )
			)
			( pin "@baseboard_fab2_lib.baseboard_fab2(sch_1):page217_i260:a"
				( attribute "PN" "1"
					( Origin gPackager )
				)
				( objectStatus "SH4U2.1" )
			)
			( pin "@baseboard_fab2_lib.baseboard_fab2(sch_1):page217_i260:b"
				( attribute "PN" "2"
					( Origin gPackager )
				)
				( objectStatus "SH4U2.2" )
			)
			( pin "@baseboard_fab2_lib.baseboard_fab2(sch_1):page223_i54:a"
				( attribute "PN" "1"
					( Origin gPackager )
				)
				( objectStatus "R1G12.1" )
			)
			( pin "@baseboard_fab2_lib.baseboard_fab2(sch_1):page223_i54:b"
				( attribute "PN" "2"
					( Origin gPackager )
				)
				( objectStatus "R1G12.2" )
			)
			( pin "@baseboard_fab2_lib.baseboard_fab2(sch_1):page223_i49:a"
				( attribute "PN" "1"
					( Origin gPackager )
				)
				( objectStatus "R1G11.1" )
			)
			( pin "@baseboard_fab2_lib.baseboard_fab2(sch_1):page223_i49:b"
				( attribute "PN" "2"
					( Origin gPackager )
				)
				( objectStatus "R1G11.2" )
			)
			( pin "@baseboard_fab2_lib.baseboard_fab2(sch_1):page221_i40:a"
				( attribute "PN" "1"
					( Origin gPackager )
				)
				( objectStatus "C5T3.1" )
			)
			( pin "@baseboard_fab2_lib.baseboard_fab2(sch_1):page221_i40:b"
				( attribute "PN" "2"
					( Origin gPackager )
				)
				( objectStatus "C5T3.2" )
			)
			( pin "@baseboard_fab2_lib.baseboard_fab2(sch_1):page218_i14:a"
				( attribute "PN" "1"
					( Origin gPackager )
				)
				( objectStatus "C7A28.1" )
			)
			( pin "@baseboard_fab2_lib.baseboard_fab2(sch_1):page218_i14:b"
				( attribute "PN" "2"
					( Origin gPackager )
				)
				( objectStatus "C7A28.2" )
			)
			( pin "@baseboard_fab2_lib.baseboard_fab2(sch_1):page218_i15:a"
				( attribute "PN" "1"
					( Origin gPackager )
				)
				( objectStatus "R3M6.1" )
			)
			( pin "@baseboard_fab2_lib.baseboard_fab2(sch_1):page218_i15:b"
				( attribute "PN" "2"
					( Origin gPackager )
				)
				( objectStatus "R3M6.2" )
			)
			( pin "@baseboard_fab2_lib.baseboard_fab2(sch_1):page218_i16:a"
				( attribute "PN" "1"
					( Origin gPackager )
				)
				( objectStatus "C7A29.1" )
			)
			( pin "@baseboard_fab2_lib.baseboard_fab2(sch_1):page218_i16:b"
				( attribute "PN" "2"
					( Origin gPackager )
				)
				( objectStatus "C7A29.2" )
			)
			( pin "@baseboard_fab2_lib.baseboard_fab2(sch_1):page218_i17:\1\"
				( attribute "PN" "1"
					( Origin gPackager )
				)
				( objectStatus "CF17.1" )
			)
			( pin "@baseboard_fab2_lib.baseboard_fab2(sch_1):page218_i17:\2\"
				( attribute "PN" "2"
					( Origin gPackager )
				)
				( objectStatus "CF17.2" )
			)
			( pin "@baseboard_fab2_lib.baseboard_fab2(sch_1):page218_i21:a"
				( attribute "PN" "1"
					( Origin gPackager )
				)
				( objectStatus "R7A17.1" )
			)
			( pin "@baseboard_fab2_lib.baseboard_fab2(sch_1):page218_i21:b"
				( attribute "PN" "2"
					( Origin gPackager )
				)
				( objectStatus "R7A17.2" )
			)
			( pin "@baseboard_fab2_lib.baseboard_fab2(sch_1):page230_i41:a"
				( attribute "PN" "1"
					( Origin gPackager )
				)
				( objectStatus "C8L3.1" )
			)
			( pin "@baseboard_fab2_lib.baseboard_fab2(sch_1):page230_i41:b"
				( attribute "PN" "2"
					( Origin gPackager )
				)
				( objectStatus "C8L3.2" )
			)
			( pin "@baseboard_fab2_lib.baseboard_fab2(sch_1):page222_i45:a"
				( attribute "PN" "1"
					( Origin gPackager )
				)
				( objectStatus "C5L4.1" )
			)
			( pin "@baseboard_fab2_lib.baseboard_fab2(sch_1):page222_i45:b"
				( attribute "PN" "2"
					( Origin gPackager )
				)
				( objectStatus "C5L4.2" )
			)
			( pin "@baseboard_fab2_lib.baseboard_fab2(sch_1):page222_i23:a"
				( attribute "PN" "1"
					( Origin gPackager )
				)
				( objectStatus "R6L9.1" )
			)
			( pin "@baseboard_fab2_lib.baseboard_fab2(sch_1):page222_i23:b"
				( attribute "PN" "2"
					( Origin gPackager )
				)
				( objectStatus "R6L9.2" )
			)
			( pin "@baseboard_fab2_lib.baseboard_fab2(sch_1):page222_i22:a"
				( attribute "PN" "1"
					( Origin gPackager )
				)
				( objectStatus "C4A12.1" )
			)
			( pin "@baseboard_fab2_lib.baseboard_fab2(sch_1):page222_i22:b"
				( attribute "PN" "2"
					( Origin gPackager )
				)
				( objectStatus "C4A12.2" )
			)
			( pin "@baseboard_fab2_lib.baseboard_fab2(sch_1):page222_i20:a"
				( attribute "PN" "1"
					( Origin gPackager )
				)
				( objectStatus "C4A9.1" )
			)
			( pin "@baseboard_fab2_lib.baseboard_fab2(sch_1):page222_i20:b"
				( attribute "PN" "2"
					( Origin gPackager )
				)
				( objectStatus "C4A9.2" )
			)
			( pin "@baseboard_fab2_lib.baseboard_fab2(sch_1):page226_i72:a"
				( attribute "PN" "1"
					( Origin gPackager )
				)
				( objectStatus "R1B12.1" )
			)
			( pin "@baseboard_fab2_lib.baseboard_fab2(sch_1):page226_i72:b"
				( attribute "PN" "2"
					( Origin gPackager )
				)
				( objectStatus "R1B12.2" )
			)
			( pin "@baseboard_fab2_lib.baseboard_fab2(sch_1):page218_i34:a"
				( attribute "PN" "1"
					( Origin gPackager )
				)
				( objectStatus "R3M5.1" )
			)
			( pin "@baseboard_fab2_lib.baseboard_fab2(sch_1):page218_i34:b"
				( attribute "PN" "2"
					( Origin gPackager )
				)
				( objectStatus "R3M5.2" )
			)
			( pin "@baseboard_fab2_lib.baseboard_fab2(sch_1):page218_i35:a"
				( attribute "PN" "1"
					( Origin gPackager )
				)
				( objectStatus "R3M1.1" )
			)
			( pin "@baseboard_fab2_lib.baseboard_fab2(sch_1):page218_i35:b"
				( attribute "PN" "2"
					( Origin gPackager )
				)
				( objectStatus "R3M1.2" )
			)
			( pin "@baseboard_fab2_lib.baseboard_fab2(sch_1):page222_i17:a"
				( attribute "PN" "1"
					( Origin gPackager )
				)
				( objectStatus "C6L3.1" )
			)
			( pin "@baseboard_fab2_lib.baseboard_fab2(sch_1):page222_i17:b"
				( attribute "PN" "2"
					( Origin gPackager )
				)
				( objectStatus "C6L3.2" )
			)
			( pin "@baseboard_fab2_lib.baseboard_fab2(sch_1):page222_i15:a"
				( attribute "PN" "1"
					( Origin gPackager )
				)
				( objectStatus "C6L4.1" )
			)
			( pin "@baseboard_fab2_lib.baseboard_fab2(sch_1):page222_i15:b"
				( attribute "PN" "2"
					( Origin gPackager )
				)
				( objectStatus "C6L4.2" )
			)
			( pin "@baseboard_fab2_lib.baseboard_fab2(sch_1):page218_i40:a"
				( attribute "PN" "1"
					( Origin gPackager )
				)
				( objectStatus "C7A37.1" )
			)
			( pin "@baseboard_fab2_lib.baseboard_fab2(sch_1):page218_i40:b"
				( attribute "PN" "2"
					( Origin gPackager )
				)
				( objectStatus "C7A37.2" )
			)
			( pin "@baseboard_fab2_lib.baseboard_fab2(sch_1):page223_i75:a"
				( attribute "PN" "1"
					( Origin gPackager )
				)
				( objectStatus "R12W31.1" )
			)
			( pin "@baseboard_fab2_lib.baseboard_fab2(sch_1):page223_i75:b"
				( attribute "PN" "2"
					( Origin gPackager )
				)
				( objectStatus "R12W31.2" )
			)
			( pin "@baseboard_fab2_lib.baseboard_fab2(sch_1):page222_i13:agnd"
				( attribute "PN" "3"
					( Origin gPackager )
				)
				( objectStatus "EU4A1.3" )
			)
			( pin "@baseboard_fab2_lib.baseboard_fab2(sch_1):page222_i13:bias"
				( attribute "PN" "2"
					( Origin gPackager )
				)
				( objectStatus "EU4A1.2" )
			)
			( pin "@baseboard_fab2_lib.baseboard_fab2(sch_1):page222_i13:en"
				( attribute "PN" "7"
					( Origin gPackager )
				)
				( objectStatus "EU4A1.7" )
			)
			( pin "@baseboard_fab2_lib.baseboard_fab2(sch_1):page222_i13:pg"
				( attribute "PN" "5"
					( Origin gPackager )
				)
				( objectStatus "EU4A1.5" )
			)
			( pin "@baseboard_fab2_lib.baseboard_fab2(sch_1):page222_i13:pgnd"
				( attribute "PN" "8"
					( Origin gPackager )
				)
				( objectStatus "EU4A1.8" )
			)
			( pin "@baseboard_fab2_lib.baseboard_fab2(sch_1):page222_i13:sns"
				( attribute "PN" "6"
					( Origin gPackager )
				)
				( objectStatus "EU4A1.6" )
			)
			( pin "@baseboard_fab2_lib.baseboard_fab2(sch_1):page222_i13:thpad"
				( attribute "PN" "11"
					( Origin gPackager )
				)
				( objectStatus "EU4A1.11" )
			)
			( pin "@baseboard_fab2_lib.baseboard_fab2(sch_1):page222_i13:vddq"
				( attribute "PN" "4"
					( Origin gPackager )
				)
				( objectStatus "EU4A1.4" )
			)
			( pin "@baseboard_fab2_lib.baseboard_fab2(sch_1):page222_i13:vin"
				( attribute "PN" "10"
					( Origin gPackager )
				)
				( objectStatus "EU4A1.10" )
			)
			( pin "@baseboard_fab2_lib.baseboard_fab2(sch_1):page222_i13:vref"
				( attribute "PN" "1"
					( Origin gPackager )
				)
				( objectStatus "EU4A1.1" )
			)
			( pin "@baseboard_fab2_lib.baseboard_fab2(sch_1):page222_i13:vtt"
				( attribute "PN" "9"
					( Origin gPackager )
				)
				( objectStatus "EU4A1.9" )
			)
			( pin "@baseboard_fab2_lib.baseboard_fab2(sch_1):page218_i59:a"
				( attribute "PN" "1"
					( Origin gPackager )
				)
				( objectStatus "R7B1.1" )
			)
			( pin "@baseboard_fab2_lib.baseboard_fab2(sch_1):page218_i59:b"
				( attribute "PN" "2"
					( Origin gPackager )
				)
				( objectStatus "R7B1.2" )
			)
			( pin "@baseboard_fab2_lib.baseboard_fab2(sch_1):page218_i60:a"
				( attribute "PN" "1"
					( Origin gPackager )
				)
				( objectStatus "R3M3.1" )
			)
			( pin "@baseboard_fab2_lib.baseboard_fab2(sch_1):page218_i60:b"
				( attribute "PN" "2"
					( Origin gPackager )
				)
				( objectStatus "R3M3.2" )
			)
			( pin "@baseboard_fab2_lib.baseboard_fab2(sch_1):page222_i10:a"
				( attribute "PN" "1"
					( Origin gPackager )
				)
				( objectStatus "R6L11.1" )
			)
			( pin "@baseboard_fab2_lib.baseboard_fab2(sch_1):page222_i10:b"
				( attribute "PN" "2"
					( Origin gPackager )
				)
				( objectStatus "R6L11.2" )
			)
			( pin "@baseboard_fab2_lib.baseboard_fab2(sch_1):page222_i9:a"
				( attribute "PN" "1"
					( Origin gPackager )
				)
				( objectStatus "C4A11.1" )
			)
			( pin "@baseboard_fab2_lib.baseboard_fab2(sch_1):page222_i9:b"
				( attribute "PN" "2"
					( Origin gPackager )
				)
				( objectStatus "C4A11.2" )
			)
			( pin "@baseboard_fab2_lib.baseboard_fab2(sch_1):page219_i44:a"
				( attribute "PN" "1"
					( Origin gPackager )
				)
				( objectStatus "C7A12.1" )
			)
			( pin "@baseboard_fab2_lib.baseboard_fab2(sch_1):page219_i44:b"
				( attribute "PN" "2"
					( Origin gPackager )
				)
				( objectStatus "C7A12.2" )
			)
			( pin "@baseboard_fab2_lib.baseboard_fab2(sch_1):page219_i45:a"
				( attribute "PN" "1"
					( Origin gPackager )
				)
				( objectStatus "C3L2.1" )
			)
			( pin "@baseboard_fab2_lib.baseboard_fab2(sch_1):page219_i45:b"
				( attribute "PN" "2"
					( Origin gPackager )
				)
				( objectStatus "C3L2.2" )
			)
			( pin "@baseboard_fab2_lib.baseboard_fab2(sch_1):page219_i46:a"
				( attribute "PN" "1"
					( Origin gPackager )
				)
				( objectStatus "C3L4.1" )
			)
			( pin "@baseboard_fab2_lib.baseboard_fab2(sch_1):page219_i46:b"
				( attribute "PN" "2"
					( Origin gPackager )
				)
				( objectStatus "C3L4.2" )
			)
			( pin "@baseboard_fab2_lib.baseboard_fab2(sch_1):page219_i47:a"
				( attribute "PN" "1"
					( Origin gPackager )
				)
				( objectStatus "C3L13.1" )
			)
			( pin "@baseboard_fab2_lib.baseboard_fab2(sch_1):page219_i47:b"
				( attribute "PN" "2"
					( Origin gPackager )
				)
				( objectStatus "C3L13.2" )
			)
			( pin "@baseboard_fab2_lib.baseboard_fab2(sch_1):page219_i48:a"
				( attribute "PN" "1"
					( Origin gPackager )
				)
				( objectStatus "C7A11.1" )
			)
			( pin "@baseboard_fab2_lib.baseboard_fab2(sch_1):page219_i48:b"
				( attribute "PN" "2"
					( Origin gPackager )
				)
				( objectStatus "C7A11.2" )
			)
			( pin "@baseboard_fab2_lib.baseboard_fab2(sch_1):page219_i50:a"
				( attribute "PN" "1"
					( Origin gPackager )
				)
				( objectStatus "C7A16.1" )
			)
			( pin "@baseboard_fab2_lib.baseboard_fab2(sch_1):page219_i50:b"
				( attribute "PN" "2"
					( Origin gPackager )
				)
				( objectStatus "C7A16.2" )
			)
			( pin "@baseboard_fab2_lib.baseboard_fab2(sch_1):page219_i51:a"
				( attribute "PN" "1"
					( Origin gPackager )
				)
				( objectStatus "C7A5.1" )
			)
			( pin "@baseboard_fab2_lib.baseboard_fab2(sch_1):page219_i51:b"
				( attribute "PN" "2"
					( Origin gPackager )
				)
				( objectStatus "C7A5.2" )
			)
			( pin "@baseboard_fab2_lib.baseboard_fab2(sch_1):page224_i151:a"
				( attribute "PN" "1"
					( Origin gPackager )
				)
				( objectStatus "R9U12.1" )
			)
			( pin "@baseboard_fab2_lib.baseboard_fab2(sch_1):page224_i151:b"
				( attribute "PN" "2"
					( Origin gPackager )
				)
				( objectStatus "R9U12.2" )
			)
			( pin "@baseboard_fab2_lib.baseboard_fab2(sch_1):page216_i150:\1\"
				( attribute "PN" "1"
					( Origin gPackager )
				)
				( objectStatus "C7G42.1" )
			)
			( pin "@baseboard_fab2_lib.baseboard_fab2(sch_1):page216_i150:\2\"
				( attribute "PN" "2"
					( Origin gPackager )
				)
				( objectStatus "C7G42.2" )
			)
			( pin "@baseboard_fab2_lib.baseboard_fab2(sch_1):page219_i54:a"
				( attribute "PN" "1"
					( Origin gPackager )
				)
				( objectStatus "C7A17.1" )
			)
			( pin "@baseboard_fab2_lib.baseboard_fab2(sch_1):page219_i54:b"
				( attribute "PN" "2"
					( Origin gPackager )
				)
				( objectStatus "C7A17.2" )
			)
			( pin "@baseboard_fab2_lib.baseboard_fab2(sch_1):page216_i153:f"
				( attribute "PN" "2"
					( Origin gPackager )
				)
				( objectStatus "L7G1.2" )
			)
			( pin "@baseboard_fab2_lib.baseboard_fab2(sch_1):page216_i153:s"
				( attribute "PN" "1"
					( Origin gPackager )
				)
				( objectStatus "L7G1.1" )
			)
			( pin "@baseboard_fab2_lib.baseboard_fab2(sch_1):page219_i158:f"
				( attribute "PN" "2"
					( Origin gPackager )
				)
				( objectStatus "L7A3.2" )
			)
			( pin "@baseboard_fab2_lib.baseboard_fab2(sch_1):page219_i158:s"
				( attribute "PN" "1"
					( Origin gPackager )
				)
				( objectStatus "L7A3.1" )
			)
			( pin "@baseboard_fab2_lib.baseboard_fab2(sch_1):page219_i68:a"
				( attribute "PN" "1"
					( Origin gPackager )
				)
				( objectStatus "C6A4.1" )
			)
			( pin "@baseboard_fab2_lib.baseboard_fab2(sch_1):page219_i68:b"
				( attribute "PN" "2"
					( Origin gPackager )
				)
				( objectStatus "C6A4.2" )
			)
			( pin "@baseboard_fab2_lib.baseboard_fab2(sch_1):page219_i72:a"
				( attribute "PN" "1"
					( Origin gPackager )
				)
				( objectStatus "C7A25.1" )
			)
			( pin "@baseboard_fab2_lib.baseboard_fab2(sch_1):page219_i72:b"
				( attribute "PN" "2"
					( Origin gPackager )
				)
				( objectStatus "C7A25.2" )
			)
			( pin "@baseboard_fab2_lib.baseboard_fab2(sch_1):page212_i143:\1\"
				( attribute "PN" "1"
					( Origin gPackager )
				)
				( objectStatus "C7C20.1" )
			)
			( pin "@baseboard_fab2_lib.baseboard_fab2(sch_1):page212_i143:\2\"
				( attribute "PN" "2"
					( Origin gPackager )
				)
				( objectStatus "C7C20.2" )
			)
			( pin "@baseboard_fab2_lib.baseboard_fab2(sch_1):page219_i75:a"
				( attribute "PN" "1"
					( Origin gPackager )
				)
				( objectStatus "C7A22.1" )
			)
			( pin "@baseboard_fab2_lib.baseboard_fab2(sch_1):page219_i75:b"
				( attribute "PN" "2"
					( Origin gPackager )
				)
				( objectStatus "C7A22.2" )
			)
			( pin "@baseboard_fab2_lib.baseboard_fab2(sch_1):page224_i150:a"
				( attribute "PN" "1"
					( Origin gPackager )
				)
				( objectStatus "R9U1.1" )
			)
			( pin "@baseboard_fab2_lib.baseboard_fab2(sch_1):page224_i150:b"
				( attribute "PN" "2"
					( Origin gPackager )
				)
				( objectStatus "R9U1.2" )
			)
			( pin "@baseboard_fab2_lib.baseboard_fab2(sch_1):page219_i77:a"
				( attribute "PN" "1"
					( Origin gPackager )
				)
				( objectStatus "C7A24.1" )
			)
			( pin "@baseboard_fab2_lib.baseboard_fab2(sch_1):page219_i77:b"
				( attribute "PN" "2"
					( Origin gPackager )
				)
				( objectStatus "C7A24.2" )
			)
			( pin "@baseboard_fab2_lib.baseboard_fab2(sch_1):page219_i78:a"
				( attribute "PN" "1"
					( Origin gPackager )
				)
				( objectStatus "C7A20.1" )
			)
			( pin "@baseboard_fab2_lib.baseboard_fab2(sch_1):page219_i78:b"
				( attribute "PN" "2"
					( Origin gPackager )
				)
				( objectStatus "C7A20.2" )
			)
			( pin "@baseboard_fab2_lib.baseboard_fab2(sch_1):page219_i79:a"
				( attribute "PN" "1"
					( Origin gPackager )
				)
				( objectStatus "C7A21.1" )
			)
			( pin "@baseboard_fab2_lib.baseboard_fab2(sch_1):page219_i79:b"
				( attribute "PN" "2"
					( Origin gPackager )
				)
				( objectStatus "C7A21.2" )
			)
			( pin "@baseboard_fab2_lib.baseboard_fab2(sch_1):page219_i80:a"
				( attribute "PN" "1"
					( Origin gPackager )
				)
				( objectStatus "C3L17.1" )
			)
			( pin "@baseboard_fab2_lib.baseboard_fab2(sch_1):page219_i80:b"
				( attribute "PN" "2"
					( Origin gPackager )
				)
				( objectStatus "C3L17.2" )
			)
			( pin "@baseboard_fab2_lib.baseboard_fab2(sch_1):page219_i81:a"
				( attribute "PN" "1"
					( Origin gPackager )
				)
				( objectStatus "C3L16.1" )
			)
			( pin "@baseboard_fab2_lib.baseboard_fab2(sch_1):page219_i81:b"
				( attribute "PN" "2"
					( Origin gPackager )
				)
				( objectStatus "C3L16.2" )
			)
			( pin "@baseboard_fab2_lib.baseboard_fab2(sch_1):page219_i84:a"
				( attribute "PN" "1"
					( Origin gPackager )
				)
				( objectStatus "C3L15.1" )
			)
			( pin "@baseboard_fab2_lib.baseboard_fab2(sch_1):page219_i84:b"
				( attribute "PN" "2"
					( Origin gPackager )
				)
				( objectStatus "C3L15.2" )
			)
			( pin "@baseboard_fab2_lib.baseboard_fab2(sch_1):page219_i87:a"
				( attribute "PN" "1"
					( Origin gPackager )
				)
				( objectStatus "C6A1.1" )
			)
			( pin "@baseboard_fab2_lib.baseboard_fab2(sch_1):page219_i87:b"
				( attribute "PN" "2"
					( Origin gPackager )
				)
				( objectStatus "C6A1.2" )
			)
			( pin "@baseboard_fab2_lib.baseboard_fab2(sch_1):page219_i106:boost"
				( attribute "PN" "33"
					( Origin gPackager )
				)
				( objectStatus "EU7A1.33" )
			)
			( pin "@baseboard_fab2_lib.baseboard_fab2(sch_1):page219_i106:en"
				( attribute "PN" "35"
					( Origin gPackager )
				)
				( objectStatus "EU7A1.35" )
			)
			( pin "@baseboard_fab2_lib.baseboard_fab2(sch_1):page219_i106:gl(0)"
				( attribute "PN" "6"
					( Origin gPackager )
				)
				( objectStatus "EU7A1.6" )
			)
			( pin "@baseboard_fab2_lib.baseboard_fab2(sch_1):page219_i106:gl(1)"
				( attribute "PN" "41"
					( Origin gPackager )
				)
				( objectStatus "EU7A1.41" )
			)
			( pin "@baseboard_fab2_lib.baseboard_fab2(sch_1):page219_i106:iout"
				( attribute "PN" "38"
					( Origin gPackager )
				)
				( objectStatus "EU7A1.38" )
			)
			( pin "@baseboard_fab2_lib.baseboard_fab2(sch_1):page219_i106:lgnd"
				( attribute "PN" "2"
					( Origin gPackager )
				)
				( objectStatus "EU7A1.2" )
			)
			( pin "@baseboard_fab2_lib.baseboard_fab2(sch_1):page219_i106:nc"
				( attribute "PN" "31"
					( Origin gPackager )
				)
				( objectStatus "EU7A1.31" )
			)
			( pin "@baseboard_fab2_lib.baseboard_fab2(sch_1):page219_i106:ocset"
				( attribute "PN" "37"
					( Origin gPackager )
				)
				( objectStatus "EU7A1.37" )
			)
			( pin "@baseboard_fab2_lib.baseboard_fab2(sch_1):page219_i106:pgnd(0)"
				( attribute "PN" "5"
					( Origin gPackager )
				)
				( objectStatus "EU7A1.5" )
			)
			( pin "@baseboard_fab2_lib.baseboard_fab2(sch_1):page219_i106:pgnd(1)"
				( attribute "PN" "7"
					( Origin gPackager )
				)
				( objectStatus "EU7A1.7" )
			)
			( pin "@baseboard_fab2_lib.baseboard_fab2(sch_1):page219_i106:pgnd(2)"
				( attribute "PN" "40"
					( Origin gPackager )
				)
				( objectStatus "EU7A1.40" )
			)
			( pin "@baseboard_fab2_lib.baseboard_fab2(sch_1):page219_i106:phase"
				( attribute "PN" "32"
					( Origin gPackager )
				)
				( objectStatus "EU7A1.32" )
			)
			( pin "@baseboard_fab2_lib.baseboard_fab2(sch_1):page219_i106:pwm"
				( attribute "PN" "34"
					( Origin gPackager )
				)
				( objectStatus "EU7A1.34" )
			)
			( pin "@baseboard_fab2_lib.baseboard_fab2(sch_1):page219_i106:refin"
				( attribute "PN" "39"
					( Origin gPackager )
				)
				( objectStatus "EU7A1.39" )
			)
			( pin "@baseboard_fab2_lib.baseboard_fab2(sch_1):page219_i106:sw"
				( attribute "PN" "10"
					( Origin gPackager )
				)
				( objectStatus "EU7A1.10" )
			)
			( pin "@baseboard_fab2_lib.baseboard_fab2(sch_1):page219_i106:tout_flt"
				( attribute "PN" "36"
					( Origin gPackager )
				)
				( objectStatus "EU7A1.36" )
			)
			( pin "@baseboard_fab2_lib.baseboard_fab2(sch_1):page219_i106:vcc"
				( attribute "PN" "3"
					( Origin gPackager )
				)
				( objectStatus "EU7A1.3" )
			)
			( pin "@baseboard_fab2_lib.baseboard_fab2(sch_1):page219_i106:vdrv"
				( attribute "PN" "4"
					( Origin gPackager )
				)
				( objectStatus "EU7A1.4" )
			)
			( pin "@baseboard_fab2_lib.baseboard_fab2(sch_1):page219_i106:vin(0)"
				( attribute "PN" "25"
					( Origin gPackager )
				)
				( objectStatus "EU7A1.25" )
			)
			( pin "@baseboard_fab2_lib.baseboard_fab2(sch_1):page219_i106:vin(1)"
				( attribute "PN" "30"
					( Origin gPackager )
				)
				( objectStatus "EU7A1.30" )
			)
			( pin "@baseboard_fab2_lib.baseboard_fab2(sch_1):page219_i106:vos"
				( attribute "PN" "1"
					( Origin gPackager )
				)
				( objectStatus "EU7A1.1" )
			)
			( pin "@baseboard_fab2_lib.baseboard_fab2(sch_1):page219_i107:boost"
				( attribute "PN" "33"
					( Origin gPackager )
				)
				( objectStatus "EU7A4.33" )
			)
			( pin "@baseboard_fab2_lib.baseboard_fab2(sch_1):page219_i107:en"
				( attribute "PN" "35"
					( Origin gPackager )
				)
				( objectStatus "EU7A4.35" )
			)
			( pin "@baseboard_fab2_lib.baseboard_fab2(sch_1):page219_i107:gl(0)"
				( attribute "PN" "6"
					( Origin gPackager )
				)
				( objectStatus "EU7A4.6" )
			)
			( pin "@baseboard_fab2_lib.baseboard_fab2(sch_1):page219_i107:gl(1)"
				( attribute "PN" "41"
					( Origin gPackager )
				)
				( objectStatus "EU7A4.41" )
			)
			( pin "@baseboard_fab2_lib.baseboard_fab2(sch_1):page219_i107:iout"
				( attribute "PN" "38"
					( Origin gPackager )
				)
				( objectStatus "EU7A4.38" )
			)
			( pin "@baseboard_fab2_lib.baseboard_fab2(sch_1):page219_i107:lgnd"
				( attribute "PN" "2"
					( Origin gPackager )
				)
				( objectStatus "EU7A4.2" )
			)
			( pin "@baseboard_fab2_lib.baseboard_fab2(sch_1):page219_i107:nc"
				( attribute "PN" "31"
					( Origin gPackager )
				)
				( objectStatus "EU7A4.31" )
			)
			( pin "@baseboard_fab2_lib.baseboard_fab2(sch_1):page219_i107:ocset"
				( attribute "PN" "37"
					( Origin gPackager )
				)
				( objectStatus "EU7A4.37" )
			)
			( pin "@baseboard_fab2_lib.baseboard_fab2(sch_1):page219_i107:pgnd(0)"
				( attribute "PN" "5"
					( Origin gPackager )
				)
				( objectStatus "EU7A4.5" )
			)
			( pin "@baseboard_fab2_lib.baseboard_fab2(sch_1):page219_i107:pgnd(1)"
				( attribute "PN" "7"
					( Origin gPackager )
				)
				( objectStatus "EU7A4.7" )
			)
			( pin "@baseboard_fab2_lib.baseboard_fab2(sch_1):page219_i107:pgnd(2)"
				( attribute "PN" "40"
					( Origin gPackager )
				)
				( objectStatus "EU7A4.40" )
			)
			( pin "@baseboard_fab2_lib.baseboard_fab2(sch_1):page219_i107:phase"
				( attribute "PN" "32"
					( Origin gPackager )
				)
				( objectStatus "EU7A4.32" )
			)
			( pin "@baseboard_fab2_lib.baseboard_fab2(sch_1):page219_i107:pwm"
				( attribute "PN" "34"
					( Origin gPackager )
				)
				( objectStatus "EU7A4.34" )
			)
			( pin "@baseboard_fab2_lib.baseboard_fab2(sch_1):page219_i107:refin"
				( attribute "PN" "39"
					( Origin gPackager )
				)
				( objectStatus "EU7A4.39" )
			)
			( pin "@baseboard_fab2_lib.baseboard_fab2(sch_1):page219_i107:sw"
				( attribute "PN" "10"
					( Origin gPackager )
				)
				( objectStatus "EU7A4.10" )
			)
			( pin "@baseboard_fab2_lib.baseboard_fab2(sch_1):page219_i107:tout_flt"
				( attribute "PN" "36"
					( Origin gPackager )
				)
				( objectStatus "EU7A4.36" )
			)
			( pin "@baseboard_fab2_lib.baseboard_fab2(sch_1):page219_i107:vcc"
				( attribute "PN" "3"
					( Origin gPackager )
				)
				( objectStatus "EU7A4.3" )
			)
			( pin "@baseboard_fab2_lib.baseboard_fab2(sch_1):page219_i107:vdrv"
				( attribute "PN" "4"
					( Origin gPackager )
				)
				( objectStatus "EU7A4.4" )
			)
			( pin "@baseboard_fab2_lib.baseboard_fab2(sch_1):page219_i107:vin(0)"
				( attribute "PN" "25"
					( Origin gPackager )
				)
				( objectStatus "EU7A4.25" )
			)
			( pin "@baseboard_fab2_lib.baseboard_fab2(sch_1):page219_i107:vin(1)"
				( attribute "PN" "30"
					( Origin gPackager )
				)
				( objectStatus "EU7A4.30" )
			)
			( pin "@baseboard_fab2_lib.baseboard_fab2(sch_1):page219_i107:vos"
				( attribute "PN" "1"
					( Origin gPackager )
				)
				( objectStatus "EU7A4.1" )
			)
			( pin "@baseboard_fab2_lib.baseboard_fab2(sch_1):page219_i108:a"
				( attribute "PN" "1"
					( Origin gPackager )
				)
				( objectStatus "R7A20.1" )
			)
			( pin "@baseboard_fab2_lib.baseboard_fab2(sch_1):page219_i108:b"
				( attribute "PN" "2"
					( Origin gPackager )
				)
				( objectStatus "R7A20.2" )
			)
			( pin "@baseboard_fab2_lib.baseboard_fab2(sch_1):page219_i110:a"
				( attribute "PN" "1"
					( Origin gPackager )
				)
				( objectStatus "R7A21.1" )
			)
			( pin "@baseboard_fab2_lib.baseboard_fab2(sch_1):page219_i110:b"
				( attribute "PN" "2"
					( Origin gPackager )
				)
				( objectStatus "R7A21.2" )
			)
			( pin "@baseboard_fab2_lib.baseboard_fab2(sch_1):page220_i58:a"
				( attribute "PN" "1"
					( Origin gPackager )
				)
				( objectStatus "R4L4.1" )
			)
			( pin "@baseboard_fab2_lib.baseboard_fab2(sch_1):page220_i58:b"
				( attribute "PN" "2"
					( Origin gPackager )
				)
				( objectStatus "R4L4.2" )
			)
			( pin "@baseboard_fab2_lib.baseboard_fab2(sch_1):page220_i74:a"
				( attribute "PN" "1"
					( Origin gPackager )
				)
				( objectStatus "R4L2.1" )
			)
			( pin "@baseboard_fab2_lib.baseboard_fab2(sch_1):page220_i74:b"
				( attribute "PN" "2"
					( Origin gPackager )
				)
				( objectStatus "R4L2.2" )
			)
			( pin "@baseboard_fab2_lib.baseboard_fab2(sch_1):page220_i75:a"
				( attribute "PN" "1"
					( Origin gPackager )
				)
				( objectStatus "C3L6.1" )
			)
			( pin "@baseboard_fab2_lib.baseboard_fab2(sch_1):page220_i75:b"
				( attribute "PN" "2"
					( Origin gPackager )
				)
				( objectStatus "C3L6.2" )
			)
			( pin "@baseboard_fab2_lib.baseboard_fab2(sch_1):page220_i76:a"
				( attribute "PN" "1"
					( Origin gPackager )
				)
				( objectStatus "C3L14.1" )
			)
			( pin "@baseboard_fab2_lib.baseboard_fab2(sch_1):page220_i76:b"
				( attribute "PN" "2"
					( Origin gPackager )
				)
				( objectStatus "C3L14.2" )
			)
			( pin "@baseboard_fab2_lib.baseboard_fab2(sch_1):page220_i77:a"
				( attribute "PN" "1"
					( Origin gPackager )
				)
				( objectStatus "C6A5.1" )
			)
			( pin "@baseboard_fab2_lib.baseboard_fab2(sch_1):page220_i77:b"
				( attribute "PN" "2"
					( Origin gPackager )
				)
				( objectStatus "C6A5.2" )
			)
			( pin "@baseboard_fab2_lib.baseboard_fab2(sch_1):page220_i78:a"
				( attribute "PN" "1"
					( Origin gPackager )
				)
				( objectStatus "C4L5.1" )
			)
			( pin "@baseboard_fab2_lib.baseboard_fab2(sch_1):page220_i78:b"
				( attribute "PN" "2"
					( Origin gPackager )
				)
				( objectStatus "C4L5.2" )
			)
			( pin "@baseboard_fab2_lib.baseboard_fab2(sch_1):page220_i317:a"
				( attribute "PN" "1"
					( Origin gPackager )
				)
				( objectStatus "C5P5.1" )
			)
			( pin "@baseboard_fab2_lib.baseboard_fab2(sch_1):page220_i317:b"
				( attribute "PN" "2"
					( Origin gPackager )
				)
				( objectStatus "C5P5.2" )
			)
			( pin "@baseboard_fab2_lib.baseboard_fab2(sch_1):page220_i315:a"
				( attribute "PN" "1"
					( Origin gPackager )
				)
				( objectStatus "C5P3.1" )
			)
			( pin "@baseboard_fab2_lib.baseboard_fab2(sch_1):page220_i315:b"
				( attribute "PN" "2"
					( Origin gPackager )
				)
				( objectStatus "C5P3.2" )
			)
			( pin "@baseboard_fab2_lib.baseboard_fab2(sch_1):page220_i313:a"
				( attribute "PN" "1"
					( Origin gPackager )
				)
				( objectStatus "C5L14.1" )
			)
			( pin "@baseboard_fab2_lib.baseboard_fab2(sch_1):page220_i313:b"
				( attribute "PN" "2"
					( Origin gPackager )
				)
				( objectStatus "C5L14.2" )
			)
			( pin "@baseboard_fab2_lib.baseboard_fab2(sch_1):page220_i318:a"
				( attribute "PN" "1"
					( Origin gPackager )
				)
				( objectStatus "C5P4.1" )
			)
			( pin "@baseboard_fab2_lib.baseboard_fab2(sch_1):page220_i318:b"
				( attribute "PN" "2"
					( Origin gPackager )
				)
				( objectStatus "C5P4.2" )
			)
			( pin "@baseboard_fab2_lib.baseboard_fab2(sch_1):page220_i312:a"
				( attribute "PN" "1"
					( Origin gPackager )
				)
				( objectStatus "C5M12.1" )
			)
			( pin "@baseboard_fab2_lib.baseboard_fab2(sch_1):page220_i312:b"
				( attribute "PN" "2"
					( Origin gPackager )
				)
				( objectStatus "C5M12.2" )
			)
			( pin "@baseboard_fab2_lib.baseboard_fab2(sch_1):page220_i314:a"
				( attribute "PN" "1"
					( Origin gPackager )
				)
				( objectStatus "C5M8.1" )
			)
			( pin "@baseboard_fab2_lib.baseboard_fab2(sch_1):page220_i314:b"
				( attribute "PN" "2"
					( Origin gPackager )
				)
				( objectStatus "C5M8.2" )
			)
			( pin "@baseboard_fab2_lib.baseboard_fab2(sch_1):page220_i311:a"
				( attribute "PN" "1"
					( Origin gPackager )
				)
				( objectStatus "C5L2.1" )
			)
			( pin "@baseboard_fab2_lib.baseboard_fab2(sch_1):page220_i311:b"
				( attribute "PN" "2"
					( Origin gPackager )
				)
				( objectStatus "C5L2.2" )
			)
			( pin "@baseboard_fab2_lib.baseboard_fab2(sch_1):page221_i44:a"
				( attribute "PN" "1"
					( Origin gPackager )
				)
				( objectStatus "C6W11.1" )
			)
			( pin "@baseboard_fab2_lib.baseboard_fab2(sch_1):page221_i44:b"
				( attribute "PN" "2"
					( Origin gPackager )
				)
				( objectStatus "C6W11.2" )
			)
			( pin "@baseboard_fab2_lib.baseboard_fab2(sch_1):page225_i253:f"
				( attribute "PN" "2"
					( Origin gPackager )
				)
				( objectStatus "L1F1.2" )
			)
			( pin "@baseboard_fab2_lib.baseboard_fab2(sch_1):page225_i253:s"
				( attribute "PN" "1"
					( Origin gPackager )
				)
				( objectStatus "L1F1.1" )
			)
			( pin "@baseboard_fab2_lib.baseboard_fab2(sch_1):page225_i315:a"
				( attribute "PN" "1"
					( Origin gPackager )
				)
				( objectStatus "C8P34.1" )
			)
			( pin "@baseboard_fab2_lib.baseboard_fab2(sch_1):page225_i315:b"
				( attribute "PN" "2"
					( Origin gPackager )
				)
				( objectStatus "C8P34.2" )
			)
			( pin "@baseboard_fab2_lib.baseboard_fab2(sch_1):page225_i314:a"
				( attribute "PN" "1"
					( Origin gPackager )
				)
				( objectStatus "C8P31.1" )
			)
			( pin "@baseboard_fab2_lib.baseboard_fab2(sch_1):page225_i314:b"
				( attribute "PN" "2"
					( Origin gPackager )
				)
				( objectStatus "C8P31.2" )
			)
			( pin "@baseboard_fab2_lib.baseboard_fab2(sch_1):page220_i265:a"
				( attribute "PN" "1"
					( Origin gPackager )
				)
				( objectStatus "C5A13.1" )
			)
			( pin "@baseboard_fab2_lib.baseboard_fab2(sch_1):page220_i265:b"
				( attribute "PN" "2"
					( Origin gPackager )
				)
				( objectStatus "C5A13.2" )
			)
			( pin "@baseboard_fab2_lib.baseboard_fab2(sch_1):page220_i264:a"
				( attribute "PN" "1"
					( Origin gPackager )
				)
				( objectStatus "C5A12.1" )
			)
			( pin "@baseboard_fab2_lib.baseboard_fab2(sch_1):page220_i264:b"
				( attribute "PN" "2"
					( Origin gPackager )
				)
				( objectStatus "C5A12.2" )
			)
			( pin "@baseboard_fab2_lib.baseboard_fab2(sch_1):page220_i263:a"
				( attribute "PN" "1"
					( Origin gPackager )
				)
				( objectStatus "C5A15.1" )
			)
			( pin "@baseboard_fab2_lib.baseboard_fab2(sch_1):page220_i263:b"
				( attribute "PN" "2"
					( Origin gPackager )
				)
				( objectStatus "C5A15.2" )
			)
			( pin "@baseboard_fab2_lib.baseboard_fab2(sch_1):page220_i262:a"
				( attribute "PN" "1"
					( Origin gPackager )
				)
				( objectStatus "C5A1.1" )
			)
			( pin "@baseboard_fab2_lib.baseboard_fab2(sch_1):page220_i262:b"
				( attribute "PN" "2"
					( Origin gPackager )
				)
				( objectStatus "C5A1.2" )
			)
			( pin "@baseboard_fab2_lib.baseboard_fab2(sch_1):page220_i192:a"
				( attribute "PN" "1"
					( Origin gPackager )
				)
				( objectStatus "C5L15.1" )
			)
			( pin "@baseboard_fab2_lib.baseboard_fab2(sch_1):page220_i192:b"
				( attribute "PN" "2"
					( Origin gPackager )
				)
				( objectStatus "C5L15.2" )
			)
			( pin "@baseboard_fab2_lib.baseboard_fab2(sch_1):page220_i193:a"
				( attribute "PN" "1"
					( Origin gPackager )
				)
				( objectStatus "C5A5.1" )
			)
			( pin "@baseboard_fab2_lib.baseboard_fab2(sch_1):page220_i193:b"
				( attribute "PN" "2"
					( Origin gPackager )
				)
				( objectStatus "C5A5.2" )
			)
			( pin "@baseboard_fab2_lib.baseboard_fab2(sch_1):page220_i194:a"
				( attribute "PN" "1"
					( Origin gPackager )
				)
				( objectStatus "C5B1.1" )
			)
			( pin "@baseboard_fab2_lib.baseboard_fab2(sch_1):page220_i194:b"
				( attribute "PN" "2"
					( Origin gPackager )
				)
				( objectStatus "C5B1.2" )
			)
			( pin "@baseboard_fab2_lib.baseboard_fab2(sch_1):page220_i195:a"
				( attribute "PN" "1"
					( Origin gPackager )
				)
				( objectStatus "C5M9.1" )
			)
			( pin "@baseboard_fab2_lib.baseboard_fab2(sch_1):page220_i195:b"
				( attribute "PN" "2"
					( Origin gPackager )
				)
				( objectStatus "C5M9.2" )
			)
			( pin "@baseboard_fab2_lib.baseboard_fab2(sch_1):page220_i196:a"
				( attribute "PN" "1"
					( Origin gPackager )
				)
				( objectStatus "C4M5.1" )
			)
			( pin "@baseboard_fab2_lib.baseboard_fab2(sch_1):page220_i196:b"
				( attribute "PN" "2"
					( Origin gPackager )
				)
				( objectStatus "C4M5.2" )
			)
			( pin "@baseboard_fab2_lib.baseboard_fab2(sch_1):page220_i197:a"
				( attribute "PN" "1"
					( Origin gPackager )
				)
				( objectStatus "C5B2.1" )
			)
			( pin "@baseboard_fab2_lib.baseboard_fab2(sch_1):page220_i197:b"
				( attribute "PN" "2"
					( Origin gPackager )
				)
				( objectStatus "C5B2.2" )
			)
			( pin "@baseboard_fab2_lib.baseboard_fab2(sch_1):page220_i198:a"
				( attribute "PN" "1"
					( Origin gPackager )
				)
				( objectStatus "C5M10.1" )
			)
			( pin "@baseboard_fab2_lib.baseboard_fab2(sch_1):page220_i198:b"
				( attribute "PN" "2"
					( Origin gPackager )
				)
				( objectStatus "C5M10.2" )
			)
			( pin "@baseboard_fab2_lib.baseboard_fab2(sch_1):page220_i199:a"
				( attribute "PN" "1"
					( Origin gPackager )
				)
				( objectStatus "C5M3.1" )
			)
			( pin "@baseboard_fab2_lib.baseboard_fab2(sch_1):page220_i199:b"
				( attribute "PN" "2"
					( Origin gPackager )
				)
				( objectStatus "C5M3.2" )
			)
			( pin "@baseboard_fab2_lib.baseboard_fab2(sch_1):page220_i200:a"
				( attribute "PN" "1"
					( Origin gPackager )
				)
				( objectStatus "C5M11.1" )
			)
			( pin "@baseboard_fab2_lib.baseboard_fab2(sch_1):page220_i200:b"
				( attribute "PN" "2"
					( Origin gPackager )
				)
				( objectStatus "C5M11.2" )
			)
			( pin "@baseboard_fab2_lib.baseboard_fab2(sch_1):page220_i293:a"
				( attribute "PN" "1"
					( Origin gPackager )
				)
				( objectStatus "C5A11.1" )
			)
			( pin "@baseboard_fab2_lib.baseboard_fab2(sch_1):page220_i293:b"
				( attribute "PN" "2"
					( Origin gPackager )
				)
				( objectStatus "C5A11.2" )
			)
			( pin "@baseboard_fab2_lib.baseboard_fab2(sch_1):page220_i292:a"
				( attribute "PN" "1"
					( Origin gPackager )
				)
				( objectStatus "C4M2.1" )
			)
			( pin "@baseboard_fab2_lib.baseboard_fab2(sch_1):page220_i292:b"
				( attribute "PN" "2"
					( Origin gPackager )
				)
				( objectStatus "C4M2.2" )
			)
			( pin "@baseboard_fab2_lib.baseboard_fab2(sch_1):page220_i291:a"
				( attribute "PN" "1"
					( Origin gPackager )
				)
				( objectStatus "C5M1.1" )
			)
			( pin "@baseboard_fab2_lib.baseboard_fab2(sch_1):page220_i291:b"
				( attribute "PN" "2"
					( Origin gPackager )
				)
				( objectStatus "C5M1.2" )
			)
			( pin "@baseboard_fab2_lib.baseboard_fab2(sch_1):page220_i290:a"
				( attribute "PN" "1"
					( Origin gPackager )
				)
				( objectStatus "C5M2.1" )
			)
			( pin "@baseboard_fab2_lib.baseboard_fab2(sch_1):page220_i290:b"
				( attribute "PN" "2"
					( Origin gPackager )
				)
				( objectStatus "C5M2.2" )
			)
			( pin "@baseboard_fab2_lib.baseboard_fab2(sch_1):page220_i289:a"
				( attribute "PN" "1"
					( Origin gPackager )
				)
				( objectStatus "C5M4.1" )
			)
			( pin "@baseboard_fab2_lib.baseboard_fab2(sch_1):page220_i289:b"
				( attribute "PN" "2"
					( Origin gPackager )
				)
				( objectStatus "C5M4.2" )
			)
			( pin "@baseboard_fab2_lib.baseboard_fab2(sch_1):page220_i288:a"
				( attribute "PN" "1"
					( Origin gPackager )
				)
				( objectStatus "C5M5.1" )
			)
			( pin "@baseboard_fab2_lib.baseboard_fab2(sch_1):page220_i288:b"
				( attribute "PN" "2"
					( Origin gPackager )
				)
				( objectStatus "C5M5.2" )
			)
			( pin "@baseboard_fab2_lib.baseboard_fab2(sch_1):page220_i287:a"
				( attribute "PN" "1"
					( Origin gPackager )
				)
				( objectStatus "C5M6.1" )
			)
			( pin "@baseboard_fab2_lib.baseboard_fab2(sch_1):page220_i287:b"
				( attribute "PN" "2"
					( Origin gPackager )
				)
				( objectStatus "C5M6.2" )
			)
			( pin "@baseboard_fab2_lib.baseboard_fab2(sch_1):page220_i286:a"
				( attribute "PN" "1"
					( Origin gPackager )
				)
				( objectStatus "C5M7.1" )
			)
			( pin "@baseboard_fab2_lib.baseboard_fab2(sch_1):page220_i286:b"
				( attribute "PN" "2"
					( Origin gPackager )
				)
				( objectStatus "C5M7.2" )
			)
			( pin "@baseboard_fab2_lib.baseboard_fab2(sch_1):page220_i285:a"
				( attribute "PN" "1"
					( Origin gPackager )
				)
				( objectStatus "C5L13.1" )
			)
			( pin "@baseboard_fab2_lib.baseboard_fab2(sch_1):page220_i285:b"
				( attribute "PN" "2"
					( Origin gPackager )
				)
				( objectStatus "C5L13.2" )
			)
			( pin "@baseboard_fab2_lib.baseboard_fab2(sch_1):page220_i284:a"
				( attribute "PN" "1"
					( Origin gPackager )
				)
				( objectStatus "C5L12.1" )
			)
			( pin "@baseboard_fab2_lib.baseboard_fab2(sch_1):page220_i284:b"
				( attribute "PN" "2"
					( Origin gPackager )
				)
				( objectStatus "C5L12.2" )
			)
			( pin "@baseboard_fab2_lib.baseboard_fab2(sch_1):page220_i283:a"
				( attribute "PN" "1"
					( Origin gPackager )
				)
				( objectStatus "C5L11.1" )
			)
			( pin "@baseboard_fab2_lib.baseboard_fab2(sch_1):page220_i283:b"
				( attribute "PN" "2"
					( Origin gPackager )
				)
				( objectStatus "C5L11.2" )
			)
			( pin "@baseboard_fab2_lib.baseboard_fab2(sch_1):page220_i282:a"
				( attribute "PN" "1"
					( Origin gPackager )
				)
				( objectStatus "C5L10.1" )
			)
			( pin "@baseboard_fab2_lib.baseboard_fab2(sch_1):page220_i282:b"
				( attribute "PN" "2"
					( Origin gPackager )
				)
				( objectStatus "C5L10.2" )
			)
			( pin "@baseboard_fab2_lib.baseboard_fab2(sch_1):page220_i281:a"
				( attribute "PN" "1"
					( Origin gPackager )
				)
				( objectStatus "C5L9.1" )
			)
			( pin "@baseboard_fab2_lib.baseboard_fab2(sch_1):page220_i281:b"
				( attribute "PN" "2"
					( Origin gPackager )
				)
				( objectStatus "C5L9.2" )
			)
			( pin "@baseboard_fab2_lib.baseboard_fab2(sch_1):page220_i280:a"
				( attribute "PN" "1"
					( Origin gPackager )
				)
				( objectStatus "C5L8.1" )
			)
			( pin "@baseboard_fab2_lib.baseboard_fab2(sch_1):page220_i280:b"
				( attribute "PN" "2"
					( Origin gPackager )
				)
				( objectStatus "C5L8.2" )
			)
			( pin "@baseboard_fab2_lib.baseboard_fab2(sch_1):page220_i279:a"
				( attribute "PN" "1"
					( Origin gPackager )
				)
				( objectStatus "C5L7.1" )
			)
			( pin "@baseboard_fab2_lib.baseboard_fab2(sch_1):page220_i279:b"
				( attribute "PN" "2"
					( Origin gPackager )
				)
				( objectStatus "C5L7.2" )
			)
			( pin "@baseboard_fab2_lib.baseboard_fab2(sch_1):page220_i278:a"
				( attribute "PN" "1"
					( Origin gPackager )
				)
				( objectStatus "C5L6.1" )
			)
			( pin "@baseboard_fab2_lib.baseboard_fab2(sch_1):page220_i278:b"
				( attribute "PN" "2"
					( Origin gPackager )
				)
				( objectStatus "C5L6.2" )
			)
			( pin "@baseboard_fab2_lib.baseboard_fab2(sch_1):page225_i287:a"
				( attribute "PN" "1"
					( Origin gPackager )
				)
				( objectStatus "C2G14.1" )
			)
			( pin "@baseboard_fab2_lib.baseboard_fab2(sch_1):page225_i287:b"
				( attribute "PN" "2"
					( Origin gPackager )
				)
				( objectStatus "C2G14.2" )
			)
			( pin "@baseboard_fab2_lib.baseboard_fab2(sch_1):page225_i286:a"
				( attribute "PN" "1"
					( Origin gPackager )
				)
				( objectStatus "C2G13.1" )
			)
			( pin "@baseboard_fab2_lib.baseboard_fab2(sch_1):page225_i286:b"
				( attribute "PN" "2"
					( Origin gPackager )
				)
				( objectStatus "C2G13.2" )
			)
			( pin "@baseboard_fab2_lib.baseboard_fab2(sch_1):page225_i285:a"
				( attribute "PN" "1"
					( Origin gPackager )
				)
				( objectStatus "C3G2.1" )
			)
			( pin "@baseboard_fab2_lib.baseboard_fab2(sch_1):page225_i285:b"
				( attribute "PN" "2"
					( Origin gPackager )
				)
				( objectStatus "C3G2.2" )
			)
			( pin "@baseboard_fab2_lib.baseboard_fab2(sch_1):page225_i284:a"
				( attribute "PN" "1"
					( Origin gPackager )
				)
				( objectStatus "C3G1.1" )
			)
			( pin "@baseboard_fab2_lib.baseboard_fab2(sch_1):page225_i284:b"
				( attribute "PN" "2"
					( Origin gPackager )
				)
				( objectStatus "C3G1.2" )
			)
			( pin "@baseboard_fab2_lib.baseboard_fab2(sch_1):page225_i283:a"
				( attribute "PN" "1"
					( Origin gPackager )
				)
				( objectStatus "C2G6.1" )
			)
			( pin "@baseboard_fab2_lib.baseboard_fab2(sch_1):page225_i283:b"
				( attribute "PN" "2"
					( Origin gPackager )
				)
				( objectStatus "C2G6.2" )
			)
			( pin "@baseboard_fab2_lib.baseboard_fab2(sch_1):page225_i282:a"
				( attribute "PN" "1"
					( Origin gPackager )
				)
				( objectStatus "C2G5.1" )
			)
			( pin "@baseboard_fab2_lib.baseboard_fab2(sch_1):page225_i282:b"
				( attribute "PN" "2"
					( Origin gPackager )
				)
				( objectStatus "C2G5.2" )
			)
			( pin "@baseboard_fab2_lib.baseboard_fab2(sch_1):page225_i281:a"
				( attribute "PN" "1"
					( Origin gPackager )
				)
				( objectStatus "C2G4.1" )
			)
			( pin "@baseboard_fab2_lib.baseboard_fab2(sch_1):page225_i281:b"
				( attribute "PN" "2"
					( Origin gPackager )
				)
				( objectStatus "C2G4.2" )
			)
			( pin "@baseboard_fab2_lib.baseboard_fab2(sch_1):page225_i280:a"
				( attribute "PN" "1"
					( Origin gPackager )
				)
				( objectStatus "C2G3.1" )
			)
			( pin "@baseboard_fab2_lib.baseboard_fab2(sch_1):page225_i280:b"
				( attribute "PN" "2"
					( Origin gPackager )
				)
				( objectStatus "C2G3.2" )
			)
			( pin "@baseboard_fab2_lib.baseboard_fab2(sch_1):page225_i279:a"
				( attribute "PN" "1"
					( Origin gPackager )
				)
				( objectStatus "C2G2.1" )
			)
			( pin "@baseboard_fab2_lib.baseboard_fab2(sch_1):page225_i279:b"
				( attribute "PN" "2"
					( Origin gPackager )
				)
				( objectStatus "C2G2.2" )
			)
			( pin "@baseboard_fab2_lib.baseboard_fab2(sch_1):page225_i278:a"
				( attribute "PN" "1"
					( Origin gPackager )
				)
				( objectStatus "C2G9.1" )
			)
			( pin "@baseboard_fab2_lib.baseboard_fab2(sch_1):page225_i278:b"
				( attribute "PN" "2"
					( Origin gPackager )
				)
				( objectStatus "C2G9.2" )
			)
			( pin "@baseboard_fab2_lib.baseboard_fab2(sch_1):page225_i277:a"
				( attribute "PN" "1"
					( Origin gPackager )
				)
				( objectStatus "C2G1.1" )
			)
			( pin "@baseboard_fab2_lib.baseboard_fab2(sch_1):page225_i277:b"
				( attribute "PN" "2"
					( Origin gPackager )
				)
				( objectStatus "C2G1.2" )
			)
			( pin "@baseboard_fab2_lib.baseboard_fab2(sch_1):page225_i276:a"
				( attribute "PN" "1"
					( Origin gPackager )
				)
				( objectStatus "C2G12.1" )
			)
			( pin "@baseboard_fab2_lib.baseboard_fab2(sch_1):page225_i276:b"
				( attribute "PN" "2"
					( Origin gPackager )
				)
				( objectStatus "C2G12.2" )
			)
			( pin "@baseboard_fab2_lib.baseboard_fab2(sch_1):page225_i273:a"
				( attribute "PN" "1"
					( Origin gPackager )
				)
				( objectStatus "C2D42.1" )
			)
			( pin "@baseboard_fab2_lib.baseboard_fab2(sch_1):page225_i273:b"
				( attribute "PN" "2"
					( Origin gPackager )
				)
				( objectStatus "C2D42.2" )
			)
			( pin "@baseboard_fab2_lib.baseboard_fab2(sch_1):page225_i272:a"
				( attribute "PN" "1"
					( Origin gPackager )
				)
				( objectStatus "C2D44.1" )
			)
			( pin "@baseboard_fab2_lib.baseboard_fab2(sch_1):page225_i272:b"
				( attribute "PN" "2"
					( Origin gPackager )
				)
				( objectStatus "C2D44.2" )
			)
			( pin "@baseboard_fab2_lib.baseboard_fab2(sch_1):page225_i271:a"
				( attribute "PN" "1"
					( Origin gPackager )
				)
				( objectStatus "C2D41.1" )
			)
			( pin "@baseboard_fab2_lib.baseboard_fab2(sch_1):page225_i271:b"
				( attribute "PN" "2"
					( Origin gPackager )
				)
				( objectStatus "C2D41.2" )
			)
			( pin "@baseboard_fab2_lib.baseboard_fab2(sch_1):page225_i270:a"
				( attribute "PN" "1"
					( Origin gPackager )
				)
				( objectStatus "C2D43.1" )
			)
			( pin "@baseboard_fab2_lib.baseboard_fab2(sch_1):page225_i270:b"
				( attribute "PN" "2"
					( Origin gPackager )
				)
				( objectStatus "C2D43.2" )
			)
			( pin "@baseboard_fab2_lib.baseboard_fab2(sch_1):page220_i239:a"
				( attribute "PN" "1"
					( Origin gPackager )
				)
				( objectStatus "SH4L2.1" )
			)
			( pin "@baseboard_fab2_lib.baseboard_fab2(sch_1):page220_i239:b"
				( attribute "PN" "2"
					( Origin gPackager )
				)
				( objectStatus "SH4L2.2" )
			)
			( pin "@baseboard_fab2_lib.baseboard_fab2(sch_1):page220_i240:a"
				( attribute "PN" "1"
					( Origin gPackager )
				)
				( objectStatus "SH4L1.1" )
			)
			( pin "@baseboard_fab2_lib.baseboard_fab2(sch_1):page220_i240:b"
				( attribute "PN" "2"
					( Origin gPackager )
				)
				( objectStatus "SH4L1.2" )
			)
			( pin "@baseboard_fab2_lib.baseboard_fab2(sch_1):page218_i57:a"
				( attribute "PN" "1"
					( Origin gPackager )
				)
				( objectStatus "R7B4.1" )
			)
			( pin "@baseboard_fab2_lib.baseboard_fab2(sch_1):page218_i57:b"
				( attribute "PN" "2"
					( Origin gPackager )
				)
				( objectStatus "R7B4.2" )
			)
			( pin "@baseboard_fab2_lib.baseboard_fab2(sch_1):page221_i15:agnd"
				( attribute "PN" "3"
					( Origin gPackager )
				)
				( objectStatus "EU4G3.3" )
			)
			( pin "@baseboard_fab2_lib.baseboard_fab2(sch_1):page221_i15:bias"
				( attribute "PN" "2"
					( Origin gPackager )
				)
				( objectStatus "EU4G3.2" )
			)
			( pin "@baseboard_fab2_lib.baseboard_fab2(sch_1):page221_i15:en"
				( attribute "PN" "7"
					( Origin gPackager )
				)
				( objectStatus "EU4G3.7" )
			)
			( pin "@baseboard_fab2_lib.baseboard_fab2(sch_1):page221_i15:pg"
				( attribute "PN" "5"
					( Origin gPackager )
				)
				( objectStatus "EU4G3.5" )
			)
			( pin "@baseboard_fab2_lib.baseboard_fab2(sch_1):page221_i15:pgnd"
				( attribute "PN" "8"
					( Origin gPackager )
				)
				( objectStatus "EU4G3.8" )
			)
			( pin "@baseboard_fab2_lib.baseboard_fab2(sch_1):page221_i15:sns"
				( attribute "PN" "6"
					( Origin gPackager )
				)
				( objectStatus "EU4G3.6" )
			)
			( pin "@baseboard_fab2_lib.baseboard_fab2(sch_1):page221_i15:thpad"
				( attribute "PN" "11"
					( Origin gPackager )
				)
				( objectStatus "EU4G3.11" )
			)
			( pin "@baseboard_fab2_lib.baseboard_fab2(sch_1):page221_i15:vddq"
				( attribute "PN" "4"
					( Origin gPackager )
				)
				( objectStatus "EU4G3.4" )
			)
			( pin "@baseboard_fab2_lib.baseboard_fab2(sch_1):page221_i15:vin"
				( attribute "PN" "10"
					( Origin gPackager )
				)
				( objectStatus "EU4G3.10" )
			)
			( pin "@baseboard_fab2_lib.baseboard_fab2(sch_1):page221_i15:vref"
				( attribute "PN" "1"
					( Origin gPackager )
				)
				( objectStatus "EU4G3.1" )
			)
			( pin "@baseboard_fab2_lib.baseboard_fab2(sch_1):page221_i15:vtt"
				( attribute "PN" "9"
					( Origin gPackager )
				)
				( objectStatus "EU4G3.9" )
			)
			( pin "@baseboard_fab2_lib.baseboard_fab2(sch_1):page218_i56:a"
				( attribute "PN" "1"
					( Origin gPackager )
				)
				( objectStatus "R7A11.1" )
			)
			( pin "@baseboard_fab2_lib.baseboard_fab2(sch_1):page218_i56:b"
				( attribute "PN" "2"
					( Origin gPackager )
				)
				( objectStatus "R7A11.2" )
			)
			( pin "@baseboard_fab2_lib.baseboard_fab2(sch_1):page221_i22:a"
				( attribute "PN" "1"
					( Origin gPackager )
				)
				( objectStatus "C4G16.1" )
			)
			( pin "@baseboard_fab2_lib.baseboard_fab2(sch_1):page221_i22:b"
				( attribute "PN" "2"
					( Origin gPackager )
				)
				( objectStatus "C4G16.2" )
			)
			( pin "@baseboard_fab2_lib.baseboard_fab2(sch_1):page221_i24:a"
				( attribute "PN" "1"
					( Origin gPackager )
				)
				( objectStatus "C4G24.1" )
			)
			( pin "@baseboard_fab2_lib.baseboard_fab2(sch_1):page221_i24:b"
				( attribute "PN" "2"
					( Origin gPackager )
				)
				( objectStatus "C4G24.2" )
			)
			( pin "@baseboard_fab2_lib.baseboard_fab2(sch_1):page218_i55:a"
				( attribute "PN" "1"
					( Origin gPackager )
				)
				( objectStatus "R12W30.1" )
			)
			( pin "@baseboard_fab2_lib.baseboard_fab2(sch_1):page218_i55:b"
				( attribute "PN" "2"
					( Origin gPackager )
				)
				( objectStatus "R12W30.2" )
			)
			( pin "@baseboard_fab2_lib.baseboard_fab2(sch_1):page218_i46:a"
				( attribute "PN" "1"
					( Origin gPackager )
				)
				( objectStatus "R12W29.1" )
			)
			( pin "@baseboard_fab2_lib.baseboard_fab2(sch_1):page218_i46:b"
				( attribute "PN" "2"
					( Origin gPackager )
				)
				( objectStatus "R12W29.2" )
			)
			( pin "@baseboard_fab2_lib.baseboard_fab2(sch_1):page218_i45:a"
				( attribute "PN" "1"
					( Origin gPackager )
				)
				( objectStatus "R7A12.1" )
			)
			( pin "@baseboard_fab2_lib.baseboard_fab2(sch_1):page218_i45:b"
				( attribute "PN" "2"
					( Origin gPackager )
				)
				( objectStatus "R7A12.2" )
			)
			( pin "@baseboard_fab2_lib.baseboard_fab2(sch_1):page225_i309:a"
				( attribute "PN" "1"
					( Origin gPackager )
				)
				( objectStatus "C7T1.1" )
			)
			( pin "@baseboard_fab2_lib.baseboard_fab2(sch_1):page225_i309:b"
				( attribute "PN" "2"
					( Origin gPackager )
				)
				( objectStatus "C7T1.2" )
			)
			( pin "@baseboard_fab2_lib.baseboard_fab2(sch_1):page218_i41:a"
				( attribute "PN" "1"
					( Origin gPackager )
				)
				( objectStatus "C7B3.1" )
			)
			( pin "@baseboard_fab2_lib.baseboard_fab2(sch_1):page218_i41:b"
				( attribute "PN" "2"
					( Origin gPackager )
				)
				( objectStatus "C7B3.2" )
			)
			( pin "@baseboard_fab2_lib.baseboard_fab2(sch_1):page218_i38:a"
				( attribute "PN" "1"
					( Origin gPackager )
				)
				( objectStatus "C7A38.1" )
			)
			( pin "@baseboard_fab2_lib.baseboard_fab2(sch_1):page218_i38:b"
				( attribute "PN" "2"
					( Origin gPackager )
				)
				( objectStatus "C7A38.2" )
			)
			( pin "@baseboard_fab2_lib.baseboard_fab2(sch_1):page223_i74:a"
				( attribute "PN" "1"
					( Origin gPackager )
				)
				( objectStatus "R1G22.1" )
			)
			( pin "@baseboard_fab2_lib.baseboard_fab2(sch_1):page223_i74:b"
				( attribute "PN" "2"
					( Origin gPackager )
				)
				( objectStatus "R1G22.2" )
			)
			( pin "@baseboard_fab2_lib.baseboard_fab2(sch_1):page218_i30:a"
				( attribute "PN" "1"
					( Origin gPackager )
				)
				( objectStatus "C7B1.1" )
			)
			( pin "@baseboard_fab2_lib.baseboard_fab2(sch_1):page218_i30:b"
				( attribute "PN" "2"
					( Origin gPackager )
				)
				( objectStatus "C7B1.2" )
			)
			( pin "@baseboard_fab2_lib.baseboard_fab2(sch_1):page218_i28:a"
				( attribute "PN" "1"
					( Origin gPackager )
				)
				( objectStatus "C7B2.1" )
			)
			( pin "@baseboard_fab2_lib.baseboard_fab2(sch_1):page218_i28:b"
				( attribute "PN" "2"
					( Origin gPackager )
				)
				( objectStatus "C7B2.2" )
			)
			( pin "@baseboard_fab2_lib.baseboard_fab2(sch_1):page218_i20:\1\"
				( attribute "PN" "1"
					( Origin gPackager )
				)
				( objectStatus "CF18.1" )
			)
			( pin "@baseboard_fab2_lib.baseboard_fab2(sch_1):page218_i20:\2\"
				( attribute "PN" "2"
					( Origin gPackager )
				)
				( objectStatus "CF18.2" )
			)
			( pin "@baseboard_fab2_lib.baseboard_fab2(sch_1):page218_i19:a"
				( attribute "PN" "1"
					( Origin gPackager )
				)
				( objectStatus "RF18.1" )
			)
			( pin "@baseboard_fab2_lib.baseboard_fab2(sch_1):page218_i19:b"
				( attribute "PN" "2"
					( Origin gPackager )
				)
				( objectStatus "RF18.2" )
			)
			( pin "@baseboard_fab2_lib.baseboard_fab2(sch_1):page218_i18:a"
				( attribute "PN" "1"
					( Origin gPackager )
				)
				( objectStatus "RF17.1" )
			)
			( pin "@baseboard_fab2_lib.baseboard_fab2(sch_1):page218_i18:b"
				( attribute "PN" "2"
					( Origin gPackager )
				)
				( objectStatus "RF17.2" )
			)
			( pin "@baseboard_fab2_lib.baseboard_fab2(sch_1):page218_i13:a"
				( attribute "PN" "1"
					( Origin gPackager )
				)
				( objectStatus "R7A7.1" )
			)
			( pin "@baseboard_fab2_lib.baseboard_fab2(sch_1):page218_i13:b"
				( attribute "PN" "2"
					( Origin gPackager )
				)
				( objectStatus "R7A7.2" )
			)
			( pin "@baseboard_fab2_lib.baseboard_fab2(sch_1):page222_i12:a"
				( attribute "PN" "1"
					( Origin gPackager )
				)
				( objectStatus "C4A10.1" )
			)
			( pin "@baseboard_fab2_lib.baseboard_fab2(sch_1):page222_i12:b"
				( attribute "PN" "2"
					( Origin gPackager )
				)
				( objectStatus "C4A10.2" )
			)
			( pin "@baseboard_fab2_lib.baseboard_fab2(sch_1):page223_i48:a"
				( attribute "PN" "1"
					( Origin gPackager )
				)
				( objectStatus "R1G16.1" )
			)
			( pin "@baseboard_fab2_lib.baseboard_fab2(sch_1):page223_i48:b"
				( attribute "PN" "2"
					( Origin gPackager )
				)
				( objectStatus "R1G16.2" )
			)
			( pin "@baseboard_fab2_lib.baseboard_fab2(sch_1):page226_i74:a"
				( attribute "PN" "1"
					( Origin gPackager )
				)
				( objectStatus "R12W34.1" )
			)
			( pin "@baseboard_fab2_lib.baseboard_fab2(sch_1):page226_i74:b"
				( attribute "PN" "2"
					( Origin gPackager )
				)
				( objectStatus "R12W34.2" )
			)
			( pin "@baseboard_fab2_lib.baseboard_fab2(sch_1):page223_i45:a"
				( attribute "PN" "1"
					( Origin gPackager )
				)
				( objectStatus "R12W32.1" )
			)
			( pin "@baseboard_fab2_lib.baseboard_fab2(sch_1):page223_i45:b"
				( attribute "PN" "2"
					( Origin gPackager )
				)
				( objectStatus "R12W32.2" )
			)
			( pin "@baseboard_fab2_lib.baseboard_fab2(sch_1):page229_i43:a"
				( attribute "PN" "1"
					( Origin gPackager )
				)
				( objectStatus "C6W12.1" )
			)
			( pin "@baseboard_fab2_lib.baseboard_fab2(sch_1):page229_i43:b"
				( attribute "PN" "2"
					( Origin gPackager )
				)
				( objectStatus "C6W12.2" )
			)
			( pin "@baseboard_fab2_lib.baseboard_fab2(sch_1):page222_i28:a"
				( attribute "PN" "1"
					( Origin gPackager )
				)
				( objectStatus "C4A1.1" )
			)
			( pin "@baseboard_fab2_lib.baseboard_fab2(sch_1):page222_i28:b"
				( attribute "PN" "2"
					( Origin gPackager )
				)
				( objectStatus "C4A1.2" )
			)
			( pin "@baseboard_fab2_lib.baseboard_fab2(sch_1):page222_i30:a"
				( attribute "PN" "1"
					( Origin gPackager )
				)
				( objectStatus "SH5L1.1" )
			)
			( pin "@baseboard_fab2_lib.baseboard_fab2(sch_1):page222_i30:b"
				( attribute "PN" "2"
					( Origin gPackager )
				)
				( objectStatus "SH5L1.2" )
			)
			( pin "@baseboard_fab2_lib.baseboard_fab2(sch_1):page222_i31:a"
				( attribute "PN" "1"
					( Origin gPackager )
				)
				( objectStatus "R4A6.1" )
			)
			( pin "@baseboard_fab2_lib.baseboard_fab2(sch_1):page222_i31:b"
				( attribute "PN" "2"
					( Origin gPackager )
				)
				( objectStatus "R4A6.2" )
			)
			( pin "@baseboard_fab2_lib.baseboard_fab2(sch_1):page223_i43:a"
				( attribute "PN" "1"
					( Origin gPackager )
				)
				( objectStatus "C1G22.1" )
			)
			( pin "@baseboard_fab2_lib.baseboard_fab2(sch_1):page223_i43:b"
				( attribute "PN" "2"
					( Origin gPackager )
				)
				( objectStatus "C1G22.2" )
			)
			( pin "@baseboard_fab2_lib.baseboard_fab2(sch_1):page223_i40:a"
				( attribute "PN" "1"
					( Origin gPackager )
				)
				( objectStatus "C1G21.1" )
			)
			( pin "@baseboard_fab2_lib.baseboard_fab2(sch_1):page223_i40:b"
				( attribute "PN" "2"
					( Origin gPackager )
				)
				( objectStatus "C1G21.2" )
			)
			( pin "@baseboard_fab2_lib.baseboard_fab2(sch_1):page223_i35:a"
				( attribute "PN" "1"
					( Origin gPackager )
				)
				( objectStatus "C1G25.1" )
			)
			( pin "@baseboard_fab2_lib.baseboard_fab2(sch_1):page223_i35:b"
				( attribute "PN" "2"
					( Origin gPackager )
				)
				( objectStatus "C1G25.2" )
			)
			( pin "@baseboard_fab2_lib.baseboard_fab2(sch_1):page223_i31:a"
				( attribute "PN" "1"
					( Origin gPackager )
				)
				( objectStatus "R9U8.1" )
			)
			( pin "@baseboard_fab2_lib.baseboard_fab2(sch_1):page223_i31:b"
				( attribute "PN" "2"
					( Origin gPackager )
				)
				( objectStatus "R9U8.2" )
			)
			( pin "@baseboard_fab2_lib.baseboard_fab2(sch_1):page223_i19:a"
				( attribute "PN" "1"
					( Origin gPackager )
				)
				( objectStatus "RF20.1" )
			)
			( pin "@baseboard_fab2_lib.baseboard_fab2(sch_1):page223_i19:b"
				( attribute "PN" "2"
					( Origin gPackager )
				)
				( objectStatus "RF20.2" )
			)
			( pin "@baseboard_fab2_lib.baseboard_fab2(sch_1):page223_i18:a"
				( attribute "PN" "1"
					( Origin gPackager )
				)
				( objectStatus "R1G7.1" )
			)
			( pin "@baseboard_fab2_lib.baseboard_fab2(sch_1):page223_i18:b"
				( attribute "PN" "2"
					( Origin gPackager )
				)
				( objectStatus "R1G7.2" )
			)
			( pin "@baseboard_fab2_lib.baseboard_fab2(sch_1):page223_i15:\1\"
				( attribute "PN" "1"
					( Origin gPackager )
				)
				( objectStatus "CF19.1" )
			)
			( pin "@baseboard_fab2_lib.baseboard_fab2(sch_1):page223_i15:\2\"
				( attribute "PN" "2"
					( Origin gPackager )
				)
				( objectStatus "CF19.2" )
			)
			( pin "@baseboard_fab2_lib.baseboard_fab2(sch_1):page223_i12:a"
				( attribute "PN" "1"
					( Origin gPackager )
				)
				( objectStatus "C1G16.1" )
			)
			( pin "@baseboard_fab2_lib.baseboard_fab2(sch_1):page223_i12:b"
				( attribute "PN" "2"
					( Origin gPackager )
				)
				( objectStatus "C1G16.2" )
			)
			( pin "@baseboard_fab2_lib.baseboard_fab2(sch_1):page268_i38:a(0)"
				( attribute "CDS_SEC" "4"
					( Origin gPackager )
				)
				( attribute "PN" "12"
					( Origin gPackager )
				)
				( attribute "SEC" "4"
					( Origin gPackager )
				)
				( objectStatus "U25W16.12" )
			)
			( pin "@baseboard_fab2_lib.baseboard_fab2(sch_1):page268_i38:a(1)"
				( attribute "CDS_SEC" "3"
					( Origin gPackager )
				)
				( attribute "PN" "9"
					( Origin gPackager )
				)
				( attribute "SEC" "3"
					( Origin gPackager )
				)
				( objectStatus "U25W16.9" )
			)
			( pin "@baseboard_fab2_lib.baseboard_fab2(sch_1):page268_i38:a(2)"
				( attribute "CDS_SEC" "2"
					( Origin gPackager )
				)
				( attribute "PN" "5"
					( Origin gPackager )
				)
				( attribute "SEC" "2"
					( Origin gPackager )
				)
				( objectStatus "U25W16.5" )
			)
			( pin "@baseboard_fab2_lib.baseboard_fab2(sch_1):page268_i38:a(3)"
				( attribute "CDS_SEC" "1"
					( Origin gPackager )
				)
				( attribute "PN" "2"
					( Origin gPackager )
				)
				( attribute "SEC" "1"
					( Origin gPackager )
				)
				( objectStatus "U25W16.2" )
			)
			( pin "@baseboard_fab2_lib.baseboard_fab2(sch_1):page268_i38:b(0)"
				( attribute "CDS_SEC" "4"
					( Origin gPackager )
				)
				( attribute "PN" "11"
					( Origin gPackager )
				)
				( attribute "SEC" "4"
					( Origin gPackager )
				)
				( objectStatus "U25W16.11" )
			)
			( pin "@baseboard_fab2_lib.baseboard_fab2(sch_1):page268_i38:b(1)"
				( attribute "CDS_SEC" "3"
					( Origin gPackager )
				)
				( attribute "PN" "8"
					( Origin gPackager )
				)
				( attribute "SEC" "3"
					( Origin gPackager )
				)
				( objectStatus "U25W16.8" )
			)
			( pin "@baseboard_fab2_lib.baseboard_fab2(sch_1):page268_i38:b(2)"
				( attribute "CDS_SEC" "2"
					( Origin gPackager )
				)
				( attribute "PN" "6"
					( Origin gPackager )
				)
				( attribute "SEC" "2"
					( Origin gPackager )
				)
				( objectStatus "U25W16.6" )
			)
			( pin "@baseboard_fab2_lib.baseboard_fab2(sch_1):page268_i38:b(3)"
				( attribute "CDS_SEC" "1"
					( Origin gPackager )
				)
				( attribute "PN" "3"
					( Origin gPackager )
				)
				( attribute "SEC" "1"
					( Origin gPackager )
				)
				( objectStatus "U25W16.3" )
			)
			( pin "@baseboard_fab2_lib.baseboard_fab2(sch_1):page268_i38:oe(0)"
				( attribute "CDS_SEC" "4"
					( Origin gPackager )
				)
				( attribute "PN" "13"
					( Origin gPackager )
				)
				( attribute "SEC" "4"
					( Origin gPackager )
				)
				( objectStatus "U25W16.13" )
			)
			( pin "@baseboard_fab2_lib.baseboard_fab2(sch_1):page268_i38:oe(1)"
				( attribute "CDS_SEC" "3"
					( Origin gPackager )
				)
				( attribute "PN" "10"
					( Origin gPackager )
				)
				( attribute "SEC" "3"
					( Origin gPackager )
				)
				( objectStatus "U25W16.10" )
			)
			( pin "@baseboard_fab2_lib.baseboard_fab2(sch_1):page268_i38:oe(2)"
				( attribute "CDS_SEC" "2"
					( Origin gPackager )
				)
				( attribute "PN" "4"
					( Origin gPackager )
				)
				( attribute "SEC" "2"
					( Origin gPackager )
				)
				( objectStatus "U25W16.4" )
			)
			( pin "@baseboard_fab2_lib.baseboard_fab2(sch_1):page268_i38:oe(3)"
				( attribute "CDS_SEC" "1"
					( Origin gPackager )
				)
				( attribute "PN" "1"
					( Origin gPackager )
				)
				( attribute "SEC" "1"
					( Origin gPackager )
				)
				( objectStatus "U25W16.1" )
			)
			( pin "@baseboard_fab2_lib.baseboard_fab2(sch_1):page223_i13:a"
				( attribute "PN" "1"
					( Origin gPackager )
				)
				( objectStatus "R1G5.1" )
			)
			( pin "@baseboard_fab2_lib.baseboard_fab2(sch_1):page223_i13:b"
				( attribute "PN" "2"
					( Origin gPackager )
				)
				( objectStatus "R1G5.2" )
			)
			( pin "@baseboard_fab2_lib.baseboard_fab2(sch_1):page223_i14:a"
				( attribute "PN" "1"
					( Origin gPackager )
				)
				( objectStatus "R9U7.1" )
			)
			( pin "@baseboard_fab2_lib.baseboard_fab2(sch_1):page223_i14:b"
				( attribute "PN" "2"
					( Origin gPackager )
				)
				( objectStatus "R9U7.2" )
			)
			( pin "@baseboard_fab2_lib.baseboard_fab2(sch_1):page223_i16:a"
				( attribute "PN" "1"
					( Origin gPackager )
				)
				( objectStatus "RF19.1" )
			)
			( pin "@baseboard_fab2_lib.baseboard_fab2(sch_1):page223_i16:b"
				( attribute "PN" "2"
					( Origin gPackager )
				)
				( objectStatus "RF19.2" )
			)
			( pin "@baseboard_fab2_lib.baseboard_fab2(sch_1):page223_i17:\1\"
				( attribute "PN" "1"
					( Origin gPackager )
				)
				( objectStatus "CF20.1" )
			)
			( pin "@baseboard_fab2_lib.baseboard_fab2(sch_1):page223_i17:\2\"
				( attribute "PN" "2"
					( Origin gPackager )
				)
				( objectStatus "CF20.2" )
			)
			( pin "@baseboard_fab2_lib.baseboard_fab2(sch_1):page226_i55:a"
				( attribute "PN" "1"
					( Origin gPackager )
				)
				( objectStatus "R1B5.1" )
			)
			( pin "@baseboard_fab2_lib.baseboard_fab2(sch_1):page226_i55:b"
				( attribute "PN" "2"
					( Origin gPackager )
				)
				( objectStatus "R1B5.2" )
			)
			( pin "@baseboard_fab2_lib.baseboard_fab2(sch_1):page226_i54:a"
				( attribute "PN" "1"
					( Origin gPackager )
				)
				( objectStatus "R1B4.1" )
			)
			( pin "@baseboard_fab2_lib.baseboard_fab2(sch_1):page226_i54:b"
				( attribute "PN" "2"
					( Origin gPackager )
				)
				( objectStatus "R1B4.2" )
			)
			( pin "@baseboard_fab2_lib.baseboard_fab2(sch_1):page229_i37:agnd"
				( attribute "PN" "3"
					( Origin gPackager )
				)
				( objectStatus "EU4G2.3" )
			)
			( pin "@baseboard_fab2_lib.baseboard_fab2(sch_1):page229_i37:bias"
				( attribute "PN" "2"
					( Origin gPackager )
				)
				( objectStatus "EU4G2.2" )
			)
			( pin "@baseboard_fab2_lib.baseboard_fab2(sch_1):page229_i37:en"
				( attribute "PN" "7"
					( Origin gPackager )
				)
				( objectStatus "EU4G2.7" )
			)
			( pin "@baseboard_fab2_lib.baseboard_fab2(sch_1):page229_i37:pg"
				( attribute "PN" "5"
					( Origin gPackager )
				)
				( objectStatus "EU4G2.5" )
			)
			( pin "@baseboard_fab2_lib.baseboard_fab2(sch_1):page229_i37:pgnd"
				( attribute "PN" "8"
					( Origin gPackager )
				)
				( objectStatus "EU4G2.8" )
			)
			( pin "@baseboard_fab2_lib.baseboard_fab2(sch_1):page229_i37:sns"
				( attribute "PN" "6"
					( Origin gPackager )
				)
				( objectStatus "EU4G2.6" )
			)
			( pin "@baseboard_fab2_lib.baseboard_fab2(sch_1):page229_i37:thpad"
				( attribute "PN" "11"
					( Origin gPackager )
				)
				( objectStatus "EU4G2.11" )
			)
			( pin "@baseboard_fab2_lib.baseboard_fab2(sch_1):page229_i37:vddq"
				( attribute "PN" "4"
					( Origin gPackager )
				)
				( objectStatus "EU4G2.4" )
			)
			( pin "@baseboard_fab2_lib.baseboard_fab2(sch_1):page229_i37:vin"
				( attribute "PN" "10"
					( Origin gPackager )
				)
				( objectStatus "EU4G2.10" )
			)
			( pin "@baseboard_fab2_lib.baseboard_fab2(sch_1):page229_i37:vref"
				( attribute "PN" "1"
					( Origin gPackager )
				)
				( objectStatus "EU4G2.1" )
			)
			( pin "@baseboard_fab2_lib.baseboard_fab2(sch_1):page229_i37:vtt"
				( attribute "PN" "9"
					( Origin gPackager )
				)
				( objectStatus "EU4G2.9" )
			)
			( pin "@baseboard_fab2_lib.baseboard_fab2(sch_1):page223_i27:a"
				( attribute "PN" "1"
					( Origin gPackager )
				)
				( objectStatus "C1G24.1" )
			)
			( pin "@baseboard_fab2_lib.baseboard_fab2(sch_1):page223_i27:b"
				( attribute "PN" "2"
					( Origin gPackager )
				)
				( objectStatus "C1G24.2" )
			)
			( pin "@baseboard_fab2_lib.baseboard_fab2(sch_1):page223_i32:a"
				( attribute "PN" "1"
					( Origin gPackager )
				)
				( objectStatus "R9U10.1" )
			)
			( pin "@baseboard_fab2_lib.baseboard_fab2(sch_1):page223_i32:b"
				( attribute "PN" "2"
					( Origin gPackager )
				)
				( objectStatus "R9U10.2" )
			)
			( pin "@baseboard_fab2_lib.baseboard_fab2(sch_1):page223_i36:a"
				( attribute "PN" "1"
					( Origin gPackager )
				)
				( objectStatus "C1G27.1" )
			)
			( pin "@baseboard_fab2_lib.baseboard_fab2(sch_1):page223_i36:b"
				( attribute "PN" "2"
					( Origin gPackager )
				)
				( objectStatus "C1G27.2" )
			)
			( pin "@baseboard_fab2_lib.baseboard_fab2(sch_1):page230_i43:a"
				( attribute "PN" "1"
					( Origin gPackager )
				)
				( objectStatus "C6W13.1" )
			)
			( pin "@baseboard_fab2_lib.baseboard_fab2(sch_1):page230_i43:b"
				( attribute "PN" "2"
					( Origin gPackager )
				)
				( objectStatus "C6W13.2" )
			)
			( pin "@baseboard_fab2_lib.baseboard_fab2(sch_1):page223_i41:a"
				( attribute "PN" "1"
					( Origin gPackager )
				)
				( objectStatus "R1G10.1" )
			)
			( pin "@baseboard_fab2_lib.baseboard_fab2(sch_1):page223_i41:b"
				( attribute "PN" "2"
					( Origin gPackager )
				)
				( objectStatus "R1G10.2" )
			)
			( pin "@baseboard_fab2_lib.baseboard_fab2(sch_1):page223_i44:a"
				( attribute "PN" "1"
					( Origin gPackager )
				)
				( objectStatus "C1G23.1" )
			)
			( pin "@baseboard_fab2_lib.baseboard_fab2(sch_1):page223_i44:b"
				( attribute "PN" "2"
					( Origin gPackager )
				)
				( objectStatus "C1G23.2" )
			)
			( pin "@baseboard_fab2_lib.baseboard_fab2(sch_1):page223_i50:a"
				( attribute "PN" "1"
					( Origin gPackager )
				)
				( objectStatus "R1G9.1" )
			)
			( pin "@baseboard_fab2_lib.baseboard_fab2(sch_1):page223_i50:b"
				( attribute "PN" "2"
					( Origin gPackager )
				)
				( objectStatus "R1G9.2" )
			)
			( pin "@baseboard_fab2_lib.baseboard_fab2(sch_1):page223_i53:a"
				( attribute "PN" "1"
					( Origin gPackager )
				)
				( objectStatus "R12W33.1" )
			)
			( pin "@baseboard_fab2_lib.baseboard_fab2(sch_1):page223_i53:b"
				( attribute "PN" "2"
					( Origin gPackager )
				)
				( objectStatus "R12W33.2" )
			)
			( pin "@baseboard_fab2_lib.baseboard_fab2(sch_1):page229_i28:a"
				( attribute "PN" "1"
					( Origin gPackager )
				)
				( objectStatus "C2F2.1" )
			)
			( pin "@baseboard_fab2_lib.baseboard_fab2(sch_1):page229_i28:b"
				( attribute "PN" "2"
					( Origin gPackager )
				)
				( objectStatus "C2F2.2" )
			)
			( pin "@baseboard_fab2_lib.baseboard_fab2(sch_1):page229_i26:a"
				( attribute "PN" "1"
					( Origin gPackager )
				)
				( objectStatus "C4G13.1" )
			)
			( pin "@baseboard_fab2_lib.baseboard_fab2(sch_1):page229_i26:b"
				( attribute "PN" "2"
					( Origin gPackager )
				)
				( objectStatus "C4G13.2" )
			)
			( pin "@baseboard_fab2_lib.baseboard_fab2(sch_1):page229_i23:a"
				( attribute "PN" "1"
					( Origin gPackager )
				)
				( objectStatus "C4G20.1" )
			)
			( pin "@baseboard_fab2_lib.baseboard_fab2(sch_1):page229_i23:b"
				( attribute "PN" "2"
					( Origin gPackager )
				)
				( objectStatus "C4G20.2" )
			)
			( pin "@baseboard_fab2_lib.baseboard_fab2(sch_1):page229_i18:a"
				( attribute "PN" "1"
					( Origin gPackager )
				)
				( objectStatus "C6U14.1" )
			)
			( pin "@baseboard_fab2_lib.baseboard_fab2(sch_1):page229_i18:b"
				( attribute "PN" "2"
					( Origin gPackager )
				)
				( objectStatus "C6U14.2" )
			)
			( pin "@baseboard_fab2_lib.baseboard_fab2(sch_1):page229_i16:a"
				( attribute "PN" "1"
					( Origin gPackager )
				)
				( objectStatus "C4G18.1" )
			)
			( pin "@baseboard_fab2_lib.baseboard_fab2(sch_1):page229_i16:b"
				( attribute "PN" "2"
					( Origin gPackager )
				)
				( objectStatus "C4G18.2" )
			)
			( pin "@baseboard_fab2_lib.baseboard_fab2(sch_1):page229_i12:a"
				( attribute "PN" "1"
					( Origin gPackager )
				)
				( objectStatus "SH8U1.1" )
			)
			( pin "@baseboard_fab2_lib.baseboard_fab2(sch_1):page229_i12:b"
				( attribute "PN" "2"
					( Origin gPackager )
				)
				( objectStatus "SH8U1.2" )
			)
			( pin "@baseboard_fab2_lib.baseboard_fab2(sch_1):page229_i11:a"
				( attribute "PN" "1"
					( Origin gPackager )
				)
				( objectStatus "C6U13.1" )
			)
			( pin "@baseboard_fab2_lib.baseboard_fab2(sch_1):page229_i11:b"
				( attribute "PN" "2"
					( Origin gPackager )
				)
				( objectStatus "C6U13.2" )
			)
			( pin "@baseboard_fab2_lib.baseboard_fab2(sch_1):page191_i195:a"
				( attribute "PN" "1"
					( Origin gPackager )
				)
				( objectStatus "R4W1.1" )
			)
			( pin "@baseboard_fab2_lib.baseboard_fab2(sch_1):page191_i195:b"
				( attribute "PN" "2"
					( Origin gPackager )
				)
				( objectStatus "R4W1.2" )
			)
			( pin "@baseboard_fab2_lib.baseboard_fab2(sch_1):page229_i9:a"
				( attribute "PN" "1"
					( Origin gPackager )
				)
				( objectStatus "R6U7.1" )
			)
			( pin "@baseboard_fab2_lib.baseboard_fab2(sch_1):page229_i9:b"
				( attribute "PN" "2"
					( Origin gPackager )
				)
				( objectStatus "R6U7.2" )
			)
			( pin "@baseboard_fab2_lib.baseboard_fab2(sch_1):page213_i101:a"
				( attribute "PN" "1"
					( Origin gPackager )
				)
				( objectStatus "C4W2.1" )
			)
			( pin "@baseboard_fab2_lib.baseboard_fab2(sch_1):page213_i101:b"
				( attribute "PN" "2"
					( Origin gPackager )
				)
				( objectStatus "C4W2.2" )
			)
			( pin "@baseboard_fab2_lib.baseboard_fab2(sch_1):page224_i6:a"
				( attribute "PN" "1"
					( Origin gPackager )
				)
				( objectStatus "C1G17.1" )
			)
			( pin "@baseboard_fab2_lib.baseboard_fab2(sch_1):page224_i6:b"
				( attribute "PN" "2"
					( Origin gPackager )
				)
				( objectStatus "C1G17.2" )
			)
			( pin "@baseboard_fab2_lib.baseboard_fab2(sch_1):page224_i44:a"
				( attribute "PN" "1"
					( Origin gPackager )
				)
				( objectStatus "C1G11.1" )
			)
			( pin "@baseboard_fab2_lib.baseboard_fab2(sch_1):page224_i44:b"
				( attribute "PN" "2"
					( Origin gPackager )
				)
				( objectStatus "C1G11.2" )
			)
			( pin "@baseboard_fab2_lib.baseboard_fab2(sch_1):page224_i45:a"
				( attribute "PN" "1"
					( Origin gPackager )
				)
				( objectStatus "C9U6.1" )
			)
			( pin "@baseboard_fab2_lib.baseboard_fab2(sch_1):page224_i45:b"
				( attribute "PN" "2"
					( Origin gPackager )
				)
				( objectStatus "C9U6.2" )
			)
			( pin "@baseboard_fab2_lib.baseboard_fab2(sch_1):page224_i46:a"
				( attribute "PN" "1"
					( Origin gPackager )
				)
				( objectStatus "C9U4.1" )
			)
			( pin "@baseboard_fab2_lib.baseboard_fab2(sch_1):page224_i46:b"
				( attribute "PN" "2"
					( Origin gPackager )
				)
				( objectStatus "C9U4.2" )
			)
			( pin "@baseboard_fab2_lib.baseboard_fab2(sch_1):page224_i47:a"
				( attribute "PN" "1"
					( Origin gPackager )
				)
				( objectStatus "C9T4.1" )
			)
			( pin "@baseboard_fab2_lib.baseboard_fab2(sch_1):page224_i47:b"
				( attribute "PN" "2"
					( Origin gPackager )
				)
				( objectStatus "C9T4.2" )
			)
			( pin "@baseboard_fab2_lib.baseboard_fab2(sch_1):page224_i48:a"
				( attribute "PN" "1"
					( Origin gPackager )
				)
				( objectStatus "C1F27.1" )
			)
			( pin "@baseboard_fab2_lib.baseboard_fab2(sch_1):page224_i48:b"
				( attribute "PN" "2"
					( Origin gPackager )
				)
				( objectStatus "C1F27.2" )
			)
			( pin "@baseboard_fab2_lib.baseboard_fab2(sch_1):page224_i50:a"
				( attribute "PN" "1"
					( Origin gPackager )
				)
				( objectStatus "C1G6.1" )
			)
			( pin "@baseboard_fab2_lib.baseboard_fab2(sch_1):page224_i50:b"
				( attribute "PN" "2"
					( Origin gPackager )
				)
				( objectStatus "C1G6.2" )
			)
			( pin "@baseboard_fab2_lib.baseboard_fab2(sch_1):page224_i51:a"
				( attribute "PN" "1"
					( Origin gPackager )
				)
				( objectStatus "C1G14.1" )
			)
			( pin "@baseboard_fab2_lib.baseboard_fab2(sch_1):page224_i51:b"
				( attribute "PN" "2"
					( Origin gPackager )
				)
				( objectStatus "C1G14.2" )
			)
			( pin "@baseboard_fab2_lib.baseboard_fab2(sch_1):page236_i177:a"
				( attribute "PN" "1"
					( Origin gPackager )
				)
				( objectStatus "R3L4.1" )
			)
			( pin "@baseboard_fab2_lib.baseboard_fab2(sch_1):page236_i177:b"
				( attribute "PN" "2"
					( Origin gPackager )
				)
				( objectStatus "R3L4.2" )
			)
			( pin "@baseboard_fab2_lib.baseboard_fab2(sch_1):page236_i181:\1\"
				( attribute "PN" "1"
					( Origin gPackager )
				)
				( objectStatus "C3L29.1" )
			)
			( pin "@baseboard_fab2_lib.baseboard_fab2(sch_1):page236_i181:\2\"
				( attribute "PN" "2"
					( Origin gPackager )
				)
				( objectStatus "C3L29.2" )
			)
			( pin "@baseboard_fab2_lib.baseboard_fab2(sch_1):page224_i54:a"
				( attribute "PN" "1"
					( Origin gPackager )
				)
				( objectStatus "C1G5.1" )
			)
			( pin "@baseboard_fab2_lib.baseboard_fab2(sch_1):page224_i54:b"
				( attribute "PN" "2"
					( Origin gPackager )
				)
				( objectStatus "C1G5.2" )
			)
			( pin "@baseboard_fab2_lib.baseboard_fab2(sch_1):page227_i152:f"
				( attribute "PN" "2"
					( Origin gPackager )
				)
				( objectStatus "L1A2.2" )
			)
			( pin "@baseboard_fab2_lib.baseboard_fab2(sch_1):page227_i152:s"
				( attribute "PN" "1"
					( Origin gPackager )
				)
				( objectStatus "L1A2.1" )
			)
			( pin "@baseboard_fab2_lib.baseboard_fab2(sch_1):page224_i68:a"
				( attribute "PN" "1"
					( Origin gPackager )
				)
				( objectStatus "C1G20.1" )
			)
			( pin "@baseboard_fab2_lib.baseboard_fab2(sch_1):page224_i68:b"
				( attribute "PN" "2"
					( Origin gPackager )
				)
				( objectStatus "C1G20.2" )
			)
			( pin "@baseboard_fab2_lib.baseboard_fab2(sch_1):page224_i72:a"
				( attribute "PN" "1"
					( Origin gPackager )
				)
				( objectStatus "C1G29.1" )
			)
			( pin "@baseboard_fab2_lib.baseboard_fab2(sch_1):page224_i72:b"
				( attribute "PN" "2"
					( Origin gPackager )
				)
				( objectStatus "C1G29.2" )
			)
			( pin "@baseboard_fab2_lib.baseboard_fab2(sch_1):page236_i180:\1\"
				( attribute "PN" "1"
					( Origin gPackager )
				)
				( objectStatus "C3L1.1" )
			)
			( pin "@baseboard_fab2_lib.baseboard_fab2(sch_1):page236_i180:\2\"
				( attribute "PN" "2"
					( Origin gPackager )
				)
				( objectStatus "C3L1.2" )
			)
			( pin "@baseboard_fab2_lib.baseboard_fab2(sch_1):page224_i75:a"
				( attribute "PN" "1"
					( Origin gPackager )
				)
				( objectStatus "C1F26.1" )
			)
			( pin "@baseboard_fab2_lib.baseboard_fab2(sch_1):page224_i75:b"
				( attribute "PN" "2"
					( Origin gPackager )
				)
				( objectStatus "C1F26.2" )
			)
			( pin "@baseboard_fab2_lib.baseboard_fab2(sch_1):page236_i175:a"
				( attribute "PN" "1"
					( Origin gPackager )
				)
				( objectStatus "R3L1.1" )
			)
			( pin "@baseboard_fab2_lib.baseboard_fab2(sch_1):page236_i175:b"
				( attribute "PN" "2"
					( Origin gPackager )
				)
				( objectStatus "R3L1.2" )
			)
			( pin "@baseboard_fab2_lib.baseboard_fab2(sch_1):page224_i77:a"
				( attribute "PN" "1"
					( Origin gPackager )
				)
				( objectStatus "C1G28.1" )
			)
			( pin "@baseboard_fab2_lib.baseboard_fab2(sch_1):page224_i77:b"
				( attribute "PN" "2"
					( Origin gPackager )
				)
				( objectStatus "C1G28.2" )
			)
			( pin "@baseboard_fab2_lib.baseboard_fab2(sch_1):page224_i78:a"
				( attribute "PN" "1"
					( Origin gPackager )
				)
				( objectStatus "C1F28.1" )
			)
			( pin "@baseboard_fab2_lib.baseboard_fab2(sch_1):page224_i78:b"
				( attribute "PN" "2"
					( Origin gPackager )
				)
				( objectStatus "C1F28.2" )
			)
			( pin "@baseboard_fab2_lib.baseboard_fab2(sch_1):page224_i79:a"
				( attribute "PN" "1"
					( Origin gPackager )
				)
				( objectStatus "C1G13.1" )
			)
			( pin "@baseboard_fab2_lib.baseboard_fab2(sch_1):page224_i79:b"
				( attribute "PN" "2"
					( Origin gPackager )
				)
				( objectStatus "C1G13.2" )
			)
			( pin "@baseboard_fab2_lib.baseboard_fab2(sch_1):page224_i80:a"
				( attribute "PN" "1"
					( Origin gPackager )
				)
				( objectStatus "C9U3.1" )
			)
			( pin "@baseboard_fab2_lib.baseboard_fab2(sch_1):page224_i80:b"
				( attribute "PN" "2"
					( Origin gPackager )
				)
				( objectStatus "C9U3.2" )
			)
			( pin "@baseboard_fab2_lib.baseboard_fab2(sch_1):page224_i81:a"
				( attribute "PN" "1"
					( Origin gPackager )
				)
				( objectStatus "C9T6.1" )
			)
			( pin "@baseboard_fab2_lib.baseboard_fab2(sch_1):page224_i81:b"
				( attribute "PN" "2"
					( Origin gPackager )
				)
				( objectStatus "C9T6.2" )
			)
			( pin "@baseboard_fab2_lib.baseboard_fab2(sch_1):page224_i84:a"
				( attribute "PN" "1"
					( Origin gPackager )
				)
				( objectStatus "C9T9.1" )
			)
			( pin "@baseboard_fab2_lib.baseboard_fab2(sch_1):page224_i84:b"
				( attribute "PN" "2"
					( Origin gPackager )
				)
				( objectStatus "C9T9.2" )
			)
			( pin "@baseboard_fab2_lib.baseboard_fab2(sch_1):page224_i110:boost"
				( attribute "PN" "33"
					( Origin gPackager )
				)
				( objectStatus "EU1G1.33" )
			)
			( pin "@baseboard_fab2_lib.baseboard_fab2(sch_1):page224_i110:en"
				( attribute "PN" "35"
					( Origin gPackager )
				)
				( objectStatus "EU1G1.35" )
			)
			( pin "@baseboard_fab2_lib.baseboard_fab2(sch_1):page224_i110:gl(0)"
				( attribute "PN" "6"
					( Origin gPackager )
				)
				( objectStatus "EU1G1.6" )
			)
			( pin "@baseboard_fab2_lib.baseboard_fab2(sch_1):page224_i110:gl(1)"
				( attribute "PN" "41"
					( Origin gPackager )
				)
				( objectStatus "EU1G1.41" )
			)
			( pin "@baseboard_fab2_lib.baseboard_fab2(sch_1):page224_i110:iout"
				( attribute "PN" "38"
					( Origin gPackager )
				)
				( objectStatus "EU1G1.38" )
			)
			( pin "@baseboard_fab2_lib.baseboard_fab2(sch_1):page224_i110:lgnd"
				( attribute "PN" "2"
					( Origin gPackager )
				)
				( objectStatus "EU1G1.2" )
			)
			( pin "@baseboard_fab2_lib.baseboard_fab2(sch_1):page224_i110:nc"
				( attribute "PN" "31"
					( Origin gPackager )
				)
				( objectStatus "EU1G1.31" )
			)
			( pin "@baseboard_fab2_lib.baseboard_fab2(sch_1):page224_i110:ocset"
				( attribute "PN" "37"
					( Origin gPackager )
				)
				( objectStatus "EU1G1.37" )
			)
			( pin "@baseboard_fab2_lib.baseboard_fab2(sch_1):page224_i110:pgnd(0)"
				( attribute "PN" "5"
					( Origin gPackager )
				)
				( objectStatus "EU1G1.5" )
			)
			( pin "@baseboard_fab2_lib.baseboard_fab2(sch_1):page224_i110:pgnd(1)"
				( attribute "PN" "7"
					( Origin gPackager )
				)
				( objectStatus "EU1G1.7" )
			)
			( pin "@baseboard_fab2_lib.baseboard_fab2(sch_1):page224_i110:pgnd(2)"
				( attribute "PN" "40"
					( Origin gPackager )
				)
				( objectStatus "EU1G1.40" )
			)
			( pin "@baseboard_fab2_lib.baseboard_fab2(sch_1):page224_i110:phase"
				( attribute "PN" "32"
					( Origin gPackager )
				)
				( objectStatus "EU1G1.32" )
			)
			( pin "@baseboard_fab2_lib.baseboard_fab2(sch_1):page224_i110:pwm"
				( attribute "PN" "34"
					( Origin gPackager )
				)
				( objectStatus "EU1G1.34" )
			)
			( pin "@baseboard_fab2_lib.baseboard_fab2(sch_1):page224_i110:refin"
				( attribute "PN" "39"
					( Origin gPackager )
				)
				( objectStatus "EU1G1.39" )
			)
			( pin "@baseboard_fab2_lib.baseboard_fab2(sch_1):page224_i110:sw"
				( attribute "PN" "10"
					( Origin gPackager )
				)
				( objectStatus "EU1G1.10" )
			)
			( pin "@baseboard_fab2_lib.baseboard_fab2(sch_1):page224_i110:tout_flt"
				( attribute "PN" "36"
					( Origin gPackager )
				)
				( objectStatus "EU1G1.36" )
			)
			( pin "@baseboard_fab2_lib.baseboard_fab2(sch_1):page224_i110:vcc"
				( attribute "PN" "3"
					( Origin gPackager )
				)
				( objectStatus "EU1G1.3" )
			)
			( pin "@baseboard_fab2_lib.baseboard_fab2(sch_1):page224_i110:vdrv"
				( attribute "PN" "4"
					( Origin gPackager )
				)
				( objectStatus "EU1G1.4" )
			)
			( pin "@baseboard_fab2_lib.baseboard_fab2(sch_1):page224_i110:vin(0)"
				( attribute "PN" "25"
					( Origin gPackager )
				)
				( objectStatus "EU1G1.25" )
			)
			( pin "@baseboard_fab2_lib.baseboard_fab2(sch_1):page224_i110:vin(1)"
				( attribute "PN" "30"
					( Origin gPackager )
				)
				( objectStatus "EU1G1.30" )
			)
			( pin "@baseboard_fab2_lib.baseboard_fab2(sch_1):page224_i110:vos"
				( attribute "PN" "1"
					( Origin gPackager )
				)
				( objectStatus "EU1G1.1" )
			)
			( pin "@baseboard_fab2_lib.baseboard_fab2(sch_1):page224_i111:boost"
				( attribute "PN" "33"
					( Origin gPackager )
				)
				( objectStatus "EU1F1.33" )
			)
			( pin "@baseboard_fab2_lib.baseboard_fab2(sch_1):page224_i111:en"
				( attribute "PN" "35"
					( Origin gPackager )
				)
				( objectStatus "EU1F1.35" )
			)
			( pin "@baseboard_fab2_lib.baseboard_fab2(sch_1):page224_i111:gl(0)"
				( attribute "PN" "6"
					( Origin gPackager )
				)
				( objectStatus "EU1F1.6" )
			)
			( pin "@baseboard_fab2_lib.baseboard_fab2(sch_1):page224_i111:gl(1)"
				( attribute "PN" "41"
					( Origin gPackager )
				)
				( objectStatus "EU1F1.41" )
			)
			( pin "@baseboard_fab2_lib.baseboard_fab2(sch_1):page224_i111:iout"
				( attribute "PN" "38"
					( Origin gPackager )
				)
				( objectStatus "EU1F1.38" )
			)
			( pin "@baseboard_fab2_lib.baseboard_fab2(sch_1):page224_i111:lgnd"
				( attribute "PN" "2"
					( Origin gPackager )
				)
				( objectStatus "EU1F1.2" )
			)
			( pin "@baseboard_fab2_lib.baseboard_fab2(sch_1):page224_i111:nc"
				( attribute "PN" "31"
					( Origin gPackager )
				)
				( objectStatus "EU1F1.31" )
			)
			( pin "@baseboard_fab2_lib.baseboard_fab2(sch_1):page224_i111:ocset"
				( attribute "PN" "37"
					( Origin gPackager )
				)
				( objectStatus "EU1F1.37" )
			)
			( pin "@baseboard_fab2_lib.baseboard_fab2(sch_1):page224_i111:pgnd(0)"
				( attribute "PN" "5"
					( Origin gPackager )
				)
				( objectStatus "EU1F1.5" )
			)
			( pin "@baseboard_fab2_lib.baseboard_fab2(sch_1):page224_i111:pgnd(1)"
				( attribute "PN" "7"
					( Origin gPackager )
				)
				( objectStatus "EU1F1.7" )
			)
			( pin "@baseboard_fab2_lib.baseboard_fab2(sch_1):page224_i111:pgnd(2)"
				( attribute "PN" "40"
					( Origin gPackager )
				)
				( objectStatus "EU1F1.40" )
			)
			( pin "@baseboard_fab2_lib.baseboard_fab2(sch_1):page224_i111:phase"
				( attribute "PN" "32"
					( Origin gPackager )
				)
				( objectStatus "EU1F1.32" )
			)
			( pin "@baseboard_fab2_lib.baseboard_fab2(sch_1):page224_i111:pwm"
				( attribute "PN" "34"
					( Origin gPackager )
				)
				( objectStatus "EU1F1.34" )
			)
			( pin "@baseboard_fab2_lib.baseboard_fab2(sch_1):page224_i111:refin"
				( attribute "PN" "39"
					( Origin gPackager )
				)
				( objectStatus "EU1F1.39" )
			)
			( pin "@baseboard_fab2_lib.baseboard_fab2(sch_1):page224_i111:sw"
				( attribute "PN" "10"
					( Origin gPackager )
				)
				( objectStatus "EU1F1.10" )
			)
			( pin "@baseboard_fab2_lib.baseboard_fab2(sch_1):page224_i111:tout_flt"
				( attribute "PN" "36"
					( Origin gPackager )
				)
				( objectStatus "EU1F1.36" )
			)
			( pin "@baseboard_fab2_lib.baseboard_fab2(sch_1):page224_i111:vcc"
				( attribute "PN" "3"
					( Origin gPackager )
				)
				( objectStatus "EU1F1.3" )
			)
			( pin "@baseboard_fab2_lib.baseboard_fab2(sch_1):page224_i111:vdrv"
				( attribute "PN" "4"
					( Origin gPackager )
				)
				( objectStatus "EU1F1.4" )
			)
			( pin "@baseboard_fab2_lib.baseboard_fab2(sch_1):page224_i111:vin(0)"
				( attribute "PN" "25"
					( Origin gPackager )
				)
				( objectStatus "EU1F1.25" )
			)
			( pin "@baseboard_fab2_lib.baseboard_fab2(sch_1):page224_i111:vin(1)"
				( attribute "PN" "30"
					( Origin gPackager )
				)
				( objectStatus "EU1F1.30" )
			)
			( pin "@baseboard_fab2_lib.baseboard_fab2(sch_1):page224_i111:vos"
				( attribute "PN" "1"
					( Origin gPackager )
				)
				( objectStatus "EU1F1.1" )
			)
			( pin "@baseboard_fab2_lib.baseboard_fab2(sch_1):page224_i112:a"
				( attribute "PN" "1"
					( Origin gPackager )
				)
				( objectStatus "R1G26.1" )
			)
			( pin "@baseboard_fab2_lib.baseboard_fab2(sch_1):page224_i112:b"
				( attribute "PN" "2"
					( Origin gPackager )
				)
				( objectStatus "R1G26.2" )
			)
			( pin "@baseboard_fab2_lib.baseboard_fab2(sch_1):page224_i114:a"
				( attribute "PN" "1"
					( Origin gPackager )
				)
				( objectStatus "R1G25.1" )
			)
			( pin "@baseboard_fab2_lib.baseboard_fab2(sch_1):page224_i114:b"
				( attribute "PN" "2"
					( Origin gPackager )
				)
				( objectStatus "R1G25.2" )
			)
			( pin "@baseboard_fab2_lib.baseboard_fab2(sch_1):page225_i58:a"
				( attribute "PN" "1"
					( Origin gPackager )
				)
				( objectStatus "R1G20.1" )
			)
			( pin "@baseboard_fab2_lib.baseboard_fab2(sch_1):page225_i58:b"
				( attribute "PN" "2"
					( Origin gPackager )
				)
				( objectStatus "R1G20.2" )
			)
			( pin "@baseboard_fab2_lib.baseboard_fab2(sch_1):page225_i74:a"
				( attribute "PN" "1"
					( Origin gPackager )
				)
				( objectStatus "R7U2.1" )
			)
			( pin "@baseboard_fab2_lib.baseboard_fab2(sch_1):page225_i74:b"
				( attribute "PN" "2"
					( Origin gPackager )
				)
				( objectStatus "R7U2.2" )
			)
			( pin "@baseboard_fab2_lib.baseboard_fab2(sch_1):page225_i75:a"
				( attribute "PN" "1"
					( Origin gPackager )
				)
				( objectStatus "C9T5.1" )
			)
			( pin "@baseboard_fab2_lib.baseboard_fab2(sch_1):page225_i75:b"
				( attribute "PN" "2"
					( Origin gPackager )
				)
				( objectStatus "C9T5.2" )
			)
			( pin "@baseboard_fab2_lib.baseboard_fab2(sch_1):page225_i76:a"
				( attribute "PN" "1"
					( Origin gPackager )
				)
				( objectStatus "C9U2.1" )
			)
			( pin "@baseboard_fab2_lib.baseboard_fab2(sch_1):page225_i76:b"
				( attribute "PN" "2"
					( Origin gPackager )
				)
				( objectStatus "C9U2.2" )
			)
			( pin "@baseboard_fab2_lib.baseboard_fab2(sch_1):page225_i77:a"
				( attribute "PN" "1"
					( Origin gPackager )
				)
				( objectStatus "C9U9.1" )
			)
			( pin "@baseboard_fab2_lib.baseboard_fab2(sch_1):page225_i77:b"
				( attribute "PN" "2"
					( Origin gPackager )
				)
				( objectStatus "C9U9.2" )
			)
			( pin "@baseboard_fab2_lib.baseboard_fab2(sch_1):page225_i78:a"
				( attribute "PN" "1"
					( Origin gPackager )
				)
				( objectStatus "C9U5.1" )
			)
			( pin "@baseboard_fab2_lib.baseboard_fab2(sch_1):page225_i78:b"
				( attribute "PN" "2"
					( Origin gPackager )
				)
				( objectStatus "C9U5.2" )
			)
			( pin "@baseboard_fab2_lib.baseboard_fab2(sch_1):page225_i320:a"
				( attribute "PN" "1"
					( Origin gPackager )
				)
				( objectStatus "C8U8.1" )
			)
			( pin "@baseboard_fab2_lib.baseboard_fab2(sch_1):page225_i320:b"
				( attribute "PN" "2"
					( Origin gPackager )
				)
				( objectStatus "C8U8.2" )
			)
			( pin "@baseboard_fab2_lib.baseboard_fab2(sch_1):page228_i301:a"
				( attribute "PN" "1"
					( Origin gPackager )
				)
				( objectStatus "C8L1.1" )
			)
			( pin "@baseboard_fab2_lib.baseboard_fab2(sch_1):page228_i301:b"
				( attribute "PN" "2"
					( Origin gPackager )
				)
				( objectStatus "C8L1.2" )
			)
			( pin "@baseboard_fab2_lib.baseboard_fab2(sch_1):page225_i311:a"
				( attribute "PN" "1"
					( Origin gPackager )
				)
				( objectStatus "C2G16.1" )
			)
			( pin "@baseboard_fab2_lib.baseboard_fab2(sch_1):page225_i311:b"
				( attribute "PN" "2"
					( Origin gPackager )
				)
				( objectStatus "C2G16.2" )
			)
			( pin "@baseboard_fab2_lib.baseboard_fab2(sch_1):page225_i308:a"
				( attribute "PN" "1"
					( Origin gPackager )
				)
				( objectStatus "C7U7.1" )
			)
			( pin "@baseboard_fab2_lib.baseboard_fab2(sch_1):page225_i308:b"
				( attribute "PN" "2"
					( Origin gPackager )
				)
				( objectStatus "C7U7.2" )
			)
			( pin "@baseboard_fab2_lib.baseboard_fab2(sch_1):page228_i302:a"
				( attribute "PN" "1"
					( Origin gPackager )
				)
				( objectStatus "C8L11.1" )
			)
			( pin "@baseboard_fab2_lib.baseboard_fab2(sch_1):page228_i302:b"
				( attribute "PN" "2"
					( Origin gPackager )
				)
				( objectStatus "C8L11.2" )
			)
			( pin "@baseboard_fab2_lib.baseboard_fab2(sch_1):page225_i310:a"
				( attribute "PN" "1"
					( Origin gPackager )
				)
				( objectStatus "C8U12.1" )
			)
			( pin "@baseboard_fab2_lib.baseboard_fab2(sch_1):page225_i310:b"
				( attribute "PN" "2"
					( Origin gPackager )
				)
				( objectStatus "C8U12.2" )
			)
			( pin "@baseboard_fab2_lib.baseboard_fab2(sch_1):page225_i313:a"
				( attribute "PN" "1"
					( Origin gPackager )
				)
				( objectStatus "C8P30.1" )
			)
			( pin "@baseboard_fab2_lib.baseboard_fab2(sch_1):page225_i313:b"
				( attribute "PN" "2"
					( Origin gPackager )
				)
				( objectStatus "C8P30.2" )
			)
			( pin "@baseboard_fab2_lib.baseboard_fab2(sch_1):page225_i312:a"
				( attribute "PN" "1"
					( Origin gPackager )
				)
				( objectStatus "C2G7.1" )
			)
			( pin "@baseboard_fab2_lib.baseboard_fab2(sch_1):page225_i312:b"
				( attribute "PN" "2"
					( Origin gPackager )
				)
				( objectStatus "C2G7.2" )
			)
			( pin "@baseboard_fab2_lib.baseboard_fab2(sch_1):page228_i247:f"
				( attribute "PN" "2"
					( Origin gPackager )
				)
				( objectStatus "L1B1.2" )
			)
			( pin "@baseboard_fab2_lib.baseboard_fab2(sch_1):page228_i247:s"
				( attribute "PN" "1"
					( Origin gPackager )
				)
				( objectStatus "L1B1.1" )
			)
			( pin "@baseboard_fab2_lib.baseboard_fab2(sch_1):page228_i305:a"
				( attribute "PN" "1"
					( Origin gPackager )
				)
				( objectStatus "C7P2.1" )
			)
			( pin "@baseboard_fab2_lib.baseboard_fab2(sch_1):page228_i305:b"
				( attribute "PN" "2"
					( Origin gPackager )
				)
				( objectStatus "C7P2.2" )
			)
			( pin "@baseboard_fab2_lib.baseboard_fab2(sch_1):page225_i275:a"
				( attribute "PN" "1"
					( Origin gPackager )
				)
				( objectStatus "C2G11.1" )
			)
			( pin "@baseboard_fab2_lib.baseboard_fab2(sch_1):page225_i275:b"
				( attribute "PN" "2"
					( Origin gPackager )
				)
				( objectStatus "C2G11.2" )
			)
			( pin "@baseboard_fab2_lib.baseboard_fab2(sch_1):page225_i274:a"
				( attribute "PN" "1"
					( Origin gPackager )
				)
				( objectStatus "C2G10.1" )
			)
			( pin "@baseboard_fab2_lib.baseboard_fab2(sch_1):page225_i274:b"
				( attribute "PN" "2"
					( Origin gPackager )
				)
				( objectStatus "C2G10.2" )
			)
			( pin "@baseboard_fab2_lib.baseboard_fab2(sch_1):page188_i121:a"
				( attribute "PN" "1"
					( Origin gPackager )
				)
				( objectStatus "C8C12.1" )
			)
			( pin "@baseboard_fab2_lib.baseboard_fab2(sch_1):page188_i121:b"
				( attribute "PN" "2"
					( Origin gPackager )
				)
				( objectStatus "C8C12.2" )
			)
			( pin "@baseboard_fab2_lib.baseboard_fab2(sch_1):page188_i120:a"
				( attribute "PN" "1"
					( Origin gPackager )
				)
				( objectStatus "C8C13.1" )
			)
			( pin "@baseboard_fab2_lib.baseboard_fab2(sch_1):page188_i120:b"
				( attribute "PN" "2"
					( Origin gPackager )
				)
				( objectStatus "C8C13.2" )
			)
			( pin "@baseboard_fab2_lib.baseboard_fab2(sch_1):page228_i306:a"
				( attribute "PN" "1"
					( Origin gPackager )
				)
				( objectStatus "C8P3.1" )
			)
			( pin "@baseboard_fab2_lib.baseboard_fab2(sch_1):page228_i306:b"
				( attribute "PN" "2"
					( Origin gPackager )
				)
				( objectStatus "C8P3.2" )
			)
			( pin "@baseboard_fab2_lib.baseboard_fab2(sch_1):page225_i250:\1\"
				( attribute "PN" "1"
					( Origin gPackager )
				)
				( objectStatus "C1G2.1" )
			)
			( pin "@baseboard_fab2_lib.baseboard_fab2(sch_1):page225_i250:\2\"
				( attribute "PN" "2"
					( Origin gPackager )
				)
				( objectStatus "C1G2.2" )
			)
			( pin "@baseboard_fab2_lib.baseboard_fab2(sch_1):page225_i249:\1\"
				( attribute "PN" "1"
					( Origin gPackager )
				)
				( objectStatus "C22W3.1" )
			)
			( pin "@baseboard_fab2_lib.baseboard_fab2(sch_1):page225_i249:\2\"
				( attribute "PN" "2"
					( Origin gPackager )
				)
				( objectStatus "C22W3.2" )
			)
			( pin "@baseboard_fab2_lib.baseboard_fab2(sch_1):page234_i223:\1\"
				( attribute "PN" "1"
					( Origin gPackager )
				)
				( objectStatus "C4B1.1" )
			)
			( pin "@baseboard_fab2_lib.baseboard_fab2(sch_1):page234_i223:\2\"
				( attribute "PN" "2"
					( Origin gPackager )
				)
				( objectStatus "C4B1.2" )
			)
			( pin "@baseboard_fab2_lib.baseboard_fab2(sch_1):page234_i222:\1\"
				( attribute "PN" "1"
					( Origin gPackager )
				)
				( objectStatus "C22W5.1" )
			)
			( pin "@baseboard_fab2_lib.baseboard_fab2(sch_1):page234_i222:\2\"
				( attribute "PN" "2"
					( Origin gPackager )
				)
				( objectStatus "C22W5.2" )
			)
			( pin "@baseboard_fab2_lib.baseboard_fab2(sch_1):page225_i196:a"
				( attribute "PN" "1"
					( Origin gPackager )
				)
				( objectStatus "C8T4.1" )
			)
			( pin "@baseboard_fab2_lib.baseboard_fab2(sch_1):page225_i196:b"
				( attribute "PN" "2"
					( Origin gPackager )
				)
				( objectStatus "C8T4.2" )
			)
			( pin "@baseboard_fab2_lib.baseboard_fab2(sch_1):page225_i197:a"
				( attribute "PN" "1"
					( Origin gPackager )
				)
				( objectStatus "C2G8.1" )
			)
			( pin "@baseboard_fab2_lib.baseboard_fab2(sch_1):page225_i197:b"
				( attribute "PN" "2"
					( Origin gPackager )
				)
				( objectStatus "C2G8.2" )
			)
			( pin "@baseboard_fab2_lib.baseboard_fab2(sch_1):page225_i198:a"
				( attribute "PN" "1"
					( Origin gPackager )
				)
				( objectStatus "C8T2.1" )
			)
			( pin "@baseboard_fab2_lib.baseboard_fab2(sch_1):page225_i198:b"
				( attribute "PN" "2"
					( Origin gPackager )
				)
				( objectStatus "C8T2.2" )
			)
			( pin "@baseboard_fab2_lib.baseboard_fab2(sch_1):page225_i199:a"
				( attribute "PN" "1"
					( Origin gPackager )
				)
				( objectStatus "C8U13.1" )
			)
			( pin "@baseboard_fab2_lib.baseboard_fab2(sch_1):page225_i199:b"
				( attribute "PN" "2"
					( Origin gPackager )
				)
				( objectStatus "C8U13.2" )
			)
			( pin "@baseboard_fab2_lib.baseboard_fab2(sch_1):page225_i200:a"
				( attribute "PN" "1"
					( Origin gPackager )
				)
				( objectStatus "C2G15.1" )
			)
			( pin "@baseboard_fab2_lib.baseboard_fab2(sch_1):page225_i200:b"
				( attribute "PN" "2"
					( Origin gPackager )
				)
				( objectStatus "C2G15.2" )
			)
			( pin "@baseboard_fab2_lib.baseboard_fab2(sch_1):page225_i201:a"
				( attribute "PN" "1"
					( Origin gPackager )
				)
				( objectStatus "C2F1.1" )
			)
			( pin "@baseboard_fab2_lib.baseboard_fab2(sch_1):page225_i201:b"
				( attribute "PN" "2"
					( Origin gPackager )
				)
				( objectStatus "C2F1.2" )
			)
			( pin "@baseboard_fab2_lib.baseboard_fab2(sch_1):page225_i202:a"
				( attribute "PN" "1"
					( Origin gPackager )
				)
				( objectStatus "C8T1.1" )
			)
			( pin "@baseboard_fab2_lib.baseboard_fab2(sch_1):page225_i202:b"
				( attribute "PN" "2"
					( Origin gPackager )
				)
				( objectStatus "C8T1.2" )
			)
			( pin "@baseboard_fab2_lib.baseboard_fab2(sch_1):page225_i203:a"
				( attribute "PN" "1"
					( Origin gPackager )
				)
				( objectStatus "C8U9.1" )
			)
			( pin "@baseboard_fab2_lib.baseboard_fab2(sch_1):page225_i203:b"
				( attribute "PN" "2"
					( Origin gPackager )
				)
				( objectStatus "C8U9.2" )
			)
			( pin "@baseboard_fab2_lib.baseboard_fab2(sch_1):page225_i204:a"
				( attribute "PN" "1"
					( Origin gPackager )
				)
				( objectStatus "C8T11.1" )
			)
			( pin "@baseboard_fab2_lib.baseboard_fab2(sch_1):page225_i204:b"
				( attribute "PN" "2"
					( Origin gPackager )
				)
				( objectStatus "C8T11.2" )
			)
			( pin "@baseboard_fab2_lib.baseboard_fab2(sch_1):page228_i283:a"
				( attribute "PN" "1"
					( Origin gPackager )
				)
				( objectStatus "C2A2.1" )
			)
			( pin "@baseboard_fab2_lib.baseboard_fab2(sch_1):page228_i283:b"
				( attribute "PN" "2"
					( Origin gPackager )
				)
				( objectStatus "C2A2.2" )
			)
			( pin "@baseboard_fab2_lib.baseboard_fab2(sch_1):page228_i282:a"
				( attribute "PN" "1"
					( Origin gPackager )
				)
				( objectStatus "C2A1.1" )
			)
			( pin "@baseboard_fab2_lib.baseboard_fab2(sch_1):page228_i282:b"
				( attribute "PN" "2"
					( Origin gPackager )
				)
				( objectStatus "C2A1.2" )
			)
			( pin "@baseboard_fab2_lib.baseboard_fab2(sch_1):page228_i281:a"
				( attribute "PN" "1"
					( Origin gPackager )
				)
				( objectStatus "C2A12.1" )
			)
			( pin "@baseboard_fab2_lib.baseboard_fab2(sch_1):page228_i281:b"
				( attribute "PN" "2"
					( Origin gPackager )
				)
				( objectStatus "C2A12.2" )
			)
			( pin "@baseboard_fab2_lib.baseboard_fab2(sch_1):page228_i280:a"
				( attribute "PN" "1"
					( Origin gPackager )
				)
				( objectStatus "C2A13.1" )
			)
			( pin "@baseboard_fab2_lib.baseboard_fab2(sch_1):page228_i280:b"
				( attribute "PN" "2"
					( Origin gPackager )
				)
				( objectStatus "C2A13.2" )
			)
			( pin "@baseboard_fab2_lib.baseboard_fab2(sch_1):page228_i279:a"
				( attribute "PN" "1"
					( Origin gPackager )
				)
				( objectStatus "C2A11.1" )
			)
			( pin "@baseboard_fab2_lib.baseboard_fab2(sch_1):page228_i279:b"
				( attribute "PN" "2"
					( Origin gPackager )
				)
				( objectStatus "C2A11.2" )
			)
			( pin "@baseboard_fab2_lib.baseboard_fab2(sch_1):page228_i278:a"
				( attribute "PN" "1"
					( Origin gPackager )
				)
				( objectStatus "C2A10.1" )
			)
			( pin "@baseboard_fab2_lib.baseboard_fab2(sch_1):page228_i278:b"
				( attribute "PN" "2"
					( Origin gPackager )
				)
				( objectStatus "C2A10.2" )
			)
			( pin "@baseboard_fab2_lib.baseboard_fab2(sch_1):page228_i277:a"
				( attribute "PN" "1"
					( Origin gPackager )
				)
				( objectStatus "C2A9.1" )
			)
			( pin "@baseboard_fab2_lib.baseboard_fab2(sch_1):page228_i277:b"
				( attribute "PN" "2"
					( Origin gPackager )
				)
				( objectStatus "C2A9.2" )
			)
			( pin "@baseboard_fab2_lib.baseboard_fab2(sch_1):page228_i276:a"
				( attribute "PN" "1"
					( Origin gPackager )
				)
				( objectStatus "C3A2.1" )
			)
			( pin "@baseboard_fab2_lib.baseboard_fab2(sch_1):page228_i276:b"
				( attribute "PN" "2"
					( Origin gPackager )
				)
				( objectStatus "C3A2.2" )
			)
			( pin "@baseboard_fab2_lib.baseboard_fab2(sch_1):page228_i275:a"
				( attribute "PN" "1"
					( Origin gPackager )
				)
				( objectStatus "C3A1.1" )
			)
			( pin "@baseboard_fab2_lib.baseboard_fab2(sch_1):page228_i275:b"
				( attribute "PN" "2"
					( Origin gPackager )
				)
				( objectStatus "C3A1.2" )
			)
			( pin "@baseboard_fab2_lib.baseboard_fab2(sch_1):page228_i274:a"
				( attribute "PN" "1"
					( Origin gPackager )
				)
				( objectStatus "C2A7.1" )
			)
			( pin "@baseboard_fab2_lib.baseboard_fab2(sch_1):page228_i274:b"
				( attribute "PN" "2"
					( Origin gPackager )
				)
				( objectStatus "C2A7.2" )
			)
			( pin "@baseboard_fab2_lib.baseboard_fab2(sch_1):page228_i273:a"
				( attribute "PN" "1"
					( Origin gPackager )
				)
				( objectStatus "C2A6.1" )
			)
			( pin "@baseboard_fab2_lib.baseboard_fab2(sch_1):page228_i273:b"
				( attribute "PN" "2"
					( Origin gPackager )
				)
				( objectStatus "C2A6.2" )
			)
			( pin "@baseboard_fab2_lib.baseboard_fab2(sch_1):page228_i272:a"
				( attribute "PN" "1"
					( Origin gPackager )
				)
				( objectStatus "C2A14.1" )
			)
			( pin "@baseboard_fab2_lib.baseboard_fab2(sch_1):page228_i272:b"
				( attribute "PN" "2"
					( Origin gPackager )
				)
				( objectStatus "C2A14.2" )
			)
			( pin "@baseboard_fab2_lib.baseboard_fab2(sch_1):page228_i267:a"
				( attribute "PN" "1"
					( Origin gPackager )
				)
				( objectStatus "C2D6.1" )
			)
			( pin "@baseboard_fab2_lib.baseboard_fab2(sch_1):page228_i267:b"
				( attribute "PN" "2"
					( Origin gPackager )
				)
				( objectStatus "C2D6.2" )
			)
			( pin "@baseboard_fab2_lib.baseboard_fab2(sch_1):page228_i266:a"
				( attribute "PN" "1"
					( Origin gPackager )
				)
				( objectStatus "C2D5.1" )
			)
			( pin "@baseboard_fab2_lib.baseboard_fab2(sch_1):page228_i266:b"
				( attribute "PN" "2"
					( Origin gPackager )
				)
				( objectStatus "C2D5.2" )
			)
			( pin "@baseboard_fab2_lib.baseboard_fab2(sch_1):page228_i265:a"
				( attribute "PN" "1"
					( Origin gPackager )
				)
				( objectStatus "C2D4.1" )
			)
			( pin "@baseboard_fab2_lib.baseboard_fab2(sch_1):page228_i265:b"
				( attribute "PN" "2"
					( Origin gPackager )
				)
				( objectStatus "C2D4.2" )
			)
			( pin "@baseboard_fab2_lib.baseboard_fab2(sch_1):page228_i264:a"
				( attribute "PN" "1"
					( Origin gPackager )
				)
				( objectStatus "C2D7.1" )
			)
			( pin "@baseboard_fab2_lib.baseboard_fab2(sch_1):page228_i264:b"
				( attribute "PN" "2"
					( Origin gPackager )
				)
				( objectStatus "C2D7.2" )
			)
			( pin "@baseboard_fab2_lib.baseboard_fab2(sch_1):page225_i243:a"
				( attribute "PN" "1"
					( Origin gPackager )
				)
				( objectStatus "SH7U1.1" )
			)
			( pin "@baseboard_fab2_lib.baseboard_fab2(sch_1):page225_i243:b"
				( attribute "PN" "2"
					( Origin gPackager )
				)
				( objectStatus "SH7U1.2" )
			)
			( pin "@baseboard_fab2_lib.baseboard_fab2(sch_1):page225_i244:a"
				( attribute "PN" "1"
					( Origin gPackager )
				)
				( objectStatus "SH7U2.1" )
			)
			( pin "@baseboard_fab2_lib.baseboard_fab2(sch_1):page225_i244:b"
				( attribute "PN" "2"
					( Origin gPackager )
				)
				( objectStatus "SH7U2.2" )
			)
			( pin "@baseboard_fab2_lib.baseboard_fab2(sch_1):page197_i114:\1\"
				( attribute "PN" "1"
					( Origin gPackager )
				)
				( objectStatus "R12W18.1" )
			)
			( pin "@baseboard_fab2_lib.baseboard_fab2(sch_1):page197_i114:\2\"
				( attribute "PN" "2"
					( Origin gPackager )
				)
				( objectStatus "R12W18.2" )
			)
			( pin "@baseboard_fab2_lib.baseboard_fab2(sch_1):page226_i13:a"
				( attribute "PN" "1"
					( Origin gPackager )
				)
				( objectStatus "R1B16.1" )
			)
			( pin "@baseboard_fab2_lib.baseboard_fab2(sch_1):page226_i13:b"
				( attribute "PN" "2"
					( Origin gPackager )
				)
				( objectStatus "R1B16.2" )
			)
			( pin "@baseboard_fab2_lib.baseboard_fab2(sch_1):page226_i14:a"
				( attribute "PN" "1"
					( Origin gPackager )
				)
				( objectStatus "R9M9.1" )
			)
			( pin "@baseboard_fab2_lib.baseboard_fab2(sch_1):page226_i14:b"
				( attribute "PN" "2"
					( Origin gPackager )
				)
				( objectStatus "R9M9.2" )
			)
			( pin "@baseboard_fab2_lib.baseboard_fab2(sch_1):page226_i16:a"
				( attribute "PN" "1"
					( Origin gPackager )
				)
				( objectStatus "RF21.1" )
			)
			( pin "@baseboard_fab2_lib.baseboard_fab2(sch_1):page226_i16:b"
				( attribute "PN" "2"
					( Origin gPackager )
				)
				( objectStatus "RF21.2" )
			)
			( pin "@baseboard_fab2_lib.baseboard_fab2(sch_1):page226_i17:\1\"
				( attribute "PN" "1"
					( Origin gPackager )
				)
				( objectStatus "CF22.1" )
			)
			( pin "@baseboard_fab2_lib.baseboard_fab2(sch_1):page226_i17:\2\"
				( attribute "PN" "2"
					( Origin gPackager )
				)
				( objectStatus "CF22.2" )
			)
			( pin "@baseboard_fab2_lib.baseboard_fab2(sch_1):page197_i21:a"
				( attribute "PN" "1"
					( Origin gPackager )
				)
				( objectStatus "R12W9.1" )
			)
			( pin "@baseboard_fab2_lib.baseboard_fab2(sch_1):page197_i21:b"
				( attribute "PN" "2"
					( Origin gPackager )
				)
				( objectStatus "R12W9.2" )
			)
			( pin "@baseboard_fab2_lib.baseboard_fab2(sch_1):page226_i23:a"
				( attribute "PN" "1"
					( Origin gPackager )
				)
				( objectStatus "C1B11.1" )
			)
			( pin "@baseboard_fab2_lib.baseboard_fab2(sch_1):page226_i23:b"
				( attribute "PN" "2"
					( Origin gPackager )
				)
				( objectStatus "C1B11.2" )
			)
			( pin "@baseboard_fab2_lib.baseboard_fab2(sch_1):page197_i19:\drain#4\"
				( attribute "PN" "4"
					( Origin gPackager )
				)
				( objectStatus "Q12W2.4" )
			)
			( pin "@baseboard_fab2_lib.baseboard_fab2(sch_1):page197_i19:\drain#6\"
				( attribute "PN" "6"
					( Origin gPackager )
				)
				( objectStatus "Q12W2.6" )
			)
			( pin "@baseboard_fab2_lib.baseboard_fab2(sch_1):page197_i19:\gate#1\"
				( attribute "PN" "1"
					( Origin gPackager )
				)
				( objectStatus "Q12W2.1" )
			)
			( pin "@baseboard_fab2_lib.baseboard_fab2(sch_1):page197_i19:\gate#3\"
				( attribute "PN" "3"
					( Origin gPackager )
				)
				( objectStatus "Q12W2.3" )
			)
			( pin "@baseboard_fab2_lib.baseboard_fab2(sch_1):page197_i19:\source#2\"
				( attribute "PN" "2"
					( Origin gPackager )
				)
				( objectStatus "Q12W2.2" )
			)
			( pin "@baseboard_fab2_lib.baseboard_fab2(sch_1):page197_i19:\source#5\"
				( attribute "PN" "5"
					( Origin gPackager )
				)
				( objectStatus "Q12W2.5" )
			)
			( pin "@baseboard_fab2_lib.baseboard_fab2(sch_1):page235_i254:a"
				( attribute "PN" "1"
					( Origin gPackager )
				)
				( objectStatus "R2L9.1" )
			)
			( pin "@baseboard_fab2_lib.baseboard_fab2(sch_1):page235_i254:b"
				( attribute "PN" "2"
					( Origin gPackager )
				)
				( objectStatus "R2L9.2" )
			)
			( pin "@baseboard_fab2_lib.baseboard_fab2(sch_1):page226_i32:a"
				( attribute "PN" "1"
					( Origin gPackager )
				)
				( objectStatus "C1B5.1" )
			)
			( pin "@baseboard_fab2_lib.baseboard_fab2(sch_1):page226_i32:b"
				( attribute "PN" "2"
					( Origin gPackager )
				)
				( objectStatus "C1B5.2" )
			)
			( pin "@baseboard_fab2_lib.baseboard_fab2(sch_1):page226_i36:a"
				( attribute "PN" "1"
					( Origin gPackager )
				)
				( objectStatus "R9M3.1" )
			)
			( pin "@baseboard_fab2_lib.baseboard_fab2(sch_1):page226_i36:b"
				( attribute "PN" "2"
					( Origin gPackager )
				)
				( objectStatus "R9M3.2" )
			)
			( pin "@baseboard_fab2_lib.baseboard_fab2(sch_1):page197_i18:a"
				( attribute "PN" "1"
					( Origin gPackager )
				)
				( objectStatus "C12W4.1" )
			)
			( pin "@baseboard_fab2_lib.baseboard_fab2(sch_1):page197_i18:b"
				( attribute "PN" "2"
					( Origin gPackager )
				)
				( objectStatus "C12W4.2" )
			)
			( pin "@baseboard_fab2_lib.baseboard_fab2(sch_1):page226_i41:a"
				( attribute "PN" "1"
					( Origin gPackager )
				)
				( objectStatus "R1B10.1" )
			)
			( pin "@baseboard_fab2_lib.baseboard_fab2(sch_1):page226_i41:b"
				( attribute "PN" "2"
					( Origin gPackager )
				)
				( objectStatus "R1B10.2" )
			)
			( pin "@baseboard_fab2_lib.baseboard_fab2(sch_1):page226_i44:a"
				( attribute "PN" "1"
					( Origin gPackager )
				)
				( objectStatus "C1B2.1" )
			)
			( pin "@baseboard_fab2_lib.baseboard_fab2(sch_1):page226_i44:b"
				( attribute "PN" "2"
					( Origin gPackager )
				)
				( objectStatus "C1B2.2" )
			)
			( pin "@baseboard_fab2_lib.baseboard_fab2(sch_1):page226_i50:a"
				( attribute "PN" "1"
					( Origin gPackager )
				)
				( objectStatus "R1B2.1" )
			)
			( pin "@baseboard_fab2_lib.baseboard_fab2(sch_1):page226_i50:b"
				( attribute "PN" "2"
					( Origin gPackager )
				)
				( objectStatus "R1B2.2" )
			)
			( pin "@baseboard_fab2_lib.baseboard_fab2(sch_1):page226_i53:a"
				( attribute "PN" "1"
					( Origin gPackager )
				)
				( objectStatus "R12W36.1" )
			)
			( pin "@baseboard_fab2_lib.baseboard_fab2(sch_1):page226_i53:b"
				( attribute "PN" "2"
					( Origin gPackager )
				)
				( objectStatus "R12W36.2" )
			)
			( pin "@baseboard_fab2_lib.baseboard_fab2(sch_1):page197_i14:a"
				( attribute "PN" "1"
					( Origin gPackager )
				)
				( objectStatus "R4F2.1" )
			)
			( pin "@baseboard_fab2_lib.baseboard_fab2(sch_1):page197_i14:b"
				( attribute "PN" "2"
					( Origin gPackager )
				)
				( objectStatus "R4F2.2" )
			)
			( pin "@baseboard_fab2_lib.baseboard_fab2(sch_1):page197_i115:\1\"
				( attribute "PN" "1"
					( Origin gPackager )
				)
				( objectStatus "R12W3.1" )
			)
			( pin "@baseboard_fab2_lib.baseboard_fab2(sch_1):page197_i115:\2\"
				( attribute "PN" "2"
					( Origin gPackager )
				)
				( objectStatus "R12W3.2" )
			)
			( pin "@baseboard_fab2_lib.baseboard_fab2(sch_1):page197_i8:a"
				( attribute "PN" "1"
					( Origin gPackager )
				)
				( objectStatus "C12W1.1" )
			)
			( pin "@baseboard_fab2_lib.baseboard_fab2(sch_1):page197_i8:b"
				( attribute "PN" "2"
					( Origin gPackager )
				)
				( objectStatus "C12W1.2" )
			)
			( pin "@baseboard_fab2_lib.baseboard_fab2(sch_1):page197_i6:a"
				( attribute "PN" "1"
					( Origin gPackager )
				)
				( objectStatus "R4B12.1" )
			)
			( pin "@baseboard_fab2_lib.baseboard_fab2(sch_1):page197_i6:b"
				( attribute "PN" "2"
					( Origin gPackager )
				)
				( objectStatus "R4B12.2" )
			)
			( pin "@baseboard_fab2_lib.baseboard_fab2(sch_1):page211_i97:a"
				( attribute "PN" "1"
					( Origin gPackager )
				)
				( objectStatus "C4W1.1" )
			)
			( pin "@baseboard_fab2_lib.baseboard_fab2(sch_1):page211_i97:b"
				( attribute "PN" "2"
					( Origin gPackager )
				)
				( objectStatus "C4W1.2" )
			)
			( pin "@baseboard_fab2_lib.baseboard_fab2(sch_1):page227_i6:a"
				( attribute "PN" "1"
					( Origin gPackager )
				)
				( objectStatus "C1A12.1" )
			)
			( pin "@baseboard_fab2_lib.baseboard_fab2(sch_1):page227_i6:b"
				( attribute "PN" "2"
					( Origin gPackager )
				)
				( objectStatus "C1A12.2" )
			)
			( pin "@baseboard_fab2_lib.baseboard_fab2(sch_1):page227_i44:a"
				( attribute "PN" "1"
					( Origin gPackager )
				)
				( objectStatus "C1A18.1" )
			)
			( pin "@baseboard_fab2_lib.baseboard_fab2(sch_1):page227_i44:b"
				( attribute "PN" "2"
					( Origin gPackager )
				)
				( objectStatus "C1A18.2" )
			)
			( pin "@baseboard_fab2_lib.baseboard_fab2(sch_1):page227_i45:a"
				( attribute "PN" "1"
					( Origin gPackager )
				)
				( objectStatus "C9L11.1" )
			)
			( pin "@baseboard_fab2_lib.baseboard_fab2(sch_1):page227_i45:b"
				( attribute "PN" "2"
					( Origin gPackager )
				)
				( objectStatus "C9L11.2" )
			)
			( pin "@baseboard_fab2_lib.baseboard_fab2(sch_1):page227_i46:a"
				( attribute "PN" "1"
					( Origin gPackager )
				)
				( objectStatus "C9L10.1" )
			)
			( pin "@baseboard_fab2_lib.baseboard_fab2(sch_1):page227_i46:b"
				( attribute "PN" "2"
					( Origin gPackager )
				)
				( objectStatus "C9L10.2" )
			)
			( pin "@baseboard_fab2_lib.baseboard_fab2(sch_1):page227_i47:a"
				( attribute "PN" "1"
					( Origin gPackager )
				)
				( objectStatus "C9L6.1" )
			)
			( pin "@baseboard_fab2_lib.baseboard_fab2(sch_1):page227_i47:b"
				( attribute "PN" "2"
					( Origin gPackager )
				)
				( objectStatus "C9L6.2" )
			)
			( pin "@baseboard_fab2_lib.baseboard_fab2(sch_1):page227_i48:a"
				( attribute "PN" "1"
					( Origin gPackager )
				)
				( objectStatus "C1A19.1" )
			)
			( pin "@baseboard_fab2_lib.baseboard_fab2(sch_1):page227_i48:b"
				( attribute "PN" "2"
					( Origin gPackager )
				)
				( objectStatus "C1A19.2" )
			)
			( pin "@baseboard_fab2_lib.baseboard_fab2(sch_1):page227_i50:a"
				( attribute "PN" "1"
					( Origin gPackager )
				)
				( objectStatus "C1B20.1" )
			)
			( pin "@baseboard_fab2_lib.baseboard_fab2(sch_1):page227_i50:b"
				( attribute "PN" "2"
					( Origin gPackager )
				)
				( objectStatus "C1B20.2" )
			)
			( pin "@baseboard_fab2_lib.baseboard_fab2(sch_1):page227_i51:a"
				( attribute "PN" "1"
					( Origin gPackager )
				)
				( objectStatus "C1A10.1" )
			)
			( pin "@baseboard_fab2_lib.baseboard_fab2(sch_1):page227_i51:b"
				( attribute "PN" "2"
					( Origin gPackager )
				)
				( objectStatus "C1A10.2" )
			)
			( pin "@baseboard_fab2_lib.baseboard_fab2(sch_1):page208_i119:\1\"
				( attribute "PN" "1"
					( Origin gPackager )
				)
				( objectStatus "C1D5.1" )
			)
			( pin "@baseboard_fab2_lib.baseboard_fab2(sch_1):page208_i119:\2\"
				( attribute "PN" "2"
					( Origin gPackager )
				)
				( objectStatus "C1D5.2" )
			)
			( pin "@baseboard_fab2_lib.baseboard_fab2(sch_1):page227_i54:a"
				( attribute "PN" "1"
					( Origin gPackager )
				)
				( objectStatus "C1B21.1" )
			)
			( pin "@baseboard_fab2_lib.baseboard_fab2(sch_1):page227_i54:b"
				( attribute "PN" "2"
					( Origin gPackager )
				)
				( objectStatus "C1B21.2" )
			)
			( pin "@baseboard_fab2_lib.baseboard_fab2(sch_1):page212_i142:f"
				( attribute "PN" "2"
					( Origin gPackager )
				)
				( objectStatus "L7C1.2" )
			)
			( pin "@baseboard_fab2_lib.baseboard_fab2(sch_1):page212_i142:s"
				( attribute "PN" "1"
					( Origin gPackager )
				)
				( objectStatus "L7C1.1" )
			)
			( pin "@baseboard_fab2_lib.baseboard_fab2(sch_1):page212_i141:f"
				( attribute "PN" "2"
					( Origin gPackager )
				)
				( objectStatus "L7C2.2" )
			)
			( pin "@baseboard_fab2_lib.baseboard_fab2(sch_1):page212_i141:s"
				( attribute "PN" "1"
					( Origin gPackager )
				)
				( objectStatus "L7C2.1" )
			)
			( pin "@baseboard_fab2_lib.baseboard_fab2(sch_1):page227_i68:a"
				( attribute "PN" "1"
					( Origin gPackager )
				)
				( objectStatus "C1A1.1" )
			)
			( pin "@baseboard_fab2_lib.baseboard_fab2(sch_1):page227_i68:b"
				( attribute "PN" "2"
					( Origin gPackager )
				)
				( objectStatus "C1A1.2" )
			)
			( pin "@baseboard_fab2_lib.baseboard_fab2(sch_1):page227_i72:a"
				( attribute "PN" "1"
					( Origin gPackager )
				)
				( objectStatus "C1A13.1" )
			)
			( pin "@baseboard_fab2_lib.baseboard_fab2(sch_1):page227_i72:b"
				( attribute "PN" "2"
					( Origin gPackager )
				)
				( objectStatus "C1A13.2" )
			)
			( pin "@baseboard_fab2_lib.baseboard_fab2(sch_1):page210_i73:\1\"
				( attribute "PN" "1"
					( Origin gPackager )
				)
				( objectStatus "C1C3.1" )
			)
			( pin "@baseboard_fab2_lib.baseboard_fab2(sch_1):page210_i73:\2\"
				( attribute "PN" "2"
					( Origin gPackager )
				)
				( objectStatus "C1C3.2" )
			)
			( pin "@baseboard_fab2_lib.baseboard_fab2(sch_1):page227_i75:a"
				( attribute "PN" "1"
					( Origin gPackager )
				)
				( objectStatus "C1A8.1" )
			)
			( pin "@baseboard_fab2_lib.baseboard_fab2(sch_1):page227_i75:b"
				( attribute "PN" "2"
					( Origin gPackager )
				)
				( objectStatus "C1A8.2" )
			)
			( pin "@baseboard_fab2_lib.baseboard_fab2(sch_1):page227_i77:a"
				( attribute "PN" "1"
					( Origin gPackager )
				)
				( objectStatus "C1A6.1" )
			)
			( pin "@baseboard_fab2_lib.baseboard_fab2(sch_1):page227_i77:b"
				( attribute "PN" "2"
					( Origin gPackager )
				)
				( objectStatus "C1A6.2" )
			)
			( pin "@baseboard_fab2_lib.baseboard_fab2(sch_1):page227_i78:a"
				( attribute "PN" "1"
					( Origin gPackager )
				)
				( objectStatus "C1A20.1" )
			)
			( pin "@baseboard_fab2_lib.baseboard_fab2(sch_1):page227_i78:b"
				( attribute "PN" "2"
					( Origin gPackager )
				)
				( objectStatus "C1A20.2" )
			)
			( pin "@baseboard_fab2_lib.baseboard_fab2(sch_1):page227_i79:a"
				( attribute "PN" "1"
					( Origin gPackager )
				)
				( objectStatus "C1A9.1" )
			)
			( pin "@baseboard_fab2_lib.baseboard_fab2(sch_1):page227_i79:b"
				( attribute "PN" "2"
					( Origin gPackager )
				)
				( objectStatus "C1A9.2" )
			)
			( pin "@baseboard_fab2_lib.baseboard_fab2(sch_1):page227_i80:a"
				( attribute "PN" "1"
					( Origin gPackager )
				)
				( objectStatus "C9L5.1" )
			)
			( pin "@baseboard_fab2_lib.baseboard_fab2(sch_1):page227_i80:b"
				( attribute "PN" "2"
					( Origin gPackager )
				)
				( objectStatus "C9L5.2" )
			)
			( pin "@baseboard_fab2_lib.baseboard_fab2(sch_1):page227_i81:a"
				( attribute "PN" "1"
					( Origin gPackager )
				)
				( objectStatus "C9L13.1" )
			)
			( pin "@baseboard_fab2_lib.baseboard_fab2(sch_1):page227_i81:b"
				( attribute "PN" "2"
					( Origin gPackager )
				)
				( objectStatus "C9L13.2" )
			)
			( pin "@baseboard_fab2_lib.baseboard_fab2(sch_1):page227_i84:a"
				( attribute "PN" "1"
					( Origin gPackager )
				)
				( objectStatus "C9L14.1" )
			)
			( pin "@baseboard_fab2_lib.baseboard_fab2(sch_1):page227_i84:b"
				( attribute "PN" "2"
					( Origin gPackager )
				)
				( objectStatus "C9L14.2" )
			)
			( pin "@baseboard_fab2_lib.baseboard_fab2(sch_1):page227_i101:boost"
				( attribute "PN" "33"
					( Origin gPackager )
				)
				( objectStatus "EU1A2.33" )
			)
			( pin "@baseboard_fab2_lib.baseboard_fab2(sch_1):page227_i101:en"
				( attribute "PN" "35"
					( Origin gPackager )
				)
				( objectStatus "EU1A2.35" )
			)
			( pin "@baseboard_fab2_lib.baseboard_fab2(sch_1):page227_i101:gl(0)"
				( attribute "PN" "6"
					( Origin gPackager )
				)
				( objectStatus "EU1A2.6" )
			)
			( pin "@baseboard_fab2_lib.baseboard_fab2(sch_1):page227_i101:gl(1)"
				( attribute "PN" "41"
					( Origin gPackager )
				)
				( objectStatus "EU1A2.41" )
			)
			( pin "@baseboard_fab2_lib.baseboard_fab2(sch_1):page227_i101:iout"
				( attribute "PN" "38"
					( Origin gPackager )
				)
				( objectStatus "EU1A2.38" )
			)
			( pin "@baseboard_fab2_lib.baseboard_fab2(sch_1):page227_i101:lgnd"
				( attribute "PN" "2"
					( Origin gPackager )
				)
				( objectStatus "EU1A2.2" )
			)
			( pin "@baseboard_fab2_lib.baseboard_fab2(sch_1):page227_i101:nc"
				( attribute "PN" "31"
					( Origin gPackager )
				)
				( objectStatus "EU1A2.31" )
			)
			( pin "@baseboard_fab2_lib.baseboard_fab2(sch_1):page227_i101:ocset"
				( attribute "PN" "37"
					( Origin gPackager )
				)
				( objectStatus "EU1A2.37" )
			)
			( pin "@baseboard_fab2_lib.baseboard_fab2(sch_1):page227_i101:pgnd(0)"
				( attribute "PN" "5"
					( Origin gPackager )
				)
				( objectStatus "EU1A2.5" )
			)
			( pin "@baseboard_fab2_lib.baseboard_fab2(sch_1):page227_i101:pgnd(1)"
				( attribute "PN" "7"
					( Origin gPackager )
				)
				( objectStatus "EU1A2.7" )
			)
			( pin "@baseboard_fab2_lib.baseboard_fab2(sch_1):page227_i101:pgnd(2)"
				( attribute "PN" "40"
					( Origin gPackager )
				)
				( objectStatus "EU1A2.40" )
			)
			( pin "@baseboard_fab2_lib.baseboard_fab2(sch_1):page227_i101:phase"
				( attribute "PN" "32"
					( Origin gPackager )
				)
				( objectStatus "EU1A2.32" )
			)
			( pin "@baseboard_fab2_lib.baseboard_fab2(sch_1):page227_i101:pwm"
				( attribute "PN" "34"
					( Origin gPackager )
				)
				( objectStatus "EU1A2.34" )
			)
			( pin "@baseboard_fab2_lib.baseboard_fab2(sch_1):page227_i101:refin"
				( attribute "PN" "39"
					( Origin gPackager )
				)
				( objectStatus "EU1A2.39" )
			)
			( pin "@baseboard_fab2_lib.baseboard_fab2(sch_1):page227_i101:sw"
				( attribute "PN" "10"
					( Origin gPackager )
				)
				( objectStatus "EU1A2.10" )
			)
			( pin "@baseboard_fab2_lib.baseboard_fab2(sch_1):page227_i101:tout_flt"
				( attribute "PN" "36"
					( Origin gPackager )
				)
				( objectStatus "EU1A2.36" )
			)
			( pin "@baseboard_fab2_lib.baseboard_fab2(sch_1):page227_i101:vcc"
				( attribute "PN" "3"
					( Origin gPackager )
				)
				( objectStatus "EU1A2.3" )
			)
			( pin "@baseboard_fab2_lib.baseboard_fab2(sch_1):page227_i101:vdrv"
				( attribute "PN" "4"
					( Origin gPackager )
				)
				( objectStatus "EU1A2.4" )
			)
			( pin "@baseboard_fab2_lib.baseboard_fab2(sch_1):page227_i101:vin(0)"
				( attribute "PN" "25"
					( Origin gPackager )
				)
				( objectStatus "EU1A2.25" )
			)
			( pin "@baseboard_fab2_lib.baseboard_fab2(sch_1):page227_i101:vin(1)"
				( attribute "PN" "30"
					( Origin gPackager )
				)
				( objectStatus "EU1A2.30" )
			)
			( pin "@baseboard_fab2_lib.baseboard_fab2(sch_1):page227_i101:vos"
				( attribute "PN" "1"
					( Origin gPackager )
				)
				( objectStatus "EU1A2.1" )
			)
			( pin "@baseboard_fab2_lib.baseboard_fab2(sch_1):page227_i102:boost"
				( attribute "PN" "33"
					( Origin gPackager )
				)
				( objectStatus "EU1A1.33" )
			)
			( pin "@baseboard_fab2_lib.baseboard_fab2(sch_1):page227_i102:en"
				( attribute "PN" "35"
					( Origin gPackager )
				)
				( objectStatus "EU1A1.35" )
			)
			( pin "@baseboard_fab2_lib.baseboard_fab2(sch_1):page227_i102:gl(0)"
				( attribute "PN" "6"
					( Origin gPackager )
				)
				( objectStatus "EU1A1.6" )
			)
			( pin "@baseboard_fab2_lib.baseboard_fab2(sch_1):page227_i102:gl(1)"
				( attribute "PN" "41"
					( Origin gPackager )
				)
				( objectStatus "EU1A1.41" )
			)
			( pin "@baseboard_fab2_lib.baseboard_fab2(sch_1):page227_i102:iout"
				( attribute "PN" "38"
					( Origin gPackager )
				)
				( objectStatus "EU1A1.38" )
			)
			( pin "@baseboard_fab2_lib.baseboard_fab2(sch_1):page227_i102:lgnd"
				( attribute "PN" "2"
					( Origin gPackager )
				)
				( objectStatus "EU1A1.2" )
			)
			( pin "@baseboard_fab2_lib.baseboard_fab2(sch_1):page227_i102:nc"
				( attribute "PN" "31"
					( Origin gPackager )
				)
				( objectStatus "EU1A1.31" )
			)
			( pin "@baseboard_fab2_lib.baseboard_fab2(sch_1):page227_i102:ocset"
				( attribute "PN" "37"
					( Origin gPackager )
				)
				( objectStatus "EU1A1.37" )
			)
			( pin "@baseboard_fab2_lib.baseboard_fab2(sch_1):page227_i102:pgnd(0)"
				( attribute "PN" "5"
					( Origin gPackager )
				)
				( objectStatus "EU1A1.5" )
			)
			( pin "@baseboard_fab2_lib.baseboard_fab2(sch_1):page227_i102:pgnd(1)"
				( attribute "PN" "7"
					( Origin gPackager )
				)
				( objectStatus "EU1A1.7" )
			)
			( pin "@baseboard_fab2_lib.baseboard_fab2(sch_1):page227_i102:pgnd(2)"
				( attribute "PN" "40"
					( Origin gPackager )
				)
				( objectStatus "EU1A1.40" )
			)
			( pin "@baseboard_fab2_lib.baseboard_fab2(sch_1):page227_i102:phase"
				( attribute "PN" "32"
					( Origin gPackager )
				)
				( objectStatus "EU1A1.32" )
			)
			( pin "@baseboard_fab2_lib.baseboard_fab2(sch_1):page227_i102:pwm"
				( attribute "PN" "34"
					( Origin gPackager )
				)
				( objectStatus "EU1A1.34" )
			)
			( pin "@baseboard_fab2_lib.baseboard_fab2(sch_1):page227_i102:refin"
				( attribute "PN" "39"
					( Origin gPackager )
				)
				( objectStatus "EU1A1.39" )
			)
			( pin "@baseboard_fab2_lib.baseboard_fab2(sch_1):page227_i102:sw"
				( attribute "PN" "10"
					( Origin gPackager )
				)
				( objectStatus "EU1A1.10" )
			)
			( pin "@baseboard_fab2_lib.baseboard_fab2(sch_1):page227_i102:tout_flt"
				( attribute "PN" "36"
					( Origin gPackager )
				)
				( objectStatus "EU1A1.36" )
			)
			( pin "@baseboard_fab2_lib.baseboard_fab2(sch_1):page227_i102:vcc"
				( attribute "PN" "3"
					( Origin gPackager )
				)
				( objectStatus "EU1A1.3" )
			)
			( pin "@baseboard_fab2_lib.baseboard_fab2(sch_1):page227_i102:vdrv"
				( attribute "PN" "4"
					( Origin gPackager )
				)
				( objectStatus "EU1A1.4" )
			)
			( pin "@baseboard_fab2_lib.baseboard_fab2(sch_1):page227_i102:vin(0)"
				( attribute "PN" "25"
					( Origin gPackager )
				)
				( objectStatus "EU1A1.25" )
			)
			( pin "@baseboard_fab2_lib.baseboard_fab2(sch_1):page227_i102:vin(1)"
				( attribute "PN" "30"
					( Origin gPackager )
				)
				( objectStatus "EU1A1.30" )
			)
			( pin "@baseboard_fab2_lib.baseboard_fab2(sch_1):page227_i102:vos"
				( attribute "PN" "1"
					( Origin gPackager )
				)
				( objectStatus "EU1A1.1" )
			)
			( pin "@baseboard_fab2_lib.baseboard_fab2(sch_1):page227_i103:a"
				( attribute "PN" "1"
					( Origin gPackager )
				)
				( objectStatus "R1A3.1" )
			)
			( pin "@baseboard_fab2_lib.baseboard_fab2(sch_1):page227_i103:b"
				( attribute "PN" "2"
					( Origin gPackager )
				)
				( objectStatus "R1A3.2" )
			)
			( pin "@baseboard_fab2_lib.baseboard_fab2(sch_1):page227_i105:a"
				( attribute "PN" "1"
					( Origin gPackager )
				)
				( objectStatus "R1A2.1" )
			)
			( pin "@baseboard_fab2_lib.baseboard_fab2(sch_1):page227_i105:b"
				( attribute "PN" "2"
					( Origin gPackager )
				)
				( objectStatus "R1A2.2" )
			)
			( pin "@baseboard_fab2_lib.baseboard_fab2(sch_1):page228_i58:a"
				( attribute "PN" "1"
					( Origin gPackager )
				)
				( objectStatus "R1A1.1" )
			)
			( pin "@baseboard_fab2_lib.baseboard_fab2(sch_1):page228_i58:b"
				( attribute "PN" "2"
					( Origin gPackager )
				)
				( objectStatus "R1A1.2" )
			)
			( pin "@baseboard_fab2_lib.baseboard_fab2(sch_1):page228_i74:a"
				( attribute "PN" "1"
					( Origin gPackager )
				)
				( objectStatus "R7L2.1" )
			)
			( pin "@baseboard_fab2_lib.baseboard_fab2(sch_1):page228_i74:b"
				( attribute "PN" "2"
					( Origin gPackager )
				)
				( objectStatus "R7L2.2" )
			)
			( pin "@baseboard_fab2_lib.baseboard_fab2(sch_1):page228_i75:a"
				( attribute "PN" "1"
					( Origin gPackager )
				)
				( objectStatus "C9L9.1" )
			)
			( pin "@baseboard_fab2_lib.baseboard_fab2(sch_1):page228_i75:b"
				( attribute "PN" "2"
					( Origin gPackager )
				)
				( objectStatus "C9L9.2" )
			)
			( pin "@baseboard_fab2_lib.baseboard_fab2(sch_1):page228_i76:a"
				( attribute "PN" "1"
					( Origin gPackager )
				)
				( objectStatus "C9L12.1" )
			)
			( pin "@baseboard_fab2_lib.baseboard_fab2(sch_1):page228_i76:b"
				( attribute "PN" "2"
					( Origin gPackager )
				)
				( objectStatus "C9L12.2" )
			)
			( pin "@baseboard_fab2_lib.baseboard_fab2(sch_1):page228_i77:a"
				( attribute "PN" "1"
					( Origin gPackager )
				)
				( objectStatus "C9L4.1" )
			)
			( pin "@baseboard_fab2_lib.baseboard_fab2(sch_1):page228_i77:b"
				( attribute "PN" "2"
					( Origin gPackager )
				)
				( objectStatus "C9L4.2" )
			)
			( pin "@baseboard_fab2_lib.baseboard_fab2(sch_1):page228_i78:a"
				( attribute "PN" "1"
					( Origin gPackager )
				)
				( objectStatus "C9L2.1" )
			)
			( pin "@baseboard_fab2_lib.baseboard_fab2(sch_1):page228_i78:b"
				( attribute "PN" "2"
					( Origin gPackager )
				)
				( objectStatus "C9L2.2" )
			)
			( pin "@baseboard_fab2_lib.baseboard_fab2(sch_1):page228_i310:a"
				( attribute "PN" "1"
					( Origin gPackager )
				)
				( objectStatus "C8L2.1" )
			)
			( pin "@baseboard_fab2_lib.baseboard_fab2(sch_1):page228_i310:b"
				( attribute "PN" "2"
					( Origin gPackager )
				)
				( objectStatus "C8L2.2" )
			)
			( pin "@baseboard_fab2_lib.baseboard_fab2(sch_1):page228_i311:a"
				( attribute "PN" "1"
					( Origin gPackager )
				)
				( objectStatus "C8M11.1" )
			)
			( pin "@baseboard_fab2_lib.baseboard_fab2(sch_1):page228_i311:b"
				( attribute "PN" "2"
					( Origin gPackager )
				)
				( objectStatus "C8M11.2" )
			)
			( pin "@baseboard_fab2_lib.baseboard_fab2(sch_1):page229_i42:a"
				( attribute "PN" "1"
					( Origin gPackager )
				)
				( objectStatus "C8U10.1" )
			)
			( pin "@baseboard_fab2_lib.baseboard_fab2(sch_1):page229_i42:b"
				( attribute "PN" "2"
					( Origin gPackager )
				)
				( objectStatus "C8U10.2" )
			)
			( pin "@baseboard_fab2_lib.baseboard_fab2(sch_1):page228_i314:a"
				( attribute "PN" "1"
					( Origin gPackager )
				)
				( objectStatus "C7L1.1" )
			)
			( pin "@baseboard_fab2_lib.baseboard_fab2(sch_1):page228_i314:b"
				( attribute "PN" "2"
					( Origin gPackager )
				)
				( objectStatus "C7L1.2" )
			)
			( pin "@baseboard_fab2_lib.baseboard_fab2(sch_1):page229_i41:a"
				( attribute "PN" "1"
					( Origin gPackager )
				)
				( objectStatus "C8T3.1" )
			)
			( pin "@baseboard_fab2_lib.baseboard_fab2(sch_1):page229_i41:b"
				( attribute "PN" "2"
					( Origin gPackager )
				)
				( objectStatus "C8T3.2" )
			)
			( pin "@baseboard_fab2_lib.baseboard_fab2(sch_1):page228_i307:a"
				( attribute "PN" "1"
					( Origin gPackager )
				)
				( objectStatus "C8P4.1" )
			)
			( pin "@baseboard_fab2_lib.baseboard_fab2(sch_1):page228_i307:b"
				( attribute "PN" "2"
					( Origin gPackager )
				)
				( objectStatus "C8P4.2" )
			)
			( pin "@baseboard_fab2_lib.baseboard_fab2(sch_1):page228_i175:a"
				( attribute "PN" "1"
					( Origin gPackager )
				)
				( objectStatus "C1B10.1" )
			)
			( pin "@baseboard_fab2_lib.baseboard_fab2(sch_1):page228_i175:b"
				( attribute "PN" "2"
					( Origin gPackager )
				)
				( objectStatus "C1B10.2" )
			)
			( pin "@baseboard_fab2_lib.baseboard_fab2(sch_1):page228_i312:a"
				( attribute "PN" "1"
					( Origin gPackager )
				)
				( objectStatus "C8M7.1" )
			)
			( pin "@baseboard_fab2_lib.baseboard_fab2(sch_1):page228_i312:b"
				( attribute "PN" "2"
					( Origin gPackager )
				)
				( objectStatus "C8M7.2" )
			)
			( pin "@baseboard_fab2_lib.baseboard_fab2(sch_1):page228_i308:a"
				( attribute "PN" "1"
					( Origin gPackager )
				)
				( objectStatus "C7P1.1" )
			)
			( pin "@baseboard_fab2_lib.baseboard_fab2(sch_1):page228_i308:b"
				( attribute "PN" "2"
					( Origin gPackager )
				)
				( objectStatus "C7P1.2" )
			)
			( pin "@baseboard_fab2_lib.baseboard_fab2(sch_1):page228_i271:a"
				( attribute "PN" "1"
					( Origin gPackager )
				)
				( objectStatus "C2A15.1" )
			)
			( pin "@baseboard_fab2_lib.baseboard_fab2(sch_1):page228_i271:b"
				( attribute "PN" "2"
					( Origin gPackager )
				)
				( objectStatus "C2A15.2" )
			)
			( pin "@baseboard_fab2_lib.baseboard_fab2(sch_1):page228_i270:a"
				( attribute "PN" "1"
					( Origin gPackager )
				)
				( objectStatus "C3A5.1" )
			)
			( pin "@baseboard_fab2_lib.baseboard_fab2(sch_1):page228_i270:b"
				( attribute "PN" "2"
					( Origin gPackager )
				)
				( objectStatus "C3A5.2" )
			)
			( pin "@baseboard_fab2_lib.baseboard_fab2(sch_1):page228_i269:a"
				( attribute "PN" "1"
					( Origin gPackager )
				)
				( objectStatus "C3A6.1" )
			)
			( pin "@baseboard_fab2_lib.baseboard_fab2(sch_1):page228_i269:b"
				( attribute "PN" "2"
					( Origin gPackager )
				)
				( objectStatus "C3A6.2" )
			)
			( pin "@baseboard_fab2_lib.baseboard_fab2(sch_1):page228_i268:a"
				( attribute "PN" "1"
					( Origin gPackager )
				)
				( objectStatus "C7L5.1" )
			)
			( pin "@baseboard_fab2_lib.baseboard_fab2(sch_1):page228_i268:b"
				( attribute "PN" "2"
					( Origin gPackager )
				)
				( objectStatus "C7L5.2" )
			)
			( pin "@baseboard_fab2_lib.baseboard_fab2(sch_1):page228_i198:a"
				( attribute "PN" "1"
					( Origin gPackager )
				)
				( objectStatus "C8M8.1" )
			)
			( pin "@baseboard_fab2_lib.baseboard_fab2(sch_1):page228_i198:b"
				( attribute "PN" "2"
					( Origin gPackager )
				)
				( objectStatus "C8M8.2" )
			)
			( pin "@baseboard_fab2_lib.baseboard_fab2(sch_1):page228_i199:a"
				( attribute "PN" "1"
					( Origin gPackager )
				)
				( objectStatus "C2A5.1" )
			)
			( pin "@baseboard_fab2_lib.baseboard_fab2(sch_1):page228_i199:b"
				( attribute "PN" "2"
					( Origin gPackager )
				)
				( objectStatus "C2A5.2" )
			)
			( pin "@baseboard_fab2_lib.baseboard_fab2(sch_1):page228_i200:a"
				( attribute "PN" "1"
					( Origin gPackager )
				)
				( objectStatus "C2B1.1" )
			)
			( pin "@baseboard_fab2_lib.baseboard_fab2(sch_1):page228_i200:b"
				( attribute "PN" "2"
					( Origin gPackager )
				)
				( objectStatus "C2B1.2" )
			)
			( pin "@baseboard_fab2_lib.baseboard_fab2(sch_1):page228_i201:a"
				( attribute "PN" "1"
					( Origin gPackager )
				)
				( objectStatus "C8L12.1" )
			)
			( pin "@baseboard_fab2_lib.baseboard_fab2(sch_1):page228_i201:b"
				( attribute "PN" "2"
					( Origin gPackager )
				)
				( objectStatus "C8L12.2" )
			)
			( pin "@baseboard_fab2_lib.baseboard_fab2(sch_1):page228_i202:a"
				( attribute "PN" "1"
					( Origin gPackager )
				)
				( objectStatus "C7M5.1" )
			)
			( pin "@baseboard_fab2_lib.baseboard_fab2(sch_1):page228_i202:b"
				( attribute "PN" "2"
					( Origin gPackager )
				)
				( objectStatus "C7M5.2" )
			)
			( pin "@baseboard_fab2_lib.baseboard_fab2(sch_1):page228_i203:a"
				( attribute "PN" "1"
					( Origin gPackager )
				)
				( objectStatus "C8M10.1" )
			)
			( pin "@baseboard_fab2_lib.baseboard_fab2(sch_1):page228_i203:b"
				( attribute "PN" "2"
					( Origin gPackager )
				)
				( objectStatus "C8M10.2" )
			)
			( pin "@baseboard_fab2_lib.baseboard_fab2(sch_1):page228_i204:a"
				( attribute "PN" "1"
					( Origin gPackager )
				)
				( objectStatus "C2B2.1" )
			)
			( pin "@baseboard_fab2_lib.baseboard_fab2(sch_1):page228_i204:b"
				( attribute "PN" "2"
					( Origin gPackager )
				)
				( objectStatus "C2B2.2" )
			)
			( pin "@baseboard_fab2_lib.baseboard_fab2(sch_1):page228_i205:a"
				( attribute "PN" "1"
					( Origin gPackager )
				)
				( objectStatus "C8M9.1" )
			)
			( pin "@baseboard_fab2_lib.baseboard_fab2(sch_1):page228_i205:b"
				( attribute "PN" "2"
					( Origin gPackager )
				)
				( objectStatus "C8M9.2" )
			)
			( pin "@baseboard_fab2_lib.baseboard_fab2(sch_1):page228_i206:a"
				( attribute "PN" "1"
					( Origin gPackager )
				)
				( objectStatus "C8M2.1" )
			)
			( pin "@baseboard_fab2_lib.baseboard_fab2(sch_1):page228_i206:b"
				( attribute "PN" "2"
					( Origin gPackager )
				)
				( objectStatus "C8M2.2" )
			)
			( pin "@baseboard_fab2_lib.baseboard_fab2(sch_1):page228_i299:a"
				( attribute "PN" "1"
					( Origin gPackager )
				)
				( objectStatus "C8M3.1" )
			)
			( pin "@baseboard_fab2_lib.baseboard_fab2(sch_1):page228_i299:b"
				( attribute "PN" "2"
					( Origin gPackager )
				)
				( objectStatus "C8M3.2" )
			)
			( pin "@baseboard_fab2_lib.baseboard_fab2(sch_1):page228_i298:a"
				( attribute "PN" "1"
					( Origin gPackager )
				)
				( objectStatus "C8M5.1" )
			)
			( pin "@baseboard_fab2_lib.baseboard_fab2(sch_1):page228_i298:b"
				( attribute "PN" "2"
					( Origin gPackager )
				)
				( objectStatus "C8M5.2" )
			)
			( pin "@baseboard_fab2_lib.baseboard_fab2(sch_1):page228_i297:a"
				( attribute "PN" "1"
					( Origin gPackager )
				)
				( objectStatus "C8L10.1" )
			)
			( pin "@baseboard_fab2_lib.baseboard_fab2(sch_1):page228_i297:b"
				( attribute "PN" "2"
					( Origin gPackager )
				)
				( objectStatus "C8L10.2" )
			)
			( pin "@baseboard_fab2_lib.baseboard_fab2(sch_1):page228_i296:a"
				( attribute "PN" "1"
					( Origin gPackager )
				)
				( objectStatus "C2A3.1" )
			)
			( pin "@baseboard_fab2_lib.baseboard_fab2(sch_1):page228_i296:b"
				( attribute "PN" "2"
					( Origin gPackager )
				)
				( objectStatus "C2A3.2" )
			)
			( pin "@baseboard_fab2_lib.baseboard_fab2(sch_1):page228_i295:a"
				( attribute "PN" "1"
					( Origin gPackager )
				)
				( objectStatus "C7M1.1" )
			)
			( pin "@baseboard_fab2_lib.baseboard_fab2(sch_1):page228_i295:b"
				( attribute "PN" "2"
					( Origin gPackager )
				)
				( objectStatus "C7M1.2" )
			)
			( pin "@baseboard_fab2_lib.baseboard_fab2(sch_1):page228_i294:a"
				( attribute "PN" "1"
					( Origin gPackager )
				)
				( objectStatus "C7M2.1" )
			)
			( pin "@baseboard_fab2_lib.baseboard_fab2(sch_1):page228_i294:b"
				( attribute "PN" "2"
					( Origin gPackager )
				)
				( objectStatus "C7M2.2" )
			)
			( pin "@baseboard_fab2_lib.baseboard_fab2(sch_1):page228_i293:a"
				( attribute "PN" "1"
					( Origin gPackager )
				)
				( objectStatus "C8M4.1" )
			)
			( pin "@baseboard_fab2_lib.baseboard_fab2(sch_1):page228_i293:b"
				( attribute "PN" "2"
					( Origin gPackager )
				)
				( objectStatus "C8M4.2" )
			)
			( pin "@baseboard_fab2_lib.baseboard_fab2(sch_1):page228_i292:a"
				( attribute "PN" "1"
					( Origin gPackager )
				)
				( objectStatus "C2A4.1" )
			)
			( pin "@baseboard_fab2_lib.baseboard_fab2(sch_1):page228_i292:b"
				( attribute "PN" "2"
					( Origin gPackager )
				)
				( objectStatus "C2A4.2" )
			)
			( pin "@baseboard_fab2_lib.baseboard_fab2(sch_1):page228_i291:a"
				( attribute "PN" "1"
					( Origin gPackager )
				)
				( objectStatus "C8M6.1" )
			)
			( pin "@baseboard_fab2_lib.baseboard_fab2(sch_1):page228_i291:b"
				( attribute "PN" "2"
					( Origin gPackager )
				)
				( objectStatus "C8M6.2" )
			)
			( pin "@baseboard_fab2_lib.baseboard_fab2(sch_1):page228_i290:a"
				( attribute "PN" "1"
					( Origin gPackager )
				)
				( objectStatus "C8L9.1" )
			)
			( pin "@baseboard_fab2_lib.baseboard_fab2(sch_1):page228_i290:b"
				( attribute "PN" "2"
					( Origin gPackager )
				)
				( objectStatus "C8L9.2" )
			)
			( pin "@baseboard_fab2_lib.baseboard_fab2(sch_1):page228_i289:a"
				( attribute "PN" "1"
					( Origin gPackager )
				)
				( objectStatus "C8L8.1" )
			)
			( pin "@baseboard_fab2_lib.baseboard_fab2(sch_1):page228_i289:b"
				( attribute "PN" "2"
					( Origin gPackager )
				)
				( objectStatus "C8L8.2" )
			)
			( pin "@baseboard_fab2_lib.baseboard_fab2(sch_1):page228_i288:a"
				( attribute "PN" "1"
					( Origin gPackager )
				)
				( objectStatus "C7L4.1" )
			)
			( pin "@baseboard_fab2_lib.baseboard_fab2(sch_1):page228_i288:b"
				( attribute "PN" "2"
					( Origin gPackager )
				)
				( objectStatus "C7L4.2" )
			)
			( pin "@baseboard_fab2_lib.baseboard_fab2(sch_1):page228_i287:a"
				( attribute "PN" "1"
					( Origin gPackager )
				)
				( objectStatus "C8L7.1" )
			)
			( pin "@baseboard_fab2_lib.baseboard_fab2(sch_1):page228_i287:b"
				( attribute "PN" "2"
					( Origin gPackager )
				)
				( objectStatus "C8L7.2" )
			)
			( pin "@baseboard_fab2_lib.baseboard_fab2(sch_1):page228_i286:a"
				( attribute "PN" "1"
					( Origin gPackager )
				)
				( objectStatus "C8L6.1" )
			)
			( pin "@baseboard_fab2_lib.baseboard_fab2(sch_1):page228_i286:b"
				( attribute "PN" "2"
					( Origin gPackager )
				)
				( objectStatus "C8L6.2" )
			)
			( pin "@baseboard_fab2_lib.baseboard_fab2(sch_1):page228_i285:a"
				( attribute "PN" "1"
					( Origin gPackager )
				)
				( objectStatus "C8L5.1" )
			)
			( pin "@baseboard_fab2_lib.baseboard_fab2(sch_1):page228_i285:b"
				( attribute "PN" "2"
					( Origin gPackager )
				)
				( objectStatus "C8L5.2" )
			)
			( pin "@baseboard_fab2_lib.baseboard_fab2(sch_1):page228_i284:a"
				( attribute "PN" "1"
					( Origin gPackager )
				)
				( objectStatus "C8M1.1" )
			)
			( pin "@baseboard_fab2_lib.baseboard_fab2(sch_1):page228_i284:b"
				( attribute "PN" "2"
					( Origin gPackager )
				)
				( objectStatus "C8M1.2" )
			)
			( pin "@baseboard_fab2_lib.baseboard_fab2(sch_1):page228_i245:a"
				( attribute "PN" "1"
					( Origin gPackager )
				)
				( objectStatus "SH7L2.1" )
			)
			( pin "@baseboard_fab2_lib.baseboard_fab2(sch_1):page228_i245:b"
				( attribute "PN" "2"
					( Origin gPackager )
				)
				( objectStatus "SH7L2.2" )
			)
			( pin "@baseboard_fab2_lib.baseboard_fab2(sch_1):page228_i246:a"
				( attribute "PN" "1"
					( Origin gPackager )
				)
				( objectStatus "SH7L1.1" )
			)
			( pin "@baseboard_fab2_lib.baseboard_fab2(sch_1):page228_i246:b"
				( attribute "PN" "2"
					( Origin gPackager )
				)
				( objectStatus "SH7L1.2" )
			)
			( pin "@baseboard_fab2_lib.baseboard_fab2(sch_1):page229_i14:a"
				( attribute "PN" "1"
					( Origin gPackager )
				)
				( objectStatus "C6U11.1" )
			)
			( pin "@baseboard_fab2_lib.baseboard_fab2(sch_1):page229_i14:b"
				( attribute "PN" "2"
					( Origin gPackager )
				)
				( objectStatus "C6U11.2" )
			)
			( pin "@baseboard_fab2_lib.baseboard_fab2(sch_1):page226_i49:a"
				( attribute "PN" "1"
					( Origin gPackager )
				)
				( objectStatus "R1B1.1" )
			)
			( pin "@baseboard_fab2_lib.baseboard_fab2(sch_1):page226_i49:b"
				( attribute "PN" "2"
					( Origin gPackager )
				)
				( objectStatus "R1B1.2" )
			)
			( pin "@baseboard_fab2_lib.baseboard_fab2(sch_1):page226_i48:a"
				( attribute "PN" "1"
					( Origin gPackager )
				)
				( objectStatus "R1B11.1" )
			)
			( pin "@baseboard_fab2_lib.baseboard_fab2(sch_1):page226_i48:b"
				( attribute "PN" "2"
					( Origin gPackager )
				)
				( objectStatus "R1B11.2" )
			)
			( pin "@baseboard_fab2_lib.baseboard_fab2(sch_1):page229_i21:a"
				( attribute "PN" "1"
					( Origin gPackager )
				)
				( objectStatus "C4G21.1" )
			)
			( pin "@baseboard_fab2_lib.baseboard_fab2(sch_1):page229_i21:b"
				( attribute "PN" "2"
					( Origin gPackager )
				)
				( objectStatus "C4G21.2" )
			)
			( pin "@baseboard_fab2_lib.baseboard_fab2(sch_1):page229_i24:a"
				( attribute "PN" "1"
					( Origin gPackager )
				)
				( objectStatus "R4G17.1" )
			)
			( pin "@baseboard_fab2_lib.baseboard_fab2(sch_1):page229_i24:b"
				( attribute "PN" "2"
					( Origin gPackager )
				)
				( objectStatus "R4G17.2" )
			)
			( pin "@baseboard_fab2_lib.baseboard_fab2(sch_1):page226_i46:a"
				( attribute "PN" "1"
					( Origin gPackager )
				)
				( objectStatus "R12W35.1" )
			)
			( pin "@baseboard_fab2_lib.baseboard_fab2(sch_1):page226_i46:b"
				( attribute "PN" "2"
					( Origin gPackager )
				)
				( objectStatus "R12W35.2" )
			)
			( pin "@baseboard_fab2_lib.baseboard_fab2(sch_1):page226_i45:a"
				( attribute "PN" "1"
					( Origin gPackager )
				)
				( objectStatus "C1B3.1" )
			)
			( pin "@baseboard_fab2_lib.baseboard_fab2(sch_1):page226_i45:b"
				( attribute "PN" "2"
					( Origin gPackager )
				)
				( objectStatus "C1B3.2" )
			)
			( pin "@baseboard_fab2_lib.baseboard_fab2(sch_1):page229_i32:a"
				( attribute "PN" "1"
					( Origin gPackager )
				)
				( objectStatus "R4G15.1" )
			)
			( pin "@baseboard_fab2_lib.baseboard_fab2(sch_1):page229_i32:b"
				( attribute "PN" "2"
					( Origin gPackager )
				)
				( objectStatus "R4G15.2" )
			)
			( pin "@baseboard_fab2_lib.baseboard_fab2(sch_1):page226_i40:a"
				( attribute "PN" "1"
					( Origin gPackager )
				)
				( objectStatus "C1B4.1" )
			)
			( pin "@baseboard_fab2_lib.baseboard_fab2(sch_1):page226_i40:b"
				( attribute "PN" "2"
					( Origin gPackager )
				)
				( objectStatus "C1B4.2" )
			)
			( pin "@baseboard_fab2_lib.baseboard_fab2(sch_1):page226_i38:a"
				( attribute "PN" "1"
					( Origin gPackager )
				)
				( objectStatus "C1B6.1" )
			)
			( pin "@baseboard_fab2_lib.baseboard_fab2(sch_1):page226_i38:b"
				( attribute "PN" "2"
					( Origin gPackager )
				)
				( objectStatus "C1B6.2" )
			)
			( pin "@baseboard_fab2_lib.baseboard_fab2(sch_1):page226_i34:a"
				( attribute "PN" "1"
					( Origin gPackager )
				)
				( objectStatus "R9M5.1" )
			)
			( pin "@baseboard_fab2_lib.baseboard_fab2(sch_1):page226_i34:b"
				( attribute "PN" "2"
					( Origin gPackager )
				)
				( objectStatus "R9M5.2" )
			)
			( pin "@baseboard_fab2_lib.baseboard_fab2(sch_1):page223_i70:a"
				( attribute "PN" "1"
					( Origin gPackager )
				)
				( objectStatus "R9U4.1" )
			)
			( pin "@baseboard_fab2_lib.baseboard_fab2(sch_1):page223_i70:b"
				( attribute "PN" "2"
					( Origin gPackager )
				)
				( objectStatus "R9U4.2" )
			)
			( pin "@baseboard_fab2_lib.baseboard_fab2(sch_1):page226_i19:a"
				( attribute "PN" "1"
					( Origin gPackager )
				)
				( objectStatus "R1B8.1" )
			)
			( pin "@baseboard_fab2_lib.baseboard_fab2(sch_1):page226_i19:b"
				( attribute "PN" "2"
					( Origin gPackager )
				)
				( objectStatus "R1B8.2" )
			)
			( pin "@baseboard_fab2_lib.baseboard_fab2(sch_1):page226_i18:a"
				( attribute "PN" "1"
					( Origin gPackager )
				)
				( objectStatus "RF22.1" )
			)
			( pin "@baseboard_fab2_lib.baseboard_fab2(sch_1):page226_i18:b"
				( attribute "PN" "2"
					( Origin gPackager )
				)
				( objectStatus "RF22.2" )
			)
			( pin "@baseboard_fab2_lib.baseboard_fab2(sch_1):page226_i15:\1\"
				( attribute "PN" "1"
					( Origin gPackager )
				)
				( objectStatus "CF21.1" )
			)
			( pin "@baseboard_fab2_lib.baseboard_fab2(sch_1):page226_i15:\2\"
				( attribute "PN" "2"
					( Origin gPackager )
				)
				( objectStatus "CF21.2" )
			)
			( pin "@baseboard_fab2_lib.baseboard_fab2(sch_1):page226_i12:a"
				( attribute "PN" "1"
					( Origin gPackager )
				)
				( objectStatus "C1B12.1" )
			)
			( pin "@baseboard_fab2_lib.baseboard_fab2(sch_1):page226_i12:b"
				( attribute "PN" "2"
					( Origin gPackager )
				)
				( objectStatus "C1B12.2" )
			)
			( pin "@baseboard_fab2_lib.baseboard_fab2(sch_1):page230_i17:a"
				( attribute "PN" "1"
					( Origin gPackager )
				)
				( objectStatus "C4A15.1" )
			)
			( pin "@baseboard_fab2_lib.baseboard_fab2(sch_1):page230_i17:b"
				( attribute "PN" "2"
					( Origin gPackager )
				)
				( objectStatus "C4A15.2" )
			)
			( pin "@baseboard_fab2_lib.baseboard_fab2(sch_1):page230_i21:a"
				( attribute "PN" "1"
					( Origin gPackager )
				)
				( objectStatus "R4A5.1" )
			)
			( pin "@baseboard_fab2_lib.baseboard_fab2(sch_1):page230_i21:b"
				( attribute "PN" "2"
					( Origin gPackager )
				)
				( objectStatus "R4A5.2" )
			)
			( pin "@baseboard_fab2_lib.baseboard_fab2(sch_1):page230_i30:a"
				( attribute "PN" "1"
					( Origin gPackager )
				)
				( objectStatus "SH8L1.1" )
			)
			( pin "@baseboard_fab2_lib.baseboard_fab2(sch_1):page230_i30:b"
				( attribute "PN" "2"
					( Origin gPackager )
				)
				( objectStatus "SH8L1.2" )
			)
			( pin "@baseboard_fab2_lib.baseboard_fab2(sch_1):page221_i45:a"
				( attribute "PN" "1"
					( Origin gPackager )
				)
				( objectStatus "C5U12.1" )
			)
			( pin "@baseboard_fab2_lib.baseboard_fab2(sch_1):page221_i45:b"
				( attribute "PN" "2"
					( Origin gPackager )
				)
				( objectStatus "C5U12.2" )
			)
			( pin "@baseboard_fab2_lib.baseboard_fab2(sch_1):page230_i37:agnd"
				( attribute "PN" "3"
					( Origin gPackager )
				)
				( objectStatus "EU4A2.3" )
			)
			( pin "@baseboard_fab2_lib.baseboard_fab2(sch_1):page230_i37:bias"
				( attribute "PN" "2"
					( Origin gPackager )
				)
				( objectStatus "EU4A2.2" )
			)
			( pin "@baseboard_fab2_lib.baseboard_fab2(sch_1):page230_i37:en"
				( attribute "PN" "7"
					( Origin gPackager )
				)
				( objectStatus "EU4A2.7" )
			)
			( pin "@baseboard_fab2_lib.baseboard_fab2(sch_1):page230_i37:pg"
				( attribute "PN" "5"
					( Origin gPackager )
				)
				( objectStatus "EU4A2.5" )
			)
			( pin "@baseboard_fab2_lib.baseboard_fab2(sch_1):page230_i37:pgnd"
				( attribute "PN" "8"
					( Origin gPackager )
				)
				( objectStatus "EU4A2.8" )
			)
			( pin "@baseboard_fab2_lib.baseboard_fab2(sch_1):page230_i37:sns"
				( attribute "PN" "6"
					( Origin gPackager )
				)
				( objectStatus "EU4A2.6" )
			)
			( pin "@baseboard_fab2_lib.baseboard_fab2(sch_1):page230_i37:thpad"
				( attribute "PN" "11"
					( Origin gPackager )
				)
				( objectStatus "EU4A2.11" )
			)
			( pin "@baseboard_fab2_lib.baseboard_fab2(sch_1):page230_i37:vddq"
				( attribute "PN" "4"
					( Origin gPackager )
				)
				( objectStatus "EU4A2.4" )
			)
			( pin "@baseboard_fab2_lib.baseboard_fab2(sch_1):page230_i37:vin"
				( attribute "PN" "10"
					( Origin gPackager )
				)
				( objectStatus "EU4A2.10" )
			)
			( pin "@baseboard_fab2_lib.baseboard_fab2(sch_1):page230_i37:vref"
				( attribute "PN" "1"
					( Origin gPackager )
				)
				( objectStatus "EU4A2.1" )
			)
			( pin "@baseboard_fab2_lib.baseboard_fab2(sch_1):page230_i37:vtt"
				( attribute "PN" "9"
					( Origin gPackager )
				)
				( objectStatus "EU4A2.9" )
			)
			( pin "@baseboard_fab2_lib.baseboard_fab2(sch_1):page231_i122:a"
				( attribute "PN" "1"
					( Origin gPackager )
				)
				( objectStatus "C6F6.1" )
			)
			( pin "@baseboard_fab2_lib.baseboard_fab2(sch_1):page231_i122:b"
				( attribute "PN" "2"
					( Origin gPackager )
				)
				( objectStatus "C6F6.2" )
			)
			( pin "@baseboard_fab2_lib.baseboard_fab2(sch_1):page231_i124:a"
				( attribute "PN" "1"
					( Origin gPackager )
				)
				( objectStatus "C4T6.1" )
			)
			( pin "@baseboard_fab2_lib.baseboard_fab2(sch_1):page231_i124:b"
				( attribute "PN" "2"
					( Origin gPackager )
				)
				( objectStatus "C4T6.2" )
			)
			( pin "@baseboard_fab2_lib.baseboard_fab2(sch_1):page231_i125:a"
				( attribute "PN" "1"
					( Origin gPackager )
				)
				( objectStatus "C4T5.1" )
			)
			( pin "@baseboard_fab2_lib.baseboard_fab2(sch_1):page231_i125:b"
				( attribute "PN" "2"
					( Origin gPackager )
				)
				( objectStatus "C4T5.2" )
			)
			( pin "@baseboard_fab2_lib.baseboard_fab2(sch_1):page231_i126:a"
				( attribute "PN" "1"
					( Origin gPackager )
				)
				( objectStatus "C6G1.1" )
			)
			( pin "@baseboard_fab2_lib.baseboard_fab2(sch_1):page231_i126:b"
				( attribute "PN" "2"
					( Origin gPackager )
				)
				( objectStatus "C6G1.2" )
			)
			( pin "@baseboard_fab2_lib.baseboard_fab2(sch_1):page231_i128:a"
				( attribute "PN" "1"
					( Origin gPackager )
				)
				( objectStatus "C6G2.1" )
			)
			( pin "@baseboard_fab2_lib.baseboard_fab2(sch_1):page231_i128:b"
				( attribute "PN" "2"
					( Origin gPackager )
				)
				( objectStatus "C6G2.2" )
			)
			( pin "@baseboard_fab2_lib.baseboard_fab2(sch_1):page231_i129:a"
				( attribute "PN" "1"
					( Origin gPackager )
				)
				( objectStatus "C4U2.1" )
			)
			( pin "@baseboard_fab2_lib.baseboard_fab2(sch_1):page231_i129:b"
				( attribute "PN" "2"
					( Origin gPackager )
				)
				( objectStatus "C4U2.2" )
			)
			( pin "@baseboard_fab2_lib.baseboard_fab2(sch_1):page231_i130:a"
				( attribute "PN" "1"
					( Origin gPackager )
				)
				( objectStatus "C4U1.1" )
			)
			( pin "@baseboard_fab2_lib.baseboard_fab2(sch_1):page231_i130:b"
				( attribute "PN" "2"
					( Origin gPackager )
				)
				( objectStatus "C4U1.2" )
			)
			( pin "@baseboard_fab2_lib.baseboard_fab2(sch_1):page231_i131:a"
				( attribute "PN" "1"
					( Origin gPackager )
				)
				( objectStatus "C6G4.1" )
			)
			( pin "@baseboard_fab2_lib.baseboard_fab2(sch_1):page231_i131:b"
				( attribute "PN" "2"
					( Origin gPackager )
				)
				( objectStatus "C6G4.2" )
			)
			( pin "@baseboard_fab2_lib.baseboard_fab2(sch_1):page231_i134:a"
				( attribute "PN" "1"
					( Origin gPackager )
				)
				( objectStatus "R7F15.1" )
			)
			( pin "@baseboard_fab2_lib.baseboard_fab2(sch_1):page231_i134:b"
				( attribute "PN" "2"
					( Origin gPackager )
				)
				( objectStatus "R7F15.2" )
			)
			( pin "@baseboard_fab2_lib.baseboard_fab2(sch_1):page231_i136:a"
				( attribute "PN" "1"
					( Origin gPackager )
				)
				( objectStatus "R7F14.1" )
			)
			( pin "@baseboard_fab2_lib.baseboard_fab2(sch_1):page231_i136:b"
				( attribute "PN" "2"
					( Origin gPackager )
				)
				( objectStatus "R7F14.2" )
			)
			( pin "@baseboard_fab2_lib.baseboard_fab2(sch_1):page231_i140:a"
				( attribute "PN" "1"
					( Origin gPackager )
				)
				( objectStatus "C7F8.1" )
			)
			( pin "@baseboard_fab2_lib.baseboard_fab2(sch_1):page231_i140:b"
				( attribute "PN" "2"
					( Origin gPackager )
				)
				( objectStatus "C7F8.2" )
			)
			( pin "@baseboard_fab2_lib.baseboard_fab2(sch_1):page231_i142:a"
				( attribute "PN" "1"
					( Origin gPackager )
				)
				( objectStatus "C7F11.1" )
			)
			( pin "@baseboard_fab2_lib.baseboard_fab2(sch_1):page231_i142:b"
				( attribute "PN" "2"
					( Origin gPackager )
				)
				( objectStatus "C7F11.2" )
			)
			( pin "@baseboard_fab2_lib.baseboard_fab2(sch_1):page231_i143:a"
				( attribute "PN" "1"
					( Origin gPackager )
				)
				( objectStatus "R7F19.1" )
			)
			( pin "@baseboard_fab2_lib.baseboard_fab2(sch_1):page231_i143:b"
				( attribute "PN" "2"
					( Origin gPackager )
				)
				( objectStatus "R7F19.2" )
			)
			( pin "@baseboard_fab2_lib.baseboard_fab2(sch_1):page231_i145:a"
				( attribute "PN" "1"
					( Origin gPackager )
				)
				( objectStatus "C6G5.1" )
			)
			( pin "@baseboard_fab2_lib.baseboard_fab2(sch_1):page231_i145:b"
				( attribute "PN" "2"
					( Origin gPackager )
				)
				( objectStatus "C6G5.2" )
			)
			( pin "@baseboard_fab2_lib.baseboard_fab2(sch_1):page231_i146:a"
				( attribute "PN" "1"
					( Origin gPackager )
				)
				( objectStatus "C4U4.1" )
			)
			( pin "@baseboard_fab2_lib.baseboard_fab2(sch_1):page231_i146:b"
				( attribute "PN" "2"
					( Origin gPackager )
				)
				( objectStatus "C4U4.2" )
			)
			( pin "@baseboard_fab2_lib.baseboard_fab2(sch_1):page231_i148:a"
				( attribute "PN" "1"
					( Origin gPackager )
				)
				( objectStatus "C4U3.1" )
			)
			( pin "@baseboard_fab2_lib.baseboard_fab2(sch_1):page231_i148:b"
				( attribute "PN" "2"
					( Origin gPackager )
				)
				( objectStatus "C4U3.2" )
			)
			( pin "@baseboard_fab2_lib.baseboard_fab2(sch_1):page231_i149:a"
				( attribute "PN" "1"
					( Origin gPackager )
				)
				( objectStatus "C6F5.1" )
			)
			( pin "@baseboard_fab2_lib.baseboard_fab2(sch_1):page231_i149:b"
				( attribute "PN" "2"
					( Origin gPackager )
				)
				( objectStatus "C6F5.2" )
			)
			( pin "@baseboard_fab2_lib.baseboard_fab2(sch_1):page240_i183:\1\"
				( attribute "PN" "1"
					( Origin gPackager )
				)
				( objectStatus "C8E11.1" )
			)
			( pin "@baseboard_fab2_lib.baseboard_fab2(sch_1):page240_i183:\2\"
				( attribute "PN" "2"
					( Origin gPackager )
				)
				( objectStatus "C8E11.2" )
			)
			( pin "@baseboard_fab2_lib.baseboard_fab2(sch_1):page232_i313:a"
				( attribute "PN" "1"
					( Origin gPackager )
				)
				( objectStatus "R7B19.1" )
			)
			( pin "@baseboard_fab2_lib.baseboard_fab2(sch_1):page232_i313:b"
				( attribute "PN" "2"
					( Origin gPackager )
				)
				( objectStatus "R7B19.2" )
			)
			( pin "@baseboard_fab2_lib.baseboard_fab2(sch_1):page231_i159:a"
				( attribute "PN" "1"
					( Origin gPackager )
				)
				( objectStatus "C7F4.1" )
			)
			( pin "@baseboard_fab2_lib.baseboard_fab2(sch_1):page231_i159:b"
				( attribute "PN" "2"
					( Origin gPackager )
				)
				( objectStatus "C7F4.2" )
			)
			( pin "@baseboard_fab2_lib.baseboard_fab2(sch_1):page231_i161:a"
				( attribute "PN" "1"
					( Origin gPackager )
				)
				( objectStatus "C3T10.1" )
			)
			( pin "@baseboard_fab2_lib.baseboard_fab2(sch_1):page231_i161:b"
				( attribute "PN" "2"
					( Origin gPackager )
				)
				( objectStatus "C3T10.2" )
			)
			( pin "@baseboard_fab2_lib.baseboard_fab2(sch_1):page231_i162:a"
				( attribute "PN" "1"
					( Origin gPackager )
				)
				( objectStatus "FB7F1.1" )
			)
			( pin "@baseboard_fab2_lib.baseboard_fab2(sch_1):page231_i162:b"
				( attribute "PN" "2"
					( Origin gPackager )
				)
				( objectStatus "FB7F1.2" )
			)
			( pin "@baseboard_fab2_lib.baseboard_fab2(sch_1):page232_i314:a"
				( attribute "PN" "1"
					( Origin gPackager )
				)
				( objectStatus "R7B13.1" )
			)
			( pin "@baseboard_fab2_lib.baseboard_fab2(sch_1):page232_i314:b"
				( attribute "PN" "2"
					( Origin gPackager )
				)
				( objectStatus "R7B13.2" )
			)
			( pin "@baseboard_fab2_lib.baseboard_fab2(sch_1):page231_i167:a"
				( attribute "PN" "1"
					( Origin gPackager )
				)
				( objectStatus "R7F13.1" )
			)
			( pin "@baseboard_fab2_lib.baseboard_fab2(sch_1):page231_i167:b"
				( attribute "PN" "2"
					( Origin gPackager )
				)
				( objectStatus "R7F13.2" )
			)
			( pin "@baseboard_fab2_lib.baseboard_fab2(sch_1):page231_i168:a"
				( attribute "PN" "1"
					( Origin gPackager )
				)
				( objectStatus "R7F12.1" )
			)
			( pin "@baseboard_fab2_lib.baseboard_fab2(sch_1):page231_i168:b"
				( attribute "PN" "2"
					( Origin gPackager )
				)
				( objectStatus "R7F12.2" )
			)
			( pin "@baseboard_fab2_lib.baseboard_fab2(sch_1):page231_i170:a"
				( attribute "PN" "1"
					( Origin gPackager )
				)
				( objectStatus "R7F35.1" )
			)
			( pin "@baseboard_fab2_lib.baseboard_fab2(sch_1):page231_i170:b"
				( attribute "PN" "2"
					( Origin gPackager )
				)
				( objectStatus "R7F35.2" )
			)
			( pin "@baseboard_fab2_lib.baseboard_fab2(sch_1):page231_i174:a"
				( attribute "PN" "1"
					( Origin gPackager )
				)
				( objectStatus "R7F7.1" )
			)
			( pin "@baseboard_fab2_lib.baseboard_fab2(sch_1):page231_i174:b"
				( attribute "PN" "2"
					( Origin gPackager )
				)
				( objectStatus "R7F7.2" )
			)
			( pin "@baseboard_fab2_lib.baseboard_fab2(sch_1):page231_i175:a"
				( attribute "PN" "1"
					( Origin gPackager )
				)
				( objectStatus "C7F3.1" )
			)
			( pin "@baseboard_fab2_lib.baseboard_fab2(sch_1):page231_i175:b"
				( attribute "PN" "2"
					( Origin gPackager )
				)
				( objectStatus "C7F3.2" )
			)
			( pin "@baseboard_fab2_lib.baseboard_fab2(sch_1):page231_i177:a"
				( attribute "PN" "1"
					( Origin gPackager )
				)
				( objectStatus "R7F10.1" )
			)
			( pin "@baseboard_fab2_lib.baseboard_fab2(sch_1):page231_i177:b"
				( attribute "PN" "2"
					( Origin gPackager )
				)
				( objectStatus "R7F10.2" )
			)
			( pin "@baseboard_fab2_lib.baseboard_fab2(sch_1):page231_i178:ina"
				( attribute "PN" "1"
					( Origin gPackager )
				)
				( objectStatus "L7F1.1" )
			)
			( pin "@baseboard_fab2_lib.baseboard_fab2(sch_1):page231_i178:inb"
				( attribute "PN" "2"
					( Origin gPackager )
				)
				( objectStatus "L7F1.2" )
			)
			( pin "@baseboard_fab2_lib.baseboard_fab2(sch_1):page231_i180:a"
				( attribute "PN" "1"
					( Origin gPackager )
				)
				( objectStatus "C6F4.1" )
			)
			( pin "@baseboard_fab2_lib.baseboard_fab2(sch_1):page231_i180:b"
				( attribute "PN" "2"
					( Origin gPackager )
				)
				( objectStatus "C6F4.2" )
			)
			( pin "@baseboard_fab2_lib.baseboard_fab2(sch_1):page231_i184:a"
				( attribute "PN" "1"
					( Origin gPackager )
				)
				( objectStatus "C3T7.1" )
			)
			( pin "@baseboard_fab2_lib.baseboard_fab2(sch_1):page231_i184:b"
				( attribute "PN" "2"
					( Origin gPackager )
				)
				( objectStatus "C3T7.2" )
			)
			( pin "@baseboard_fab2_lib.baseboard_fab2(sch_1):page231_i186:a"
				( attribute "PN" "1"
					( Origin gPackager )
				)
				( objectStatus "C3T9.1" )
			)
			( pin "@baseboard_fab2_lib.baseboard_fab2(sch_1):page231_i186:b"
				( attribute "PN" "2"
					( Origin gPackager )
				)
				( objectStatus "C3T9.2" )
			)
			( pin "@baseboard_fab2_lib.baseboard_fab2(sch_1):page231_i193:agnd"
				( attribute "PN" "5"
					( Origin gPackager )
				)
				( objectStatus "EU7F1.5" )
			)
			( pin "@baseboard_fab2_lib.baseboard_fab2(sch_1):page231_i193:bst"
				( attribute "PN" "36"
					( Origin gPackager )
				)
				( objectStatus "EU7F1.36" )
			)
			( pin "@baseboard_fab2_lib.baseboard_fab2(sch_1):page231_i193:comp"
				( attribute "PN" "3"
					( Origin gPackager )
				)
				( objectStatus "EU7F1.3" )
			)
			( pin "@baseboard_fab2_lib.baseboard_fab2(sch_1):page231_i193:en"
				( attribute "PN" "40"
					( Origin gPackager )
				)
				( objectStatus "EU7F1.40" )
			)
			( pin "@baseboard_fab2_lib.baseboard_fab2(sch_1):page231_i193:fb"
				( attribute "PN" "2"
					( Origin gPackager )
				)
				( objectStatus "EU7F1.2" )
			)
			( pin "@baseboard_fab2_lib.baseboard_fab2(sch_1):page231_i193:gnd"
				( attribute "PN" "41"
					( Origin gPackager )
				)
				( objectStatus "EU7F1.41" )
			)
			( pin "@baseboard_fab2_lib.baseboard_fab2(sch_1):page231_i193:iset"
				( attribute "PN" "4"
					( Origin gPackager )
				)
				( objectStatus "EU7F1.4" )
			)
			( pin "@baseboard_fab2_lib.baseboard_fab2(sch_1):page231_i193:ots"
				( attribute "PN" "6"
					( Origin gPackager )
				)
				( objectStatus "EU7F1.6" )
			)
			( pin "@baseboard_fab2_lib.baseboard_fab2(sch_1):page231_i193:pg"
				( attribute "PN" "7"
					( Origin gPackager )
				)
				( objectStatus "EU7F1.7" )
			)
			( pin "@baseboard_fab2_lib.baseboard_fab2(sch_1):page231_i193:pgnd(0)"
				( attribute "PN" "16"
					( Origin gPackager )
				)
				( objectStatus "EU7F1.16" )
			)
			( pin "@baseboard_fab2_lib.baseboard_fab2(sch_1):page231_i193:pgnd(1)"
				( attribute "PN" "17"
					( Origin gPackager )
				)
				( objectStatus "EU7F1.17" )
			)
			( pin "@baseboard_fab2_lib.baseboard_fab2(sch_1):page231_i193:pgnd(2)"
				( attribute "PN" "18"
					( Origin gPackager )
				)
				( objectStatus "EU7F1.18" )
			)
			( pin "@baseboard_fab2_lib.baseboard_fab2(sch_1):page231_i193:pgnd(3)"
				( attribute "PN" "19"
					( Origin gPackager )
				)
				( objectStatus "EU7F1.19" )
			)
			( pin "@baseboard_fab2_lib.baseboard_fab2(sch_1):page231_i193:pgnd(4)"
				( attribute "PN" "20"
					( Origin gPackager )
				)
				( objectStatus "EU7F1.20" )
			)
			( pin "@baseboard_fab2_lib.baseboard_fab2(sch_1):page231_i193:pgnd(5)"
				( attribute "PN" "21"
					( Origin gPackager )
				)
				( objectStatus "EU7F1.21" )
			)
			( pin "@baseboard_fab2_lib.baseboard_fab2(sch_1):page231_i193:pgnd(6)"
				( attribute "PN" "22"
					( Origin gPackager )
				)
				( objectStatus "EU7F1.22" )
			)
			( pin "@baseboard_fab2_lib.baseboard_fab2(sch_1):page231_i193:pgnd(7)"
				( attribute "PN" "23"
					( Origin gPackager )
				)
				( objectStatus "EU7F1.23" )
			)
			( pin "@baseboard_fab2_lib.baseboard_fab2(sch_1):page231_i193:pgnd(8)"
				( attribute "PN" "24"
					( Origin gPackager )
				)
				( objectStatus "EU7F1.24" )
			)
			( pin "@baseboard_fab2_lib.baseboard_fab2(sch_1):page231_i193:pgnd(9)"
				( attribute "PN" "25"
					( Origin gPackager )
				)
				( objectStatus "EU7F1.25" )
			)
			( pin "@baseboard_fab2_lib.baseboard_fab2(sch_1):page231_i193:pgnd(10)"
				( attribute "PN" "26"
					( Origin gPackager )
				)
				( objectStatus "EU7F1.26" )
			)
			( pin "@baseboard_fab2_lib.baseboard_fab2(sch_1):page231_i193:pgnd(11)"
				( attribute "PN" "27"
					( Origin gPackager )
				)
				( objectStatus "EU7F1.27" )
			)
			( pin "@baseboard_fab2_lib.baseboard_fab2(sch_1):page231_i193:pgnd(12)"
				( attribute "PN" "28"
					( Origin gPackager )
				)
				( objectStatus "EU7F1.28" )
			)
			( pin "@baseboard_fab2_lib.baseboard_fab2(sch_1):page231_i193:pgnd(13)"
				( attribute "PN" "37"
					( Origin gPackager )
				)
				( objectStatus "EU7F1.37" )
			)
			( pin "@baseboard_fab2_lib.baseboard_fab2(sch_1):page231_i193:ss"
				( attribute "PN" "1"
					( Origin gPackager )
				)
				( objectStatus "EU7F1.1" )
			)
			( pin "@baseboard_fab2_lib.baseboard_fab2(sch_1):page231_i193:vb"
				( attribute "PN" "38"
					( Origin gPackager )
				)
				( objectStatus "EU7F1.38" )
			)
			( pin "@baseboard_fab2_lib.baseboard_fab2(sch_1):page231_i193:vcc"
				( attribute "PN" "39"
					( Origin gPackager )
				)
				( objectStatus "EU7F1.39" )
			)
			( pin "@baseboard_fab2_lib.baseboard_fab2(sch_1):page231_i193:vin(0)"
				( attribute "PN" "8"
					( Origin gPackager )
				)
				( objectStatus "EU7F1.8" )
			)
			( pin "@baseboard_fab2_lib.baseboard_fab2(sch_1):page231_i193:vin(1)"
				( attribute "PN" "9"
					( Origin gPackager )
				)
				( objectStatus "EU7F1.9" )
			)
			( pin "@baseboard_fab2_lib.baseboard_fab2(sch_1):page231_i193:vin(2)"
				( attribute "PN" "10"
					( Origin gPackager )
				)
				( objectStatus "EU7F1.10" )
			)
			( pin "@baseboard_fab2_lib.baseboard_fab2(sch_1):page231_i193:vin(3)"
				( attribute "PN" "11"
					( Origin gPackager )
				)
				( objectStatus "EU7F1.11" )
			)
			( pin "@baseboard_fab2_lib.baseboard_fab2(sch_1):page231_i193:vin(4)"
				( attribute "PN" "12"
					( Origin gPackager )
				)
				( objectStatus "EU7F1.12" )
			)
			( pin "@baseboard_fab2_lib.baseboard_fab2(sch_1):page231_i193:vin(5)"
				( attribute "PN" "13"
					( Origin gPackager )
				)
				( objectStatus "EU7F1.13" )
			)
			( pin "@baseboard_fab2_lib.baseboard_fab2(sch_1):page231_i193:vin(6)"
				( attribute "PN" "14"
					( Origin gPackager )
				)
				( objectStatus "EU7F1.14" )
			)
			( pin "@baseboard_fab2_lib.baseboard_fab2(sch_1):page231_i193:vin(7)"
				( attribute "PN" "42"
					( Origin gPackager )
				)
				( objectStatus "EU7F1.42" )
			)
			( pin "@baseboard_fab2_lib.baseboard_fab2(sch_1):page231_i193:vsw"
				( attribute "PN" "35"
					( Origin gPackager )
				)
				( objectStatus "EU7F1.35" )
			)
			( pin "@baseboard_fab2_lib.baseboard_fab2(sch_1):page231_i193:vswh(0)"
				( attribute "PN" "15"
					( Origin gPackager )
				)
				( objectStatus "EU7F1.15" )
			)
			( pin "@baseboard_fab2_lib.baseboard_fab2(sch_1):page231_i193:vswh(1)"
				( attribute "PN" "29"
					( Origin gPackager )
				)
				( objectStatus "EU7F1.29" )
			)
			( pin "@baseboard_fab2_lib.baseboard_fab2(sch_1):page231_i193:vswh(2)"
				( attribute "PN" "30"
					( Origin gPackager )
				)
				( objectStatus "EU7F1.30" )
			)
			( pin "@baseboard_fab2_lib.baseboard_fab2(sch_1):page231_i193:vswh(3)"
				( attribute "PN" "31"
					( Origin gPackager )
				)
				( objectStatus "EU7F1.31" )
			)
			( pin "@baseboard_fab2_lib.baseboard_fab2(sch_1):page231_i193:vswh(4)"
				( attribute "PN" "32"
					( Origin gPackager )
				)
				( objectStatus "EU7F1.32" )
			)
			( pin "@baseboard_fab2_lib.baseboard_fab2(sch_1):page231_i193:vswh(5)"
				( attribute "PN" "33"
					( Origin gPackager )
				)
				( objectStatus "EU7F1.33" )
			)
			( pin "@baseboard_fab2_lib.baseboard_fab2(sch_1):page231_i193:vswh(6)"
				( attribute "PN" "34"
					( Origin gPackager )
				)
				( objectStatus "EU7F1.34" )
			)
			( pin "@baseboard_fab2_lib.baseboard_fab2(sch_1):page231_i193:vswh(7)"
				( attribute "PN" "43"
					( Origin gPackager )
				)
				( objectStatus "EU7F1.43" )
			)
			( pin "@baseboard_fab2_lib.baseboard_fab2(sch_1):page231_i194:a"
				( attribute "PN" "1"
					( Origin gPackager )
				)
				( objectStatus "C7F10.1" )
			)
			( pin "@baseboard_fab2_lib.baseboard_fab2(sch_1):page231_i194:b"
				( attribute "PN" "2"
					( Origin gPackager )
				)
				( objectStatus "C7F10.2" )
			)
			( pin "@baseboard_fab2_lib.baseboard_fab2(sch_1):page231_i199:a"
				( attribute "PN" "1"
					( Origin gPackager )
				)
				( objectStatus "C7F9.1" )
			)
			( pin "@baseboard_fab2_lib.baseboard_fab2(sch_1):page231_i199:b"
				( attribute "PN" "2"
					( Origin gPackager )
				)
				( objectStatus "C7F9.2" )
			)
			( pin "@baseboard_fab2_lib.baseboard_fab2(sch_1):page231_i200:a"
				( attribute "PN" "1"
					( Origin gPackager )
				)
				( objectStatus "C7F12.1" )
			)
			( pin "@baseboard_fab2_lib.baseboard_fab2(sch_1):page231_i200:b"
				( attribute "PN" "2"
					( Origin gPackager )
				)
				( objectStatus "C7F12.2" )
			)
			( pin "@baseboard_fab2_lib.baseboard_fab2(sch_1):page231_i201:a"
				( attribute "PN" "1"
					( Origin gPackager )
				)
				( objectStatus "R7F18.1" )
			)
			( pin "@baseboard_fab2_lib.baseboard_fab2(sch_1):page231_i201:b"
				( attribute "PN" "2"
					( Origin gPackager )
				)
				( objectStatus "R7F18.2" )
			)
			( pin "@baseboard_fab2_lib.baseboard_fab2(sch_1):page231_i202:a"
				( attribute "PN" "1"
					( Origin gPackager )
				)
				( objectStatus "C3T11.1" )
			)
			( pin "@baseboard_fab2_lib.baseboard_fab2(sch_1):page231_i202:b"
				( attribute "PN" "2"
					( Origin gPackager )
				)
				( objectStatus "C3T11.2" )
			)
			( pin "@baseboard_fab2_lib.baseboard_fab2(sch_1):page231_i205:a"
				( attribute "PN" "1"
					( Origin gPackager )
				)
				( objectStatus "C7F6.1" )
			)
			( pin "@baseboard_fab2_lib.baseboard_fab2(sch_1):page231_i205:b"
				( attribute "PN" "2"
					( Origin gPackager )
				)
				( objectStatus "C7F6.2" )
			)
			( pin "@baseboard_fab2_lib.baseboard_fab2(sch_1):page231_i208:a"
				( attribute "PN" "1"
					( Origin gPackager )
				)
				( objectStatus "R7F16.1" )
			)
			( pin "@baseboard_fab2_lib.baseboard_fab2(sch_1):page231_i208:b"
				( attribute "PN" "2"
					( Origin gPackager )
				)
				( objectStatus "R7F16.2" )
			)
			( pin "@baseboard_fab2_lib.baseboard_fab2(sch_1):page231_i209:a"
				( attribute "PN" "1"
					( Origin gPackager )
				)
				( objectStatus "C7F5.1" )
			)
			( pin "@baseboard_fab2_lib.baseboard_fab2(sch_1):page231_i209:b"
				( attribute "PN" "2"
					( Origin gPackager )
				)
				( objectStatus "C7F5.2" )
			)
			( pin "@baseboard_fab2_lib.baseboard_fab2(sch_1):page231_i210:a"
				( attribute "PN" "1"
					( Origin gPackager )
				)
				( objectStatus "C3T8.1" )
			)
			( pin "@baseboard_fab2_lib.baseboard_fab2(sch_1):page231_i210:b"
				( attribute "PN" "2"
					( Origin gPackager )
				)
				( objectStatus "C3T8.2" )
			)
			( pin "@baseboard_fab2_lib.baseboard_fab2(sch_1):page231_i211:a"
				( attribute "PN" "1"
					( Origin gPackager )
				)
				( objectStatus "C3T14.1" )
			)
			( pin "@baseboard_fab2_lib.baseboard_fab2(sch_1):page231_i211:b"
				( attribute "PN" "2"
					( Origin gPackager )
				)
				( objectStatus "C3T14.2" )
			)
			( pin "@baseboard_fab2_lib.baseboard_fab2(sch_1):page231_i215:a"
				( attribute "PN" "1"
					( Origin gPackager )
				)
				( objectStatus "C3T12.1" )
			)
			( pin "@baseboard_fab2_lib.baseboard_fab2(sch_1):page231_i215:b"
				( attribute "PN" "2"
					( Origin gPackager )
				)
				( objectStatus "C3T12.2" )
			)
			( pin "@baseboard_fab2_lib.baseboard_fab2(sch_1):page231_i217:a"
				( attribute "PN" "1"
					( Origin gPackager )
				)
				( objectStatus "C4T3.1" )
			)
			( pin "@baseboard_fab2_lib.baseboard_fab2(sch_1):page231_i217:b"
				( attribute "PN" "2"
					( Origin gPackager )
				)
				( objectStatus "C4T3.2" )
			)
			( pin "@baseboard_fab2_lib.baseboard_fab2(sch_1):page231_i218:a"
				( attribute "PN" "1"
					( Origin gPackager )
				)
				( objectStatus "R7F17.1" )
			)
			( pin "@baseboard_fab2_lib.baseboard_fab2(sch_1):page231_i218:b"
				( attribute "PN" "2"
					( Origin gPackager )
				)
				( objectStatus "R7F17.2" )
			)
			( pin "@baseboard_fab2_lib.baseboard_fab2(sch_1):page231_i219:a"
				( attribute "PN" "1"
					( Origin gPackager )
				)
				( objectStatus "C7F13.1" )
			)
			( pin "@baseboard_fab2_lib.baseboard_fab2(sch_1):page231_i219:b"
				( attribute "PN" "2"
					( Origin gPackager )
				)
				( objectStatus "C7F13.2" )
			)
			( pin "@baseboard_fab2_lib.baseboard_fab2(sch_1):page231_i220:a"
				( attribute "PN" "1"
					( Origin gPackager )
				)
				( objectStatus "R7F9.1" )
			)
			( pin "@baseboard_fab2_lib.baseboard_fab2(sch_1):page231_i220:b"
				( attribute "PN" "2"
					( Origin gPackager )
				)
				( objectStatus "R7F9.2" )
			)
			( pin "@baseboard_fab2_lib.baseboard_fab2(sch_1):page232_i102:a"
				( attribute "PN" "1"
					( Origin gPackager )
				)
				( objectStatus "C4L2.1" )
			)
			( pin "@baseboard_fab2_lib.baseboard_fab2(sch_1):page232_i102:b"
				( attribute "PN" "2"
					( Origin gPackager )
				)
				( objectStatus "C4L2.2" )
			)
			( pin "@baseboard_fab2_lib.baseboard_fab2(sch_1):page232_i104:a"
				( attribute "PN" "1"
					( Origin gPackager )
				)
				( objectStatus "C6A3.1" )
			)
			( pin "@baseboard_fab2_lib.baseboard_fab2(sch_1):page232_i104:b"
				( attribute "PN" "2"
					( Origin gPackager )
				)
				( objectStatus "C6A3.2" )
			)
			( pin "@baseboard_fab2_lib.baseboard_fab2(sch_1):page232_i105:a"
				( attribute "PN" "1"
					( Origin gPackager )
				)
				( objectStatus "C6A2.1" )
			)
			( pin "@baseboard_fab2_lib.baseboard_fab2(sch_1):page232_i105:b"
				( attribute "PN" "2"
					( Origin gPackager )
				)
				( objectStatus "C6A2.2" )
			)
			( pin "@baseboard_fab2_lib.baseboard_fab2(sch_1):page232_i106:a"
				( attribute "PN" "1"
					( Origin gPackager )
				)
				( objectStatus "C4L3.1" )
			)
			( pin "@baseboard_fab2_lib.baseboard_fab2(sch_1):page232_i106:b"
				( attribute "PN" "2"
					( Origin gPackager )
				)
				( objectStatus "C4L3.2" )
			)
			( pin "@baseboard_fab2_lib.baseboard_fab2(sch_1):page232_i108:a"
				( attribute "PN" "1"
					( Origin gPackager )
				)
				( objectStatus "C4L4.1" )
			)
			( pin "@baseboard_fab2_lib.baseboard_fab2(sch_1):page232_i108:b"
				( attribute "PN" "2"
					( Origin gPackager )
				)
				( objectStatus "C4L4.2" )
			)
			( pin "@baseboard_fab2_lib.baseboard_fab2(sch_1):page232_i109:a"
				( attribute "PN" "1"
					( Origin gPackager )
				)
				( objectStatus "C6A7.1" )
			)
			( pin "@baseboard_fab2_lib.baseboard_fab2(sch_1):page232_i109:b"
				( attribute "PN" "2"
					( Origin gPackager )
				)
				( objectStatus "C6A7.2" )
			)
			( pin "@baseboard_fab2_lib.baseboard_fab2(sch_1):page232_i110:a"
				( attribute "PN" "1"
					( Origin gPackager )
				)
				( objectStatus "C6A6.1" )
			)
			( pin "@baseboard_fab2_lib.baseboard_fab2(sch_1):page232_i110:b"
				( attribute "PN" "2"
					( Origin gPackager )
				)
				( objectStatus "C6A6.2" )
			)
			( pin "@baseboard_fab2_lib.baseboard_fab2(sch_1):page232_i111:a"
				( attribute "PN" "1"
					( Origin gPackager )
				)
				( objectStatus "C4M3.1" )
			)
			( pin "@baseboard_fab2_lib.baseboard_fab2(sch_1):page232_i111:b"
				( attribute "PN" "2"
					( Origin gPackager )
				)
				( objectStatus "C4M3.2" )
			)
			( pin "@baseboard_fab2_lib.baseboard_fab2(sch_1):page232_i125:a"
				( attribute "PN" "1"
					( Origin gPackager )
				)
				( objectStatus "C4M4.1" )
			)
			( pin "@baseboard_fab2_lib.baseboard_fab2(sch_1):page232_i125:b"
				( attribute "PN" "2"
					( Origin gPackager )
				)
				( objectStatus "C4M4.2" )
			)
			( pin "@baseboard_fab2_lib.baseboard_fab2(sch_1):page232_i126:a"
				( attribute "PN" "1"
					( Origin gPackager )
				)
				( objectStatus "C6B2.1" )
			)
			( pin "@baseboard_fab2_lib.baseboard_fab2(sch_1):page232_i126:b"
				( attribute "PN" "2"
					( Origin gPackager )
				)
				( objectStatus "C6B2.2" )
			)
			( pin "@baseboard_fab2_lib.baseboard_fab2(sch_1):page232_i128:a"
				( attribute "PN" "1"
					( Origin gPackager )
				)
				( objectStatus "C6B1.1" )
			)
			( pin "@baseboard_fab2_lib.baseboard_fab2(sch_1):page232_i128:b"
				( attribute "PN" "2"
					( Origin gPackager )
				)
				( objectStatus "C6B1.2" )
			)
			( pin "@baseboard_fab2_lib.baseboard_fab2(sch_1):page232_i129:a"
				( attribute "PN" "1"
					( Origin gPackager )
				)
				( objectStatus "C4L1.1" )
			)
			( pin "@baseboard_fab2_lib.baseboard_fab2(sch_1):page232_i129:b"
				( attribute "PN" "2"
					( Origin gPackager )
				)
				( objectStatus "C4L1.2" )
			)
			( pin "@baseboard_fab2_lib.baseboard_fab2(sch_1):page232_i150:a"
				( attribute "PN" "1"
					( Origin gPackager )
				)
				( objectStatus "R7B20.1" )
			)
			( pin "@baseboard_fab2_lib.baseboard_fab2(sch_1):page232_i150:b"
				( attribute "PN" "2"
					( Origin gPackager )
				)
				( objectStatus "R7B20.2" )
			)
			( pin "@baseboard_fab2_lib.baseboard_fab2(sch_1):page232_i185:a"
				( attribute "PN" "1"
					( Origin gPackager )
				)
				( objectStatus "C7B9.1" )
			)
			( pin "@baseboard_fab2_lib.baseboard_fab2(sch_1):page232_i185:b"
				( attribute "PN" "2"
					( Origin gPackager )
				)
				( objectStatus "C7B9.2" )
			)
			( pin "@baseboard_fab2_lib.baseboard_fab2(sch_1):page233_i284:a"
				( attribute "PN" "1"
					( Origin gPackager )
				)
				( objectStatus "R4G11.1" )
			)
			( pin "@baseboard_fab2_lib.baseboard_fab2(sch_1):page233_i284:b"
				( attribute "PN" "2"
					( Origin gPackager )
				)
				( objectStatus "R4G11.2" )
			)
			( pin "@baseboard_fab2_lib.baseboard_fab2(sch_1):page232_i197:a"
				( attribute "PN" "1"
					( Origin gPackager )
				)
				( objectStatus "C7B11.1" )
			)
			( pin "@baseboard_fab2_lib.baseboard_fab2(sch_1):page232_i197:b"
				( attribute "PN" "2"
					( Origin gPackager )
				)
				( objectStatus "C7B11.2" )
			)
			( pin "@baseboard_fab2_lib.baseboard_fab2(sch_1):page232_i200:a"
				( attribute "PN" "1"
					( Origin gPackager )
				)
				( objectStatus "FB7B1.1" )
			)
			( pin "@baseboard_fab2_lib.baseboard_fab2(sch_1):page232_i200:b"
				( attribute "PN" "2"
					( Origin gPackager )
				)
				( objectStatus "FB7B1.2" )
			)
			( pin "@baseboard_fab2_lib.baseboard_fab2(sch_1):page241_i92:\1\"
				( attribute "PN" "1"
					( Origin gPackager )
				)
				( objectStatus "C7E13.1" )
			)
			( pin "@baseboard_fab2_lib.baseboard_fab2(sch_1):page241_i92:\2\"
				( attribute "PN" "2"
					( Origin gPackager )
				)
				( objectStatus "C7E13.2" )
			)
			( pin "@baseboard_fab2_lib.baseboard_fab2(sch_1):page232_i207:a"
				( attribute "PN" "1"
					( Origin gPackager )
				)
				( objectStatus "C3M9.1" )
			)
			( pin "@baseboard_fab2_lib.baseboard_fab2(sch_1):page232_i207:b"
				( attribute "PN" "2"
					( Origin gPackager )
				)
				( objectStatus "C3M9.2" )
			)
			( pin "@baseboard_fab2_lib.baseboard_fab2(sch_1):page232_i209:a"
				( attribute "PN" "1"
					( Origin gPackager )
				)
				( objectStatus "C7B12.1" )
			)
			( pin "@baseboard_fab2_lib.baseboard_fab2(sch_1):page232_i209:b"
				( attribute "PN" "2"
					( Origin gPackager )
				)
				( objectStatus "C7B12.2" )
			)
			( pin "@baseboard_fab2_lib.baseboard_fab2(sch_1):page232_i210:a"
				( attribute "PN" "1"
					( Origin gPackager )
				)
				( objectStatus "R7B17.1" )
			)
			( pin "@baseboard_fab2_lib.baseboard_fab2(sch_1):page232_i210:b"
				( attribute "PN" "2"
					( Origin gPackager )
				)
				( objectStatus "R7B17.2" )
			)
			( pin "@baseboard_fab2_lib.baseboard_fab2(sch_1):page232_i214:agnd"
				( attribute "PN" "5"
					( Origin gPackager )
				)
				( objectStatus "EU7B1.5" )
			)
			( pin "@baseboard_fab2_lib.baseboard_fab2(sch_1):page232_i214:bst"
				( attribute "PN" "36"
					( Origin gPackager )
				)
				( objectStatus "EU7B1.36" )
			)
			( pin "@baseboard_fab2_lib.baseboard_fab2(sch_1):page232_i214:comp"
				( attribute "PN" "3"
					( Origin gPackager )
				)
				( objectStatus "EU7B1.3" )
			)
			( pin "@baseboard_fab2_lib.baseboard_fab2(sch_1):page232_i214:en"
				( attribute "PN" "40"
					( Origin gPackager )
				)
				( objectStatus "EU7B1.40" )
			)
			( pin "@baseboard_fab2_lib.baseboard_fab2(sch_1):page232_i214:fb"
				( attribute "PN" "2"
					( Origin gPackager )
				)
				( objectStatus "EU7B1.2" )
			)
			( pin "@baseboard_fab2_lib.baseboard_fab2(sch_1):page232_i214:gnd"
				( attribute "PN" "41"
					( Origin gPackager )
				)
				( objectStatus "EU7B1.41" )
			)
			( pin "@baseboard_fab2_lib.baseboard_fab2(sch_1):page232_i214:iset"
				( attribute "PN" "4"
					( Origin gPackager )
				)
				( objectStatus "EU7B1.4" )
			)
			( pin "@baseboard_fab2_lib.baseboard_fab2(sch_1):page232_i214:ots"
				( attribute "PN" "6"
					( Origin gPackager )
				)
				( objectStatus "EU7B1.6" )
			)
			( pin "@baseboard_fab2_lib.baseboard_fab2(sch_1):page232_i214:pg"
				( attribute "PN" "7"
					( Origin gPackager )
				)
				( objectStatus "EU7B1.7" )
			)
			( pin "@baseboard_fab2_lib.baseboard_fab2(sch_1):page232_i214:pgnd(0)"
				( attribute "PN" "16"
					( Origin gPackager )
				)
				( objectStatus "EU7B1.16" )
			)
			( pin "@baseboard_fab2_lib.baseboard_fab2(sch_1):page232_i214:pgnd(1)"
				( attribute "PN" "17"
					( Origin gPackager )
				)
				( objectStatus "EU7B1.17" )
			)
			( pin "@baseboard_fab2_lib.baseboard_fab2(sch_1):page232_i214:pgnd(2)"
				( attribute "PN" "18"
					( Origin gPackager )
				)
				( objectStatus "EU7B1.18" )
			)
			( pin "@baseboard_fab2_lib.baseboard_fab2(sch_1):page232_i214:pgnd(3)"
				( attribute "PN" "19"
					( Origin gPackager )
				)
				( objectStatus "EU7B1.19" )
			)
			( pin "@baseboard_fab2_lib.baseboard_fab2(sch_1):page232_i214:pgnd(4)"
				( attribute "PN" "20"
					( Origin gPackager )
				)
				( objectStatus "EU7B1.20" )
			)
			( pin "@baseboard_fab2_lib.baseboard_fab2(sch_1):page232_i214:pgnd(5)"
				( attribute "PN" "21"
					( Origin gPackager )
				)
				( objectStatus "EU7B1.21" )
			)
			( pin "@baseboard_fab2_lib.baseboard_fab2(sch_1):page232_i214:pgnd(6)"
				( attribute "PN" "22"
					( Origin gPackager )
				)
				( objectStatus "EU7B1.22" )
			)
			( pin "@baseboard_fab2_lib.baseboard_fab2(sch_1):page232_i214:pgnd(7)"
				( attribute "PN" "23"
					( Origin gPackager )
				)
				( objectStatus "EU7B1.23" )
			)
			( pin "@baseboard_fab2_lib.baseboard_fab2(sch_1):page232_i214:pgnd(8)"
				( attribute "PN" "24"
					( Origin gPackager )
				)
				( objectStatus "EU7B1.24" )
			)
			( pin "@baseboard_fab2_lib.baseboard_fab2(sch_1):page232_i214:pgnd(9)"
				( attribute "PN" "25"
					( Origin gPackager )
				)
				( objectStatus "EU7B1.25" )
			)
			( pin "@baseboard_fab2_lib.baseboard_fab2(sch_1):page232_i214:pgnd(10)"
				( attribute "PN" "26"
					( Origin gPackager )
				)
				( objectStatus "EU7B1.26" )
			)
			( pin "@baseboard_fab2_lib.baseboard_fab2(sch_1):page232_i214:pgnd(11)"
				( attribute "PN" "27"
					( Origin gPackager )
				)
				( objectStatus "EU7B1.27" )
			)
			( pin "@baseboard_fab2_lib.baseboard_fab2(sch_1):page232_i214:pgnd(12)"
				( attribute "PN" "28"
					( Origin gPackager )
				)
				( objectStatus "EU7B1.28" )
			)
			( pin "@baseboard_fab2_lib.baseboard_fab2(sch_1):page232_i214:pgnd(13)"
				( attribute "PN" "37"
					( Origin gPackager )
				)
				( objectStatus "EU7B1.37" )
			)
			( pin "@baseboard_fab2_lib.baseboard_fab2(sch_1):page232_i214:ss"
				( attribute "PN" "1"
					( Origin gPackager )
				)
				( objectStatus "EU7B1.1" )
			)
			( pin "@baseboard_fab2_lib.baseboard_fab2(sch_1):page232_i214:vb"
				( attribute "PN" "38"
					( Origin gPackager )
				)
				( objectStatus "EU7B1.38" )
			)
			( pin "@baseboard_fab2_lib.baseboard_fab2(sch_1):page232_i214:vcc"
				( attribute "PN" "39"
					( Origin gPackager )
				)
				( objectStatus "EU7B1.39" )
			)
			( pin "@baseboard_fab2_lib.baseboard_fab2(sch_1):page232_i214:vin(0)"
				( attribute "PN" "8"
					( Origin gPackager )
				)
				( objectStatus "EU7B1.8" )
			)
			( pin "@baseboard_fab2_lib.baseboard_fab2(sch_1):page232_i214:vin(1)"
				( attribute "PN" "9"
					( Origin gPackager )
				)
				( objectStatus "EU7B1.9" )
			)
			( pin "@baseboard_fab2_lib.baseboard_fab2(sch_1):page232_i214:vin(2)"
				( attribute "PN" "10"
					( Origin gPackager )
				)
				( objectStatus "EU7B1.10" )
			)
			( pin "@baseboard_fab2_lib.baseboard_fab2(sch_1):page232_i214:vin(3)"
				( attribute "PN" "11"
					( Origin gPackager )
				)
				( objectStatus "EU7B1.11" )
			)
			( pin "@baseboard_fab2_lib.baseboard_fab2(sch_1):page232_i214:vin(4)"
				( attribute "PN" "12"
					( Origin gPackager )
				)
				( objectStatus "EU7B1.12" )
			)
			( pin "@baseboard_fab2_lib.baseboard_fab2(sch_1):page232_i214:vin(5)"
				( attribute "PN" "13"
					( Origin gPackager )
				)
				( objectStatus "EU7B1.13" )
			)
			( pin "@baseboard_fab2_lib.baseboard_fab2(sch_1):page232_i214:vin(6)"
				( attribute "PN" "14"
					( Origin gPackager )
				)
				( objectStatus "EU7B1.14" )
			)
			( pin "@baseboard_fab2_lib.baseboard_fab2(sch_1):page232_i214:vin(7)"
				( attribute "PN" "42"
					( Origin gPackager )
				)
				( objectStatus "EU7B1.42" )
			)
			( pin "@baseboard_fab2_lib.baseboard_fab2(sch_1):page232_i214:vsw"
				( attribute "PN" "35"
					( Origin gPackager )
				)
				( objectStatus "EU7B1.35" )
			)
			( pin "@baseboard_fab2_lib.baseboard_fab2(sch_1):page232_i214:vswh(0)"
				( attribute "PN" "15"
					( Origin gPackager )
				)
				( objectStatus "EU7B1.15" )
			)
			( pin "@baseboard_fab2_lib.baseboard_fab2(sch_1):page232_i214:vswh(1)"
				( attribute "PN" "29"
					( Origin gPackager )
				)
				( objectStatus "EU7B1.29" )
			)
			( pin "@baseboard_fab2_lib.baseboard_fab2(sch_1):page232_i214:vswh(2)"
				( attribute "PN" "30"
					( Origin gPackager )
				)
				( objectStatus "EU7B1.30" )
			)
			( pin "@baseboard_fab2_lib.baseboard_fab2(sch_1):page232_i214:vswh(3)"
				( attribute "PN" "31"
					( Origin gPackager )
				)
				( objectStatus "EU7B1.31" )
			)
			( pin "@baseboard_fab2_lib.baseboard_fab2(sch_1):page232_i214:vswh(4)"
				( attribute "PN" "32"
					( Origin gPackager )
				)
				( objectStatus "EU7B1.32" )
			)
			( pin "@baseboard_fab2_lib.baseboard_fab2(sch_1):page232_i214:vswh(5)"
				( attribute "PN" "33"
					( Origin gPackager )
				)
				( objectStatus "EU7B1.33" )
			)
			( pin "@baseboard_fab2_lib.baseboard_fab2(sch_1):page232_i214:vswh(6)"
				( attribute "PN" "34"
					( Origin gPackager )
				)
				( objectStatus "EU7B1.34" )
			)
			( pin "@baseboard_fab2_lib.baseboard_fab2(sch_1):page232_i214:vswh(7)"
				( attribute "PN" "43"
					( Origin gPackager )
				)
				( objectStatus "EU7B1.43" )
			)
			( pin "@baseboard_fab2_lib.baseboard_fab2(sch_1):page232_i218:a"
				( attribute "PN" "1"
					( Origin gPackager )
				)
				( objectStatus "R7A15.1" )
			)
			( pin "@baseboard_fab2_lib.baseboard_fab2(sch_1):page232_i218:b"
				( attribute "PN" "2"
					( Origin gPackager )
				)
				( objectStatus "R7A15.2" )
			)
			( pin "@baseboard_fab2_lib.baseboard_fab2(sch_1):page232_i220:a"
				( attribute "PN" "1"
					( Origin gPackager )
				)
				( objectStatus "C7A34.1" )
			)
			( pin "@baseboard_fab2_lib.baseboard_fab2(sch_1):page232_i220:b"
				( attribute "PN" "2"
					( Origin gPackager )
				)
				( objectStatus "C7A34.2" )
			)
			( pin "@baseboard_fab2_lib.baseboard_fab2(sch_1):page232_i227:a"
				( attribute "PN" "1"
					( Origin gPackager )
				)
				( objectStatus "R7B10.1" )
			)
			( pin "@baseboard_fab2_lib.baseboard_fab2(sch_1):page232_i227:b"
				( attribute "PN" "2"
					( Origin gPackager )
				)
				( objectStatus "R7B10.2" )
			)
			( pin "@baseboard_fab2_lib.baseboard_fab2(sch_1):page232_i229:a"
				( attribute "PN" "1"
					( Origin gPackager )
				)
				( objectStatus "C6B7.1" )
			)
			( pin "@baseboard_fab2_lib.baseboard_fab2(sch_1):page232_i229:b"
				( attribute "PN" "2"
					( Origin gPackager )
				)
				( objectStatus "C6B7.2" )
			)
			( pin "@baseboard_fab2_lib.baseboard_fab2(sch_1):page232_i236:a"
				( attribute "PN" "1"
					( Origin gPackager )
				)
				( objectStatus "C6B3.1" )
			)
			( pin "@baseboard_fab2_lib.baseboard_fab2(sch_1):page232_i236:b"
				( attribute "PN" "2"
					( Origin gPackager )
				)
				( objectStatus "C6B3.2" )
			)
			( pin "@baseboard_fab2_lib.baseboard_fab2(sch_1):page232_i238:a"
				( attribute "PN" "1"
					( Origin gPackager )
				)
				( objectStatus "C7B7.1" )
			)
			( pin "@baseboard_fab2_lib.baseboard_fab2(sch_1):page232_i238:b"
				( attribute "PN" "2"
					( Origin gPackager )
				)
				( objectStatus "C7B7.2" )
			)
			( pin "@baseboard_fab2_lib.baseboard_fab2(sch_1):page232_i239:ina"
				( attribute "PN" "1"
					( Origin gPackager )
				)
				( objectStatus "L7B1.1" )
			)
			( pin "@baseboard_fab2_lib.baseboard_fab2(sch_1):page232_i239:inb"
				( attribute "PN" "2"
					( Origin gPackager )
				)
				( objectStatus "L7B1.2" )
			)
			( pin "@baseboard_fab2_lib.baseboard_fab2(sch_1):page234_i226:a"
				( attribute "PN" "1"
					( Origin gPackager )
				)
				( objectStatus "R4B13.1" )
			)
			( pin "@baseboard_fab2_lib.baseboard_fab2(sch_1):page234_i226:b"
				( attribute "PN" "2"
					( Origin gPackager )
				)
				( objectStatus "R4B13.2" )
			)
			( pin "@baseboard_fab2_lib.baseboard_fab2(sch_1):page232_i241:a"
				( attribute "PN" "1"
					( Origin gPackager )
				)
				( objectStatus "C7B30.1" )
			)
			( pin "@baseboard_fab2_lib.baseboard_fab2(sch_1):page232_i241:b"
				( attribute "PN" "2"
					( Origin gPackager )
				)
				( objectStatus "C7B30.2" )
			)
			( pin "@baseboard_fab2_lib.baseboard_fab2(sch_1):page232_i252:a"
				( attribute "PN" "1"
					( Origin gPackager )
				)
				( objectStatus "C7B6.1" )
			)
			( pin "@baseboard_fab2_lib.baseboard_fab2(sch_1):page232_i252:b"
				( attribute "PN" "2"
					( Origin gPackager )
				)
				( objectStatus "C7B6.2" )
			)
			( pin "@baseboard_fab2_lib.baseboard_fab2(sch_1):page232_i253:a"
				( attribute "PN" "1"
					( Origin gPackager )
				)
				( objectStatus "C3M10.1" )
			)
			( pin "@baseboard_fab2_lib.baseboard_fab2(sch_1):page232_i253:b"
				( attribute "PN" "2"
					( Origin gPackager )
				)
				( objectStatus "C3M10.2" )
			)
			( pin "@baseboard_fab2_lib.baseboard_fab2(sch_1):page232_i257:a"
				( attribute "PN" "1"
					( Origin gPackager )
				)
				( objectStatus "R7B12.1" )
			)
			( pin "@baseboard_fab2_lib.baseboard_fab2(sch_1):page232_i257:b"
				( attribute "PN" "2"
					( Origin gPackager )
				)
				( objectStatus "R7B12.2" )
			)
			( pin "@baseboard_fab2_lib.baseboard_fab2(sch_1):page232_i259:a"
				( attribute "PN" "1"
					( Origin gPackager )
				)
				( objectStatus "C3M8.1" )
			)
			( pin "@baseboard_fab2_lib.baseboard_fab2(sch_1):page232_i259:b"
				( attribute "PN" "2"
					( Origin gPackager )
				)
				( objectStatus "C3M8.2" )
			)
			( pin "@baseboard_fab2_lib.baseboard_fab2(sch_1):page232_i260:a"
				( attribute "PN" "1"
					( Origin gPackager )
				)
				( objectStatus "C3M15.1" )
			)
			( pin "@baseboard_fab2_lib.baseboard_fab2(sch_1):page232_i260:b"
				( attribute "PN" "2"
					( Origin gPackager )
				)
				( objectStatus "C3M15.2" )
			)
			( pin "@baseboard_fab2_lib.baseboard_fab2(sch_1):page232_i261:a"
				( attribute "PN" "1"
					( Origin gPackager )
				)
				( objectStatus "C3M16.1" )
			)
			( pin "@baseboard_fab2_lib.baseboard_fab2(sch_1):page232_i261:b"
				( attribute "PN" "2"
					( Origin gPackager )
				)
				( objectStatus "C3M16.2" )
			)
			( pin "@baseboard_fab2_lib.baseboard_fab2(sch_1):page232_i262:a"
				( attribute "PN" "1"
					( Origin gPackager )
				)
				( objectStatus "C7B5.1" )
			)
			( pin "@baseboard_fab2_lib.baseboard_fab2(sch_1):page232_i262:b"
				( attribute "PN" "2"
					( Origin gPackager )
				)
				( objectStatus "C7B5.2" )
			)
			( pin "@baseboard_fab2_lib.baseboard_fab2(sch_1):page232_i267:a"
				( attribute "PN" "1"
					( Origin gPackager )
				)
				( objectStatus "C4M1.1" )
			)
			( pin "@baseboard_fab2_lib.baseboard_fab2(sch_1):page232_i267:b"
				( attribute "PN" "2"
					( Origin gPackager )
				)
				( objectStatus "C4M1.2" )
			)
			( pin "@baseboard_fab2_lib.baseboard_fab2(sch_1):page232_i298:a"
				( attribute "PN" "1"
					( Origin gPackager )
				)
				( objectStatus "R7B18.1" )
			)
			( pin "@baseboard_fab2_lib.baseboard_fab2(sch_1):page232_i298:b"
				( attribute "PN" "2"
					( Origin gPackager )
				)
				( objectStatus "R7B18.2" )
			)
			( pin "@baseboard_fab2_lib.baseboard_fab2(sch_1):page232_i299:a"
				( attribute "PN" "1"
					( Origin gPackager )
				)
				( objectStatus "R7B11.1" )
			)
			( pin "@baseboard_fab2_lib.baseboard_fab2(sch_1):page232_i299:b"
				( attribute "PN" "2"
					( Origin gPackager )
				)
				( objectStatus "R7B11.2" )
			)
			( pin "@baseboard_fab2_lib.baseboard_fab2(sch_1):page232_i300:a"
				( attribute "PN" "1"
					( Origin gPackager )
				)
				( objectStatus "R7B16.1" )
			)
			( pin "@baseboard_fab2_lib.baseboard_fab2(sch_1):page232_i300:b"
				( attribute "PN" "2"
					( Origin gPackager )
				)
				( objectStatus "R7B16.2" )
			)
			( pin "@baseboard_fab2_lib.baseboard_fab2(sch_1):page232_i301:a"
				( attribute "PN" "1"
					( Origin gPackager )
				)
				( objectStatus "C7B10.1" )
			)
			( pin "@baseboard_fab2_lib.baseboard_fab2(sch_1):page232_i301:b"
				( attribute "PN" "2"
					( Origin gPackager )
				)
				( objectStatus "C7B10.2" )
			)
			( pin "@baseboard_fab2_lib.baseboard_fab2(sch_1):page232_i302:a"
				( attribute "PN" "1"
					( Origin gPackager )
				)
				( objectStatus "C7B13.1" )
			)
			( pin "@baseboard_fab2_lib.baseboard_fab2(sch_1):page232_i302:b"
				( attribute "PN" "2"
					( Origin gPackager )
				)
				( objectStatus "C7B13.2" )
			)
			( pin "@baseboard_fab2_lib.baseboard_fab2(sch_1):page232_i303:a"
				( attribute "PN" "1"
					( Origin gPackager )
				)
				( objectStatus "R7B15.1" )
			)
			( pin "@baseboard_fab2_lib.baseboard_fab2(sch_1):page232_i303:b"
				( attribute "PN" "2"
					( Origin gPackager )
				)
				( objectStatus "R7B15.2" )
			)
			( pin "@baseboard_fab2_lib.baseboard_fab2(sch_1):page233_i283:a"
				( attribute "PN" "1"
					( Origin gPackager )
				)
				( objectStatus "R4G9.1" )
			)
			( pin "@baseboard_fab2_lib.baseboard_fab2(sch_1):page233_i283:b"
				( attribute "PN" "2"
					( Origin gPackager )
				)
				( objectStatus "R4G9.2" )
			)
			( pin "@baseboard_fab2_lib.baseboard_fab2(sch_1):page232_i306:a"
				( attribute "PN" "1"
					( Origin gPackager )
				)
				( objectStatus "C7B14.1" )
			)
			( pin "@baseboard_fab2_lib.baseboard_fab2(sch_1):page232_i306:b"
				( attribute "PN" "2"
					( Origin gPackager )
				)
				( objectStatus "C7B14.2" )
			)
			( pin "@baseboard_fab2_lib.baseboard_fab2(sch_1):page232_i307:a"
				( attribute "PN" "1"
					( Origin gPackager )
				)
				( objectStatus "R7B9.1" )
			)
			( pin "@baseboard_fab2_lib.baseboard_fab2(sch_1):page232_i307:b"
				( attribute "PN" "2"
					( Origin gPackager )
				)
				( objectStatus "R7B9.2" )
			)
			( pin "@baseboard_fab2_lib.baseboard_fab2(sch_1):page233_i109:a"
				( attribute "PN" "1"
					( Origin gPackager )
				)
				( objectStatus "C7U4.1" )
			)
			( pin "@baseboard_fab2_lib.baseboard_fab2(sch_1):page233_i109:b"
				( attribute "PN" "2"
					( Origin gPackager )
				)
				( objectStatus "C7U4.2" )
			)
			( pin "@baseboard_fab2_lib.baseboard_fab2(sch_1):page233_i111:a"
				( attribute "PN" "1"
					( Origin gPackager )
				)
				( objectStatus "C7U5.1" )
			)
			( pin "@baseboard_fab2_lib.baseboard_fab2(sch_1):page233_i111:b"
				( attribute "PN" "2"
					( Origin gPackager )
				)
				( objectStatus "C7U5.2" )
			)
			( pin "@baseboard_fab2_lib.baseboard_fab2(sch_1):page233_i112:a"
				( attribute "PN" "1"
					( Origin gPackager )
				)
				( objectStatus "C7T2.1" )
			)
			( pin "@baseboard_fab2_lib.baseboard_fab2(sch_1):page233_i112:b"
				( attribute "PN" "2"
					( Origin gPackager )
				)
				( objectStatus "C7T2.2" )
			)
			( pin "@baseboard_fab2_lib.baseboard_fab2(sch_1):page233_i113:a"
				( attribute "PN" "1"
					( Origin gPackager )
				)
				( objectStatus "C7T3.1" )
			)
			( pin "@baseboard_fab2_lib.baseboard_fab2(sch_1):page233_i113:b"
				( attribute "PN" "2"
					( Origin gPackager )
				)
				( objectStatus "C7T3.2" )
			)
			( pin "@baseboard_fab2_lib.baseboard_fab2(sch_1):page233_i115:a"
				( attribute "PN" "1"
					( Origin gPackager )
				)
				( objectStatus "C7U6.1" )
			)
			( pin "@baseboard_fab2_lib.baseboard_fab2(sch_1):page233_i115:b"
				( attribute "PN" "2"
					( Origin gPackager )
				)
				( objectStatus "C7U6.2" )
			)
			( pin "@baseboard_fab2_lib.baseboard_fab2(sch_1):page233_i116:a"
				( attribute "PN" "1"
					( Origin gPackager )
				)
				( objectStatus "C3F3.1" )
			)
			( pin "@baseboard_fab2_lib.baseboard_fab2(sch_1):page233_i116:b"
				( attribute "PN" "2"
					( Origin gPackager )
				)
				( objectStatus "C3F3.2" )
			)
			( pin "@baseboard_fab2_lib.baseboard_fab2(sch_1):page233_i117:a"
				( attribute "PN" "1"
					( Origin gPackager )
				)
				( objectStatus "C3F4.1" )
			)
			( pin "@baseboard_fab2_lib.baseboard_fab2(sch_1):page233_i117:b"
				( attribute "PN" "2"
					( Origin gPackager )
				)
				( objectStatus "C3F4.2" )
			)
			( pin "@baseboard_fab2_lib.baseboard_fab2(sch_1):page233_i118:a"
				( attribute "PN" "1"
					( Origin gPackager )
				)
				( objectStatus "C3G3.1" )
			)
			( pin "@baseboard_fab2_lib.baseboard_fab2(sch_1):page233_i118:b"
				( attribute "PN" "2"
					( Origin gPackager )
				)
				( objectStatus "C3G3.2" )
			)
			( pin "@baseboard_fab2_lib.baseboard_fab2(sch_1):page233_i132:a"
				( attribute "PN" "1"
					( Origin gPackager )
				)
				( objectStatus "C3G7.1" )
			)
			( pin "@baseboard_fab2_lib.baseboard_fab2(sch_1):page233_i132:b"
				( attribute "PN" "2"
					( Origin gPackager )
				)
				( objectStatus "C3G7.2" )
			)
			( pin "@baseboard_fab2_lib.baseboard_fab2(sch_1):page233_i133:a"
				( attribute "PN" "1"
					( Origin gPackager )
				)
				( objectStatus "C3G4.1" )
			)
			( pin "@baseboard_fab2_lib.baseboard_fab2(sch_1):page233_i133:b"
				( attribute "PN" "2"
					( Origin gPackager )
				)
				( objectStatus "C3G4.2" )
			)
			( pin "@baseboard_fab2_lib.baseboard_fab2(sch_1):page233_i135:a"
				( attribute "PN" "1"
					( Origin gPackager )
				)
				( objectStatus "C3G8.1" )
			)
			( pin "@baseboard_fab2_lib.baseboard_fab2(sch_1):page233_i135:b"
				( attribute "PN" "2"
					( Origin gPackager )
				)
				( objectStatus "C3G8.2" )
			)
			( pin "@baseboard_fab2_lib.baseboard_fab2(sch_1):page233_i136:a"
				( attribute "PN" "1"
					( Origin gPackager )
				)
				( objectStatus "C7U3.1" )
			)
			( pin "@baseboard_fab2_lib.baseboard_fab2(sch_1):page233_i136:b"
				( attribute "PN" "2"
					( Origin gPackager )
				)
				( objectStatus "C7U3.2" )
			)
			( pin "@baseboard_fab2_lib.baseboard_fab2(sch_1):page233_i157:a"
				( attribute "PN" "1"
					( Origin gPackager )
				)
				( objectStatus "R4G25.1" )
			)
			( pin "@baseboard_fab2_lib.baseboard_fab2(sch_1):page233_i157:b"
				( attribute "PN" "2"
					( Origin gPackager )
				)
				( objectStatus "R4G25.2" )
			)
			( pin "@baseboard_fab2_lib.baseboard_fab2(sch_1):page233_i182:a"
				( attribute "PN" "1"
					( Origin gPackager )
				)
				( objectStatus "R4G5.1" )
			)
			( pin "@baseboard_fab2_lib.baseboard_fab2(sch_1):page233_i182:b"
				( attribute "PN" "2"
					( Origin gPackager )
				)
				( objectStatus "R4G5.2" )
			)
			( pin "@baseboard_fab2_lib.baseboard_fab2(sch_1):page233_i183:a"
				( attribute "PN" "1"
					( Origin gPackager )
				)
				( objectStatus "C4G7.1" )
			)
			( pin "@baseboard_fab2_lib.baseboard_fab2(sch_1):page233_i183:b"
				( attribute "PN" "2"
					( Origin gPackager )
				)
				( objectStatus "C4G7.2" )
			)
			( pin "@baseboard_fab2_lib.baseboard_fab2(sch_1):page234_i228:a"
				( attribute "PN" "1"
					( Origin gPackager )
				)
				( objectStatus "R4B6.1" )
			)
			( pin "@baseboard_fab2_lib.baseboard_fab2(sch_1):page234_i228:b"
				( attribute "PN" "2"
					( Origin gPackager )
				)
				( objectStatus "R4B6.2" )
			)
			( pin "@baseboard_fab2_lib.baseboard_fab2(sch_1):page233_i185:a"
				( attribute "PN" "1"
					( Origin gPackager )
				)
				( objectStatus "R4G14.1" )
			)
			( pin "@baseboard_fab2_lib.baseboard_fab2(sch_1):page233_i185:b"
				( attribute "PN" "2"
					( Origin gPackager )
				)
				( objectStatus "R4G14.2" )
			)
			( pin "@baseboard_fab2_lib.baseboard_fab2(sch_1):page233_i187:a"
				( attribute "PN" "1"
					( Origin gPackager )
				)
				( objectStatus "C6U6.1" )
			)
			( pin "@baseboard_fab2_lib.baseboard_fab2(sch_1):page233_i187:b"
				( attribute "PN" "2"
					( Origin gPackager )
				)
				( objectStatus "C6U6.2" )
			)
			( pin "@baseboard_fab2_lib.baseboard_fab2(sch_1):page232_i309:\1\"
				( attribute "PN" "1"
					( Origin gPackager )
				)
				( objectStatus "C7B8.1" )
			)
			( pin "@baseboard_fab2_lib.baseboard_fab2(sch_1):page232_i309:\2\"
				( attribute "PN" "2"
					( Origin gPackager )
				)
				( objectStatus "C7B8.2" )
			)
			( pin "@baseboard_fab2_lib.baseboard_fab2(sch_1):page233_i194:a"
				( attribute "PN" "1"
					( Origin gPackager )
				)
				( objectStatus "C4G8.1" )
			)
			( pin "@baseboard_fab2_lib.baseboard_fab2(sch_1):page233_i194:b"
				( attribute "PN" "2"
					( Origin gPackager )
				)
				( objectStatus "C4G8.2" )
			)
			( pin "@baseboard_fab2_lib.baseboard_fab2(sch_1):page233_i196:a"
				( attribute "PN" "1"
					( Origin gPackager )
				)
				( objectStatus "C4G4.1" )
			)
			( pin "@baseboard_fab2_lib.baseboard_fab2(sch_1):page233_i196:b"
				( attribute "PN" "2"
					( Origin gPackager )
				)
				( objectStatus "C4G4.2" )
			)
			( pin "@baseboard_fab2_lib.baseboard_fab2(sch_1):page233_i198:a"
				( attribute "PN" "1"
					( Origin gPackager )
				)
				( objectStatus "FB4G1.1" )
			)
			( pin "@baseboard_fab2_lib.baseboard_fab2(sch_1):page233_i198:b"
				( attribute "PN" "2"
					( Origin gPackager )
				)
				( objectStatus "FB4G1.2" )
			)
			( pin "@baseboard_fab2_lib.baseboard_fab2(sch_1):page233_i201:a"
				( attribute "PN" "1"
					( Origin gPackager )
				)
				( objectStatus "C4G9.1" )
			)
			( pin "@baseboard_fab2_lib.baseboard_fab2(sch_1):page233_i201:b"
				( attribute "PN" "2"
					( Origin gPackager )
				)
				( objectStatus "C4G9.2" )
			)
			( pin "@baseboard_fab2_lib.baseboard_fab2(sch_1):page233_i208:a"
				( attribute "PN" "1"
					( Origin gPackager )
				)
				( objectStatus "R4F6.1" )
			)
			( pin "@baseboard_fab2_lib.baseboard_fab2(sch_1):page233_i208:b"
				( attribute "PN" "2"
					( Origin gPackager )
				)
				( objectStatus "R4F6.2" )
			)
			( pin "@baseboard_fab2_lib.baseboard_fab2(sch_1):page233_i209:a"
				( attribute "PN" "1"
					( Origin gPackager )
				)
				( objectStatus "C4F12.1" )
			)
			( pin "@baseboard_fab2_lib.baseboard_fab2(sch_1):page233_i209:b"
				( attribute "PN" "2"
					( Origin gPackager )
				)
				( objectStatus "C4F12.2" )
			)
			( pin "@baseboard_fab2_lib.baseboard_fab2(sch_1):page233_i211:a"
				( attribute "PN" "1"
					( Origin gPackager )
				)
				( objectStatus "R4G6.1" )
			)
			( pin "@baseboard_fab2_lib.baseboard_fab2(sch_1):page233_i211:b"
				( attribute "PN" "2"
					( Origin gPackager )
				)
				( objectStatus "R4G6.2" )
			)
			( pin "@baseboard_fab2_lib.baseboard_fab2(sch_1):page233_i217:a"
				( attribute "PN" "1"
					( Origin gPackager )
				)
				( objectStatus "C4F7.1" )
			)
			( pin "@baseboard_fab2_lib.baseboard_fab2(sch_1):page233_i217:b"
				( attribute "PN" "2"
					( Origin gPackager )
				)
				( objectStatus "C4F7.2" )
			)
			( pin "@baseboard_fab2_lib.baseboard_fab2(sch_1):page233_i221:a"
				( attribute "PN" "1"
					( Origin gPackager )
				)
				( objectStatus "C6U3.1" )
			)
			( pin "@baseboard_fab2_lib.baseboard_fab2(sch_1):page233_i221:b"
				( attribute "PN" "2"
					( Origin gPackager )
				)
				( objectStatus "C6U3.2" )
			)
			( pin "@baseboard_fab2_lib.baseboard_fab2(sch_1):page233_i223:a"
				( attribute "PN" "1"
					( Origin gPackager )
				)
				( objectStatus "C6U2.1" )
			)
			( pin "@baseboard_fab2_lib.baseboard_fab2(sch_1):page233_i223:b"
				( attribute "PN" "2"
					( Origin gPackager )
				)
				( objectStatus "C6U2.2" )
			)
			( pin "@baseboard_fab2_lib.baseboard_fab2(sch_1):page233_i224:a"
				( attribute "PN" "1"
					( Origin gPackager )
				)
				( objectStatus "C4G26.1" )
			)
			( pin "@baseboard_fab2_lib.baseboard_fab2(sch_1):page233_i224:b"
				( attribute "PN" "2"
					( Origin gPackager )
				)
				( objectStatus "C4G26.2" )
			)
			( pin "@baseboard_fab2_lib.baseboard_fab2(sch_1):page233_i225:agnd"
				( attribute "PN" "5"
					( Origin gPackager )
				)
				( objectStatus "EU4G1.5" )
			)
			( pin "@baseboard_fab2_lib.baseboard_fab2(sch_1):page233_i225:bst"
				( attribute "PN" "36"
					( Origin gPackager )
				)
				( objectStatus "EU4G1.36" )
			)
			( pin "@baseboard_fab2_lib.baseboard_fab2(sch_1):page233_i225:comp"
				( attribute "PN" "3"
					( Origin gPackager )
				)
				( objectStatus "EU4G1.3" )
			)
			( pin "@baseboard_fab2_lib.baseboard_fab2(sch_1):page233_i225:en"
				( attribute "PN" "40"
					( Origin gPackager )
				)
				( objectStatus "EU4G1.40" )
			)
			( pin "@baseboard_fab2_lib.baseboard_fab2(sch_1):page233_i225:fb"
				( attribute "PN" "2"
					( Origin gPackager )
				)
				( objectStatus "EU4G1.2" )
			)
			( pin "@baseboard_fab2_lib.baseboard_fab2(sch_1):page233_i225:gnd"
				( attribute "PN" "41"
					( Origin gPackager )
				)
				( objectStatus "EU4G1.41" )
			)
			( pin "@baseboard_fab2_lib.baseboard_fab2(sch_1):page233_i225:iset"
				( attribute "PN" "4"
					( Origin gPackager )
				)
				( objectStatus "EU4G1.4" )
			)
			( pin "@baseboard_fab2_lib.baseboard_fab2(sch_1):page233_i225:ots"
				( attribute "PN" "6"
					( Origin gPackager )
				)
				( objectStatus "EU4G1.6" )
			)
			( pin "@baseboard_fab2_lib.baseboard_fab2(sch_1):page233_i225:pg"
				( attribute "PN" "7"
					( Origin gPackager )
				)
				( objectStatus "EU4G1.7" )
			)
			( pin "@baseboard_fab2_lib.baseboard_fab2(sch_1):page233_i225:pgnd(0)"
				( attribute "PN" "16"
					( Origin gPackager )
				)
				( objectStatus "EU4G1.16" )
			)
			( pin "@baseboard_fab2_lib.baseboard_fab2(sch_1):page233_i225:pgnd(1)"
				( attribute "PN" "17"
					( Origin gPackager )
				)
				( objectStatus "EU4G1.17" )
			)
			( pin "@baseboard_fab2_lib.baseboard_fab2(sch_1):page233_i225:pgnd(2)"
				( attribute "PN" "18"
					( Origin gPackager )
				)
				( objectStatus "EU4G1.18" )
			)
			( pin "@baseboard_fab2_lib.baseboard_fab2(sch_1):page233_i225:pgnd(3)"
				( attribute "PN" "19"
					( Origin gPackager )
				)
				( objectStatus "EU4G1.19" )
			)
			( pin "@baseboard_fab2_lib.baseboard_fab2(sch_1):page233_i225:pgnd(4)"
				( attribute "PN" "20"
					( Origin gPackager )
				)
				( objectStatus "EU4G1.20" )
			)
			( pin "@baseboard_fab2_lib.baseboard_fab2(sch_1):page233_i225:pgnd(5)"
				( attribute "PN" "21"
					( Origin gPackager )
				)
				( objectStatus "EU4G1.21" )
			)
			( pin "@baseboard_fab2_lib.baseboard_fab2(sch_1):page233_i225:pgnd(6)"
				( attribute "PN" "22"
					( Origin gPackager )
				)
				( objectStatus "EU4G1.22" )
			)
			( pin "@baseboard_fab2_lib.baseboard_fab2(sch_1):page233_i225:pgnd(7)"
				( attribute "PN" "23"
					( Origin gPackager )
				)
				( objectStatus "EU4G1.23" )
			)
			( pin "@baseboard_fab2_lib.baseboard_fab2(sch_1):page233_i225:pgnd(8)"
				( attribute "PN" "24"
					( Origin gPackager )
				)
				( objectStatus "EU4G1.24" )
			)
			( pin "@baseboard_fab2_lib.baseboard_fab2(sch_1):page233_i225:pgnd(9)"
				( attribute "PN" "25"
					( Origin gPackager )
				)
				( objectStatus "EU4G1.25" )
			)
			( pin "@baseboard_fab2_lib.baseboard_fab2(sch_1):page233_i225:pgnd(10)"
				( attribute "PN" "26"
					( Origin gPackager )
				)
				( objectStatus "EU4G1.26" )
			)
			( pin "@baseboard_fab2_lib.baseboard_fab2(sch_1):page233_i225:pgnd(11)"
				( attribute "PN" "27"
					( Origin gPackager )
				)
				( objectStatus "EU4G1.27" )
			)
			( pin "@baseboard_fab2_lib.baseboard_fab2(sch_1):page233_i225:pgnd(12)"
				( attribute "PN" "28"
					( Origin gPackager )
				)
				( objectStatus "EU4G1.28" )
			)
			( pin "@baseboard_fab2_lib.baseboard_fab2(sch_1):page233_i225:pgnd(13)"
				( attribute "PN" "37"
					( Origin gPackager )
				)
				( objectStatus "EU4G1.37" )
			)
			( pin "@baseboard_fab2_lib.baseboard_fab2(sch_1):page233_i225:ss"
				( attribute "PN" "1"
					( Origin gPackager )
				)
				( objectStatus "EU4G1.1" )
			)
			( pin "@baseboard_fab2_lib.baseboard_fab2(sch_1):page233_i225:vb"
				( attribute "PN" "38"
					( Origin gPackager )
				)
				( objectStatus "EU4G1.38" )
			)
			( pin "@baseboard_fab2_lib.baseboard_fab2(sch_1):page233_i225:vcc"
				( attribute "PN" "39"
					( Origin gPackager )
				)
				( objectStatus "EU4G1.39" )
			)
			( pin "@baseboard_fab2_lib.baseboard_fab2(sch_1):page233_i225:vin(0)"
				( attribute "PN" "8"
					( Origin gPackager )
				)
				( objectStatus "EU4G1.8" )
			)
			( pin "@baseboard_fab2_lib.baseboard_fab2(sch_1):page233_i225:vin(1)"
				( attribute "PN" "9"
					( Origin gPackager )
				)
				( objectStatus "EU4G1.9" )
			)
			( pin "@baseboard_fab2_lib.baseboard_fab2(sch_1):page233_i225:vin(2)"
				( attribute "PN" "10"
					( Origin gPackager )
				)
				( objectStatus "EU4G1.10" )
			)
			( pin "@baseboard_fab2_lib.baseboard_fab2(sch_1):page233_i225:vin(3)"
				( attribute "PN" "11"
					( Origin gPackager )
				)
				( objectStatus "EU4G1.11" )
			)
			( pin "@baseboard_fab2_lib.baseboard_fab2(sch_1):page233_i225:vin(4)"
				( attribute "PN" "12"
					( Origin gPackager )
				)
				( objectStatus "EU4G1.12" )
			)
			( pin "@baseboard_fab2_lib.baseboard_fab2(sch_1):page233_i225:vin(5)"
				( attribute "PN" "13"
					( Origin gPackager )
				)
				( objectStatus "EU4G1.13" )
			)
			( pin "@baseboard_fab2_lib.baseboard_fab2(sch_1):page233_i225:vin(6)"
				( attribute "PN" "14"
					( Origin gPackager )
				)
				( objectStatus "EU4G1.14" )
			)
			( pin "@baseboard_fab2_lib.baseboard_fab2(sch_1):page233_i225:vin(7)"
				( attribute "PN" "42"
					( Origin gPackager )
				)
				( objectStatus "EU4G1.42" )
			)
			( pin "@baseboard_fab2_lib.baseboard_fab2(sch_1):page233_i225:vsw"
				( attribute "PN" "35"
					( Origin gPackager )
				)
				( objectStatus "EU4G1.35" )
			)
			( pin "@baseboard_fab2_lib.baseboard_fab2(sch_1):page233_i225:vswh(0)"
				( attribute "PN" "15"
					( Origin gPackager )
				)
				( objectStatus "EU4G1.15" )
			)
			( pin "@baseboard_fab2_lib.baseboard_fab2(sch_1):page233_i225:vswh(1)"
				( attribute "PN" "29"
					( Origin gPackager )
				)
				( objectStatus "EU4G1.29" )
			)
			( pin "@baseboard_fab2_lib.baseboard_fab2(sch_1):page233_i225:vswh(2)"
				( attribute "PN" "30"
					( Origin gPackager )
				)
				( objectStatus "EU4G1.30" )
			)
			( pin "@baseboard_fab2_lib.baseboard_fab2(sch_1):page233_i225:vswh(3)"
				( attribute "PN" "31"
					( Origin gPackager )
				)
				( objectStatus "EU4G1.31" )
			)
			( pin "@baseboard_fab2_lib.baseboard_fab2(sch_1):page233_i225:vswh(4)"
				( attribute "PN" "32"
					( Origin gPackager )
				)
				( objectStatus "EU4G1.32" )
			)
			( pin "@baseboard_fab2_lib.baseboard_fab2(sch_1):page233_i225:vswh(5)"
				( attribute "PN" "33"
					( Origin gPackager )
				)
				( objectStatus "EU4G1.33" )
			)
			( pin "@baseboard_fab2_lib.baseboard_fab2(sch_1):page233_i225:vswh(6)"
				( attribute "PN" "34"
					( Origin gPackager )
				)
				( objectStatus "EU4G1.34" )
			)
			( pin "@baseboard_fab2_lib.baseboard_fab2(sch_1):page233_i225:vswh(7)"
				( attribute "PN" "43"
					( Origin gPackager )
				)
				( objectStatus "EU4G1.43" )
			)
			( pin "@baseboard_fab2_lib.baseboard_fab2(sch_1):page233_i242:a"
				( attribute "PN" "1"
					( Origin gPackager )
				)
				( objectStatus "C6U5.1" )
			)
			( pin "@baseboard_fab2_lib.baseboard_fab2(sch_1):page233_i242:b"
				( attribute "PN" "2"
					( Origin gPackager )
				)
				( objectStatus "C6U5.2" )
			)
			( pin "@baseboard_fab2_lib.baseboard_fab2(sch_1):page233_i247:a"
				( attribute "PN" "1"
					( Origin gPackager )
				)
				( objectStatus "R4G12.1" )
			)
			( pin "@baseboard_fab2_lib.baseboard_fab2(sch_1):page233_i247:b"
				( attribute "PN" "2"
					( Origin gPackager )
				)
				( objectStatus "R4G12.2" )
			)
			( pin "@baseboard_fab2_lib.baseboard_fab2(sch_1):page233_i248:a"
				( attribute "PN" "1"
					( Origin gPackager )
				)
				( objectStatus "C6U4.1" )
			)
			( pin "@baseboard_fab2_lib.baseboard_fab2(sch_1):page233_i248:b"
				( attribute "PN" "2"
					( Origin gPackager )
				)
				( objectStatus "C6U4.2" )
			)
			( pin "@baseboard_fab2_lib.baseboard_fab2(sch_1):page233_i253:a"
				( attribute "PN" "1"
					( Origin gPackager )
				)
				( objectStatus "C4G2.1" )
			)
			( pin "@baseboard_fab2_lib.baseboard_fab2(sch_1):page233_i253:b"
				( attribute "PN" "2"
					( Origin gPackager )
				)
				( objectStatus "C4G2.2" )
			)
			( pin "@baseboard_fab2_lib.baseboard_fab2(sch_1):page233_i254:a"
				( attribute "PN" "1"
					( Origin gPackager )
				)
				( objectStatus "C6U7.1" )
			)
			( pin "@baseboard_fab2_lib.baseboard_fab2(sch_1):page233_i254:b"
				( attribute "PN" "2"
					( Origin gPackager )
				)
				( objectStatus "C6U7.2" )
			)
			( pin "@baseboard_fab2_lib.baseboard_fab2(sch_1):page233_i255:a"
				( attribute "PN" "1"
					( Origin gPackager )
				)
				( objectStatus "C6U8.1" )
			)
			( pin "@baseboard_fab2_lib.baseboard_fab2(sch_1):page233_i255:b"
				( attribute "PN" "2"
					( Origin gPackager )
				)
				( objectStatus "C6U8.2" )
			)
			( pin "@baseboard_fab2_lib.baseboard_fab2(sch_1):page233_i256:a"
				( attribute "PN" "1"
					( Origin gPackager )
				)
				( objectStatus "C4F11.1" )
			)
			( pin "@baseboard_fab2_lib.baseboard_fab2(sch_1):page233_i256:b"
				( attribute "PN" "2"
					( Origin gPackager )
				)
				( objectStatus "C4F11.2" )
			)
			( pin "@baseboard_fab2_lib.baseboard_fab2(sch_1):page233_i266:a"
				( attribute "PN" "1"
					( Origin gPackager )
				)
				( objectStatus "R4G10.1" )
			)
			( pin "@baseboard_fab2_lib.baseboard_fab2(sch_1):page233_i266:b"
				( attribute "PN" "2"
					( Origin gPackager )
				)
				( objectStatus "R4G10.2" )
			)
			( pin "@baseboard_fab2_lib.baseboard_fab2(sch_1):page233_i267:a"
				( attribute "PN" "1"
					( Origin gPackager )
				)
				( objectStatus "C4G11.1" )
			)
			( pin "@baseboard_fab2_lib.baseboard_fab2(sch_1):page233_i267:b"
				( attribute "PN" "2"
					( Origin gPackager )
				)
				( objectStatus "C4G11.2" )
			)
			( pin "@baseboard_fab2_lib.baseboard_fab2(sch_1):page234_i227:a"
				( attribute "PN" "1"
					( Origin gPackager )
				)
				( objectStatus "R4B4.1" )
			)
			( pin "@baseboard_fab2_lib.baseboard_fab2(sch_1):page234_i227:b"
				( attribute "PN" "2"
					( Origin gPackager )
				)
				( objectStatus "R4B4.2" )
			)
			( pin "@baseboard_fab2_lib.baseboard_fab2(sch_1):page233_i270:a"
				( attribute "PN" "1"
					( Origin gPackager )
				)
				( objectStatus "R4G7.1" )
			)
			( pin "@baseboard_fab2_lib.baseboard_fab2(sch_1):page233_i270:b"
				( attribute "PN" "2"
					( Origin gPackager )
				)
				( objectStatus "R4G7.2" )
			)
			( pin "@baseboard_fab2_lib.baseboard_fab2(sch_1):page233_i271:a"
				( attribute "PN" "1"
					( Origin gPackager )
				)
				( objectStatus "R4G8.1" )
			)
			( pin "@baseboard_fab2_lib.baseboard_fab2(sch_1):page233_i271:b"
				( attribute "PN" "2"
					( Origin gPackager )
				)
				( objectStatus "R4G8.2" )
			)
			( pin "@baseboard_fab2_lib.baseboard_fab2(sch_1):page233_i272:a"
				( attribute "PN" "1"
					( Origin gPackager )
				)
				( objectStatus "R4G13.1" )
			)
			( pin "@baseboard_fab2_lib.baseboard_fab2(sch_1):page233_i272:b"
				( attribute "PN" "2"
					( Origin gPackager )
				)
				( objectStatus "R4G13.2" )
			)
			( pin "@baseboard_fab2_lib.baseboard_fab2(sch_1):page233_i273:a"
				( attribute "PN" "1"
					( Origin gPackager )
				)
				( objectStatus "C4G6.1" )
			)
			( pin "@baseboard_fab2_lib.baseboard_fab2(sch_1):page233_i273:b"
				( attribute "PN" "2"
					( Origin gPackager )
				)
				( objectStatus "C4G6.2" )
			)
			( pin "@baseboard_fab2_lib.baseboard_fab2(sch_1):page233_i274:a"
				( attribute "PN" "1"
					( Origin gPackager )
				)
				( objectStatus "C4G10.1" )
			)
			( pin "@baseboard_fab2_lib.baseboard_fab2(sch_1):page233_i274:b"
				( attribute "PN" "2"
					( Origin gPackager )
				)
				( objectStatus "C4G10.2" )
			)
			( pin "@baseboard_fab2_lib.baseboard_fab2(sch_1):page233_i275:a"
				( attribute "PN" "1"
					( Origin gPackager )
				)
				( objectStatus "R4G4.1" )
			)
			( pin "@baseboard_fab2_lib.baseboard_fab2(sch_1):page233_i275:b"
				( attribute "PN" "2"
					( Origin gPackager )
				)
				( objectStatus "R4G4.2" )
			)
			( pin "@baseboard_fab2_lib.baseboard_fab2(sch_1):page233_i277:ina"
				( attribute "PN" "1"
					( Origin gPackager )
				)
				( objectStatus "L4G1.1" )
			)
			( pin "@baseboard_fab2_lib.baseboard_fab2(sch_1):page233_i277:inb"
				( attribute "PN" "2"
					( Origin gPackager )
				)
				( objectStatus "L4G1.2" )
			)
			( pin "@baseboard_fab2_lib.baseboard_fab2(sch_1):page234_i29:a"
				( attribute "PN" "1"
					( Origin gPackager )
				)
				( objectStatus "R4B14.1" )
			)
			( pin "@baseboard_fab2_lib.baseboard_fab2(sch_1):page234_i29:b"
				( attribute "PN" "2"
					( Origin gPackager )
				)
				( objectStatus "R4B14.2" )
			)
			( pin "@baseboard_fab2_lib.baseboard_fab2(sch_1):page234_i84:a"
				( attribute "PN" "1"
					( Origin gPackager )
				)
				( objectStatus "C3B2.1" )
			)
			( pin "@baseboard_fab2_lib.baseboard_fab2(sch_1):page234_i84:b"
				( attribute "PN" "2"
					( Origin gPackager )
				)
				( objectStatus "C3B2.2" )
			)
			( pin "@baseboard_fab2_lib.baseboard_fab2(sch_1):page234_i86:a"
				( attribute "PN" "1"
					( Origin gPackager )
				)
				( objectStatus "C3A8.1" )
			)
			( pin "@baseboard_fab2_lib.baseboard_fab2(sch_1):page234_i86:b"
				( attribute "PN" "2"
					( Origin gPackager )
				)
				( objectStatus "C3A8.2" )
			)
			( pin "@baseboard_fab2_lib.baseboard_fab2(sch_1):page234_i87:a"
				( attribute "PN" "1"
					( Origin gPackager )
				)
				( objectStatus "C7L3.1" )
			)
			( pin "@baseboard_fab2_lib.baseboard_fab2(sch_1):page234_i87:b"
				( attribute "PN" "2"
					( Origin gPackager )
				)
				( objectStatus "C7L3.2" )
			)
			( pin "@baseboard_fab2_lib.baseboard_fab2(sch_1):page234_i88:a"
				( attribute "PN" "1"
					( Origin gPackager )
				)
				( objectStatus "C7L2.1" )
			)
			( pin "@baseboard_fab2_lib.baseboard_fab2(sch_1):page234_i88:b"
				( attribute "PN" "2"
					( Origin gPackager )
				)
				( objectStatus "C7L2.2" )
			)
			( pin "@baseboard_fab2_lib.baseboard_fab2(sch_1):page234_i89:a"
				( attribute "PN" "1"
					( Origin gPackager )
				)
				( objectStatus "C7L7.1" )
			)
			( pin "@baseboard_fab2_lib.baseboard_fab2(sch_1):page234_i89:b"
				( attribute "PN" "2"
					( Origin gPackager )
				)
				( objectStatus "C7L7.2" )
			)
			( pin "@baseboard_fab2_lib.baseboard_fab2(sch_1):page234_i90:a"
				( attribute "PN" "1"
					( Origin gPackager )
				)
				( objectStatus "C7L6.1" )
			)
			( pin "@baseboard_fab2_lib.baseboard_fab2(sch_1):page234_i90:b"
				( attribute "PN" "2"
					( Origin gPackager )
				)
				( objectStatus "C7L6.2" )
			)
			( pin "@baseboard_fab2_lib.baseboard_fab2(sch_1):page234_i91:a"
				( attribute "PN" "1"
					( Origin gPackager )
				)
				( objectStatus "C7M4.1" )
			)
			( pin "@baseboard_fab2_lib.baseboard_fab2(sch_1):page234_i91:b"
				( attribute "PN" "2"
					( Origin gPackager )
				)
				( objectStatus "C7M4.2" )
			)
			( pin "@baseboard_fab2_lib.baseboard_fab2(sch_1):page234_i92:a"
				( attribute "PN" "1"
					( Origin gPackager )
				)
				( objectStatus "C7M3.1" )
			)
			( pin "@baseboard_fab2_lib.baseboard_fab2(sch_1):page234_i92:b"
				( attribute "PN" "2"
					( Origin gPackager )
				)
				( objectStatus "C7M3.2" )
			)
			( pin "@baseboard_fab2_lib.baseboard_fab2(sch_1):page234_i93:a"
				( attribute "PN" "1"
					( Origin gPackager )
				)
				( objectStatus "C3A4.1" )
			)
			( pin "@baseboard_fab2_lib.baseboard_fab2(sch_1):page234_i93:b"
				( attribute "PN" "2"
					( Origin gPackager )
				)
				( objectStatus "C3A4.2" )
			)
			( pin "@baseboard_fab2_lib.baseboard_fab2(sch_1):page234_i94:a"
				( attribute "PN" "1"
					( Origin gPackager )
				)
				( objectStatus "C3B1.1" )
			)
			( pin "@baseboard_fab2_lib.baseboard_fab2(sch_1):page234_i94:b"
				( attribute "PN" "2"
					( Origin gPackager )
				)
				( objectStatus "C3B1.2" )
			)
			( pin "@baseboard_fab2_lib.baseboard_fab2(sch_1):page234_i95:a"
				( attribute "PN" "1"
					( Origin gPackager )
				)
				( objectStatus "C3A7.1" )
			)
			( pin "@baseboard_fab2_lib.baseboard_fab2(sch_1):page234_i95:b"
				( attribute "PN" "2"
					( Origin gPackager )
				)
				( objectStatus "C3A7.2" )
			)
			( pin "@baseboard_fab2_lib.baseboard_fab2(sch_1):page234_i97:a"
				( attribute "PN" "1"
					( Origin gPackager )
				)
				( objectStatus "C3A3.1" )
			)
			( pin "@baseboard_fab2_lib.baseboard_fab2(sch_1):page234_i97:b"
				( attribute "PN" "2"
					( Origin gPackager )
				)
				( objectStatus "C3A3.2" )
			)
			( pin "@baseboard_fab2_lib.baseboard_fab2(sch_1):page234_i129:a"
				( attribute "PN" "1"
					( Origin gPackager )
				)
				( objectStatus "C4B5.1" )
			)
			( pin "@baseboard_fab2_lib.baseboard_fab2(sch_1):page234_i129:b"
				( attribute "PN" "2"
					( Origin gPackager )
				)
				( objectStatus "C4B5.2" )
			)
			( pin "@baseboard_fab2_lib.baseboard_fab2(sch_1):page233_i278:\1\"
				( attribute "PN" "1"
					( Origin gPackager )
				)
				( objectStatus "C22W6.1" )
			)
			( pin "@baseboard_fab2_lib.baseboard_fab2(sch_1):page233_i278:\2\"
				( attribute "PN" "2"
					( Origin gPackager )
				)
				( objectStatus "C22W6.2" )
			)
			( pin "@baseboard_fab2_lib.baseboard_fab2(sch_1):page234_i139:a"
				( attribute "PN" "1"
					( Origin gPackager )
				)
				( objectStatus "C4B8.1" )
			)
			( pin "@baseboard_fab2_lib.baseboard_fab2(sch_1):page234_i139:b"
				( attribute "PN" "2"
					( Origin gPackager )
				)
				( objectStatus "C4B8.2" )
			)
			( pin "@baseboard_fab2_lib.baseboard_fab2(sch_1):page234_i143:a"
				( attribute "PN" "1"
					( Origin gPackager )
				)
				( objectStatus "R4B10.1" )
			)
			( pin "@baseboard_fab2_lib.baseboard_fab2(sch_1):page234_i143:b"
				( attribute "PN" "2"
					( Origin gPackager )
				)
				( objectStatus "R4B10.2" )
			)
			( pin "@baseboard_fab2_lib.baseboard_fab2(sch_1):page234_i144:a"
				( attribute "PN" "1"
					( Origin gPackager )
				)
				( objectStatus "C6L12.1" )
			)
			( pin "@baseboard_fab2_lib.baseboard_fab2(sch_1):page234_i144:b"
				( attribute "PN" "2"
					( Origin gPackager )
				)
				( objectStatus "C6L12.2" )
			)
			( pin "@baseboard_fab2_lib.baseboard_fab2(sch_1):page234_i146:a"
				( attribute "PN" "1"
					( Origin gPackager )
				)
				( objectStatus "C4B6.1" )
			)
			( pin "@baseboard_fab2_lib.baseboard_fab2(sch_1):page234_i146:b"
				( attribute "PN" "2"
					( Origin gPackager )
				)
				( objectStatus "C4B6.2" )
			)
			( pin "@baseboard_fab2_lib.baseboard_fab2(sch_1):page234_i152:a"
				( attribute "PN" "1"
					( Origin gPackager )
				)
				( objectStatus "C6L11.1" )
			)
			( pin "@baseboard_fab2_lib.baseboard_fab2(sch_1):page234_i152:b"
				( attribute "PN" "2"
					( Origin gPackager )
				)
				( objectStatus "C6L11.2" )
			)
			( pin "@baseboard_fab2_lib.baseboard_fab2(sch_1):page234_i154:a"
				( attribute "PN" "1"
					( Origin gPackager )
				)
				( objectStatus "FB4A1.1" )
			)
			( pin "@baseboard_fab2_lib.baseboard_fab2(sch_1):page234_i154:b"
				( attribute "PN" "2"
					( Origin gPackager )
				)
				( objectStatus "FB4A1.2" )
			)
			( pin "@baseboard_fab2_lib.baseboard_fab2(sch_1):page233_i282:a"
				( attribute "PN" "1"
					( Origin gPackager )
				)
				( objectStatus "R4G24.1" )
			)
			( pin "@baseboard_fab2_lib.baseboard_fab2(sch_1):page233_i282:b"
				( attribute "PN" "2"
					( Origin gPackager )
				)
				( objectStatus "R4G24.2" )
			)
			( pin "@baseboard_fab2_lib.baseboard_fab2(sch_1):page234_i162:a"
				( attribute "PN" "1"
					( Origin gPackager )
				)
				( objectStatus "R4A7.1" )
			)
			( pin "@baseboard_fab2_lib.baseboard_fab2(sch_1):page234_i162:b"
				( attribute "PN" "2"
					( Origin gPackager )
				)
				( objectStatus "R4A7.2" )
			)
			( pin "@baseboard_fab2_lib.baseboard_fab2(sch_1):page234_i163:a"
				( attribute "PN" "1"
					( Origin gPackager )
				)
				( objectStatus "C4A16.1" )
			)
			( pin "@baseboard_fab2_lib.baseboard_fab2(sch_1):page234_i163:b"
				( attribute "PN" "2"
					( Origin gPackager )
				)
				( objectStatus "C4A16.2" )
			)
			( pin "@baseboard_fab2_lib.baseboard_fab2(sch_1):page234_i164:ina"
				( attribute "PN" "1"
					( Origin gPackager )
				)
				( objectStatus "L4A1.1" )
			)
			( pin "@baseboard_fab2_lib.baseboard_fab2(sch_1):page234_i164:inb"
				( attribute "PN" "2"
					( Origin gPackager )
				)
				( objectStatus "L4A1.2" )
			)
			( pin "@baseboard_fab2_lib.baseboard_fab2(sch_1):page234_i167:a"
				( attribute "PN" "1"
					( Origin gPackager )
				)
				( objectStatus "C3B3.1" )
			)
			( pin "@baseboard_fab2_lib.baseboard_fab2(sch_1):page234_i167:b"
				( attribute "PN" "2"
					( Origin gPackager )
				)
				( objectStatus "C3B3.2" )
			)
			( pin "@baseboard_fab2_lib.baseboard_fab2(sch_1):page234_i177:a"
				( attribute "PN" "1"
					( Origin gPackager )
				)
				( objectStatus "C4B3.1" )
			)
			( pin "@baseboard_fab2_lib.baseboard_fab2(sch_1):page234_i177:b"
				( attribute "PN" "2"
					( Origin gPackager )
				)
				( objectStatus "C4B3.2" )
			)
			( pin "@baseboard_fab2_lib.baseboard_fab2(sch_1):page234_i180:a"
				( attribute "PN" "1"
					( Origin gPackager )
				)
				( objectStatus "C4B2.1" )
			)
			( pin "@baseboard_fab2_lib.baseboard_fab2(sch_1):page234_i180:b"
				( attribute "PN" "2"
					( Origin gPackager )
				)
				( objectStatus "C4B2.2" )
			)
			( pin "@baseboard_fab2_lib.baseboard_fab2(sch_1):page234_i182:a"
				( attribute "PN" "1"
					( Origin gPackager )
				)
				( objectStatus "C4B15.1" )
			)
			( pin "@baseboard_fab2_lib.baseboard_fab2(sch_1):page234_i182:b"
				( attribute "PN" "2"
					( Origin gPackager )
				)
				( objectStatus "C4B15.2" )
			)
			( pin "@baseboard_fab2_lib.baseboard_fab2(sch_1):page234_i183:a"
				( attribute "PN" "1"
					( Origin gPackager )
				)
				( objectStatus "R4B2.1" )
			)
			( pin "@baseboard_fab2_lib.baseboard_fab2(sch_1):page234_i183:b"
				( attribute "PN" "2"
					( Origin gPackager )
				)
				( objectStatus "R4B2.2" )
			)
			( pin "@baseboard_fab2_lib.baseboard_fab2(sch_1):page234_i184:agnd"
				( attribute "PN" "5"
					( Origin gPackager )
				)
				( objectStatus "EU4A3.5" )
			)
			( pin "@baseboard_fab2_lib.baseboard_fab2(sch_1):page234_i184:bst"
				( attribute "PN" "36"
					( Origin gPackager )
				)
				( objectStatus "EU4A3.36" )
			)
			( pin "@baseboard_fab2_lib.baseboard_fab2(sch_1):page234_i184:comp"
				( attribute "PN" "3"
					( Origin gPackager )
				)
				( objectStatus "EU4A3.3" )
			)
			( pin "@baseboard_fab2_lib.baseboard_fab2(sch_1):page234_i184:en"
				( attribute "PN" "40"
					( Origin gPackager )
				)
				( objectStatus "EU4A3.40" )
			)
			( pin "@baseboard_fab2_lib.baseboard_fab2(sch_1):page234_i184:fb"
				( attribute "PN" "2"
					( Origin gPackager )
				)
				( objectStatus "EU4A3.2" )
			)
			( pin "@baseboard_fab2_lib.baseboard_fab2(sch_1):page234_i184:gnd"
				( attribute "PN" "41"
					( Origin gPackager )
				)
				( objectStatus "EU4A3.41" )
			)
			( pin "@baseboard_fab2_lib.baseboard_fab2(sch_1):page234_i184:iset"
				( attribute "PN" "4"
					( Origin gPackager )
				)
				( objectStatus "EU4A3.4" )
			)
			( pin "@baseboard_fab2_lib.baseboard_fab2(sch_1):page234_i184:ots"
				( attribute "PN" "6"
					( Origin gPackager )
				)
				( objectStatus "EU4A3.6" )
			)
			( pin "@baseboard_fab2_lib.baseboard_fab2(sch_1):page234_i184:pg"
				( attribute "PN" "7"
					( Origin gPackager )
				)
				( objectStatus "EU4A3.7" )
			)
			( pin "@baseboard_fab2_lib.baseboard_fab2(sch_1):page234_i184:pgnd(0)"
				( attribute "PN" "16"
					( Origin gPackager )
				)
				( objectStatus "EU4A3.16" )
			)
			( pin "@baseboard_fab2_lib.baseboard_fab2(sch_1):page234_i184:pgnd(1)"
				( attribute "PN" "17"
					( Origin gPackager )
				)
				( objectStatus "EU4A3.17" )
			)
			( pin "@baseboard_fab2_lib.baseboard_fab2(sch_1):page234_i184:pgnd(2)"
				( attribute "PN" "18"
					( Origin gPackager )
				)
				( objectStatus "EU4A3.18" )
			)
			( pin "@baseboard_fab2_lib.baseboard_fab2(sch_1):page234_i184:pgnd(3)"
				( attribute "PN" "19"
					( Origin gPackager )
				)
				( objectStatus "EU4A3.19" )
			)
			( pin "@baseboard_fab2_lib.baseboard_fab2(sch_1):page234_i184:pgnd(4)"
				( attribute "PN" "20"
					( Origin gPackager )
				)
				( objectStatus "EU4A3.20" )
			)
			( pin "@baseboard_fab2_lib.baseboard_fab2(sch_1):page234_i184:pgnd(5)"
				( attribute "PN" "21"
					( Origin gPackager )
				)
				( objectStatus "EU4A3.21" )
			)
			( pin "@baseboard_fab2_lib.baseboard_fab2(sch_1):page234_i184:pgnd(6)"
				( attribute "PN" "22"
					( Origin gPackager )
				)
				( objectStatus "EU4A3.22" )
			)
			( pin "@baseboard_fab2_lib.baseboard_fab2(sch_1):page234_i184:pgnd(7)"
				( attribute "PN" "23"
					( Origin gPackager )
				)
				( objectStatus "EU4A3.23" )
			)
			( pin "@baseboard_fab2_lib.baseboard_fab2(sch_1):page234_i184:pgnd(8)"
				( attribute "PN" "24"
					( Origin gPackager )
				)
				( objectStatus "EU4A3.24" )
			)
			( pin "@baseboard_fab2_lib.baseboard_fab2(sch_1):page234_i184:pgnd(9)"
				( attribute "PN" "25"
					( Origin gPackager )
				)
				( objectStatus "EU4A3.25" )
			)
			( pin "@baseboard_fab2_lib.baseboard_fab2(sch_1):page234_i184:pgnd(10)"
				( attribute "PN" "26"
					( Origin gPackager )
				)
				( objectStatus "EU4A3.26" )
			)
			( pin "@baseboard_fab2_lib.baseboard_fab2(sch_1):page234_i184:pgnd(11)"
				( attribute "PN" "27"
					( Origin gPackager )
				)
				( objectStatus "EU4A3.27" )
			)
			( pin "@baseboard_fab2_lib.baseboard_fab2(sch_1):page234_i184:pgnd(12)"
				( attribute "PN" "28"
					( Origin gPackager )
				)
				( objectStatus "EU4A3.28" )
			)
			( pin "@baseboard_fab2_lib.baseboard_fab2(sch_1):page234_i184:pgnd(13)"
				( attribute "PN" "37"
					( Origin gPackager )
				)
				( objectStatus "EU4A3.37" )
			)
			( pin "@baseboard_fab2_lib.baseboard_fab2(sch_1):page234_i184:ss"
				( attribute "PN" "1"
					( Origin gPackager )
				)
				( objectStatus "EU4A3.1" )
			)
			( pin "@baseboard_fab2_lib.baseboard_fab2(sch_1):page234_i184:vb"
				( attribute "PN" "38"
					( Origin gPackager )
				)
				( objectStatus "EU4A3.38" )
			)
			( pin "@baseboard_fab2_lib.baseboard_fab2(sch_1):page234_i184:vcc"
				( attribute "PN" "39"
					( Origin gPackager )
				)
				( objectStatus "EU4A3.39" )
			)
			( pin "@baseboard_fab2_lib.baseboard_fab2(sch_1):page234_i184:vin(0)"
				( attribute "PN" "8"
					( Origin gPackager )
				)
				( objectStatus "EU4A3.8" )
			)
			( pin "@baseboard_fab2_lib.baseboard_fab2(sch_1):page234_i184:vin(1)"
				( attribute "PN" "9"
					( Origin gPackager )
				)
				( objectStatus "EU4A3.9" )
			)
			( pin "@baseboard_fab2_lib.baseboard_fab2(sch_1):page234_i184:vin(2)"
				( attribute "PN" "10"
					( Origin gPackager )
				)
				( objectStatus "EU4A3.10" )
			)
			( pin "@baseboard_fab2_lib.baseboard_fab2(sch_1):page234_i184:vin(3)"
				( attribute "PN" "11"
					( Origin gPackager )
				)
				( objectStatus "EU4A3.11" )
			)
			( pin "@baseboard_fab2_lib.baseboard_fab2(sch_1):page234_i184:vin(4)"
				( attribute "PN" "12"
					( Origin gPackager )
				)
				( objectStatus "EU4A3.12" )
			)
			( pin "@baseboard_fab2_lib.baseboard_fab2(sch_1):page234_i184:vin(5)"
				( attribute "PN" "13"
					( Origin gPackager )
				)
				( objectStatus "EU4A3.13" )
			)
			( pin "@baseboard_fab2_lib.baseboard_fab2(sch_1):page234_i184:vin(6)"
				( attribute "PN" "14"
					( Origin gPackager )
				)
				( objectStatus "EU4A3.14" )
			)
			( pin "@baseboard_fab2_lib.baseboard_fab2(sch_1):page234_i184:vin(7)"
				( attribute "PN" "42"
					( Origin gPackager )
				)
				( objectStatus "EU4A3.42" )
			)
			( pin "@baseboard_fab2_lib.baseboard_fab2(sch_1):page234_i184:vsw"
				( attribute "PN" "35"
					( Origin gPackager )
				)
				( objectStatus "EU4A3.35" )
			)
			( pin "@baseboard_fab2_lib.baseboard_fab2(sch_1):page234_i184:vswh(0)"
				( attribute "PN" "15"
					( Origin gPackager )
				)
				( objectStatus "EU4A3.15" )
			)
			( pin "@baseboard_fab2_lib.baseboard_fab2(sch_1):page234_i184:vswh(1)"
				( attribute "PN" "29"
					( Origin gPackager )
				)
				( objectStatus "EU4A3.29" )
			)
			( pin "@baseboard_fab2_lib.baseboard_fab2(sch_1):page234_i184:vswh(2)"
				( attribute "PN" "30"
					( Origin gPackager )
				)
				( objectStatus "EU4A3.30" )
			)
			( pin "@baseboard_fab2_lib.baseboard_fab2(sch_1):page234_i184:vswh(3)"
				( attribute "PN" "31"
					( Origin gPackager )
				)
				( objectStatus "EU4A3.31" )
			)
			( pin "@baseboard_fab2_lib.baseboard_fab2(sch_1):page234_i184:vswh(4)"
				( attribute "PN" "32"
					( Origin gPackager )
				)
				( objectStatus "EU4A3.32" )
			)
			( pin "@baseboard_fab2_lib.baseboard_fab2(sch_1):page234_i184:vswh(5)"
				( attribute "PN" "33"
					( Origin gPackager )
				)
				( objectStatus "EU4A3.33" )
			)
			( pin "@baseboard_fab2_lib.baseboard_fab2(sch_1):page234_i184:vswh(6)"
				( attribute "PN" "34"
					( Origin gPackager )
				)
				( objectStatus "EU4A3.34" )
			)
			( pin "@baseboard_fab2_lib.baseboard_fab2(sch_1):page234_i184:vswh(7)"
				( attribute "PN" "43"
					( Origin gPackager )
				)
				( objectStatus "EU4A3.43" )
			)
			( pin "@baseboard_fab2_lib.baseboard_fab2(sch_1):page234_i199:a"
				( attribute "PN" "1"
					( Origin gPackager )
				)
				( objectStatus "C4A20.1" )
			)
			( pin "@baseboard_fab2_lib.baseboard_fab2(sch_1):page234_i199:b"
				( attribute "PN" "2"
					( Origin gPackager )
				)
				( objectStatus "C4A20.2" )
			)
			( pin "@baseboard_fab2_lib.baseboard_fab2(sch_1):page234_i201:a"
				( attribute "PN" "1"
					( Origin gPackager )
				)
				( objectStatus "R4B7.1" )
			)
			( pin "@baseboard_fab2_lib.baseboard_fab2(sch_1):page234_i201:b"
				( attribute "PN" "2"
					( Origin gPackager )
				)
				( objectStatus "R4B7.2" )
			)
			( pin "@baseboard_fab2_lib.baseboard_fab2(sch_1):page234_i202:a"
				( attribute "PN" "1"
					( Origin gPackager )
				)
				( objectStatus "C6L10.1" )
			)
			( pin "@baseboard_fab2_lib.baseboard_fab2(sch_1):page234_i202:b"
				( attribute "PN" "2"
					( Origin gPackager )
				)
				( objectStatus "C6L10.2" )
			)
			( pin "@baseboard_fab2_lib.baseboard_fab2(sch_1):page234_i203:a"
				( attribute "PN" "1"
					( Origin gPackager )
				)
				( objectStatus "C6M3.1" )
			)
			( pin "@baseboard_fab2_lib.baseboard_fab2(sch_1):page234_i203:b"
				( attribute "PN" "2"
					( Origin gPackager )
				)
				( objectStatus "C6M3.2" )
			)
			( pin "@baseboard_fab2_lib.baseboard_fab2(sch_1):page234_i204:a"
				( attribute "PN" "1"
					( Origin gPackager )
				)
				( objectStatus "C6M5.1" )
			)
			( pin "@baseboard_fab2_lib.baseboard_fab2(sch_1):page234_i204:b"
				( attribute "PN" "2"
					( Origin gPackager )
				)
				( objectStatus "C6M5.2" )
			)
			( pin "@baseboard_fab2_lib.baseboard_fab2(sch_1):page234_i205:a"
				( attribute "PN" "1"
					( Origin gPackager )
				)
				( objectStatus "C4A19.1" )
			)
			( pin "@baseboard_fab2_lib.baseboard_fab2(sch_1):page234_i205:b"
				( attribute "PN" "2"
					( Origin gPackager )
				)
				( objectStatus "C4A19.2" )
			)
			( pin "@baseboard_fab2_lib.baseboard_fab2(sch_1):page234_i210:a"
				( attribute "PN" "1"
					( Origin gPackager )
				)
				( objectStatus "C6L8.1" )
			)
			( pin "@baseboard_fab2_lib.baseboard_fab2(sch_1):page234_i210:b"
				( attribute "PN" "2"
					( Origin gPackager )
				)
				( objectStatus "C6L8.2" )
			)
			( pin "@baseboard_fab2_lib.baseboard_fab2(sch_1):page234_i211:a"
				( attribute "PN" "1"
					( Origin gPackager )
				)
				( objectStatus "C4B9.1" )
			)
			( pin "@baseboard_fab2_lib.baseboard_fab2(sch_1):page234_i211:b"
				( attribute "PN" "2"
					( Origin gPackager )
				)
				( objectStatus "C4B9.2" )
			)
			( pin "@baseboard_fab2_lib.baseboard_fab2(sch_1):page234_i212:a"
				( attribute "PN" "1"
					( Origin gPackager )
				)
				( objectStatus "C4B4.1" )
			)
			( pin "@baseboard_fab2_lib.baseboard_fab2(sch_1):page234_i212:b"
				( attribute "PN" "2"
					( Origin gPackager )
				)
				( objectStatus "C4B4.2" )
			)
			( pin "@baseboard_fab2_lib.baseboard_fab2(sch_1):page234_i213:a"
				( attribute "PN" "1"
					( Origin gPackager )
				)
				( objectStatus "R4B8.1" )
			)
			( pin "@baseboard_fab2_lib.baseboard_fab2(sch_1):page234_i213:b"
				( attribute "PN" "2"
					( Origin gPackager )
				)
				( objectStatus "R4B8.2" )
			)
			( pin "@baseboard_fab2_lib.baseboard_fab2(sch_1):page234_i214:a"
				( attribute "PN" "1"
					( Origin gPackager )
				)
				( objectStatus "R4B3.1" )
			)
			( pin "@baseboard_fab2_lib.baseboard_fab2(sch_1):page234_i214:b"
				( attribute "PN" "2"
					( Origin gPackager )
				)
				( objectStatus "R4B3.2" )
			)
			( pin "@baseboard_fab2_lib.baseboard_fab2(sch_1):page234_i215:a"
				( attribute "PN" "1"
					( Origin gPackager )
				)
				( objectStatus "R4B5.1" )
			)
			( pin "@baseboard_fab2_lib.baseboard_fab2(sch_1):page234_i215:b"
				( attribute "PN" "2"
					( Origin gPackager )
				)
				( objectStatus "R4B5.2" )
			)
			( pin "@baseboard_fab2_lib.baseboard_fab2(sch_1):page234_i218:a"
				( attribute "PN" "1"
					( Origin gPackager )
				)
				( objectStatus "C4B7.1" )
			)
			( pin "@baseboard_fab2_lib.baseboard_fab2(sch_1):page234_i218:b"
				( attribute "PN" "2"
					( Origin gPackager )
				)
				( objectStatus "C4B7.2" )
			)
			( pin "@baseboard_fab2_lib.baseboard_fab2(sch_1):page234_i219:a"
				( attribute "PN" "1"
					( Origin gPackager )
				)
				( objectStatus "R4B9.1" )
			)
			( pin "@baseboard_fab2_lib.baseboard_fab2(sch_1):page234_i219:b"
				( attribute "PN" "2"
					( Origin gPackager )
				)
				( objectStatus "R4B9.2" )
			)
			( pin "@baseboard_fab2_lib.baseboard_fab2(sch_1):page234_i220:a"
				( attribute "PN" "1"
					( Origin gPackager )
				)
				( objectStatus "R4B1.1" )
			)
			( pin "@baseboard_fab2_lib.baseboard_fab2(sch_1):page234_i220:b"
				( attribute "PN" "2"
					( Origin gPackager )
				)
				( objectStatus "R4B1.2" )
			)
			( pin "@baseboard_fab2_lib.baseboard_fab2(sch_1):page235_i143:a"
				( attribute "PN" "1"
					( Origin gPackager )
				)
				( objectStatus "C8A7.1" )
			)
			( pin "@baseboard_fab2_lib.baseboard_fab2(sch_1):page235_i143:b"
				( attribute "PN" "2"
					( Origin gPackager )
				)
				( objectStatus "C8A7.2" )
			)
			( pin "@baseboard_fab2_lib.baseboard_fab2(sch_1):page235_i145:a"
				( attribute "PN" "1"
					( Origin gPackager )
				)
				( objectStatus "C8A8.1" )
			)
			( pin "@baseboard_fab2_lib.baseboard_fab2(sch_1):page235_i145:b"
				( attribute "PN" "2"
					( Origin gPackager )
				)
				( objectStatus "C8A8.2" )
			)
			( pin "@baseboard_fab2_lib.baseboard_fab2(sch_1):page235_i147:a"
				( attribute "PN" "1"
					( Origin gPackager )
				)
				( objectStatus "R2L16.1" )
			)
			( pin "@baseboard_fab2_lib.baseboard_fab2(sch_1):page235_i147:b"
				( attribute "PN" "2"
					( Origin gPackager )
				)
				( objectStatus "R2L16.2" )
			)
			( pin "@baseboard_fab2_lib.baseboard_fab2(sch_1):page235_i148:a"
				( attribute "PN" "1"
					( Origin gPackager )
				)
				( objectStatus "R2L24.1" )
			)
			( pin "@baseboard_fab2_lib.baseboard_fab2(sch_1):page235_i148:b"
				( attribute "PN" "2"
					( Origin gPackager )
				)
				( objectStatus "R2L24.2" )
			)
			( pin "@baseboard_fab2_lib.baseboard_fab2(sch_1):page235_i149:a"
				( attribute "PN" "1"
					( Origin gPackager )
				)
				( objectStatus "R8A6.1" )
			)
			( pin "@baseboard_fab2_lib.baseboard_fab2(sch_1):page235_i149:b"
				( attribute "PN" "2"
					( Origin gPackager )
				)
				( objectStatus "R8A6.2" )
			)
			( pin "@baseboard_fab2_lib.baseboard_fab2(sch_1):page235_i151:a"
				( attribute "PN" "1"
					( Origin gPackager )
				)
				( objectStatus "C2L8.1" )
			)
			( pin "@baseboard_fab2_lib.baseboard_fab2(sch_1):page235_i151:b"
				( attribute "PN" "2"
					( Origin gPackager )
				)
				( objectStatus "C2L8.2" )
			)
			( pin "@baseboard_fab2_lib.baseboard_fab2(sch_1):page235_i153:a"
				( attribute "PN" "1"
					( Origin gPackager )
				)
				( objectStatus "C2L2.1" )
			)
			( pin "@baseboard_fab2_lib.baseboard_fab2(sch_1):page235_i153:b"
				( attribute "PN" "2"
					( Origin gPackager )
				)
				( objectStatus "C2L2.2" )
			)
			( pin "@baseboard_fab2_lib.baseboard_fab2(sch_1):page235_i154:a"
				( attribute "PN" "1"
					( Origin gPackager )
				)
				( objectStatus "R2L8.1" )
			)
			( pin "@baseboard_fab2_lib.baseboard_fab2(sch_1):page235_i154:b"
				( attribute "PN" "2"
					( Origin gPackager )
				)
				( objectStatus "R2L8.2" )
			)
			( pin "@baseboard_fab2_lib.baseboard_fab2(sch_1):page235_i159:a"
				( attribute "PN" "1"
					( Origin gPackager )
				)
				( objectStatus "R2L14.1" )
			)
			( pin "@baseboard_fab2_lib.baseboard_fab2(sch_1):page235_i159:b"
				( attribute "PN" "2"
					( Origin gPackager )
				)
				( objectStatus "R2L14.2" )
			)
			( pin "@baseboard_fab2_lib.baseboard_fab2(sch_1):page235_i165:a"
				( attribute "PN" "1"
					( Origin gPackager )
				)
				( objectStatus "R8A4.1" )
			)
			( pin "@baseboard_fab2_lib.baseboard_fab2(sch_1):page235_i165:b"
				( attribute "PN" "2"
					( Origin gPackager )
				)
				( objectStatus "R8A4.2" )
			)
			( pin "@baseboard_fab2_lib.baseboard_fab2(sch_1):page235_i166:a"
				( attribute "PN" "1"
					( Origin gPackager )
				)
				( objectStatus "R2L10.1" )
			)
			( pin "@baseboard_fab2_lib.baseboard_fab2(sch_1):page235_i166:b"
				( attribute "PN" "2"
					( Origin gPackager )
				)
				( objectStatus "R2L10.2" )
			)
			( pin "@baseboard_fab2_lib.baseboard_fab2(sch_1):page235_i169:a"
				( attribute "PN" "1"
					( Origin gPackager )
				)
				( objectStatus "C2L11.1" )
			)
			( pin "@baseboard_fab2_lib.baseboard_fab2(sch_1):page235_i169:b"
				( attribute "PN" "2"
					( Origin gPackager )
				)
				( objectStatus "C2L11.2" )
			)
			( pin "@baseboard_fab2_lib.baseboard_fab2(sch_1):page235_i209:a"
				( attribute "PN" "1"
					( Origin gPackager )
				)
				( objectStatus "C8A2.1" )
			)
			( pin "@baseboard_fab2_lib.baseboard_fab2(sch_1):page235_i209:b"
				( attribute "PN" "2"
					( Origin gPackager )
				)
				( objectStatus "C8A2.2" )
			)
			( pin "@baseboard_fab2_lib.baseboard_fab2(sch_1):page235_i210:a"
				( attribute "PN" "1"
					( Origin gPackager )
				)
				( objectStatus "R8A1.1" )
			)
			( pin "@baseboard_fab2_lib.baseboard_fab2(sch_1):page235_i210:b"
				( attribute "PN" "2"
					( Origin gPackager )
				)
				( objectStatus "R8A1.2" )
			)
			( pin "@baseboard_fab2_lib.baseboard_fab2(sch_1):page235_i216:a"
				( attribute "PN" "1"
					( Origin gPackager )
				)
				( objectStatus "R8A5.1" )
			)
			( pin "@baseboard_fab2_lib.baseboard_fab2(sch_1):page235_i216:b"
				( attribute "PN" "2"
					( Origin gPackager )
				)
				( objectStatus "R8A5.2" )
			)
			( pin "@baseboard_fab2_lib.baseboard_fab2(sch_1):page235_i217:a"
				( attribute "PN" "1"
					( Origin gPackager )
				)
				( objectStatus "R8A2.1" )
			)
			( pin "@baseboard_fab2_lib.baseboard_fab2(sch_1):page235_i217:b"
				( attribute "PN" "2"
					( Origin gPackager )
				)
				( objectStatus "R8A2.2" )
			)
			( pin "@baseboard_fab2_lib.baseboard_fab2(sch_1):page235_i218:a"
				( attribute "PN" "1"
					( Origin gPackager )
				)
				( objectStatus "C8A9.1" )
			)
			( pin "@baseboard_fab2_lib.baseboard_fab2(sch_1):page235_i218:b"
				( attribute "PN" "2"
					( Origin gPackager )
				)
				( objectStatus "C8A9.2" )
			)
			( pin "@baseboard_fab2_lib.baseboard_fab2(sch_1):page235_i221:a"
				( attribute "PN" "1"
					( Origin gPackager )
				)
				( objectStatus "R2L17.1" )
			)
			( pin "@baseboard_fab2_lib.baseboard_fab2(sch_1):page235_i221:b"
				( attribute "PN" "2"
					( Origin gPackager )
				)
				( objectStatus "R2L17.2" )
			)
			( pin "@baseboard_fab2_lib.baseboard_fab2(sch_1):page235_i222:a"
				( attribute "PN" "1"
					( Origin gPackager )
				)
				( objectStatus "R8A7.1" )
			)
			( pin "@baseboard_fab2_lib.baseboard_fab2(sch_1):page235_i222:b"
				( attribute "PN" "2"
					( Origin gPackager )
				)
				( objectStatus "R8A7.2" )
			)
			( pin "@baseboard_fab2_lib.baseboard_fab2(sch_1):page235_i229:airef1"
				( attribute "PN" "21"
					( Origin gPackager )
				)
				( objectStatus "EU8A1.21" )
			)
			( pin "@baseboard_fab2_lib.baseboard_fab2(sch_1):page235_i229:aisen1"
				( attribute "PN" "22"
					( Origin gPackager )
				)
				( objectStatus "EU8A1.22" )
			)
			( pin "@baseboard_fab2_lib.baseboard_fab2(sch_1):page235_i229:apwm1"
				( attribute "PN" "5"
					( Origin gPackager )
				)
				( objectStatus "EU8A1.5" )
			)
			( pin "@baseboard_fab2_lib.baseboard_fab2(sch_1):page235_i229:atsen"
				( attribute "PN" "35"
					( Origin gPackager )
				)
				( objectStatus "EU8A1.35" )
			)
			( pin "@baseboard_fab2_lib.baseboard_fab2(sch_1):page235_i229:avref"
				( attribute "PN" "20"
					( Origin gPackager )
				)
				( objectStatus "EU8A1.20" )
			)
			( pin "@baseboard_fab2_lib.baseboard_fab2(sch_1):page235_i229:avren"
				( attribute "PN" "10"
					( Origin gPackager )
				)
				( objectStatus "EU8A1.10" )
			)
			( pin "@baseboard_fab2_lib.baseboard_fab2(sch_1):page235_i229:avrrdy"
				( attribute "PN" "9"
					( Origin gPackager )
				)
				( objectStatus "EU8A1.9" )
			)
			( pin "@baseboard_fab2_lib.baseboard_fab2(sch_1):page235_i229:avsen"
				( attribute "PN" "19"
					( Origin gPackager )
				)
				( objectStatus "EU8A1.19" )
			)
			( pin "@baseboard_fab2_lib.baseboard_fab2(sch_1):page235_i229:biref1"
				( attribute "PN" "25"
					( Origin gPackager )
				)
				( objectStatus "EU8A1.25" )
			)
			( pin "@baseboard_fab2_lib.baseboard_fab2(sch_1):page235_i229:bisen1"
				( attribute "PN" "26"
					( Origin gPackager )
				)
				( objectStatus "EU8A1.26" )
			)
			( pin "@baseboard_fab2_lib.baseboard_fab2(sch_1):page235_i229:bpwm1"
				( attribute "PN" "3"
					( Origin gPackager )
				)
				( objectStatus "EU8A1.3" )
			)
			( pin "@baseboard_fab2_lib.baseboard_fab2(sch_1):page235_i229:btsen"
				( attribute "PN" "34"
					( Origin gPackager )
				)
				( objectStatus "EU8A1.34" )
			)
			( pin "@baseboard_fab2_lib.baseboard_fab2(sch_1):page235_i229:bvref"
				( attribute "PN" "30"
					( Origin gPackager )
				)
				( objectStatus "EU8A1.30" )
			)
			( pin "@baseboard_fab2_lib.baseboard_fab2(sch_1):page235_i229:bvsen"
				( attribute "PN" "29"
					( Origin gPackager )
				)
				( objectStatus "EU8A1.29" )
			)
			( pin "@baseboard_fab2_lib.baseboard_fab2(sch_1):page235_i229:dnc(0)"
				( attribute "PN" "1"
					( Origin gPackager )
				)
				( objectStatus "EU8A1.1" )
			)
			( pin "@baseboard_fab2_lib.baseboard_fab2(sch_1):page235_i229:dnc(1)"
				( attribute "PN" "2"
					( Origin gPackager )
				)
				( objectStatus "EU8A1.2" )
			)
			( pin "@baseboard_fab2_lib.baseboard_fab2(sch_1):page235_i229:dnc(2)"
				( attribute "PN" "4"
					( Origin gPackager )
				)
				( objectStatus "EU8A1.4" )
			)
			( pin "@baseboard_fab2_lib.baseboard_fab2(sch_1):page235_i229:dnc(3)"
				( attribute "PN" "24"
					( Origin gPackager )
				)
				( objectStatus "EU8A1.24" )
			)
			( pin "@baseboard_fab2_lib.baseboard_fab2(sch_1):page235_i229:dnc(4)"
				( attribute "PN" "28"
					( Origin gPackager )
				)
				( objectStatus "EU8A1.28" )
			)
			( pin "@baseboard_fab2_lib.baseboard_fab2(sch_1):page235_i229:gnd(0)"
				( attribute "PN" "27"
					( Origin gPackager )
				)
				( objectStatus "EU8A1.27" )
			)
			( pin "@baseboard_fab2_lib.baseboard_fab2(sch_1):page235_i229:gnd(1)"
				( attribute "PN" "23"
					( Origin gPackager )
				)
				( objectStatus "EU8A1.23" )
			)
			( pin "@baseboard_fab2_lib.baseboard_fab2(sch_1):page235_i229:iinsen"
				( attribute "PN" "38"
					( Origin gPackager )
				)
				( objectStatus "EU8A1.38" )
			)
			( pin "@baseboard_fab2_lib.baseboard_fab2(sch_1):page235_i229:mp0"
				( attribute "PN" "13"
					( Origin gPackager )
				)
				( objectStatus "EU8A1.13" )
			)
			( pin "@baseboard_fab2_lib.baseboard_fab2(sch_1):page235_i229:mp1"
				( attribute "PN" "14"
					( Origin gPackager )
				)
				( objectStatus "EU8A1.14" )
			)
			( pin "@baseboard_fab2_lib.baseboard_fab2(sch_1):page235_i229:mp2"
				( attribute "PN" "18"
					( Origin gPackager )
				)
				( objectStatus "EU8A1.18" )
			)
			( pin "@baseboard_fab2_lib.baseboard_fab2(sch_1):page235_i229:mp3"
				( attribute "PN" "31"
					( Origin gPackager )
				)
				( objectStatus "EU8A1.31" )
			)
			( pin "@baseboard_fab2_lib.baseboard_fab2(sch_1):page235_i229:mp4"
				( attribute "PN" "32"
					( Origin gPackager )
				)
				( objectStatus "EU8A1.32" )
			)
			( pin "@baseboard_fab2_lib.baseboard_fab2(sch_1):page235_i229:pinalrt_n"
				( attribute "PN" "12"
					( Origin gPackager )
				)
				( objectStatus "EU8A1.12" )
			)
			( pin "@baseboard_fab2_lib.baseboard_fab2(sch_1):page235_i229:reset_n"
				( attribute "PN" "8"
					( Origin gPackager )
				)
				( objectStatus "EU8A1.8" )
			)
			( pin "@baseboard_fab2_lib.baseboard_fab2(sch_1):page235_i229:scl"
				( attribute "PN" "7"
					( Origin gPackager )
				)
				( objectStatus "EU8A1.7" )
			)
			( pin "@baseboard_fab2_lib.baseboard_fab2(sch_1):page235_i229:sda"
				( attribute "PN" "6"
					( Origin gPackager )
				)
				( objectStatus "EU8A1.6" )
			)
			( pin "@baseboard_fab2_lib.baseboard_fab2(sch_1):page235_i229:thpad"
				( attribute "PN" "41"
					( Origin gPackager )
				)
				( objectStatus "EU8A1.41" )
			)
			( pin "@baseboard_fab2_lib.baseboard_fab2(sch_1):page235_i229:valrt_n"
				( attribute "PN" "17"
					( Origin gPackager )
				)
				( objectStatus "EU8A1.17" )
			)
			( pin "@baseboard_fab2_lib.baseboard_fab2(sch_1):page235_i229:vclk"
				( attribute "PN" "15"
					( Origin gPackager )
				)
				( objectStatus "EU8A1.15" )
			)
			( pin "@baseboard_fab2_lib.baseboard_fab2(sch_1):page235_i229:vd12"
				( attribute "PN" "40"
					( Origin gPackager )
				)
				( objectStatus "EU8A1.40" )
			)
			( pin "@baseboard_fab2_lib.baseboard_fab2(sch_1):page235_i229:vdd"
				( attribute "PN" "39"
					( Origin gPackager )
				)
				( objectStatus "EU8A1.39" )
			)
			( pin "@baseboard_fab2_lib.baseboard_fab2(sch_1):page235_i229:vdio"
				( attribute "PN" "16"
					( Origin gPackager )
				)
				( objectStatus "EU8A1.16" )
			)
			( pin "@baseboard_fab2_lib.baseboard_fab2(sch_1):page235_i229:vinsen"
				( attribute "PN" "37"
					( Origin gPackager )
				)
				( objectStatus "EU8A1.37" )
			)
			( pin "@baseboard_fab2_lib.baseboard_fab2(sch_1):page235_i229:vrhot_n"
				( attribute "PN" "11"
					( Origin gPackager )
				)
				( objectStatus "EU8A1.11" )
			)
			( pin "@baseboard_fab2_lib.baseboard_fab2(sch_1):page235_i229:xaddr1"
				( attribute "PN" "36"
					( Origin gPackager )
				)
				( objectStatus "EU8A1.36" )
			)
			( pin "@baseboard_fab2_lib.baseboard_fab2(sch_1):page235_i229:xaddr2"
				( attribute "PN" "33"
					( Origin gPackager )
				)
				( objectStatus "EU8A1.33" )
			)
			( pin "@baseboard_fab2_lib.baseboard_fab2(sch_1):page170_i75:a"
				( attribute "PN" "1"
					( Origin gPackager )
				)
				( objectStatus "R2P8.1" )
			)
			( pin "@baseboard_fab2_lib.baseboard_fab2(sch_1):page170_i75:b"
				( attribute "PN" "2"
					( Origin gPackager )
				)
				( objectStatus "R2P8.2" )
			)
			( pin "@baseboard_fab2_lib.baseboard_fab2(sch_1):page236_i9:a"
				( attribute "PN" "1"
					( Origin gPackager )
				)
				( objectStatus "C7A30.1" )
			)
			( pin "@baseboard_fab2_lib.baseboard_fab2(sch_1):page236_i9:b"
				( attribute "PN" "2"
					( Origin gPackager )
				)
				( objectStatus "C7A30.2" )
			)
			( pin "@baseboard_fab2_lib.baseboard_fab2(sch_1):page236_i16:a"
				( attribute "PN" "1"
					( Origin gPackager )
				)
				( objectStatus "C7A8.1" )
			)
			( pin "@baseboard_fab2_lib.baseboard_fab2(sch_1):page236_i16:b"
				( attribute "PN" "2"
					( Origin gPackager )
				)
				( objectStatus "C7A8.2" )
			)
			( pin "@baseboard_fab2_lib.baseboard_fab2(sch_1):page203_i133:\1\"
				( attribute "PN" "1"
					( Origin gPackager )
				)
				( objectStatus "C4D6.1" )
			)
			( pin "@baseboard_fab2_lib.baseboard_fab2(sch_1):page203_i133:\2\"
				( attribute "PN" "2"
					( Origin gPackager )
				)
				( objectStatus "C4D6.2" )
			)
			( pin "@baseboard_fab2_lib.baseboard_fab2(sch_1):page236_i19:a"
				( attribute "PN" "1"
					( Origin gPackager )
				)
				( objectStatus "C7A6.1" )
			)
			( pin "@baseboard_fab2_lib.baseboard_fab2(sch_1):page236_i19:b"
				( attribute "PN" "2"
					( Origin gPackager )
				)
				( objectStatus "C7A6.2" )
			)
			( pin "@baseboard_fab2_lib.baseboard_fab2(sch_1):page236_i20:a"
				( attribute "PN" "1"
					( Origin gPackager )
				)
				( objectStatus "C7A39.1" )
			)
			( pin "@baseboard_fab2_lib.baseboard_fab2(sch_1):page236_i20:b"
				( attribute "PN" "2"
					( Origin gPackager )
				)
				( objectStatus "C7A39.2" )
			)
			( pin "@baseboard_fab2_lib.baseboard_fab2(sch_1):page236_i21:a"
				( attribute "PN" "1"
					( Origin gPackager )
				)
				( objectStatus "C7A43.1" )
			)
			( pin "@baseboard_fab2_lib.baseboard_fab2(sch_1):page236_i21:b"
				( attribute "PN" "2"
					( Origin gPackager )
				)
				( objectStatus "C7A43.2" )
			)
			( pin "@baseboard_fab2_lib.baseboard_fab2(sch_1):page236_i22:a"
				( attribute "PN" "1"
					( Origin gPackager )
				)
				( objectStatus "C7A7.1" )
			)
			( pin "@baseboard_fab2_lib.baseboard_fab2(sch_1):page236_i22:b"
				( attribute "PN" "2"
					( Origin gPackager )
				)
				( objectStatus "C7A7.2" )
			)
			( pin "@baseboard_fab2_lib.baseboard_fab2(sch_1):page236_i23:a"
				( attribute "PN" "1"
					( Origin gPackager )
				)
				( objectStatus "C3L12.1" )
			)
			( pin "@baseboard_fab2_lib.baseboard_fab2(sch_1):page236_i23:b"
				( attribute "PN" "2"
					( Origin gPackager )
				)
				( objectStatus "C3L12.2" )
			)
			( pin "@baseboard_fab2_lib.baseboard_fab2(sch_1):page236_i24:a"
				( attribute "PN" "1"
					( Origin gPackager )
				)
				( objectStatus "C3L11.1" )
			)
			( pin "@baseboard_fab2_lib.baseboard_fab2(sch_1):page236_i24:b"
				( attribute "PN" "2"
					( Origin gPackager )
				)
				( objectStatus "C3L11.2" )
			)
			( pin "@baseboard_fab2_lib.baseboard_fab2(sch_1):page236_i26:a"
				( attribute "PN" "1"
					( Origin gPackager )
				)
				( objectStatus "C3L8.1" )
			)
			( pin "@baseboard_fab2_lib.baseboard_fab2(sch_1):page236_i26:b"
				( attribute "PN" "2"
					( Origin gPackager )
				)
				( objectStatus "C3L8.2" )
			)
			( pin "@baseboard_fab2_lib.baseboard_fab2(sch_1):page236_i29:a"
				( attribute "PN" "1"
					( Origin gPackager )
				)
				( objectStatus "C3L9.1" )
			)
			( pin "@baseboard_fab2_lib.baseboard_fab2(sch_1):page236_i29:b"
				( attribute "PN" "2"
					( Origin gPackager )
				)
				( objectStatus "C3L9.2" )
			)
			( pin "@baseboard_fab2_lib.baseboard_fab2(sch_1):page236_i31:a"
				( attribute "PN" "1"
					( Origin gPackager )
				)
				( objectStatus "C3L7.1" )
			)
			( pin "@baseboard_fab2_lib.baseboard_fab2(sch_1):page236_i31:b"
				( attribute "PN" "2"
					( Origin gPackager )
				)
				( objectStatus "C3L7.2" )
			)
			( pin "@baseboard_fab2_lib.baseboard_fab2(sch_1):page236_i32:a"
				( attribute "PN" "1"
					( Origin gPackager )
				)
				( objectStatus "C3L10.1" )
			)
			( pin "@baseboard_fab2_lib.baseboard_fab2(sch_1):page236_i32:b"
				( attribute "PN" "2"
					( Origin gPackager )
				)
				( objectStatus "C3L10.2" )
			)
			( pin "@baseboard_fab2_lib.baseboard_fab2(sch_1):page236_i33:a"
				( attribute "PN" "1"
					( Origin gPackager )
				)
				( objectStatus "C7A9.1" )
			)
			( pin "@baseboard_fab2_lib.baseboard_fab2(sch_1):page236_i33:b"
				( attribute "PN" "2"
					( Origin gPackager )
				)
				( objectStatus "C7A9.2" )
			)
			( pin "@baseboard_fab2_lib.baseboard_fab2(sch_1):page236_i34:a"
				( attribute "PN" "1"
					( Origin gPackager )
				)
				( objectStatus "C7A44.1" )
			)
			( pin "@baseboard_fab2_lib.baseboard_fab2(sch_1):page236_i34:b"
				( attribute "PN" "2"
					( Origin gPackager )
				)
				( objectStatus "C7A44.2" )
			)
			( pin "@baseboard_fab2_lib.baseboard_fab2(sch_1):page236_i35:a"
				( attribute "PN" "1"
					( Origin gPackager )
				)
				( objectStatus "C7A40.1" )
			)
			( pin "@baseboard_fab2_lib.baseboard_fab2(sch_1):page236_i35:b"
				( attribute "PN" "2"
					( Origin gPackager )
				)
				( objectStatus "C7A40.2" )
			)
			( pin "@baseboard_fab2_lib.baseboard_fab2(sch_1):page236_i36:a"
				( attribute "PN" "1"
					( Origin gPackager )
				)
				( objectStatus "C7A10.1" )
			)
			( pin "@baseboard_fab2_lib.baseboard_fab2(sch_1):page236_i36:b"
				( attribute "PN" "2"
					( Origin gPackager )
				)
				( objectStatus "C7A10.2" )
			)
			( pin "@baseboard_fab2_lib.baseboard_fab2(sch_1):page205_i83:\1\"
				( attribute "PN" "1"
					( Origin gPackager )
				)
				( objectStatus "C4C4.1" )
			)
			( pin "@baseboard_fab2_lib.baseboard_fab2(sch_1):page205_i83:\2\"
				( attribute "PN" "2"
					( Origin gPackager )
				)
				( objectStatus "C4C4.2" )
			)
			( pin "@baseboard_fab2_lib.baseboard_fab2(sch_1):page236_i39:a"
				( attribute "PN" "1"
					( Origin gPackager )
				)
				( objectStatus "C7A41.1" )
			)
			( pin "@baseboard_fab2_lib.baseboard_fab2(sch_1):page236_i39:b"
				( attribute "PN" "2"
					( Origin gPackager )
				)
				( objectStatus "C7A41.2" )
			)
			( pin "@baseboard_fab2_lib.baseboard_fab2(sch_1):page204_i105:f"
				( attribute "PN" "2"
					( Origin gPackager )
				)
				( objectStatus "L4C1.2" )
			)
			( pin "@baseboard_fab2_lib.baseboard_fab2(sch_1):page204_i105:s"
				( attribute "PN" "1"
					( Origin gPackager )
				)
				( objectStatus "L4C1.1" )
			)
			( pin "@baseboard_fab2_lib.baseboard_fab2(sch_1):page236_i46:a"
				( attribute "PN" "1"
					( Origin gPackager )
				)
				( objectStatus "C7A42.1" )
			)
			( pin "@baseboard_fab2_lib.baseboard_fab2(sch_1):page236_i46:b"
				( attribute "PN" "2"
					( Origin gPackager )
				)
				( objectStatus "C7A42.2" )
			)
			( pin "@baseboard_fab2_lib.baseboard_fab2(sch_1):page236_i56:a"
				( attribute "PN" "1"
					( Origin gPackager )
				)
				( objectStatus "R8B14.1" )
			)
			( pin "@baseboard_fab2_lib.baseboard_fab2(sch_1):page236_i56:b"
				( attribute "PN" "2"
					( Origin gPackager )
				)
				( objectStatus "R8B14.2" )
			)
			( pin "@baseboard_fab2_lib.baseboard_fab2(sch_1):page236_i57:a"
				( attribute "PN" "1"
					( Origin gPackager )
				)
				( objectStatus "R8B15.1" )
			)
			( pin "@baseboard_fab2_lib.baseboard_fab2(sch_1):page236_i57:b"
				( attribute "PN" "2"
					( Origin gPackager )
				)
				( objectStatus "R8B15.2" )
			)
			( pin "@baseboard_fab2_lib.baseboard_fab2(sch_1):page236_i59:a"
				( attribute "PN" "1"
					( Origin gPackager )
				)
				( objectStatus "R8B12.1" )
			)
			( pin "@baseboard_fab2_lib.baseboard_fab2(sch_1):page236_i59:b"
				( attribute "PN" "2"
					( Origin gPackager )
				)
				( objectStatus "R8B12.2" )
			)
			( pin "@baseboard_fab2_lib.baseboard_fab2(sch_1):page212_i126:\1\"
				( attribute "PN" "1"
					( Origin gPackager )
				)
				( objectStatus "C22W32.1" )
			)
			( pin "@baseboard_fab2_lib.baseboard_fab2(sch_1):page212_i126:\2\"
				( attribute "PN" "2"
					( Origin gPackager )
				)
				( objectStatus "C22W32.2" )
			)
			( pin "@baseboard_fab2_lib.baseboard_fab2(sch_1):page212_i124:\1\"
				( attribute "PN" "1"
					( Origin gPackager )
				)
				( objectStatus "C22W33.1" )
			)
			( pin "@baseboard_fab2_lib.baseboard_fab2(sch_1):page212_i124:\2\"
				( attribute "PN" "2"
					( Origin gPackager )
				)
				( objectStatus "C22W33.2" )
			)
			( pin "@baseboard_fab2_lib.baseboard_fab2(sch_1):page236_i71:a"
				( attribute "PN" "1"
					( Origin gPackager )
				)
				( objectStatus "C3L18.1" )
			)
			( pin "@baseboard_fab2_lib.baseboard_fab2(sch_1):page236_i71:b"
				( attribute "PN" "2"
					( Origin gPackager )
				)
				( objectStatus "C3L18.2" )
			)
			( pin "@baseboard_fab2_lib.baseboard_fab2(sch_1):page236_i73:a"
				( attribute "PN" "1"
					( Origin gPackager )
				)
				( objectStatus "C3L20.1" )
			)
			( pin "@baseboard_fab2_lib.baseboard_fab2(sch_1):page236_i73:b"
				( attribute "PN" "2"
					( Origin gPackager )
				)
				( objectStatus "C3L20.2" )
			)
			( pin "@baseboard_fab2_lib.baseboard_fab2(sch_1):page236_i74:a"
				( attribute "PN" "1"
					( Origin gPackager )
				)
				( objectStatus "C3L21.1" )
			)
			( pin "@baseboard_fab2_lib.baseboard_fab2(sch_1):page236_i74:b"
				( attribute "PN" "2"
					( Origin gPackager )
				)
				( objectStatus "C3L21.2" )
			)
			( pin "@baseboard_fab2_lib.baseboard_fab2(sch_1):page236_i75:a"
				( attribute "PN" "1"
					( Origin gPackager )
				)
				( objectStatus "C7A27.1" )
			)
			( pin "@baseboard_fab2_lib.baseboard_fab2(sch_1):page236_i75:b"
				( attribute "PN" "2"
					( Origin gPackager )
				)
				( objectStatus "C7A27.2" )
			)
			( pin "@baseboard_fab2_lib.baseboard_fab2(sch_1):page236_i76:a"
				( attribute "PN" "1"
					( Origin gPackager )
				)
				( objectStatus "C3L19.1" )
			)
			( pin "@baseboard_fab2_lib.baseboard_fab2(sch_1):page236_i76:b"
				( attribute "PN" "2"
					( Origin gPackager )
				)
				( objectStatus "C3L19.2" )
			)
			( pin "@baseboard_fab2_lib.baseboard_fab2(sch_1):page236_i77:a"
				( attribute "PN" "1"
					( Origin gPackager )
				)
				( objectStatus "C2L46.1" )
			)
			( pin "@baseboard_fab2_lib.baseboard_fab2(sch_1):page236_i77:b"
				( attribute "PN" "2"
					( Origin gPackager )
				)
				( objectStatus "C2L46.2" )
			)
			( pin "@baseboard_fab2_lib.baseboard_fab2(sch_1):page236_i78:a"
				( attribute "PN" "1"
					( Origin gPackager )
				)
				( objectStatus "C8A15.1" )
			)
			( pin "@baseboard_fab2_lib.baseboard_fab2(sch_1):page236_i78:b"
				( attribute "PN" "2"
					( Origin gPackager )
				)
				( objectStatus "C8A15.2" )
			)
			( pin "@baseboard_fab2_lib.baseboard_fab2(sch_1):page236_i79:a"
				( attribute "PN" "1"
					( Origin gPackager )
				)
				( objectStatus "C2L25.1" )
			)
			( pin "@baseboard_fab2_lib.baseboard_fab2(sch_1):page236_i79:b"
				( attribute "PN" "2"
					( Origin gPackager )
				)
				( objectStatus "C2L25.2" )
			)
			( pin "@baseboard_fab2_lib.baseboard_fab2(sch_1):page236_i90:a"
				( attribute "PN" "1"
					( Origin gPackager )
				)
				( objectStatus "R7A13.1" )
			)
			( pin "@baseboard_fab2_lib.baseboard_fab2(sch_1):page236_i90:b"
				( attribute "PN" "2"
					( Origin gPackager )
				)
				( objectStatus "R7A13.2" )
			)
			( pin "@baseboard_fab2_lib.baseboard_fab2(sch_1):page236_i92:a"
				( attribute "PN" "1"
					( Origin gPackager )
				)
				( objectStatus "R7A18.1" )
			)
			( pin "@baseboard_fab2_lib.baseboard_fab2(sch_1):page236_i92:b"
				( attribute "PN" "2"
					( Origin gPackager )
				)
				( objectStatus "R7A18.2" )
			)
			( pin "@baseboard_fab2_lib.baseboard_fab2(sch_1):page236_i93:a"
				( attribute "PN" "1"
					( Origin gPackager )
				)
				( objectStatus "R7A19.1" )
			)
			( pin "@baseboard_fab2_lib.baseboard_fab2(sch_1):page236_i93:b"
				( attribute "PN" "2"
					( Origin gPackager )
				)
				( objectStatus "R7A19.2" )
			)
			( pin "@baseboard_fab2_lib.baseboard_fab2(sch_1):page236_i94:a"
				( attribute "PN" "1"
					( Origin gPackager )
				)
				( objectStatus "R7A14.1" )
			)
			( pin "@baseboard_fab2_lib.baseboard_fab2(sch_1):page236_i94:b"
				( attribute "PN" "2"
					( Origin gPackager )
				)
				( objectStatus "R7A14.2" )
			)
			( pin "@baseboard_fab2_lib.baseboard_fab2(sch_1):page236_i116:boost"
				( attribute "PN" "33"
					( Origin gPackager )
				)
				( objectStatus "EU7A3.33" )
			)
			( pin "@baseboard_fab2_lib.baseboard_fab2(sch_1):page236_i116:en"
				( attribute "PN" "35"
					( Origin gPackager )
				)
				( objectStatus "EU7A3.35" )
			)
			( pin "@baseboard_fab2_lib.baseboard_fab2(sch_1):page236_i116:gl(0)"
				( attribute "PN" "6"
					( Origin gPackager )
				)
				( objectStatus "EU7A3.6" )
			)
			( pin "@baseboard_fab2_lib.baseboard_fab2(sch_1):page236_i116:gl(1)"
				( attribute "PN" "41"
					( Origin gPackager )
				)
				( objectStatus "EU7A3.41" )
			)
			( pin "@baseboard_fab2_lib.baseboard_fab2(sch_1):page236_i116:iout"
				( attribute "PN" "38"
					( Origin gPackager )
				)
				( objectStatus "EU7A3.38" )
			)
			( pin "@baseboard_fab2_lib.baseboard_fab2(sch_1):page236_i116:lgnd"
				( attribute "PN" "2"
					( Origin gPackager )
				)
				( objectStatus "EU7A3.2" )
			)
			( pin "@baseboard_fab2_lib.baseboard_fab2(sch_1):page236_i116:nc"
				( attribute "PN" "31"
					( Origin gPackager )
				)
				( objectStatus "EU7A3.31" )
			)
			( pin "@baseboard_fab2_lib.baseboard_fab2(sch_1):page236_i116:ocset"
				( attribute "PN" "37"
					( Origin gPackager )
				)
				( objectStatus "EU7A3.37" )
			)
			( pin "@baseboard_fab2_lib.baseboard_fab2(sch_1):page236_i116:pgnd(0)"
				( attribute "PN" "5"
					( Origin gPackager )
				)
				( objectStatus "EU7A3.5" )
			)
			( pin "@baseboard_fab2_lib.baseboard_fab2(sch_1):page236_i116:pgnd(1)"
				( attribute "PN" "7"
					( Origin gPackager )
				)
				( objectStatus "EU7A3.7" )
			)
			( pin "@baseboard_fab2_lib.baseboard_fab2(sch_1):page236_i116:pgnd(2)"
				( attribute "PN" "40"
					( Origin gPackager )
				)
				( objectStatus "EU7A3.40" )
			)
			( pin "@baseboard_fab2_lib.baseboard_fab2(sch_1):page236_i116:phase"
				( attribute "PN" "32"
					( Origin gPackager )
				)
				( objectStatus "EU7A3.32" )
			)
			( pin "@baseboard_fab2_lib.baseboard_fab2(sch_1):page236_i116:pwm"
				( attribute "PN" "34"
					( Origin gPackager )
				)
				( objectStatus "EU7A3.34" )
			)
			( pin "@baseboard_fab2_lib.baseboard_fab2(sch_1):page236_i116:refin"
				( attribute "PN" "39"
					( Origin gPackager )
				)
				( objectStatus "EU7A3.39" )
			)
			( pin "@baseboard_fab2_lib.baseboard_fab2(sch_1):page236_i116:sw"
				( attribute "PN" "10"
					( Origin gPackager )
				)
				( objectStatus "EU7A3.10" )
			)
			( pin "@baseboard_fab2_lib.baseboard_fab2(sch_1):page236_i116:tout_flt"
				( attribute "PN" "36"
					( Origin gPackager )
				)
				( objectStatus "EU7A3.36" )
			)
			( pin "@baseboard_fab2_lib.baseboard_fab2(sch_1):page236_i116:vcc"
				( attribute "PN" "3"
					( Origin gPackager )
				)
				( objectStatus "EU7A3.3" )
			)
			( pin "@baseboard_fab2_lib.baseboard_fab2(sch_1):page236_i116:vdrv"
				( attribute "PN" "4"
					( Origin gPackager )
				)
				( objectStatus "EU7A3.4" )
			)
			( pin "@baseboard_fab2_lib.baseboard_fab2(sch_1):page236_i116:vin(0)"
				( attribute "PN" "25"
					( Origin gPackager )
				)
				( objectStatus "EU7A3.25" )
			)
			( pin "@baseboard_fab2_lib.baseboard_fab2(sch_1):page236_i116:vin(1)"
				( attribute "PN" "30"
					( Origin gPackager )
				)
				( objectStatus "EU7A3.30" )
			)
			( pin "@baseboard_fab2_lib.baseboard_fab2(sch_1):page236_i116:vos"
				( attribute "PN" "1"
					( Origin gPackager )
				)
				( objectStatus "EU7A3.1" )
			)
			( pin "@baseboard_fab2_lib.baseboard_fab2(sch_1):page236_i117:boost"
				( attribute "PN" "33"
					( Origin gPackager )
				)
				( objectStatus "EU7A2.33" )
			)
			( pin "@baseboard_fab2_lib.baseboard_fab2(sch_1):page236_i117:en"
				( attribute "PN" "35"
					( Origin gPackager )
				)
				( objectStatus "EU7A2.35" )
			)
			( pin "@baseboard_fab2_lib.baseboard_fab2(sch_1):page236_i117:gl(0)"
				( attribute "PN" "6"
					( Origin gPackager )
				)
				( objectStatus "EU7A2.6" )
			)
			( pin "@baseboard_fab2_lib.baseboard_fab2(sch_1):page236_i117:gl(1)"
				( attribute "PN" "41"
					( Origin gPackager )
				)
				( objectStatus "EU7A2.41" )
			)
			( pin "@baseboard_fab2_lib.baseboard_fab2(sch_1):page236_i117:iout"
				( attribute "PN" "38"
					( Origin gPackager )
				)
				( objectStatus "EU7A2.38" )
			)
			( pin "@baseboard_fab2_lib.baseboard_fab2(sch_1):page236_i117:lgnd"
				( attribute "PN" "2"
					( Origin gPackager )
				)
				( objectStatus "EU7A2.2" )
			)
			( pin "@baseboard_fab2_lib.baseboard_fab2(sch_1):page236_i117:nc"
				( attribute "PN" "31"
					( Origin gPackager )
				)
				( objectStatus "EU7A2.31" )
			)
			( pin "@baseboard_fab2_lib.baseboard_fab2(sch_1):page236_i117:ocset"
				( attribute "PN" "37"
					( Origin gPackager )
				)
				( objectStatus "EU7A2.37" )
			)
			( pin "@baseboard_fab2_lib.baseboard_fab2(sch_1):page236_i117:pgnd(0)"
				( attribute "PN" "5"
					( Origin gPackager )
				)
				( objectStatus "EU7A2.5" )
			)
			( pin "@baseboard_fab2_lib.baseboard_fab2(sch_1):page236_i117:pgnd(1)"
				( attribute "PN" "7"
					( Origin gPackager )
				)
				( objectStatus "EU7A2.7" )
			)
			( pin "@baseboard_fab2_lib.baseboard_fab2(sch_1):page236_i117:pgnd(2)"
				( attribute "PN" "40"
					( Origin gPackager )
				)
				( objectStatus "EU7A2.40" )
			)
			( pin "@baseboard_fab2_lib.baseboard_fab2(sch_1):page236_i117:phase"
				( attribute "PN" "32"
					( Origin gPackager )
				)
				( objectStatus "EU7A2.32" )
			)
			( pin "@baseboard_fab2_lib.baseboard_fab2(sch_1):page236_i117:pwm"
				( attribute "PN" "34"
					( Origin gPackager )
				)
				( objectStatus "EU7A2.34" )
			)
			( pin "@baseboard_fab2_lib.baseboard_fab2(sch_1):page236_i117:refin"
				( attribute "PN" "39"
					( Origin gPackager )
				)
				( objectStatus "EU7A2.39" )
			)
			( pin "@baseboard_fab2_lib.baseboard_fab2(sch_1):page236_i117:sw"
				( attribute "PN" "10"
					( Origin gPackager )
				)
				( objectStatus "EU7A2.10" )
			)
			( pin "@baseboard_fab2_lib.baseboard_fab2(sch_1):page236_i117:tout_flt"
				( attribute "PN" "36"
					( Origin gPackager )
				)
				( objectStatus "EU7A2.36" )
			)
			( pin "@baseboard_fab2_lib.baseboard_fab2(sch_1):page236_i117:vcc"
				( attribute "PN" "3"
					( Origin gPackager )
				)
				( objectStatus "EU7A2.3" )
			)
			( pin "@baseboard_fab2_lib.baseboard_fab2(sch_1):page236_i117:vdrv"
				( attribute "PN" "4"
					( Origin gPackager )
				)
				( objectStatus "EU7A2.4" )
			)
			( pin "@baseboard_fab2_lib.baseboard_fab2(sch_1):page236_i117:vin(0)"
				( attribute "PN" "25"
					( Origin gPackager )
				)
				( objectStatus "EU7A2.25" )
			)
			( pin "@baseboard_fab2_lib.baseboard_fab2(sch_1):page236_i117:vin(1)"
				( attribute "PN" "30"
					( Origin gPackager )
				)
				( objectStatus "EU7A2.30" )
			)
			( pin "@baseboard_fab2_lib.baseboard_fab2(sch_1):page236_i117:vos"
				( attribute "PN" "1"
					( Origin gPackager )
				)
				( objectStatus "EU7A2.1" )
			)
			( pin "@baseboard_fab2_lib.baseboard_fab2(sch_1):page236_i118:a"
				( attribute "PN" "1"
					( Origin gPackager )
				)
				( objectStatus "R3L15.1" )
			)
			( pin "@baseboard_fab2_lib.baseboard_fab2(sch_1):page236_i118:b"
				( attribute "PN" "2"
					( Origin gPackager )
				)
				( objectStatus "R3L15.2" )
			)
			( pin "@baseboard_fab2_lib.baseboard_fab2(sch_1):page236_i120:a"
				( attribute "PN" "1"
					( Origin gPackager )
				)
				( objectStatus "R3L14.1" )
			)
			( pin "@baseboard_fab2_lib.baseboard_fab2(sch_1):page236_i120:b"
				( attribute "PN" "2"
					( Origin gPackager )
				)
				( objectStatus "R3L14.2" )
			)
			( pin "@baseboard_fab2_lib.baseboard_fab2(sch_1):page237_i3:a"
				( attribute "PN" "1"
					( Origin gPackager )
				)
				( objectStatus "R8A10.1" )
			)
			( pin "@baseboard_fab2_lib.baseboard_fab2(sch_1):page237_i3:b"
				( attribute "PN" "2"
					( Origin gPackager )
				)
				( objectStatus "R8A10.2" )
			)
			( pin "@baseboard_fab2_lib.baseboard_fab2(sch_1):page237_i5:a"
				( attribute "PN" "1"
					( Origin gPackager )
				)
				( objectStatus "C8A11.1" )
			)
			( pin "@baseboard_fab2_lib.baseboard_fab2(sch_1):page237_i5:b"
				( attribute "PN" "2"
					( Origin gPackager )
				)
				( objectStatus "C8A11.2" )
			)
			( pin "@baseboard_fab2_lib.baseboard_fab2(sch_1):page237_i12:a"
				( attribute "PN" "1"
					( Origin gPackager )
				)
				( objectStatus "C2L45.1" )
			)
			( pin "@baseboard_fab2_lib.baseboard_fab2(sch_1):page237_i12:b"
				( attribute "PN" "2"
					( Origin gPackager )
				)
				( objectStatus "C2L45.2" )
			)
			( pin "@baseboard_fab2_lib.baseboard_fab2(sch_1):page237_i13:a"
				( attribute "PN" "1"
					( Origin gPackager )
				)
				( objectStatus "C8A14.1" )
			)
			( pin "@baseboard_fab2_lib.baseboard_fab2(sch_1):page237_i13:b"
				( attribute "PN" "2"
					( Origin gPackager )
				)
				( objectStatus "C8A14.2" )
			)
			( pin "@baseboard_fab2_lib.baseboard_fab2(sch_1):page237_i15:a"
				( attribute "PN" "1"
					( Origin gPackager )
				)
				( objectStatus "R8A12.1" )
			)
			( pin "@baseboard_fab2_lib.baseboard_fab2(sch_1):page237_i15:b"
				( attribute "PN" "2"
					( Origin gPackager )
				)
				( objectStatus "R8A12.2" )
			)
			( pin "@baseboard_fab2_lib.baseboard_fab2(sch_1):page237_i29:a"
				( attribute "PN" "1"
					( Origin gPackager )
				)
				( objectStatus "C8A6.1" )
			)
			( pin "@baseboard_fab2_lib.baseboard_fab2(sch_1):page237_i29:b"
				( attribute "PN" "2"
					( Origin gPackager )
				)
				( objectStatus "C8A6.2" )
			)
			( pin "@baseboard_fab2_lib.baseboard_fab2(sch_1):page237_i31:a"
				( attribute "PN" "1"
					( Origin gPackager )
				)
				( objectStatus "C8A4.1" )
			)
			( pin "@baseboard_fab2_lib.baseboard_fab2(sch_1):page237_i31:b"
				( attribute "PN" "2"
					( Origin gPackager )
				)
				( objectStatus "C8A4.2" )
			)
			( pin "@baseboard_fab2_lib.baseboard_fab2(sch_1):page237_i55:a"
				( attribute "PN" "1"
					( Origin gPackager )
				)
				( objectStatus "C8A10.1" )
			)
			( pin "@baseboard_fab2_lib.baseboard_fab2(sch_1):page237_i55:b"
				( attribute "PN" "2"
					( Origin gPackager )
				)
				( objectStatus "C8A10.2" )
			)
			( pin "@baseboard_fab2_lib.baseboard_fab2(sch_1):page237_i77:a"
				( attribute "PN" "1"
					( Origin gPackager )
				)
				( objectStatus "C8A12.1" )
			)
			( pin "@baseboard_fab2_lib.baseboard_fab2(sch_1):page237_i77:b"
				( attribute "PN" "2"
					( Origin gPackager )
				)
				( objectStatus "C8A12.2" )
			)
			( pin "@baseboard_fab2_lib.baseboard_fab2(sch_1):page237_i79:a"
				( attribute "PN" "1"
					( Origin gPackager )
				)
				( objectStatus "C2L32.1" )
			)
			( pin "@baseboard_fab2_lib.baseboard_fab2(sch_1):page237_i79:b"
				( attribute "PN" "2"
					( Origin gPackager )
				)
				( objectStatus "C2L32.2" )
			)
			( pin "@baseboard_fab2_lib.baseboard_fab2(sch_1):page237_i80:a"
				( attribute "PN" "1"
					( Origin gPackager )
				)
				( objectStatus "R2L19.1" )
			)
			( pin "@baseboard_fab2_lib.baseboard_fab2(sch_1):page237_i80:b"
				( attribute "PN" "2"
					( Origin gPackager )
				)
				( objectStatus "R2L19.2" )
			)
			( pin "@baseboard_fab2_lib.baseboard_fab2(sch_1):page237_i81:a"
				( attribute "PN" "1"
					( Origin gPackager )
				)
				( objectStatus "R2L20.1" )
			)
			( pin "@baseboard_fab2_lib.baseboard_fab2(sch_1):page237_i81:b"
				( attribute "PN" "2"
					( Origin gPackager )
				)
				( objectStatus "R2L20.2" )
			)
			( pin "@baseboard_fab2_lib.baseboard_fab2(sch_1):page237_i86:adj_nc"
				( attribute "PN" "4"
					( Origin gPackager )
				)
				( objectStatus "EU8A2.4" )
			)
			( pin "@baseboard_fab2_lib.baseboard_fab2(sch_1):page237_i86:en"
				( attribute "PN" "6"
					( Origin gPackager )
				)
				( objectStatus "EU8A2.6" )
			)
			( pin "@baseboard_fab2_lib.baseboard_fab2(sch_1):page237_i86:gnd"
				( attribute "PN" "11"
					( Origin gPackager )
				)
				( objectStatus "EU8A2.11" )
			)
			( pin "@baseboard_fab2_lib.baseboard_fab2(sch_1):page237_i86:pgood"
				( attribute "PN" "5"
					( Origin gPackager )
				)
				( objectStatus "EU8A2.5" )
			)
			( pin "@baseboard_fab2_lib.baseboard_fab2(sch_1):page237_i86:vdd"
				( attribute "PN" "10"
					( Origin gPackager )
				)
				( objectStatus "EU8A2.10" )
			)
			( pin "@baseboard_fab2_lib.baseboard_fab2(sch_1):page237_i86:vin(0)"
				( attribute "PN" "7"
					( Origin gPackager )
				)
				( objectStatus "EU8A2.7" )
			)
			( pin "@baseboard_fab2_lib.baseboard_fab2(sch_1):page237_i86:vin(1)"
				( attribute "PN" "8"
					( Origin gPackager )
				)
				( objectStatus "EU8A2.8" )
			)
			( pin "@baseboard_fab2_lib.baseboard_fab2(sch_1):page237_i86:vin(2)"
				( attribute "PN" "9"
					( Origin gPackager )
				)
				( objectStatus "EU8A2.9" )
			)
			( pin "@baseboard_fab2_lib.baseboard_fab2(sch_1):page237_i86:vout(0)"
				( attribute "PN" "1"
					( Origin gPackager )
				)
				( objectStatus "EU8A2.1" )
			)
			( pin "@baseboard_fab2_lib.baseboard_fab2(sch_1):page237_i86:vout(1)"
				( attribute "PN" "2"
					( Origin gPackager )
				)
				( objectStatus "EU8A2.2" )
			)
			( pin "@baseboard_fab2_lib.baseboard_fab2(sch_1):page237_i86:vout(2)"
				( attribute "PN" "3"
					( Origin gPackager )
				)
				( objectStatus "EU8A2.3" )
			)
			( pin "@baseboard_fab2_lib.baseboard_fab2(sch_1):page237_i90:a"
				( attribute "PN" "1"
					( Origin gPackager )
				)
				( objectStatus "R8A11.1" )
			)
			( pin "@baseboard_fab2_lib.baseboard_fab2(sch_1):page237_i90:b"
				( attribute "PN" "2"
					( Origin gPackager )
				)
				( objectStatus "R8A11.2" )
			)
			( pin "@baseboard_fab2_lib.baseboard_fab2(sch_1):page238_i5:a"
				( attribute "PN" "1"
					( Origin gPackager )
				)
				( objectStatus "C9F9.1" )
			)
			( pin "@baseboard_fab2_lib.baseboard_fab2(sch_1):page238_i5:b"
				( attribute "PN" "2"
					( Origin gPackager )
				)
				( objectStatus "C9F9.2" )
			)
			( pin "@baseboard_fab2_lib.baseboard_fab2(sch_1):page238_i7:a"
				( attribute "PN" "1"
					( Origin gPackager )
				)
				( objectStatus "C9F3.1" )
			)
			( pin "@baseboard_fab2_lib.baseboard_fab2(sch_1):page238_i7:b"
				( attribute "PN" "2"
					( Origin gPackager )
				)
				( objectStatus "C9F3.2" )
			)
			( pin "@baseboard_fab2_lib.baseboard_fab2(sch_1):page238_i14:a"
				( attribute "PN" "1"
					( Origin gPackager )
				)
				( objectStatus "R9F8.1" )
			)
			( pin "@baseboard_fab2_lib.baseboard_fab2(sch_1):page238_i14:b"
				( attribute "PN" "2"
					( Origin gPackager )
				)
				( objectStatus "R9F8.2" )
			)
			( pin "@baseboard_fab2_lib.baseboard_fab2(sch_1):page238_i19:a"
				( attribute "PN" "1"
					( Origin gPackager )
				)
				( objectStatus "C9F8.1" )
			)
			( pin "@baseboard_fab2_lib.baseboard_fab2(sch_1):page238_i19:b"
				( attribute "PN" "2"
					( Origin gPackager )
				)
				( objectStatus "C9F8.2" )
			)
			( pin "@baseboard_fab2_lib.baseboard_fab2(sch_1):page238_i21:a"
				( attribute "PN" "1"
					( Origin gPackager )
				)
				( objectStatus "R9F13.1" )
			)
			( pin "@baseboard_fab2_lib.baseboard_fab2(sch_1):page238_i21:b"
				( attribute "PN" "2"
					( Origin gPackager )
				)
				( objectStatus "R9F13.2" )
			)
			( pin "@baseboard_fab2_lib.baseboard_fab2(sch_1):page238_i23:a"
				( attribute "PN" "1"
					( Origin gPackager )
				)
				( objectStatus "C9E10.1" )
			)
			( pin "@baseboard_fab2_lib.baseboard_fab2(sch_1):page238_i23:b"
				( attribute "PN" "2"
					( Origin gPackager )
				)
				( objectStatus "C9E10.2" )
			)
			( pin "@baseboard_fab2_lib.baseboard_fab2(sch_1):page238_i30:a"
				( attribute "PN" "1"
					( Origin gPackager )
				)
				( objectStatus "C9F4.1" )
			)
			( pin "@baseboard_fab2_lib.baseboard_fab2(sch_1):page238_i30:b"
				( attribute "PN" "2"
					( Origin gPackager )
				)
				( objectStatus "C9F4.2" )
			)
			( pin "@baseboard_fab2_lib.baseboard_fab2(sch_1):page238_i39:a"
				( attribute "PN" "1"
					( Origin gPackager )
				)
				( objectStatus "C9E11.1" )
			)
			( pin "@baseboard_fab2_lib.baseboard_fab2(sch_1):page238_i39:b"
				( attribute "PN" "2"
					( Origin gPackager )
				)
				( objectStatus "C9E11.2" )
			)
			( pin "@baseboard_fab2_lib.baseboard_fab2(sch_1):page238_i40:adj_nc"
				( attribute "PN" "4"
					( Origin gPackager )
				)
				( objectStatus "EU9F1.4" )
			)
			( pin "@baseboard_fab2_lib.baseboard_fab2(sch_1):page238_i40:en"
				( attribute "PN" "6"
					( Origin gPackager )
				)
				( objectStatus "EU9F1.6" )
			)
			( pin "@baseboard_fab2_lib.baseboard_fab2(sch_1):page238_i40:gnd"
				( attribute "PN" "11"
					( Origin gPackager )
				)
				( objectStatus "EU9F1.11" )
			)
			( pin "@baseboard_fab2_lib.baseboard_fab2(sch_1):page238_i40:pgood"
				( attribute "PN" "5"
					( Origin gPackager )
				)
				( objectStatus "EU9F1.5" )
			)
			( pin "@baseboard_fab2_lib.baseboard_fab2(sch_1):page238_i40:vdd"
				( attribute "PN" "10"
					( Origin gPackager )
				)
				( objectStatus "EU9F1.10" )
			)
			( pin "@baseboard_fab2_lib.baseboard_fab2(sch_1):page238_i40:vin(0)"
				( attribute "PN" "7"
					( Origin gPackager )
				)
				( objectStatus "EU9F1.7" )
			)
			( pin "@baseboard_fab2_lib.baseboard_fab2(sch_1):page238_i40:vin(1)"
				( attribute "PN" "8"
					( Origin gPackager )
				)
				( objectStatus "EU9F1.8" )
			)
			( pin "@baseboard_fab2_lib.baseboard_fab2(sch_1):page238_i40:vin(2)"
				( attribute "PN" "9"
					( Origin gPackager )
				)
				( objectStatus "EU9F1.9" )
			)
			( pin "@baseboard_fab2_lib.baseboard_fab2(sch_1):page238_i40:vout(0)"
				( attribute "PN" "1"
					( Origin gPackager )
				)
				( objectStatus "EU9F1.1" )
			)
			( pin "@baseboard_fab2_lib.baseboard_fab2(sch_1):page238_i40:vout(1)"
				( attribute "PN" "2"
					( Origin gPackager )
				)
				( objectStatus "EU9F1.2" )
			)
			( pin "@baseboard_fab2_lib.baseboard_fab2(sch_1):page238_i40:vout(2)"
				( attribute "PN" "3"
					( Origin gPackager )
				)
				( objectStatus "EU9F1.3" )
			)
			( pin "@baseboard_fab2_lib.baseboard_fab2(sch_1):page238_i41:a"
				( attribute "PN" "1"
					( Origin gPackager )
				)
				( objectStatus "R9F11.1" )
			)
			( pin "@baseboard_fab2_lib.baseboard_fab2(sch_1):page238_i41:b"
				( attribute "PN" "2"
					( Origin gPackager )
				)
				( objectStatus "R9F11.2" )
			)
			( pin "@baseboard_fab2_lib.baseboard_fab2(sch_1):page239_i4:a"
				( attribute "PN" "1"
					( Origin gPackager )
				)
				( objectStatus "C9F10.1" )
			)
			( pin "@baseboard_fab2_lib.baseboard_fab2(sch_1):page239_i4:b"
				( attribute "PN" "2"
					( Origin gPackager )
				)
				( objectStatus "C9F10.2" )
			)
			( pin "@baseboard_fab2_lib.baseboard_fab2(sch_1):page239_i6:a"
				( attribute "PN" "1"
					( Origin gPackager )
				)
				( objectStatus "R9F12.1" )
			)
			( pin "@baseboard_fab2_lib.baseboard_fab2(sch_1):page239_i6:b"
				( attribute "PN" "2"
					( Origin gPackager )
				)
				( objectStatus "R9F12.2" )
			)
			( pin "@baseboard_fab2_lib.baseboard_fab2(sch_1):page239_i7:a"
				( attribute "PN" "1"
					( Origin gPackager )
				)
				( objectStatus "C9F13.1" )
			)
			( pin "@baseboard_fab2_lib.baseboard_fab2(sch_1):page239_i7:b"
				( attribute "PN" "2"
					( Origin gPackager )
				)
				( objectStatus "C9F13.2" )
			)
			( pin "@baseboard_fab2_lib.baseboard_fab2(sch_1):page239_i12:a"
				( attribute "PN" "1"
					( Origin gPackager )
				)
				( objectStatus "C1T15.1" )
			)
			( pin "@baseboard_fab2_lib.baseboard_fab2(sch_1):page239_i12:b"
				( attribute "PN" "2"
					( Origin gPackager )
				)
				( objectStatus "C1T15.2" )
			)
			( pin "@baseboard_fab2_lib.baseboard_fab2(sch_1):page238_i45:\1\"
				( attribute "PN" "1"
					( Origin gPackager )
				)
				( objectStatus "R9F6.1" )
			)
			( pin "@baseboard_fab2_lib.baseboard_fab2(sch_1):page238_i45:\2\"
				( attribute "PN" "2"
					( Origin gPackager )
				)
				( objectStatus "R9F6.2" )
			)
			( pin "@baseboard_fab2_lib.baseboard_fab2(sch_1):page239_i22:a"
				( attribute "PN" "1"
					( Origin gPackager )
				)
				( objectStatus "C1T7.1" )
			)
			( pin "@baseboard_fab2_lib.baseboard_fab2(sch_1):page239_i22:b"
				( attribute "PN" "2"
					( Origin gPackager )
				)
				( objectStatus "C1T7.2" )
			)
			( pin "@baseboard_fab2_lib.baseboard_fab2(sch_1):page239_i30:a"
				( attribute "PN" "1"
					( Origin gPackager )
				)
				( objectStatus "C9F6.1" )
			)
			( pin "@baseboard_fab2_lib.baseboard_fab2(sch_1):page239_i30:b"
				( attribute "PN" "2"
					( Origin gPackager )
				)
				( objectStatus "C9F6.2" )
			)
			( pin "@baseboard_fab2_lib.baseboard_fab2(sch_1):page239_i70:adj_nc"
				( attribute "PN" "4"
					( Origin gPackager )
				)
				( objectStatus "EU9F2.4" )
			)
			( pin "@baseboard_fab2_lib.baseboard_fab2(sch_1):page239_i70:en"
				( attribute "PN" "6"
					( Origin gPackager )
				)
				( objectStatus "EU9F2.6" )
			)
			( pin "@baseboard_fab2_lib.baseboard_fab2(sch_1):page239_i70:gnd"
				( attribute "PN" "11"
					( Origin gPackager )
				)
				( objectStatus "EU9F2.11" )
			)
			( pin "@baseboard_fab2_lib.baseboard_fab2(sch_1):page239_i70:pgood"
				( attribute "PN" "5"
					( Origin gPackager )
				)
				( objectStatus "EU9F2.5" )
			)
			( pin "@baseboard_fab2_lib.baseboard_fab2(sch_1):page239_i70:vdd"
				( attribute "PN" "10"
					( Origin gPackager )
				)
				( objectStatus "EU9F2.10" )
			)
			( pin "@baseboard_fab2_lib.baseboard_fab2(sch_1):page239_i70:vin(0)"
				( attribute "PN" "7"
					( Origin gPackager )
				)
				( objectStatus "EU9F2.7" )
			)
			( pin "@baseboard_fab2_lib.baseboard_fab2(sch_1):page239_i70:vin(1)"
				( attribute "PN" "8"
					( Origin gPackager )
				)
				( objectStatus "EU9F2.8" )
			)
			( pin "@baseboard_fab2_lib.baseboard_fab2(sch_1):page239_i70:vin(2)"
				( attribute "PN" "9"
					( Origin gPackager )
				)
				( objectStatus "EU9F2.9" )
			)
			( pin "@baseboard_fab2_lib.baseboard_fab2(sch_1):page239_i70:vout(0)"
				( attribute "PN" "1"
					( Origin gPackager )
				)
				( objectStatus "EU9F2.1" )
			)
			( pin "@baseboard_fab2_lib.baseboard_fab2(sch_1):page239_i70:vout(1)"
				( attribute "PN" "2"
					( Origin gPackager )
				)
				( objectStatus "EU9F2.2" )
			)
			( pin "@baseboard_fab2_lib.baseboard_fab2(sch_1):page239_i70:vout(2)"
				( attribute "PN" "3"
					( Origin gPackager )
				)
				( objectStatus "EU9F2.3" )
			)
			( pin "@baseboard_fab2_lib.baseboard_fab2(sch_1):page239_i71:a"
				( attribute "PN" "1"
					( Origin gPackager )
				)
				( objectStatus "C9F5.1" )
			)
			( pin "@baseboard_fab2_lib.baseboard_fab2(sch_1):page239_i71:b"
				( attribute "PN" "2"
					( Origin gPackager )
				)
				( objectStatus "C9F5.2" )
			)
			( pin "@baseboard_fab2_lib.baseboard_fab2(sch_1):page239_i72:a"
				( attribute "PN" "1"
					( Origin gPackager )
				)
				( objectStatus "R1T9.1" )
			)
			( pin "@baseboard_fab2_lib.baseboard_fab2(sch_1):page239_i72:b"
				( attribute "PN" "2"
					( Origin gPackager )
				)
				( objectStatus "R1T9.2" )
			)
			( pin "@baseboard_fab2_lib.baseboard_fab2(sch_1):page232_i315:a"
				( attribute "PN" "1"
					( Origin gPackager )
				)
				( objectStatus "R7B14.1" )
			)
			( pin "@baseboard_fab2_lib.baseboard_fab2(sch_1):page232_i315:b"
				( attribute "PN" "2"
					( Origin gPackager )
				)
				( objectStatus "R7B14.2" )
			)
			( pin "@baseboard_fab2_lib.baseboard_fab2(sch_1):page186_i357:\1\"
				( attribute "PN" "1"
					( Origin gPackager )
				)
				( objectStatus "C9B9.1" )
			)
			( pin "@baseboard_fab2_lib.baseboard_fab2(sch_1):page186_i357:\2\"
				( attribute "PN" "2"
					( Origin gPackager )
				)
				( objectStatus "C9B9.2" )
			)
			( pin "@baseboard_fab2_lib.baseboard_fab2(sch_1):page240_i111:a"
				( attribute "PN" "1"
					( Origin gPackager )
				)
				( objectStatus "R8F1.1" )
			)
			( pin "@baseboard_fab2_lib.baseboard_fab2(sch_1):page240_i111:b"
				( attribute "PN" "2"
					( Origin gPackager )
				)
				( objectStatus "R8F1.2" )
			)
			( pin "@baseboard_fab2_lib.baseboard_fab2(sch_1):page240_i113:a"
				( attribute "PN" "1"
					( Origin gPackager )
				)
				( objectStatus "C8E17.1" )
			)
			( pin "@baseboard_fab2_lib.baseboard_fab2(sch_1):page240_i113:b"
				( attribute "PN" "2"
					( Origin gPackager )
				)
				( objectStatus "C8E17.2" )
			)
			( pin "@baseboard_fab2_lib.baseboard_fab2(sch_1):page240_i116:a"
				( attribute "PN" "1"
					( Origin gPackager )
				)
				( objectStatus "C8F2.1" )
			)
			( pin "@baseboard_fab2_lib.baseboard_fab2(sch_1):page240_i116:b"
				( attribute "PN" "2"
					( Origin gPackager )
				)
				( objectStatus "C8F2.2" )
			)
			( pin "@baseboard_fab2_lib.baseboard_fab2(sch_1):page240_i117:a"
				( attribute "PN" "1"
					( Origin gPackager )
				)
				( objectStatus "R8F5.1" )
			)
			( pin "@baseboard_fab2_lib.baseboard_fab2(sch_1):page240_i117:b"
				( attribute "PN" "2"
					( Origin gPackager )
				)
				( objectStatus "R8F5.2" )
			)
			( pin "@baseboard_fab2_lib.baseboard_fab2(sch_1):page240_i125:boot"
				( attribute "PN" "4"
					( Origin gPackager )
				)
				( objectStatus "EU8F1.4" )
			)
			( pin "@baseboard_fab2_lib.baseboard_fab2(sch_1):page240_i125:cs"
				( attribute "PN" "10"
					( Origin gPackager )
				)
				( objectStatus "EU8F1.10" )
			)
			( pin "@baseboard_fab2_lib.baseboard_fab2(sch_1):page240_i125:en"
				( attribute "PN" "8"
					( Origin gPackager )
				)
				( objectStatus "EU8F1.8" )
			)
			( pin "@baseboard_fab2_lib.baseboard_fab2(sch_1):page240_i125:g0"
				( attribute "PN" "11"
					( Origin gPackager )
				)
				( objectStatus "EU8F1.11" )
			)
			( pin "@baseboard_fab2_lib.baseboard_fab2(sch_1):page240_i125:gnd(0)"
				( attribute "PN" "12"
					( Origin gPackager )
				)
				( objectStatus "EU8F1.12" )
			)
			( pin "@baseboard_fab2_lib.baseboard_fab2(sch_1):page240_i125:gnd(1)"
				( attribute "PN" "13"
					( Origin gPackager )
				)
				( objectStatus "EU8F1.13" )
			)
			( pin "@baseboard_fab2_lib.baseboard_fab2(sch_1):page240_i125:lgate"
				( attribute "PN" "1"
					( Origin gPackager )
				)
				( objectStatus "EU8F1.1" )
			)
			( pin "@baseboard_fab2_lib.baseboard_fab2(sch_1):page240_i125:pgood"
				( attribute "PN" "9"
					( Origin gPackager )
				)
				( objectStatus "EU8F1.9" )
			)
			( pin "@baseboard_fab2_lib.baseboard_fab2(sch_1):page240_i125:phase"
				( attribute "PN" "2"
					( Origin gPackager )
				)
				( objectStatus "EU8F1.2" )
			)
			( pin "@baseboard_fab2_lib.baseboard_fab2(sch_1):page240_i125:rgnd"
				( attribute "PN" "7"
					( Origin gPackager )
				)
				( objectStatus "EU8F1.7" )
			)
			( pin "@baseboard_fab2_lib.baseboard_fab2(sch_1):page240_i125:ugate"
				( attribute "PN" "3"
					( Origin gPackager )
				)
				( objectStatus "EU8F1.3" )
			)
			( pin "@baseboard_fab2_lib.baseboard_fab2(sch_1):page240_i125:vcc"
				( attribute "PN" "5"
					( Origin gPackager )
				)
				( objectStatus "EU8F1.5" )
			)
			( pin "@baseboard_fab2_lib.baseboard_fab2(sch_1):page240_i125:vout"
				( attribute "PN" "6"
					( Origin gPackager )
				)
				( objectStatus "EU8F1.6" )
			)
			( pin "@baseboard_fab2_lib.baseboard_fab2(sch_1):page240_i127:a"
				( attribute "PN" "1"
					( Origin gPackager )
				)
				( objectStatus "R8E35.1" )
			)
			( pin "@baseboard_fab2_lib.baseboard_fab2(sch_1):page240_i127:b"
				( attribute "PN" "2"
					( Origin gPackager )
				)
				( objectStatus "R8E35.2" )
			)
			( pin "@baseboard_fab2_lib.baseboard_fab2(sch_1):page240_i129:a"
				( attribute "PN" "1"
					( Origin gPackager )
				)
				( objectStatus "C8E12.1" )
			)
			( pin "@baseboard_fab2_lib.baseboard_fab2(sch_1):page240_i129:b"
				( attribute "PN" "2"
					( Origin gPackager )
				)
				( objectStatus "C8E12.2" )
			)
			( pin "@baseboard_fab2_lib.baseboard_fab2(sch_1):page176_i162:en"
				( attribute "PN" "5"
					( Origin gPackager )
				)
				( objectStatus "U1W3.5" )
			)
			( pin "@baseboard_fab2_lib.baseboard_fab2(sch_1):page176_i162:scla"
				( attribute "PN" "2"
					( Origin gPackager )
				)
				( objectStatus "U1W3.2" )
			)
			( pin "@baseboard_fab2_lib.baseboard_fab2(sch_1):page176_i162:sclb"
				( attribute "PN" "7"
					( Origin gPackager )
				)
				( objectStatus "U1W3.7" )
			)
			( pin "@baseboard_fab2_lib.baseboard_fab2(sch_1):page176_i162:sdaa"
				( attribute "PN" "3"
					( Origin gPackager )
				)
				( objectStatus "U1W3.3" )
			)
			( pin "@baseboard_fab2_lib.baseboard_fab2(sch_1):page176_i162:sdab"
				( attribute "PN" "6"
					( Origin gPackager )
				)
				( objectStatus "U1W3.6" )
			)
			( pin "@baseboard_fab2_lib.baseboard_fab2(sch_1):page176_i162:vcca"
				( attribute "PN" "1"
					( Origin gPackager )
				)
				( objectStatus "U1W3.1" )
			)
			( pin "@baseboard_fab2_lib.baseboard_fab2(sch_1):page176_i162:vccb"
				( attribute "PN" "8"
					( Origin gPackager )
				)
				( objectStatus "U1W3.8" )
			)
			( pin "@baseboard_fab2_lib.baseboard_fab2(sch_1):page214_i149:\1\"
				( attribute "PN" "1"
					( Origin gPackager )
				)
				( objectStatus "C22W13.1" )
			)
			( pin "@baseboard_fab2_lib.baseboard_fab2(sch_1):page214_i149:\2\"
				( attribute "PN" "2"
					( Origin gPackager )
				)
				( objectStatus "C22W13.2" )
			)
			( pin "@baseboard_fab2_lib.baseboard_fab2(sch_1):page214_i148:\1\"
				( attribute "PN" "1"
					( Origin gPackager )
				)
				( objectStatus "C4E14.1" )
			)
			( pin "@baseboard_fab2_lib.baseboard_fab2(sch_1):page214_i148:\2\"
				( attribute "PN" "2"
					( Origin gPackager )
				)
				( objectStatus "C4E14.2" )
			)
			( pin "@baseboard_fab2_lib.baseboard_fab2(sch_1):page240_i137:a"
				( attribute "PN" "1"
					( Origin gPackager )
				)
				( objectStatus "C8E10.1" )
			)
			( pin "@baseboard_fab2_lib.baseboard_fab2(sch_1):page240_i137:b"
				( attribute "PN" "2"
					( Origin gPackager )
				)
				( objectStatus "C8E10.2" )
			)
			( pin "@baseboard_fab2_lib.baseboard_fab2(sch_1):page240_i139:a"
				( attribute "PN" "1"
					( Origin gPackager )
				)
				( objectStatus "C8E14.1" )
			)
			( pin "@baseboard_fab2_lib.baseboard_fab2(sch_1):page240_i139:b"
				( attribute "PN" "2"
					( Origin gPackager )
				)
				( objectStatus "C8E14.2" )
			)
			( pin "@baseboard_fab2_lib.baseboard_fab2(sch_1):page240_i140:a"
				( attribute "PN" "1"
					( Origin gPackager )
				)
				( objectStatus "R8E38.1" )
			)
			( pin "@baseboard_fab2_lib.baseboard_fab2(sch_1):page240_i140:b"
				( attribute "PN" "2"
					( Origin gPackager )
				)
				( objectStatus "R8E38.2" )
			)
			( pin "@baseboard_fab2_lib.baseboard_fab2(sch_1):page240_i142:a"
				( attribute "PN" "1"
					( Origin gPackager )
				)
				( objectStatus "R8E34.1" )
			)
			( pin "@baseboard_fab2_lib.baseboard_fab2(sch_1):page240_i142:b"
				( attribute "PN" "2"
					( Origin gPackager )
				)
				( objectStatus "R8E34.2" )
			)
			( pin "@baseboard_fab2_lib.baseboard_fab2(sch_1):page240_i143:a"
				( attribute "PN" "1"
					( Origin gPackager )
				)
				( objectStatus "R8E31.1" )
			)
			( pin "@baseboard_fab2_lib.baseboard_fab2(sch_1):page240_i143:b"
				( attribute "PN" "2"
					( Origin gPackager )
				)
				( objectStatus "R8E31.2" )
			)
			( pin "@baseboard_fab2_lib.baseboard_fab2(sch_1):page240_i144:a"
				( attribute "PN" "1"
					( Origin gPackager )
				)
				( objectStatus "R8E25.1" )
			)
			( pin "@baseboard_fab2_lib.baseboard_fab2(sch_1):page240_i144:b"
				( attribute "PN" "2"
					( Origin gPackager )
				)
				( objectStatus "R8E25.2" )
			)
			( pin "@baseboard_fab2_lib.baseboard_fab2(sch_1):page240_i146:a"
				( attribute "PN" "1"
					( Origin gPackager )
				)
				( objectStatus "R8F11.1" )
			)
			( pin "@baseboard_fab2_lib.baseboard_fab2(sch_1):page240_i146:b"
				( attribute "PN" "2"
					( Origin gPackager )
				)
				( objectStatus "R8F11.2" )
			)
			( pin "@baseboard_fab2_lib.baseboard_fab2(sch_1):page240_i148:a"
				( attribute "PN" "1"
					( Origin gPackager )
				)
				( objectStatus "R8F3.1" )
			)
			( pin "@baseboard_fab2_lib.baseboard_fab2(sch_1):page240_i148:b"
				( attribute "PN" "2"
					( Origin gPackager )
				)
				( objectStatus "R8F3.2" )
			)
			( pin "@baseboard_fab2_lib.baseboard_fab2(sch_1):page240_i152:a"
				( attribute "PN" "1"
					( Origin gPackager )
				)
				( objectStatus "R2T4.1" )
			)
			( pin "@baseboard_fab2_lib.baseboard_fab2(sch_1):page240_i152:b"
				( attribute "PN" "2"
					( Origin gPackager )
				)
				( objectStatus "R2T4.2" )
			)
			( pin "@baseboard_fab2_lib.baseboard_fab2(sch_1):page240_i158:a"
				( attribute "PN" "1"
					( Origin gPackager )
				)
				( objectStatus "C2T7.1" )
			)
			( pin "@baseboard_fab2_lib.baseboard_fab2(sch_1):page240_i158:b"
				( attribute "PN" "2"
					( Origin gPackager )
				)
				( objectStatus "C2T7.2" )
			)
			( pin "@baseboard_fab2_lib.baseboard_fab2(sch_1):page240_i160:a"
				( attribute "PN" "1"
					( Origin gPackager )
				)
				( objectStatus "C2T6.1" )
			)
			( pin "@baseboard_fab2_lib.baseboard_fab2(sch_1):page240_i160:b"
				( attribute "PN" "2"
					( Origin gPackager )
				)
				( objectStatus "C2T6.2" )
			)
			( pin "@baseboard_fab2_lib.baseboard_fab2(sch_1):page240_i163:a"
				( attribute "PN" "1"
					( Origin gPackager )
				)
				( objectStatus "C8F3.1" )
			)
			( pin "@baseboard_fab2_lib.baseboard_fab2(sch_1):page240_i163:b"
				( attribute "PN" "2"
					( Origin gPackager )
				)
				( objectStatus "C8F3.2" )
			)
			( pin "@baseboard_fab2_lib.baseboard_fab2(sch_1):page240_i170:bg"
				( attribute "PN" "4"
					( Origin gPackager )
				)
				( objectStatus "EU8E1.4" )
			)
			( pin "@baseboard_fab2_lib.baseboard_fab2(sch_1):page240_i170:pgnd"
				( attribute "PN" "3"
					( Origin gPackager )
				)
				( objectStatus "EU8E1.3" )
			)
			( pin "@baseboard_fab2_lib.baseboard_fab2(sch_1):page240_i170:tg"
				( attribute "PN" "1"
					( Origin gPackager )
				)
				( objectStatus "EU8E1.1" )
			)
			( pin "@baseboard_fab2_lib.baseboard_fab2(sch_1):page240_i170:vin"
				( attribute "PN" "2"
					( Origin gPackager )
				)
				( objectStatus "EU8E1.2" )
			)
			( pin "@baseboard_fab2_lib.baseboard_fab2(sch_1):page240_i170:vsw"
				( attribute "PN" "5"
					( Origin gPackager )
				)
				( objectStatus "EU8E1.5" )
			)
			( pin "@baseboard_fab2_lib.baseboard_fab2(sch_1):page240_i171:a"
				( attribute "PN" "1"
					( Origin gPackager )
				)
				( objectStatus "R8F10.1" )
			)
			( pin "@baseboard_fab2_lib.baseboard_fab2(sch_1):page240_i171:b"
				( attribute "PN" "2"
					( Origin gPackager )
				)
				( objectStatus "R8F10.2" )
			)
			( pin "@baseboard_fab2_lib.baseboard_fab2(sch_1):page175_i99:a"
				( attribute "PN" "1"
					( Origin gPackager )
				)
				( objectStatus "R1L19.1" )
			)
			( pin "@baseboard_fab2_lib.baseboard_fab2(sch_1):page175_i99:b"
				( attribute "PN" "2"
					( Origin gPackager )
				)
				( objectStatus "R1L19.2" )
			)
			( pin "@baseboard_fab2_lib.baseboard_fab2(sch_1):page240_i174:a"
				( attribute "PN" "1"
					( Origin gPackager )
				)
				( objectStatus "C2T9.1" )
			)
			( pin "@baseboard_fab2_lib.baseboard_fab2(sch_1):page240_i174:b"
				( attribute "PN" "2"
					( Origin gPackager )
				)
				( objectStatus "C2T9.2" )
			)
			( pin "@baseboard_fab2_lib.baseboard_fab2(sch_1):page240_i176:a"
				( attribute "PN" "1"
					( Origin gPackager )
				)
				( objectStatus "R8F2.1" )
			)
			( pin "@baseboard_fab2_lib.baseboard_fab2(sch_1):page240_i176:b"
				( attribute "PN" "2"
					( Origin gPackager )
				)
				( objectStatus "R8F2.2" )
			)
			( pin "@baseboard_fab2_lib.baseboard_fab2(sch_1):page240_i177:a"
				( attribute "PN" "1"
					( Origin gPackager )
				)
				( objectStatus "R8E40.1" )
			)
			( pin "@baseboard_fab2_lib.baseboard_fab2(sch_1):page240_i177:b"
				( attribute "PN" "2"
					( Origin gPackager )
				)
				( objectStatus "R8E40.2" )
			)
			( pin "@baseboard_fab2_lib.baseboard_fab2(sch_1):page227_i148:\1\"
				( attribute "PN" "1"
					( Origin gPackager )
				)
				( objectStatus "C1A2.1" )
			)
			( pin "@baseboard_fab2_lib.baseboard_fab2(sch_1):page227_i148:\2\"
				( attribute "PN" "2"
					( Origin gPackager )
				)
				( objectStatus "C1A2.2" )
			)
			( pin "@baseboard_fab2_lib.baseboard_fab2(sch_1):page240_i191:\1\"
				( attribute "PN" "1"
					( Origin gPackager )
				)
				( objectStatus "C2R11.1" )
			)
			( pin "@baseboard_fab2_lib.baseboard_fab2(sch_1):page240_i191:\2\"
				( attribute "PN" "2"
					( Origin gPackager )
				)
				( objectStatus "C2R11.2" )
			)
			( pin "@baseboard_fab2_lib.baseboard_fab2(sch_1):page241_i9:a"
				( attribute "PN" "1"
					( Origin gPackager )
				)
				( objectStatus "R8E18.1" )
			)
			( pin "@baseboard_fab2_lib.baseboard_fab2(sch_1):page241_i9:b"
				( attribute "PN" "2"
					( Origin gPackager )
				)
				( objectStatus "R8E18.2" )
			)
			( pin "@baseboard_fab2_lib.baseboard_fab2(sch_1):page241_i11:a"
				( attribute "PN" "1"
					( Origin gPackager )
				)
				( objectStatus "R7E12.1" )
			)
			( pin "@baseboard_fab2_lib.baseboard_fab2(sch_1):page241_i11:b"
				( attribute "PN" "2"
					( Origin gPackager )
				)
				( objectStatus "R7E12.2" )
			)
			( pin "@baseboard_fab2_lib.baseboard_fab2(sch_1):page241_i12:a"
				( attribute "PN" "1"
					( Origin gPackager )
				)
				( objectStatus "C8E6.1" )
			)
			( pin "@baseboard_fab2_lib.baseboard_fab2(sch_1):page241_i12:b"
				( attribute "PN" "2"
					( Origin gPackager )
				)
				( objectStatus "C8E6.2" )
			)
			( pin "@baseboard_fab2_lib.baseboard_fab2(sch_1):page241_i14:a"
				( attribute "PN" "1"
					( Origin gPackager )
				)
				( objectStatus "C7E10.1" )
			)
			( pin "@baseboard_fab2_lib.baseboard_fab2(sch_1):page241_i14:b"
				( attribute "PN" "2"
					( Origin gPackager )
				)
				( objectStatus "C7E10.2" )
			)
			( pin "@baseboard_fab2_lib.baseboard_fab2(sch_1):page241_i18:a"
				( attribute "PN" "1"
					( Origin gPackager )
				)
				( objectStatus "R7E14.1" )
			)
			( pin "@baseboard_fab2_lib.baseboard_fab2(sch_1):page241_i18:b"
				( attribute "PN" "2"
					( Origin gPackager )
				)
				( objectStatus "R7E14.2" )
			)
			( pin "@baseboard_fab2_lib.baseboard_fab2(sch_1):page241_i30:a"
				( attribute "PN" "1"
					( Origin gPackager )
				)
				( objectStatus "C7E14.1" )
			)
			( pin "@baseboard_fab2_lib.baseboard_fab2(sch_1):page241_i30:b"
				( attribute "PN" "2"
					( Origin gPackager )
				)
				( objectStatus "C7E14.2" )
			)
			( pin "@baseboard_fab2_lib.baseboard_fab2(sch_1):page241_i37:a"
				( attribute "PN" "1"
					( Origin gPackager )
				)
				( objectStatus "R7E17.1" )
			)
			( pin "@baseboard_fab2_lib.baseboard_fab2(sch_1):page241_i37:b"
				( attribute "PN" "2"
					( Origin gPackager )
				)
				( objectStatus "R7E17.2" )
			)
			( pin "@baseboard_fab2_lib.baseboard_fab2(sch_1):page241_i39:a"
				( attribute "PN" "1"
					( Origin gPackager )
				)
				( objectStatus "C7E11.1" )
			)
			( pin "@baseboard_fab2_lib.baseboard_fab2(sch_1):page241_i39:b"
				( attribute "PN" "2"
					( Origin gPackager )
				)
				( objectStatus "C7E11.2" )
			)
			( pin "@baseboard_fab2_lib.baseboard_fab2(sch_1):page241_i41:a"
				( attribute "PN" "1"
					( Origin gPackager )
				)
				( objectStatus "C8E13.1" )
			)
			( pin "@baseboard_fab2_lib.baseboard_fab2(sch_1):page241_i41:b"
				( attribute "PN" "2"
					( Origin gPackager )
				)
				( objectStatus "C8E13.2" )
			)
			( pin "@baseboard_fab2_lib.baseboard_fab2(sch_1):page240_i182:\1\"
				( attribute "PN" "1"
					( Origin gPackager )
				)
				( objectStatus "C22W11.1" )
			)
			( pin "@baseboard_fab2_lib.baseboard_fab2(sch_1):page240_i182:\2\"
				( attribute "PN" "2"
					( Origin gPackager )
				)
				( objectStatus "C22W11.2" )
			)
			( pin "@baseboard_fab2_lib.baseboard_fab2(sch_1):page241_i50:a"
				( attribute "PN" "1"
					( Origin gPackager )
				)
				( objectStatus "R7F1.1" )
			)
			( pin "@baseboard_fab2_lib.baseboard_fab2(sch_1):page241_i50:b"
				( attribute "PN" "2"
					( Origin gPackager )
				)
				( objectStatus "R7F1.2" )
			)
			( pin "@baseboard_fab2_lib.baseboard_fab2(sch_1):page241_i51:a"
				( attribute "PN" "1"
					( Origin gPackager )
				)
				( objectStatus "R7E16.1" )
			)
			( pin "@baseboard_fab2_lib.baseboard_fab2(sch_1):page241_i51:b"
				( attribute "PN" "2"
					( Origin gPackager )
				)
				( objectStatus "R7E16.2" )
			)
			( pin "@baseboard_fab2_lib.baseboard_fab2(sch_1):page241_i53:a"
				( attribute "PN" "1"
					( Origin gPackager )
				)
				( objectStatus "C8E16.1" )
			)
			( pin "@baseboard_fab2_lib.baseboard_fab2(sch_1):page241_i53:b"
				( attribute "PN" "2"
					( Origin gPackager )
				)
				( objectStatus "C8E16.2" )
			)
			( pin "@baseboard_fab2_lib.baseboard_fab2(sch_1):page241_i54:a"
				( attribute "PN" "1"
					( Origin gPackager )
				)
				( objectStatus "R8E39.1" )
			)
			( pin "@baseboard_fab2_lib.baseboard_fab2(sch_1):page241_i54:b"
				( attribute "PN" "2"
					( Origin gPackager )
				)
				( objectStatus "R8E39.2" )
			)
			( pin "@baseboard_fab2_lib.baseboard_fab2(sch_1):page241_i57:a"
				( attribute "PN" "1"
					( Origin gPackager )
				)
				( objectStatus "C8F1.1" )
			)
			( pin "@baseboard_fab2_lib.baseboard_fab2(sch_1):page241_i57:b"
				( attribute "PN" "2"
					( Origin gPackager )
				)
				( objectStatus "C8F1.2" )
			)
			( pin "@baseboard_fab2_lib.baseboard_fab2(sch_1):page241_i58:a"
				( attribute "PN" "1"
					( Origin gPackager )
				)
				( objectStatus "R7E13.1" )
			)
			( pin "@baseboard_fab2_lib.baseboard_fab2(sch_1):page241_i58:b"
				( attribute "PN" "2"
					( Origin gPackager )
				)
				( objectStatus "R7E13.2" )
			)
			( pin "@baseboard_fab2_lib.baseboard_fab2(sch_1):page241_i63:a"
				( attribute "PN" "1"
					( Origin gPackager )
				)
				( objectStatus "C8E15.1" )
			)
			( pin "@baseboard_fab2_lib.baseboard_fab2(sch_1):page241_i63:b"
				( attribute "PN" "2"
					( Origin gPackager )
				)
				( objectStatus "C8E15.2" )
			)
			( pin "@baseboard_fab2_lib.baseboard_fab2(sch_1):page241_i78:a"
				( attribute "PN" "1"
					( Origin gPackager )
				)
				( objectStatus "R8E37.1" )
			)
			( pin "@baseboard_fab2_lib.baseboard_fab2(sch_1):page241_i78:b"
				( attribute "PN" "2"
					( Origin gPackager )
				)
				( objectStatus "R8E37.2" )
			)
			( pin "@baseboard_fab2_lib.baseboard_fab2(sch_1):page241_i82:a"
				( attribute "PN" "1"
					( Origin gPackager )
				)
				( objectStatus "FB7E1.1" )
			)
			( pin "@baseboard_fab2_lib.baseboard_fab2(sch_1):page241_i82:b"
				( attribute "PN" "2"
					( Origin gPackager )
				)
				( objectStatus "FB7E1.2" )
			)
			( pin "@baseboard_fab2_lib.baseboard_fab2(sch_1):page241_i83:boot"
				( attribute "PN" "13"
					( Origin gPackager )
				)
				( objectStatus "EU7E2.13" )
			)
			( pin "@baseboard_fab2_lib.baseboard_fab2(sch_1):page241_i83:comp"
				( attribute "PN" "8"
					( Origin gPackager )
				)
				( objectStatus "EU7E2.8" )
			)
			( pin "@baseboard_fab2_lib.baseboard_fab2(sch_1):page241_i83:en"
				( attribute "PN" "10"
					( Origin gPackager )
				)
				( objectStatus "EU7E2.10" )
			)
			( pin "@baseboard_fab2_lib.baseboard_fab2(sch_1):page241_i83:gnd(0)"
				( attribute "PN" "2"
					( Origin gPackager )
				)
				( objectStatus "EU7E2.2" )
			)
			( pin "@baseboard_fab2_lib.baseboard_fab2(sch_1):page241_i83:gnd(1)"
				( attribute "PN" "3"
					( Origin gPackager )
				)
				( objectStatus "EU7E2.3" )
			)
			( pin "@baseboard_fab2_lib.baseboard_fab2(sch_1):page241_i83:ph(0)"
				( attribute "PN" "11"
					( Origin gPackager )
				)
				( objectStatus "EU7E2.11" )
			)
			( pin "@baseboard_fab2_lib.baseboard_fab2(sch_1):page241_i83:ph(1)"
				( attribute "PN" "12"
					( Origin gPackager )
				)
				( objectStatus "EU7E2.12" )
			)
			( pin "@baseboard_fab2_lib.baseboard_fab2(sch_1):page241_i83:pvin(0)"
				( attribute "PN" "4"
					( Origin gPackager )
				)
				( objectStatus "EU7E2.4" )
			)
			( pin "@baseboard_fab2_lib.baseboard_fab2(sch_1):page241_i83:pvin(1)"
				( attribute "PN" "5"
					( Origin gPackager )
				)
				( objectStatus "EU7E2.5" )
			)
			( pin "@baseboard_fab2_lib.baseboard_fab2(sch_1):page241_i83:pwrgd"
				( attribute "PN" "14"
					( Origin gPackager )
				)
				( objectStatus "EU7E2.14" )
			)
			( pin "@baseboard_fab2_lib.baseboard_fab2(sch_1):page241_i83:rt_clk"
				( attribute "PN" "1"
					( Origin gPackager )
				)
				( objectStatus "EU7E2.1" )
			)
			( pin "@baseboard_fab2_lib.baseboard_fab2(sch_1):page241_i83:ss_tr"
				( attribute "PN" "9"
					( Origin gPackager )
				)
				( objectStatus "EU7E2.9" )
			)
			( pin "@baseboard_fab2_lib.baseboard_fab2(sch_1):page241_i83:thpad"
				( attribute "PN" "15"
					( Origin gPackager )
				)
				( objectStatus "EU7E2.15" )
			)
			( pin "@baseboard_fab2_lib.baseboard_fab2(sch_1):page241_i83:vin"
				( attribute "PN" "6"
					( Origin gPackager )
				)
				( objectStatus "EU7E2.6" )
			)
			( pin "@baseboard_fab2_lib.baseboard_fab2(sch_1):page241_i83:vsense"
				( attribute "PN" "7"
					( Origin gPackager )
				)
				( objectStatus "EU7E2.7" )
			)
			( pin "@baseboard_fab2_lib.baseboard_fab2(sch_1):page241_i89:a"
				( attribute "PN" "1"
					( Origin gPackager )
				)
				( objectStatus "R7E15.1" )
			)
			( pin "@baseboard_fab2_lib.baseboard_fab2(sch_1):page241_i89:b"
				( attribute "PN" "2"
					( Origin gPackager )
				)
				( objectStatus "R7E15.2" )
			)
			( pin "@baseboard_fab2_lib.baseboard_fab2(sch_1):page241_i90:ina"
				( attribute "PN" "1"
					( Origin gPackager )
				)
				( objectStatus "L8E1.1" )
			)
			( pin "@baseboard_fab2_lib.baseboard_fab2(sch_1):page241_i90:inb"
				( attribute "PN" "2"
					( Origin gPackager )
				)
				( objectStatus "L8E1.2" )
			)
			( pin "@baseboard_fab2_lib.baseboard_fab2(sch_1):page241_i91:a"
				( attribute "PN" "1"
					( Origin gPackager )
				)
				( objectStatus "R8E33.1" )
			)
			( pin "@baseboard_fab2_lib.baseboard_fab2(sch_1):page241_i91:b"
				( attribute "PN" "2"
					( Origin gPackager )
				)
				( objectStatus "R8E33.2" )
			)
			( pin "@baseboard_fab2_lib.baseboard_fab2(sch_1):page243_i88:a"
				( attribute "PN" "1"
					( Origin gPackager )
				)
				( objectStatus "C5G106.1" )
			)
			( pin "@baseboard_fab2_lib.baseboard_fab2(sch_1):page243_i88:b"
				( attribute "PN" "2"
					( Origin gPackager )
				)
				( objectStatus "C5G106.2" )
			)
			( pin "@baseboard_fab2_lib.baseboard_fab2(sch_1):page243_i87:a"
				( attribute "PN" "1"
					( Origin gPackager )
				)
				( objectStatus "C5G107.1" )
			)
			( pin "@baseboard_fab2_lib.baseboard_fab2(sch_1):page243_i87:b"
				( attribute "PN" "2"
					( Origin gPackager )
				)
				( objectStatus "C5G107.2" )
			)
			( pin "@baseboard_fab2_lib.baseboard_fab2(sch_1):page243_i86:a"
				( attribute "PN" "1"
					( Origin gPackager )
				)
				( objectStatus "C5G108.1" )
			)
			( pin "@baseboard_fab2_lib.baseboard_fab2(sch_1):page243_i86:b"
				( attribute "PN" "2"
					( Origin gPackager )
				)
				( objectStatus "C5G108.2" )
			)
			( pin "@baseboard_fab2_lib.baseboard_fab2(sch_1):page243_i85:a"
				( attribute "PN" "1"
					( Origin gPackager )
				)
				( objectStatus "C5G109.1" )
			)
			( pin "@baseboard_fab2_lib.baseboard_fab2(sch_1):page243_i85:b"
				( attribute "PN" "2"
					( Origin gPackager )
				)
				( objectStatus "C5G109.2" )
			)
			( pin "@baseboard_fab2_lib.baseboard_fab2(sch_1):page243_i84:a"
				( attribute "PN" "1"
					( Origin gPackager )
				)
				( objectStatus "C5G110.1" )
			)
			( pin "@baseboard_fab2_lib.baseboard_fab2(sch_1):page243_i84:b"
				( attribute "PN" "2"
					( Origin gPackager )
				)
				( objectStatus "C5G110.2" )
			)
			( pin "@baseboard_fab2_lib.baseboard_fab2(sch_1):page243_i83:a"
				( attribute "PN" "1"
					( Origin gPackager )
				)
				( objectStatus "C5G111.1" )
			)
			( pin "@baseboard_fab2_lib.baseboard_fab2(sch_1):page243_i83:b"
				( attribute "PN" "2"
					( Origin gPackager )
				)
				( objectStatus "C5G111.2" )
			)
			( pin "@baseboard_fab2_lib.baseboard_fab2(sch_1):page243_i82:a"
				( attribute "PN" "1"
					( Origin gPackager )
				)
				( objectStatus "C5G112.1" )
			)
			( pin "@baseboard_fab2_lib.baseboard_fab2(sch_1):page243_i82:b"
				( attribute "PN" "2"
					( Origin gPackager )
				)
				( objectStatus "C5G112.2" )
			)
			( pin "@baseboard_fab2_lib.baseboard_fab2(sch_1):page243_i81:a"
				( attribute "PN" "1"
					( Origin gPackager )
				)
				( objectStatus "C5G113.1" )
			)
			( pin "@baseboard_fab2_lib.baseboard_fab2(sch_1):page243_i81:b"
				( attribute "PN" "2"
					( Origin gPackager )
				)
				( objectStatus "C5G113.2" )
			)
			( pin "@baseboard_fab2_lib.baseboard_fab2(sch_1):page243_i92:a"
				( attribute "PN" "1"
					( Origin gPackager )
				)
				( objectStatus "C5G117.1" )
			)
			( pin "@baseboard_fab2_lib.baseboard_fab2(sch_1):page243_i92:b"
				( attribute "PN" "2"
					( Origin gPackager )
				)
				( objectStatus "C5G117.2" )
			)
			( pin "@baseboard_fab2_lib.baseboard_fab2(sch_1):page243_i80:a"
				( attribute "PN" "1"
					( Origin gPackager )
				)
				( objectStatus "C5G114.1" )
			)
			( pin "@baseboard_fab2_lib.baseboard_fab2(sch_1):page243_i80:b"
				( attribute "PN" "2"
					( Origin gPackager )
				)
				( objectStatus "C5G114.2" )
			)
			( pin "@baseboard_fab2_lib.baseboard_fab2(sch_1):page243_i79:a"
				( attribute "PN" "1"
					( Origin gPackager )
				)
				( objectStatus "C5G97.1" )
			)
			( pin "@baseboard_fab2_lib.baseboard_fab2(sch_1):page243_i79:b"
				( attribute "PN" "2"
					( Origin gPackager )
				)
				( objectStatus "C5G97.2" )
			)
			( pin "@baseboard_fab2_lib.baseboard_fab2(sch_1):page243_i78:a"
				( attribute "PN" "1"
					( Origin gPackager )
				)
				( objectStatus "C5G98.1" )
			)
			( pin "@baseboard_fab2_lib.baseboard_fab2(sch_1):page243_i78:b"
				( attribute "PN" "2"
					( Origin gPackager )
				)
				( objectStatus "C5G98.2" )
			)
			( pin "@baseboard_fab2_lib.baseboard_fab2(sch_1):page243_i77:a"
				( attribute "PN" "1"
					( Origin gPackager )
				)
				( objectStatus "C5G99.1" )
			)
			( pin "@baseboard_fab2_lib.baseboard_fab2(sch_1):page243_i77:b"
				( attribute "PN" "2"
					( Origin gPackager )
				)
				( objectStatus "C5G99.2" )
			)
			( pin "@baseboard_fab2_lib.baseboard_fab2(sch_1):page243_i76:a"
				( attribute "PN" "1"
					( Origin gPackager )
				)
				( objectStatus "C5G100.1" )
			)
			( pin "@baseboard_fab2_lib.baseboard_fab2(sch_1):page243_i76:b"
				( attribute "PN" "2"
					( Origin gPackager )
				)
				( objectStatus "C5G100.2" )
			)
			( pin "@baseboard_fab2_lib.baseboard_fab2(sch_1):page243_i75:a"
				( attribute "PN" "1"
					( Origin gPackager )
				)
				( objectStatus "C5G101.1" )
			)
			( pin "@baseboard_fab2_lib.baseboard_fab2(sch_1):page243_i75:b"
				( attribute "PN" "2"
					( Origin gPackager )
				)
				( objectStatus "C5G101.2" )
			)
			( pin "@baseboard_fab2_lib.baseboard_fab2(sch_1):page243_i74:a"
				( attribute "PN" "1"
					( Origin gPackager )
				)
				( objectStatus "C5G102.1" )
			)
			( pin "@baseboard_fab2_lib.baseboard_fab2(sch_1):page243_i74:b"
				( attribute "PN" "2"
					( Origin gPackager )
				)
				( objectStatus "C5G102.2" )
			)
			( pin "@baseboard_fab2_lib.baseboard_fab2(sch_1):page243_i73:a"
				( attribute "PN" "1"
					( Origin gPackager )
				)
				( objectStatus "C5G105.1" )
			)
			( pin "@baseboard_fab2_lib.baseboard_fab2(sch_1):page243_i73:b"
				( attribute "PN" "2"
					( Origin gPackager )
				)
				( objectStatus "C5G105.2" )
			)
			( pin "@baseboard_fab2_lib.baseboard_fab2(sch_1):page243_i72:a"
				( attribute "PN" "1"
					( Origin gPackager )
				)
				( objectStatus "C5G104.1" )
			)
			( pin "@baseboard_fab2_lib.baseboard_fab2(sch_1):page243_i72:b"
				( attribute "PN" "2"
					( Origin gPackager )
				)
				( objectStatus "C5G104.2" )
			)
			( pin "@baseboard_fab2_lib.baseboard_fab2(sch_1):page243_i71:a"
				( attribute "PN" "1"
					( Origin gPackager )
				)
				( objectStatus "C5G103.1" )
			)
			( pin "@baseboard_fab2_lib.baseboard_fab2(sch_1):page243_i71:b"
				( attribute "PN" "2"
					( Origin gPackager )
				)
				( objectStatus "C5G103.2" )
			)
			( pin "@baseboard_fab2_lib.baseboard_fab2(sch_1):page243_i70:a"
				( attribute "PN" "1"
					( Origin gPackager )
				)
				( objectStatus "C5G88.1" )
			)
			( pin "@baseboard_fab2_lib.baseboard_fab2(sch_1):page243_i70:b"
				( attribute "PN" "2"
					( Origin gPackager )
				)
				( objectStatus "C5G88.2" )
			)
			( pin "@baseboard_fab2_lib.baseboard_fab2(sch_1):page243_i69:a"
				( attribute "PN" "1"
					( Origin gPackager )
				)
				( objectStatus "C5G89.1" )
			)
			( pin "@baseboard_fab2_lib.baseboard_fab2(sch_1):page243_i69:b"
				( attribute "PN" "2"
					( Origin gPackager )
				)
				( objectStatus "C5G89.2" )
			)
			( pin "@baseboard_fab2_lib.baseboard_fab2(sch_1):page243_i68:a"
				( attribute "PN" "1"
					( Origin gPackager )
				)
				( objectStatus "C5G90.1" )
			)
			( pin "@baseboard_fab2_lib.baseboard_fab2(sch_1):page243_i68:b"
				( attribute "PN" "2"
					( Origin gPackager )
				)
				( objectStatus "C5G90.2" )
			)
			( pin "@baseboard_fab2_lib.baseboard_fab2(sch_1):page243_i67:a"
				( attribute "PN" "1"
					( Origin gPackager )
				)
				( objectStatus "C5G91.1" )
			)
			( pin "@baseboard_fab2_lib.baseboard_fab2(sch_1):page243_i67:b"
				( attribute "PN" "2"
					( Origin gPackager )
				)
				( objectStatus "C5G91.2" )
			)
			( pin "@baseboard_fab2_lib.baseboard_fab2(sch_1):page243_i66:a"
				( attribute "PN" "1"
					( Origin gPackager )
				)
				( objectStatus "C5G92.1" )
			)
			( pin "@baseboard_fab2_lib.baseboard_fab2(sch_1):page243_i66:b"
				( attribute "PN" "2"
					( Origin gPackager )
				)
				( objectStatus "C5G92.2" )
			)
			( pin "@baseboard_fab2_lib.baseboard_fab2(sch_1):page243_i91:a"
				( attribute "PN" "1"
					( Origin gPackager )
				)
				( objectStatus "C5G118.1" )
			)
			( pin "@baseboard_fab2_lib.baseboard_fab2(sch_1):page243_i91:b"
				( attribute "PN" "2"
					( Origin gPackager )
				)
				( objectStatus "C5G118.2" )
			)
			( pin "@baseboard_fab2_lib.baseboard_fab2(sch_1):page243_i65:a"
				( attribute "PN" "1"
					( Origin gPackager )
				)
				( objectStatus "C5G93.1" )
			)
			( pin "@baseboard_fab2_lib.baseboard_fab2(sch_1):page243_i65:b"
				( attribute "PN" "2"
					( Origin gPackager )
				)
				( objectStatus "C5G93.2" )
			)
			( pin "@baseboard_fab2_lib.baseboard_fab2(sch_1):page243_i64:a"
				( attribute "PN" "1"
					( Origin gPackager )
				)
				( objectStatus "C5G94.1" )
			)
			( pin "@baseboard_fab2_lib.baseboard_fab2(sch_1):page243_i64:b"
				( attribute "PN" "2"
					( Origin gPackager )
				)
				( objectStatus "C5G94.2" )
			)
			( pin "@baseboard_fab2_lib.baseboard_fab2(sch_1):page243_i63:a"
				( attribute "PN" "1"
					( Origin gPackager )
				)
				( objectStatus "C5G95.1" )
			)
			( pin "@baseboard_fab2_lib.baseboard_fab2(sch_1):page243_i63:b"
				( attribute "PN" "2"
					( Origin gPackager )
				)
				( objectStatus "C5G95.2" )
			)
			( pin "@baseboard_fab2_lib.baseboard_fab2(sch_1):page243_i90:a"
				( attribute "PN" "1"
					( Origin gPackager )
				)
				( objectStatus "C5G116.1" )
			)
			( pin "@baseboard_fab2_lib.baseboard_fab2(sch_1):page243_i90:b"
				( attribute "PN" "2"
					( Origin gPackager )
				)
				( objectStatus "C5G116.2" )
			)
			( pin "@baseboard_fab2_lib.baseboard_fab2(sch_1):page243_i62:a"
				( attribute "PN" "1"
					( Origin gPackager )
				)
				( objectStatus "C5G96.1" )
			)
			( pin "@baseboard_fab2_lib.baseboard_fab2(sch_1):page243_i62:b"
				( attribute "PN" "2"
					( Origin gPackager )
				)
				( objectStatus "C5G96.2" )
			)
			( pin "@baseboard_fab2_lib.baseboard_fab2(sch_1):page243_i61:a"
				( attribute "PN" "1"
					( Origin gPackager )
				)
				( objectStatus "C5G80.1" )
			)
			( pin "@baseboard_fab2_lib.baseboard_fab2(sch_1):page243_i61:b"
				( attribute "PN" "2"
					( Origin gPackager )
				)
				( objectStatus "C5G80.2" )
			)
			( pin "@baseboard_fab2_lib.baseboard_fab2(sch_1):page243_i60:a"
				( attribute "PN" "1"
					( Origin gPackager )
				)
				( objectStatus "C5G81.1" )
			)
			( pin "@baseboard_fab2_lib.baseboard_fab2(sch_1):page243_i60:b"
				( attribute "PN" "2"
					( Origin gPackager )
				)
				( objectStatus "C5G81.2" )
			)
			( pin "@baseboard_fab2_lib.baseboard_fab2(sch_1):page243_i59:a"
				( attribute "PN" "1"
					( Origin gPackager )
				)
				( objectStatus "C5G82.1" )
			)
			( pin "@baseboard_fab2_lib.baseboard_fab2(sch_1):page243_i59:b"
				( attribute "PN" "2"
					( Origin gPackager )
				)
				( objectStatus "C5G82.2" )
			)
			( pin "@baseboard_fab2_lib.baseboard_fab2(sch_1):page243_i58:a"
				( attribute "PN" "1"
					( Origin gPackager )
				)
				( objectStatus "C5G83.1" )
			)
			( pin "@baseboard_fab2_lib.baseboard_fab2(sch_1):page243_i58:b"
				( attribute "PN" "2"
					( Origin gPackager )
				)
				( objectStatus "C5G83.2" )
			)
			( pin "@baseboard_fab2_lib.baseboard_fab2(sch_1):page243_i57:a"
				( attribute "PN" "1"
					( Origin gPackager )
				)
				( objectStatus "C5G84.1" )
			)
			( pin "@baseboard_fab2_lib.baseboard_fab2(sch_1):page243_i57:b"
				( attribute "PN" "2"
					( Origin gPackager )
				)
				( objectStatus "C5G84.2" )
			)
			( pin "@baseboard_fab2_lib.baseboard_fab2(sch_1):page243_i56:a"
				( attribute "PN" "1"
					( Origin gPackager )
				)
				( objectStatus "C5G85.1" )
			)
			( pin "@baseboard_fab2_lib.baseboard_fab2(sch_1):page243_i56:b"
				( attribute "PN" "2"
					( Origin gPackager )
				)
				( objectStatus "C5G85.2" )
			)
			( pin "@baseboard_fab2_lib.baseboard_fab2(sch_1):page243_i55:a"
				( attribute "PN" "1"
					( Origin gPackager )
				)
				( objectStatus "C5G86.1" )
			)
			( pin "@baseboard_fab2_lib.baseboard_fab2(sch_1):page243_i55:b"
				( attribute "PN" "2"
					( Origin gPackager )
				)
				( objectStatus "C5G86.2" )
			)
			( pin "@baseboard_fab2_lib.baseboard_fab2(sch_1):page243_i54:a"
				( attribute "PN" "1"
					( Origin gPackager )
				)
				( objectStatus "C5G87.1" )
			)
			( pin "@baseboard_fab2_lib.baseboard_fab2(sch_1):page243_i54:b"
				( attribute "PN" "2"
					( Origin gPackager )
				)
				( objectStatus "C5G87.2" )
			)
			( pin "@baseboard_fab2_lib.baseboard_fab2(sch_1):page243_i53:a"
				( attribute "PN" "1"
					( Origin gPackager )
				)
				( objectStatus "C5G79.1" )
			)
			( pin "@baseboard_fab2_lib.baseboard_fab2(sch_1):page243_i53:b"
				( attribute "PN" "2"
					( Origin gPackager )
				)
				( objectStatus "C5G79.2" )
			)
			( pin "@baseboard_fab2_lib.baseboard_fab2(sch_1):page219_i138:a"
				( attribute "PN" "1"
					( Origin gPackager )
				)
				( objectStatus "CT47.1" )
			)
			( pin "@baseboard_fab2_lib.baseboard_fab2(sch_1):page219_i138:b"
				( attribute "PN" "2"
					( Origin gPackager )
				)
				( objectStatus "CT47.2" )
			)
			( pin "@baseboard_fab2_lib.baseboard_fab2(sch_1):page203_i119:a"
				( attribute "PN" "1"
					( Origin gPackager )
				)
				( objectStatus "CT41.1" )
			)
			( pin "@baseboard_fab2_lib.baseboard_fab2(sch_1):page203_i119:b"
				( attribute "PN" "2"
					( Origin gPackager )
				)
				( objectStatus "CT41.2" )
			)
			( pin "@baseboard_fab2_lib.baseboard_fab2(sch_1):page203_i118:a"
				( attribute "PN" "1"
					( Origin gPackager )
				)
				( objectStatus "CT38.1" )
			)
			( pin "@baseboard_fab2_lib.baseboard_fab2(sch_1):page203_i118:b"
				( attribute "PN" "2"
					( Origin gPackager )
				)
				( objectStatus "CT38.2" )
			)
			( pin "@baseboard_fab2_lib.baseboard_fab2(sch_1):page242_i53:a"
				( attribute "PN" "1"
					( Origin gPackager )
				)
				( objectStatus "C5G41.1" )
			)
			( pin "@baseboard_fab2_lib.baseboard_fab2(sch_1):page242_i53:b"
				( attribute "PN" "2"
					( Origin gPackager )
				)
				( objectStatus "C5G41.2" )
			)
			( pin "@baseboard_fab2_lib.baseboard_fab2(sch_1):page242_i54:a"
				( attribute "PN" "1"
					( Origin gPackager )
				)
				( objectStatus "C5G42.1" )
			)
			( pin "@baseboard_fab2_lib.baseboard_fab2(sch_1):page242_i54:b"
				( attribute "PN" "2"
					( Origin gPackager )
				)
				( objectStatus "C5G42.2" )
			)
			( pin "@baseboard_fab2_lib.baseboard_fab2(sch_1):page242_i55:a"
				( attribute "PN" "1"
					( Origin gPackager )
				)
				( objectStatus "C5G44.1" )
			)
			( pin "@baseboard_fab2_lib.baseboard_fab2(sch_1):page242_i55:b"
				( attribute "PN" "2"
					( Origin gPackager )
				)
				( objectStatus "C5G44.2" )
			)
			( pin "@baseboard_fab2_lib.baseboard_fab2(sch_1):page242_i56:a"
				( attribute "PN" "1"
					( Origin gPackager )
				)
				( objectStatus "C5G43.1" )
			)
			( pin "@baseboard_fab2_lib.baseboard_fab2(sch_1):page242_i56:b"
				( attribute "PN" "2"
					( Origin gPackager )
				)
				( objectStatus "C5G43.2" )
			)
			( pin "@baseboard_fab2_lib.baseboard_fab2(sch_1):page242_i57:a"
				( attribute "PN" "1"
					( Origin gPackager )
				)
				( objectStatus "C5G48.1" )
			)
			( pin "@baseboard_fab2_lib.baseboard_fab2(sch_1):page242_i57:b"
				( attribute "PN" "2"
					( Origin gPackager )
				)
				( objectStatus "C5G48.2" )
			)
			( pin "@baseboard_fab2_lib.baseboard_fab2(sch_1):page242_i58:a"
				( attribute "PN" "1"
					( Origin gPackager )
				)
				( objectStatus "C5G47.1" )
			)
			( pin "@baseboard_fab2_lib.baseboard_fab2(sch_1):page242_i58:b"
				( attribute "PN" "2"
					( Origin gPackager )
				)
				( objectStatus "C5G47.2" )
			)
			( pin "@baseboard_fab2_lib.baseboard_fab2(sch_1):page242_i59:a"
				( attribute "PN" "1"
					( Origin gPackager )
				)
				( objectStatus "C5G46.1" )
			)
			( pin "@baseboard_fab2_lib.baseboard_fab2(sch_1):page242_i59:b"
				( attribute "PN" "2"
					( Origin gPackager )
				)
				( objectStatus "C5G46.2" )
			)
			( pin "@baseboard_fab2_lib.baseboard_fab2(sch_1):page242_i60:a"
				( attribute "PN" "1"
					( Origin gPackager )
				)
				( objectStatus "C5G45.1" )
			)
			( pin "@baseboard_fab2_lib.baseboard_fab2(sch_1):page242_i60:b"
				( attribute "PN" "2"
					( Origin gPackager )
				)
				( objectStatus "C5G45.2" )
			)
			( pin "@baseboard_fab2_lib.baseboard_fab2(sch_1):page242_i61:a"
				( attribute "PN" "1"
					( Origin gPackager )
				)
				( objectStatus "C5G49.1" )
			)
			( pin "@baseboard_fab2_lib.baseboard_fab2(sch_1):page242_i61:b"
				( attribute "PN" "2"
					( Origin gPackager )
				)
				( objectStatus "C5G49.2" )
			)
			( pin "@baseboard_fab2_lib.baseboard_fab2(sch_1):page242_i62:a"
				( attribute "PN" "1"
					( Origin gPackager )
				)
				( objectStatus "C5G54.1" )
			)
			( pin "@baseboard_fab2_lib.baseboard_fab2(sch_1):page242_i62:b"
				( attribute "PN" "2"
					( Origin gPackager )
				)
				( objectStatus "C5G54.2" )
			)
			( pin "@baseboard_fab2_lib.baseboard_fab2(sch_1):page242_i63:a"
				( attribute "PN" "1"
					( Origin gPackager )
				)
				( objectStatus "C5G58.1" )
			)
			( pin "@baseboard_fab2_lib.baseboard_fab2(sch_1):page242_i63:b"
				( attribute "PN" "2"
					( Origin gPackager )
				)
				( objectStatus "C5G58.2" )
			)
			( pin "@baseboard_fab2_lib.baseboard_fab2(sch_1):page242_i64:a"
				( attribute "PN" "1"
					( Origin gPackager )
				)
				( objectStatus "C5G57.1" )
			)
			( pin "@baseboard_fab2_lib.baseboard_fab2(sch_1):page242_i64:b"
				( attribute "PN" "2"
					( Origin gPackager )
				)
				( objectStatus "C5G57.2" )
			)
			( pin "@baseboard_fab2_lib.baseboard_fab2(sch_1):page242_i65:a"
				( attribute "PN" "1"
					( Origin gPackager )
				)
				( objectStatus "C5G56.1" )
			)
			( pin "@baseboard_fab2_lib.baseboard_fab2(sch_1):page242_i65:b"
				( attribute "PN" "2"
					( Origin gPackager )
				)
				( objectStatus "C5G56.2" )
			)
			( pin "@baseboard_fab2_lib.baseboard_fab2(sch_1):page242_i66:a"
				( attribute "PN" "1"
					( Origin gPackager )
				)
				( objectStatus "C5G55.1" )
			)
			( pin "@baseboard_fab2_lib.baseboard_fab2(sch_1):page242_i66:b"
				( attribute "PN" "2"
					( Origin gPackager )
				)
				( objectStatus "C5G55.2" )
			)
			( pin "@baseboard_fab2_lib.baseboard_fab2(sch_1):page242_i67:a"
				( attribute "PN" "1"
					( Origin gPackager )
				)
				( objectStatus "C5G53.1" )
			)
			( pin "@baseboard_fab2_lib.baseboard_fab2(sch_1):page242_i67:b"
				( attribute "PN" "2"
					( Origin gPackager )
				)
				( objectStatus "C5G53.2" )
			)
			( pin "@baseboard_fab2_lib.baseboard_fab2(sch_1):page242_i68:a"
				( attribute "PN" "1"
					( Origin gPackager )
				)
				( objectStatus "C5G52.1" )
			)
			( pin "@baseboard_fab2_lib.baseboard_fab2(sch_1):page242_i68:b"
				( attribute "PN" "2"
					( Origin gPackager )
				)
				( objectStatus "C5G52.2" )
			)
			( pin "@baseboard_fab2_lib.baseboard_fab2(sch_1):page242_i69:a"
				( attribute "PN" "1"
					( Origin gPackager )
				)
				( objectStatus "C5G51.1" )
			)
			( pin "@baseboard_fab2_lib.baseboard_fab2(sch_1):page242_i69:b"
				( attribute "PN" "2"
					( Origin gPackager )
				)
				( objectStatus "C5G51.2" )
			)
			( pin "@baseboard_fab2_lib.baseboard_fab2(sch_1):page242_i70:a"
				( attribute "PN" "1"
					( Origin gPackager )
				)
				( objectStatus "C5G50.1" )
			)
			( pin "@baseboard_fab2_lib.baseboard_fab2(sch_1):page242_i70:b"
				( attribute "PN" "2"
					( Origin gPackager )
				)
				( objectStatus "C5G50.2" )
			)
			( pin "@baseboard_fab2_lib.baseboard_fab2(sch_1):page242_i71:a"
				( attribute "PN" "1"
					( Origin gPackager )
				)
				( objectStatus "C5G67.1" )
			)
			( pin "@baseboard_fab2_lib.baseboard_fab2(sch_1):page242_i71:b"
				( attribute "PN" "2"
					( Origin gPackager )
				)
				( objectStatus "C5G67.2" )
			)
			( pin "@baseboard_fab2_lib.baseboard_fab2(sch_1):page242_i72:a"
				( attribute "PN" "1"
					( Origin gPackager )
				)
				( objectStatus "C5G66.1" )
			)
			( pin "@baseboard_fab2_lib.baseboard_fab2(sch_1):page242_i72:b"
				( attribute "PN" "2"
					( Origin gPackager )
				)
				( objectStatus "C5G66.2" )
			)
			( pin "@baseboard_fab2_lib.baseboard_fab2(sch_1):page242_i73:a"
				( attribute "PN" "1"
					( Origin gPackager )
				)
				( objectStatus "C5G65.1" )
			)
			( pin "@baseboard_fab2_lib.baseboard_fab2(sch_1):page242_i73:b"
				( attribute "PN" "2"
					( Origin gPackager )
				)
				( objectStatus "C5G65.2" )
			)
			( pin "@baseboard_fab2_lib.baseboard_fab2(sch_1):page242_i74:a"
				( attribute "PN" "1"
					( Origin gPackager )
				)
				( objectStatus "C5G64.1" )
			)
			( pin "@baseboard_fab2_lib.baseboard_fab2(sch_1):page242_i74:b"
				( attribute "PN" "2"
					( Origin gPackager )
				)
				( objectStatus "C5G64.2" )
			)
			( pin "@baseboard_fab2_lib.baseboard_fab2(sch_1):page242_i75:a"
				( attribute "PN" "1"
					( Origin gPackager )
				)
				( objectStatus "C5G63.1" )
			)
			( pin "@baseboard_fab2_lib.baseboard_fab2(sch_1):page242_i75:b"
				( attribute "PN" "2"
					( Origin gPackager )
				)
				( objectStatus "C5G63.2" )
			)
			( pin "@baseboard_fab2_lib.baseboard_fab2(sch_1):page242_i76:a"
				( attribute "PN" "1"
					( Origin gPackager )
				)
				( objectStatus "C5G62.1" )
			)
			( pin "@baseboard_fab2_lib.baseboard_fab2(sch_1):page242_i76:b"
				( attribute "PN" "2"
					( Origin gPackager )
				)
				( objectStatus "C5G62.2" )
			)
			( pin "@baseboard_fab2_lib.baseboard_fab2(sch_1):page242_i77:a"
				( attribute "PN" "1"
					( Origin gPackager )
				)
				( objectStatus "C5G61.1" )
			)
			( pin "@baseboard_fab2_lib.baseboard_fab2(sch_1):page242_i77:b"
				( attribute "PN" "2"
					( Origin gPackager )
				)
				( objectStatus "C5G61.2" )
			)
			( pin "@baseboard_fab2_lib.baseboard_fab2(sch_1):page242_i78:a"
				( attribute "PN" "1"
					( Origin gPackager )
				)
				( objectStatus "C5G60.1" )
			)
			( pin "@baseboard_fab2_lib.baseboard_fab2(sch_1):page242_i78:b"
				( attribute "PN" "2"
					( Origin gPackager )
				)
				( objectStatus "C5G60.2" )
			)
			( pin "@baseboard_fab2_lib.baseboard_fab2(sch_1):page242_i79:a"
				( attribute "PN" "1"
					( Origin gPackager )
				)
				( objectStatus "C5G59.1" )
			)
			( pin "@baseboard_fab2_lib.baseboard_fab2(sch_1):page242_i79:b"
				( attribute "PN" "2"
					( Origin gPackager )
				)
				( objectStatus "C5G59.2" )
			)
			( pin "@baseboard_fab2_lib.baseboard_fab2(sch_1):page242_i80:a"
				( attribute "PN" "1"
					( Origin gPackager )
				)
				( objectStatus "C5G76.1" )
			)
			( pin "@baseboard_fab2_lib.baseboard_fab2(sch_1):page242_i80:b"
				( attribute "PN" "2"
					( Origin gPackager )
				)
				( objectStatus "C5G76.2" )
			)
			( pin "@baseboard_fab2_lib.baseboard_fab2(sch_1):page242_i81:a"
				( attribute "PN" "1"
					( Origin gPackager )
				)
				( objectStatus "C5G75.1" )
			)
			( pin "@baseboard_fab2_lib.baseboard_fab2(sch_1):page242_i81:b"
				( attribute "PN" "2"
					( Origin gPackager )
				)
				( objectStatus "C5G75.2" )
			)
			( pin "@baseboard_fab2_lib.baseboard_fab2(sch_1):page242_i82:a"
				( attribute "PN" "1"
					( Origin gPackager )
				)
				( objectStatus "C5G74.1" )
			)
			( pin "@baseboard_fab2_lib.baseboard_fab2(sch_1):page242_i82:b"
				( attribute "PN" "2"
					( Origin gPackager )
				)
				( objectStatus "C5G74.2" )
			)
			( pin "@baseboard_fab2_lib.baseboard_fab2(sch_1):page242_i83:a"
				( attribute "PN" "1"
					( Origin gPackager )
				)
				( objectStatus "C5G73.1" )
			)
			( pin "@baseboard_fab2_lib.baseboard_fab2(sch_1):page242_i83:b"
				( attribute "PN" "2"
					( Origin gPackager )
				)
				( objectStatus "C5G73.2" )
			)
			( pin "@baseboard_fab2_lib.baseboard_fab2(sch_1):page242_i84:a"
				( attribute "PN" "1"
					( Origin gPackager )
				)
				( objectStatus "C5G72.1" )
			)
			( pin "@baseboard_fab2_lib.baseboard_fab2(sch_1):page242_i84:b"
				( attribute "PN" "2"
					( Origin gPackager )
				)
				( objectStatus "C5G72.2" )
			)
			( pin "@baseboard_fab2_lib.baseboard_fab2(sch_1):page242_i85:a"
				( attribute "PN" "1"
					( Origin gPackager )
				)
				( objectStatus "C5G71.1" )
			)
			( pin "@baseboard_fab2_lib.baseboard_fab2(sch_1):page242_i85:b"
				( attribute "PN" "2"
					( Origin gPackager )
				)
				( objectStatus "C5G71.2" )
			)
			( pin "@baseboard_fab2_lib.baseboard_fab2(sch_1):page242_i86:a"
				( attribute "PN" "1"
					( Origin gPackager )
				)
				( objectStatus "C5G70.1" )
			)
			( pin "@baseboard_fab2_lib.baseboard_fab2(sch_1):page242_i86:b"
				( attribute "PN" "2"
					( Origin gPackager )
				)
				( objectStatus "C5G70.2" )
			)
			( pin "@baseboard_fab2_lib.baseboard_fab2(sch_1):page242_i87:a"
				( attribute "PN" "1"
					( Origin gPackager )
				)
				( objectStatus "C5G69.1" )
			)
			( pin "@baseboard_fab2_lib.baseboard_fab2(sch_1):page242_i87:b"
				( attribute "PN" "2"
					( Origin gPackager )
				)
				( objectStatus "C5G69.2" )
			)
			( pin "@baseboard_fab2_lib.baseboard_fab2(sch_1):page242_i88:a"
				( attribute "PN" "1"
					( Origin gPackager )
				)
				( objectStatus "C5G68.1" )
			)
			( pin "@baseboard_fab2_lib.baseboard_fab2(sch_1):page242_i88:b"
				( attribute "PN" "2"
					( Origin gPackager )
				)
				( objectStatus "C5G68.2" )
			)
			( pin "@baseboard_fab2_lib.baseboard_fab2(sch_1):page207_i100:a"
				( attribute "PN" "1"
					( Origin gPackager )
				)
				( objectStatus "RT17.1" )
			)
			( pin "@baseboard_fab2_lib.baseboard_fab2(sch_1):page207_i100:b"
				( attribute "PN" "2"
					( Origin gPackager )
				)
				( objectStatus "RT17.2" )
			)
			( pin "@baseboard_fab2_lib.baseboard_fab2(sch_1):page202_i70:a"
				( attribute "PN" "1"
					( Origin gPackager )
				)
				( objectStatus "CT1.1" )
			)
			( pin "@baseboard_fab2_lib.baseboard_fab2(sch_1):page202_i70:b"
				( attribute "PN" "2"
					( Origin gPackager )
				)
				( objectStatus "CT1.2" )
			)
			( pin "@baseboard_fab2_lib.baseboard_fab2(sch_1):page204_i114:\1\"
				( attribute "PN" "1"
					( Origin gPackager )
				)
				( objectStatus "RT24.1" )
			)
			( pin "@baseboard_fab2_lib.baseboard_fab2(sch_1):page204_i114:\2\"
				( attribute "PN" "2"
					( Origin gPackager )
				)
				( objectStatus "RT24.2" )
			)
			( pin "@baseboard_fab2_lib.baseboard_fab2(sch_1):page204_i97:a"
				( attribute "PN" "1"
					( Origin gPackager )
				)
				( objectStatus "CT35.1" )
			)
			( pin "@baseboard_fab2_lib.baseboard_fab2(sch_1):page204_i97:b"
				( attribute "PN" "2"
					( Origin gPackager )
				)
				( objectStatus "CT35.2" )
			)
			( pin "@baseboard_fab2_lib.baseboard_fab2(sch_1):page202_i78:a"
				( attribute "PN" "1"
					( Origin gPackager )
				)
				( objectStatus "CT2.1" )
			)
			( pin "@baseboard_fab2_lib.baseboard_fab2(sch_1):page202_i78:b"
				( attribute "PN" "2"
					( Origin gPackager )
				)
				( objectStatus "CT2.2" )
			)
			( pin "@baseboard_fab2_lib.baseboard_fab2(sch_1):page202_i81:a"
				( attribute "PN" "1"
					( Origin gPackager )
				)
				( objectStatus "CT6.1" )
			)
			( pin "@baseboard_fab2_lib.baseboard_fab2(sch_1):page202_i81:b"
				( attribute "PN" "2"
					( Origin gPackager )
				)
				( objectStatus "CT6.2" )
			)
			( pin "@baseboard_fab2_lib.baseboard_fab2(sch_1):page207_i96:a"
				( attribute "PN" "1"
					( Origin gPackager )
				)
				( objectStatus "CT27.1" )
			)
			( pin "@baseboard_fab2_lib.baseboard_fab2(sch_1):page207_i96:b"
				( attribute "PN" "2"
					( Origin gPackager )
				)
				( objectStatus "CT27.2" )
			)
			( pin "@baseboard_fab2_lib.baseboard_fab2(sch_1):page227_i109:a"
				( attribute "PN" "1"
					( Origin gPackager )
				)
				( objectStatus "CT7.1" )
			)
			( pin "@baseboard_fab2_lib.baseboard_fab2(sch_1):page227_i109:b"
				( attribute "PN" "2"
					( Origin gPackager )
				)
				( objectStatus "CT7.2" )
			)
			( pin "@baseboard_fab2_lib.baseboard_fab2(sch_1):page216_i136:a"
				( attribute "PN" "1"
					( Origin gPackager )
				)
				( objectStatus "CT53.1" )
			)
			( pin "@baseboard_fab2_lib.baseboard_fab2(sch_1):page216_i136:b"
				( attribute "PN" "2"
					( Origin gPackager )
				)
				( objectStatus "CT53.2" )
			)
			( pin "@baseboard_fab2_lib.baseboard_fab2(sch_1):page227_i114:a"
				( attribute "PN" "1"
					( Origin gPackager )
				)
				( objectStatus "CT8.1" )
			)
			( pin "@baseboard_fab2_lib.baseboard_fab2(sch_1):page227_i114:b"
				( attribute "PN" "2"
					( Origin gPackager )
				)
				( objectStatus "CT8.2" )
			)
			( pin "@baseboard_fab2_lib.baseboard_fab2(sch_1):page227_i119:a"
				( attribute "PN" "1"
					( Origin gPackager )
				)
				( objectStatus "CT10.1" )
			)
			( pin "@baseboard_fab2_lib.baseboard_fab2(sch_1):page227_i119:b"
				( attribute "PN" "2"
					( Origin gPackager )
				)
				( objectStatus "CT10.2" )
			)
			( pin "@baseboard_fab2_lib.baseboard_fab2(sch_1):page227_i122:a"
				( attribute "PN" "1"
					( Origin gPackager )
				)
				( objectStatus "CT12.1" )
			)
			( pin "@baseboard_fab2_lib.baseboard_fab2(sch_1):page227_i122:b"
				( attribute "PN" "2"
					( Origin gPackager )
				)
				( objectStatus "CT12.2" )
			)
			( pin "@baseboard_fab2_lib.baseboard_fab2(sch_1):page210_i66:a"
				( attribute "PN" "1"
					( Origin gPackager )
				)
				( objectStatus "CT56.1" )
			)
			( pin "@baseboard_fab2_lib.baseboard_fab2(sch_1):page210_i66:b"
				( attribute "PN" "2"
					( Origin gPackager )
				)
				( objectStatus "CT56.2" )
			)
			( pin "@baseboard_fab2_lib.baseboard_fab2(sch_1):page209_i62:a"
				( attribute "PN" "1"
					( Origin gPackager )
				)
				( objectStatus "CT13.1" )
			)
			( pin "@baseboard_fab2_lib.baseboard_fab2(sch_1):page209_i62:b"
				( attribute "PN" "2"
					( Origin gPackager )
				)
				( objectStatus "CT13.2" )
			)
			( pin "@baseboard_fab2_lib.baseboard_fab2(sch_1):page207_i95:a"
				( attribute "PN" "1"
					( Origin gPackager )
				)
				( objectStatus "CT23.1" )
			)
			( pin "@baseboard_fab2_lib.baseboard_fab2(sch_1):page207_i95:b"
				( attribute "PN" "2"
					( Origin gPackager )
				)
				( objectStatus "CT23.2" )
			)
			( pin "@baseboard_fab2_lib.baseboard_fab2(sch_1):page224_i156:\1\"
				( attribute "PN" "1"
					( Origin gPackager )
				)
				( objectStatus "RT20.1" )
			)
			( pin "@baseboard_fab2_lib.baseboard_fab2(sch_1):page224_i156:\2\"
				( attribute "PN" "2"
					( Origin gPackager )
				)
				( objectStatus "RT20.2" )
			)
			( pin "@baseboard_fab2_lib.baseboard_fab2(sch_1):page209_i67:a"
				( attribute "PN" "1"
					( Origin gPackager )
				)
				( objectStatus "CT15.1" )
			)
			( pin "@baseboard_fab2_lib.baseboard_fab2(sch_1):page209_i67:b"
				( attribute "PN" "2"
					( Origin gPackager )
				)
				( objectStatus "CT15.2" )
			)
			( pin "@baseboard_fab2_lib.baseboard_fab2(sch_1):page208_i80:a"
				( attribute "PN" "1"
					( Origin gPackager )
				)
				( objectStatus "CT16.1" )
			)
			( pin "@baseboard_fab2_lib.baseboard_fab2(sch_1):page208_i80:b"
				( attribute "PN" "2"
					( Origin gPackager )
				)
				( objectStatus "CT16.2" )
			)
			( pin "@baseboard_fab2_lib.baseboard_fab2(sch_1):page208_i82:a"
				( attribute "PN" "1"
					( Origin gPackager )
				)
				( objectStatus "CTI7.1" )
			)
			( pin "@baseboard_fab2_lib.baseboard_fab2(sch_1):page208_i82:b"
				( attribute "PN" "2"
					( Origin gPackager )
				)
				( objectStatus "CTI7.2" )
			)
			( pin "@baseboard_fab2_lib.baseboard_fab2(sch_1):page208_i87:a"
				( attribute "PN" "1"
					( Origin gPackager )
				)
				( objectStatus "CT21.1" )
			)
			( pin "@baseboard_fab2_lib.baseboard_fab2(sch_1):page208_i87:b"
				( attribute "PN" "2"
					( Origin gPackager )
				)
				( objectStatus "CT21.2" )
			)
			( pin "@baseboard_fab2_lib.baseboard_fab2(sch_1):page208_i90:a"
				( attribute "PN" "1"
					( Origin gPackager )
				)
				( objectStatus "CT19.1" )
			)
			( pin "@baseboard_fab2_lib.baseboard_fab2(sch_1):page208_i90:b"
				( attribute "PN" "2"
					( Origin gPackager )
				)
				( objectStatus "CT19.2" )
			)
			( pin "@baseboard_fab2_lib.baseboard_fab2(sch_1):page212_i144:\1\"
				( attribute "PN" "1"
					( Origin gPackager )
				)
				( objectStatus "RT48.1" )
			)
			( pin "@baseboard_fab2_lib.baseboard_fab2(sch_1):page212_i144:\2\"
				( attribute "PN" "2"
					( Origin gPackager )
				)
				( objectStatus "RT48.2" )
			)
			( pin "@baseboard_fab2_lib.baseboard_fab2(sch_1):page207_i71:a"
				( attribute "PN" "1"
					( Origin gPackager )
				)
				( objectStatus "CT24.1" )
			)
			( pin "@baseboard_fab2_lib.baseboard_fab2(sch_1):page207_i71:b"
				( attribute "PN" "2"
					( Origin gPackager )
				)
				( objectStatus "CT24.2" )
			)
			( pin "@baseboard_fab2_lib.baseboard_fab2(sch_1):page207_i74:a"
				( attribute "PN" "1"
					( Origin gPackager )
				)
				( objectStatus "CT22.1" )
			)
			( pin "@baseboard_fab2_lib.baseboard_fab2(sch_1):page207_i74:b"
				( attribute "PN" "2"
					( Origin gPackager )
				)
				( objectStatus "CT22.2" )
			)
			( pin "@baseboard_fab2_lib.baseboard_fab2(sch_1):page216_i151:\1\"
				( attribute "PN" "1"
					( Origin gPackager )
				)
				( objectStatus "RT34.1" )
			)
			( pin "@baseboard_fab2_lib.baseboard_fab2(sch_1):page216_i151:\2\"
				( attribute "PN" "2"
					( Origin gPackager )
				)
				( objectStatus "RT34.2" )
			)
			( pin "@baseboard_fab2_lib.baseboard_fab2(sch_1):page214_i143:a"
				( attribute "PN" "1"
					( Origin gPackager )
				)
				( objectStatus "CT62.1" )
			)
			( pin "@baseboard_fab2_lib.baseboard_fab2(sch_1):page214_i143:b"
				( attribute "PN" "2"
					( Origin gPackager )
				)
				( objectStatus "CT62.2" )
			)
			( pin "@baseboard_fab2_lib.baseboard_fab2(sch_1):page224_i117:a"
				( attribute "PN" "1"
					( Origin gPackager )
				)
				( objectStatus "CT30.1" )
			)
			( pin "@baseboard_fab2_lib.baseboard_fab2(sch_1):page224_i117:b"
				( attribute "PN" "2"
					( Origin gPackager )
				)
				( objectStatus "CT30.2" )
			)
			( pin "@baseboard_fab2_lib.baseboard_fab2(sch_1):page236_i149:a"
				( attribute "PN" "1"
					( Origin gPackager )
				)
				( objectStatus "CT65.1" )
			)
			( pin "@baseboard_fab2_lib.baseboard_fab2(sch_1):page236_i149:b"
				( attribute "PN" "2"
					( Origin gPackager )
				)
				( objectStatus "CT65.2" )
			)
			( pin "@baseboard_fab2_lib.baseboard_fab2(sch_1):page224_i122:a"
				( attribute "PN" "1"
					( Origin gPackager )
				)
				( objectStatus "CT28.1" )
			)
			( pin "@baseboard_fab2_lib.baseboard_fab2(sch_1):page224_i122:b"
				( attribute "PN" "2"
					( Origin gPackager )
				)
				( objectStatus "CT28.2" )
			)
			( pin "@baseboard_fab2_lib.baseboard_fab2(sch_1):page224_i124:a"
				( attribute "PN" "1"
					( Origin gPackager )
				)
				( objectStatus "CT31.1" )
			)
			( pin "@baseboard_fab2_lib.baseboard_fab2(sch_1):page224_i124:b"
				( attribute "PN" "2"
					( Origin gPackager )
				)
				( objectStatus "CT31.2" )
			)
			( pin "@baseboard_fab2_lib.baseboard_fab2(sch_1):page236_i150:a"
				( attribute "PN" "1"
					( Origin gPackager )
				)
				( objectStatus "CT68.1" )
			)
			( pin "@baseboard_fab2_lib.baseboard_fab2(sch_1):page236_i150:b"
				( attribute "PN" "2"
					( Origin gPackager )
				)
				( objectStatus "CT68.2" )
			)
			( pin "@baseboard_fab2_lib.baseboard_fab2(sch_1):page224_i130:a"
				( attribute "PN" "1"
					( Origin gPackager )
				)
				( objectStatus "CT32.1" )
			)
			( pin "@baseboard_fab2_lib.baseboard_fab2(sch_1):page224_i130:b"
				( attribute "PN" "2"
					( Origin gPackager )
				)
				( objectStatus "CT32.2" )
			)
			( pin "@baseboard_fab2_lib.baseboard_fab2(sch_1):page204_i85:a"
				( attribute "PN" "1"
					( Origin gPackager )
				)
				( objectStatus "CT36.1" )
			)
			( pin "@baseboard_fab2_lib.baseboard_fab2(sch_1):page204_i85:b"
				( attribute "PN" "2"
					( Origin gPackager )
				)
				( objectStatus "CT36.2" )
			)
			( pin "@baseboard_fab2_lib.baseboard_fab2(sch_1):page208_i108:a"
				( attribute "PN" "1"
					( Origin gPackager )
				)
				( objectStatus "RT11.1" )
			)
			( pin "@baseboard_fab2_lib.baseboard_fab2(sch_1):page208_i108:b"
				( attribute "PN" "2"
					( Origin gPackager )
				)
				( objectStatus "RT11.2" )
			)
			( pin "@baseboard_fab2_lib.baseboard_fab2(sch_1):page204_i88:a"
				( attribute "PN" "1"
					( Origin gPackager )
				)
				( objectStatus "CT34.1" )
			)
			( pin "@baseboard_fab2_lib.baseboard_fab2(sch_1):page204_i88:b"
				( attribute "PN" "2"
					( Origin gPackager )
				)
				( objectStatus "CT34.2" )
			)
			( pin "@baseboard_fab2_lib.baseboard_fab2(sch_1):page242_i89:a"
				( attribute "PN" "1"
					( Origin gPackager )
				)
				( objectStatus "C5G77.1" )
			)
			( pin "@baseboard_fab2_lib.baseboard_fab2(sch_1):page242_i89:b"
				( attribute "PN" "2"
					( Origin gPackager )
				)
				( objectStatus "C5G77.2" )
			)
			( pin "@baseboard_fab2_lib.baseboard_fab2(sch_1):page210_i74:\1\"
				( attribute "PN" "1"
					( Origin gPackager )
				)
				( objectStatus "RT38.1" )
			)
			( pin "@baseboard_fab2_lib.baseboard_fab2(sch_1):page210_i74:\2\"
				( attribute "PN" "2"
					( Origin gPackager )
				)
				( objectStatus "RT38.2" )
			)
			( pin "@baseboard_fab2_lib.baseboard_fab2(sch_1):page203_i93:a"
				( attribute "PN" "1"
					( Origin gPackager )
				)
				( objectStatus "CT40.1" )
			)
			( pin "@baseboard_fab2_lib.baseboard_fab2(sch_1):page203_i93:b"
				( attribute "PN" "2"
					( Origin gPackager )
				)
				( objectStatus "CT40.2" )
			)
			( pin "@baseboard_fab2_lib.baseboard_fab2(sch_1):page227_i139:a"
				( attribute "PN" "1"
					( Origin gPackager )
				)
				( objectStatus "RT8.1" )
			)
			( pin "@baseboard_fab2_lib.baseboard_fab2(sch_1):page227_i139:b"
				( attribute "PN" "2"
					( Origin gPackager )
				)
				( objectStatus "RT8.2" )
			)
			( pin "@baseboard_fab2_lib.baseboard_fab2(sch_1):page203_i96:a"
				( attribute "PN" "1"
					( Origin gPackager )
				)
				( objectStatus "CT39.1" )
			)
			( pin "@baseboard_fab2_lib.baseboard_fab2(sch_1):page203_i96:b"
				( attribute "PN" "2"
					( Origin gPackager )
				)
				( objectStatus "CT39.2" )
			)
			( pin "@baseboard_fab2_lib.baseboard_fab2(sch_1):page227_i138:a"
				( attribute "PN" "1"
					( Origin gPackager )
				)
				( objectStatus "RT5.1" )
			)
			( pin "@baseboard_fab2_lib.baseboard_fab2(sch_1):page227_i138:b"
				( attribute "PN" "2"
					( Origin gPackager )
				)
				( objectStatus "RT5.2" )
			)
			( pin "@baseboard_fab2_lib.baseboard_fab2(sch_1):page203_i99:a"
				( attribute "PN" "1"
					( Origin gPackager )
				)
				( objectStatus "CT37.1" )
			)
			( pin "@baseboard_fab2_lib.baseboard_fab2(sch_1):page203_i99:b"
				( attribute "PN" "2"
					( Origin gPackager )
				)
				( objectStatus "CT37.2" )
			)
			( pin "@baseboard_fab2_lib.baseboard_fab2(sch_1):page242_i90:a"
				( attribute "PN" "1"
					( Origin gPackager )
				)
				( objectStatus "C5G22.1" )
			)
			( pin "@baseboard_fab2_lib.baseboard_fab2(sch_1):page242_i90:b"
				( attribute "PN" "2"
					( Origin gPackager )
				)
				( objectStatus "C5G22.2" )
			)
			( pin "@baseboard_fab2_lib.baseboard_fab2(sch_1):page224_i157:\1\"
				( attribute "PN" "1"
					( Origin gPackager )
				)
				( objectStatus "RT22.1" )
			)
			( pin "@baseboard_fab2_lib.baseboard_fab2(sch_1):page224_i157:\2\"
				( attribute "PN" "2"
					( Origin gPackager )
				)
				( objectStatus "RT22.2" )
			)
			( pin "@baseboard_fab2_lib.baseboard_fab2(sch_1):page209_i90:\1\"
				( attribute "PN" "1"
					( Origin gPackager )
				)
				( objectStatus "RT10.1" )
			)
			( pin "@baseboard_fab2_lib.baseboard_fab2(sch_1):page209_i90:\2\"
				( attribute "PN" "2"
					( Origin gPackager )
				)
				( objectStatus "RT10.2" )
			)
			( pin "@baseboard_fab2_lib.baseboard_fab2(sch_1):page205_i76:a"
				( attribute "PN" "1"
					( Origin gPackager )
				)
				( objectStatus "CT59.1" )
			)
			( pin "@baseboard_fab2_lib.baseboard_fab2(sch_1):page205_i76:b"
				( attribute "PN" "2"
					( Origin gPackager )
				)
				( objectStatus "CT59.2" )
			)
			( pin "@baseboard_fab2_lib.baseboard_fab2(sch_1):page203_i108:a"
				( attribute "PN" "1"
					( Origin gPackager )
				)
				( objectStatus "CT42.1" )
			)
			( pin "@baseboard_fab2_lib.baseboard_fab2(sch_1):page203_i108:b"
				( attribute "PN" "2"
					( Origin gPackager )
				)
				( objectStatus "CT42.2" )
			)
			( pin "@baseboard_fab2_lib.baseboard_fab2(sch_1):page219_i113:a"
				( attribute "PN" "1"
					( Origin gPackager )
				)
				( objectStatus "CT46.1" )
			)
			( pin "@baseboard_fab2_lib.baseboard_fab2(sch_1):page219_i113:b"
				( attribute "PN" "2"
					( Origin gPackager )
				)
				( objectStatus "CT46.2" )
			)
			( pin "@baseboard_fab2_lib.baseboard_fab2(sch_1):page224_i145:a"
				( attribute "PN" "1"
					( Origin gPackager )
				)
				( objectStatus "RT21.1" )
			)
			( pin "@baseboard_fab2_lib.baseboard_fab2(sch_1):page224_i145:b"
				( attribute "PN" "2"
					( Origin gPackager )
				)
				( objectStatus "RT21.2" )
			)
			( pin "@baseboard_fab2_lib.baseboard_fab2(sch_1):page219_i116:a"
				( attribute "PN" "1"
					( Origin gPackager )
				)
				( objectStatus "CT45.1" )
			)
			( pin "@baseboard_fab2_lib.baseboard_fab2(sch_1):page219_i116:b"
				( attribute "PN" "2"
					( Origin gPackager )
				)
				( objectStatus "CT45.2" )
			)
			( pin "@baseboard_fab2_lib.baseboard_fab2(sch_1):page224_i144:a"
				( attribute "PN" "1"
					( Origin gPackager )
				)
				( objectStatus "RT19.1" )
			)
			( pin "@baseboard_fab2_lib.baseboard_fab2(sch_1):page224_i144:b"
				( attribute "PN" "2"
					( Origin gPackager )
				)
				( objectStatus "RT19.2" )
			)
			( pin "@baseboard_fab2_lib.baseboard_fab2(sch_1):page219_i119:a"
				( attribute "PN" "1"
					( Origin gPackager )
				)
				( objectStatus "CT48.1" )
			)
			( pin "@baseboard_fab2_lib.baseboard_fab2(sch_1):page219_i119:b"
				( attribute "PN" "2"
					( Origin gPackager )
				)
				( objectStatus "CT48.2" )
			)
			( pin "@baseboard_fab2_lib.baseboard_fab2(sch_1):page227_i134:a"
				( attribute "PN" "1"
					( Origin gPackager )
				)
				( objectStatus "CT9.1" )
			)
			( pin "@baseboard_fab2_lib.baseboard_fab2(sch_1):page227_i134:b"
				( attribute "PN" "2"
					( Origin gPackager )
				)
				( objectStatus "CT9.2" )
			)
			( pin "@baseboard_fab2_lib.baseboard_fab2(sch_1):page219_i124:a"
				( attribute "PN" "1"
					( Origin gPackager )
				)
				( objectStatus "CT43.1" )
			)
			( pin "@baseboard_fab2_lib.baseboard_fab2(sch_1):page219_i124:b"
				( attribute "PN" "2"
					( Origin gPackager )
				)
				( objectStatus "CT43.2" )
			)
			( pin "@baseboard_fab2_lib.baseboard_fab2(sch_1):page227_i135:a"
				( attribute "PN" "1"
					( Origin gPackager )
				)
				( objectStatus "CT11.1" )
			)
			( pin "@baseboard_fab2_lib.baseboard_fab2(sch_1):page227_i135:b"
				( attribute "PN" "2"
					( Origin gPackager )
				)
				( objectStatus "CT11.2" )
			)
			( pin "@baseboard_fab2_lib.baseboard_fab2(sch_1):page216_i108:a"
				( attribute "PN" "1"
					( Origin gPackager )
				)
				( objectStatus "CT51.1" )
			)
			( pin "@baseboard_fab2_lib.baseboard_fab2(sch_1):page216_i108:b"
				( attribute "PN" "2"
					( Origin gPackager )
				)
				( objectStatus "CT51.2" )
			)
			( pin "@baseboard_fab2_lib.baseboard_fab2(sch_1):page216_i128:a"
				( attribute "PN" "1"
					( Origin gPackager )
				)
				( objectStatus "C7G38.1" )
			)
			( pin "@baseboard_fab2_lib.baseboard_fab2(sch_1):page216_i128:b"
				( attribute "PN" "2"
					( Origin gPackager )
				)
				( objectStatus "C7G38.2" )
			)
			( pin "@baseboard_fab2_lib.baseboard_fab2(sch_1):page216_i111:a"
				( attribute "PN" "1"
					( Origin gPackager )
				)
				( objectStatus "CT52.1" )
			)
			( pin "@baseboard_fab2_lib.baseboard_fab2(sch_1):page216_i111:b"
				( attribute "PN" "2"
					( Origin gPackager )
				)
				( objectStatus "CT52.2" )
			)
			( pin "@baseboard_fab2_lib.baseboard_fab2(sch_1):page214_i145:a"
				( attribute "PN" "1"
					( Origin gPackager )
				)
				( objectStatus "RT41.1" )
			)
			( pin "@baseboard_fab2_lib.baseboard_fab2(sch_1):page214_i145:b"
				( attribute "PN" "2"
					( Origin gPackager )
				)
				( objectStatus "RT41.2" )
			)
			( pin "@baseboard_fab2_lib.baseboard_fab2(sch_1):page219_i154:\1\"
				( attribute "PN" "1"
					( Origin gPackager )
				)
				( objectStatus "RT32.1" )
			)
			( pin "@baseboard_fab2_lib.baseboard_fab2(sch_1):page219_i154:\2\"
				( attribute "PN" "2"
					( Origin gPackager )
				)
				( objectStatus "RT32.2" )
			)
			( pin "@baseboard_fab2_lib.baseboard_fab2(sch_1):page216_i118:a"
				( attribute "PN" "1"
					( Origin gPackager )
				)
				( objectStatus "CT49.1" )
			)
			( pin "@baseboard_fab2_lib.baseboard_fab2(sch_1):page216_i118:b"
				( attribute "PN" "2"
					( Origin gPackager )
				)
				( objectStatus "CT49.2" )
			)
			( pin "@baseboard_fab2_lib.baseboard_fab2(sch_1):page224_i140:a"
				( attribute "PN" "1"
					( Origin gPackager )
				)
				( objectStatus "CT29.1" )
			)
			( pin "@baseboard_fab2_lib.baseboard_fab2(sch_1):page224_i140:b"
				( attribute "PN" "2"
					( Origin gPackager )
				)
				( objectStatus "CT29.2" )
			)
			( pin "@baseboard_fab2_lib.baseboard_fab2(sch_1):page216_i121:a"
				( attribute "PN" "1"
					( Origin gPackager )
				)
				( objectStatus "CT54.1" )
			)
			( pin "@baseboard_fab2_lib.baseboard_fab2(sch_1):page216_i121:b"
				( attribute "PN" "2"
					( Origin gPackager )
				)
				( objectStatus "CT54.2" )
			)
			( pin "@baseboard_fab2_lib.baseboard_fab2(sch_1):page224_i141:a"
				( attribute "PN" "1"
					( Origin gPackager )
				)
				( objectStatus "CT33.1" )
			)
			( pin "@baseboard_fab2_lib.baseboard_fab2(sch_1):page224_i141:b"
				( attribute "PN" "2"
					( Origin gPackager )
				)
				( objectStatus "CT33.2" )
			)
			( pin "@baseboard_fab2_lib.baseboard_fab2(sch_1):page212_i120:a"
				( attribute "PN" "1"
					( Origin gPackager )
				)
				( objectStatus "RT47.1" )
			)
			( pin "@baseboard_fab2_lib.baseboard_fab2(sch_1):page212_i120:b"
				( attribute "PN" "2"
					( Origin gPackager )
				)
				( objectStatus "RT47.2" )
			)
			( pin "@baseboard_fab2_lib.baseboard_fab2(sch_1):page208_i104:a"
				( attribute "PN" "1"
					( Origin gPackager )
				)
				( objectStatus "CT18.1" )
			)
			( pin "@baseboard_fab2_lib.baseboard_fab2(sch_1):page208_i104:b"
				( attribute "PN" "2"
					( Origin gPackager )
				)
				( objectStatus "CT18.2" )
			)
			( pin "@baseboard_fab2_lib.baseboard_fab2(sch_1):page236_i183:\1\"
				( attribute "PN" "1"
					( Origin gPackager )
				)
				( objectStatus "RT45.1" )
			)
			( pin "@baseboard_fab2_lib.baseboard_fab2(sch_1):page236_i183:\2\"
				( attribute "PN" "2"
					( Origin gPackager )
				)
				( objectStatus "RT45.2" )
			)
			( pin "@baseboard_fab2_lib.baseboard_fab2(sch_1):page210_i60:a"
				( attribute "PN" "1"
					( Origin gPackager )
				)
				( objectStatus "CT55.1" )
			)
			( pin "@baseboard_fab2_lib.baseboard_fab2(sch_1):page210_i60:b"
				( attribute "PN" "2"
					( Origin gPackager )
				)
				( objectStatus "CT55.2" )
			)
			( pin "@baseboard_fab2_lib.baseboard_fab2(sch_1):page212_i118:a"
				( attribute "PN" "1"
					( Origin gPackager )
				)
				( objectStatus "CT72.1" )
			)
			( pin "@baseboard_fab2_lib.baseboard_fab2(sch_1):page212_i118:b"
				( attribute "PN" "2"
					( Origin gPackager )
				)
				( objectStatus "CT72.2" )
			)
			( pin "@baseboard_fab2_lib.baseboard_fab2(sch_1):page205_i65:a"
				( attribute "PN" "1"
					( Origin gPackager )
				)
				( objectStatus "CT58.1" )
			)
			( pin "@baseboard_fab2_lib.baseboard_fab2(sch_1):page205_i65:b"
				( attribute "PN" "2"
					( Origin gPackager )
				)
				( objectStatus "CT58.2" )
			)
			( pin "@baseboard_fab2_lib.baseboard_fab2(sch_1):page214_i176:\1\"
				( attribute "PN" "1"
					( Origin gPackager )
				)
				( objectStatus "RT42.1" )
			)
			( pin "@baseboard_fab2_lib.baseboard_fab2(sch_1):page214_i176:\2\"
				( attribute "PN" "2"
					( Origin gPackager )
				)
				( objectStatus "RT42.2" )
			)
			( pin "@baseboard_fab2_lib.baseboard_fab2(sch_1):page205_i69:a"
				( attribute "PN" "1"
					( Origin gPackager )
				)
				( objectStatus "CT60.1" )
			)
			( pin "@baseboard_fab2_lib.baseboard_fab2(sch_1):page205_i69:b"
				( attribute "PN" "2"
					( Origin gPackager )
				)
				( objectStatus "CT60.2" )
			)
			( pin "@baseboard_fab2_lib.baseboard_fab2(sch_1):page219_i142:a"
				( attribute "PN" "1"
					( Origin gPackager )
				)
				( objectStatus "RT31.1" )
			)
			( pin "@baseboard_fab2_lib.baseboard_fab2(sch_1):page219_i142:b"
				( attribute "PN" "2"
					( Origin gPackager )
				)
				( objectStatus "RT31.2" )
			)
			( pin "@baseboard_fab2_lib.baseboard_fab2(sch_1):page219_i141:a"
				( attribute "PN" "1"
					( Origin gPackager )
				)
				( objectStatus "RT30.1" )
			)
			( pin "@baseboard_fab2_lib.baseboard_fab2(sch_1):page219_i141:b"
				( attribute "PN" "2"
					( Origin gPackager )
				)
				( objectStatus "RT30.2" )
			)
			( pin "@baseboard_fab2_lib.baseboard_fab2(sch_1):page214_i134:a"
				( attribute "PN" "1"
					( Origin gPackager )
				)
				( objectStatus "CT61.1" )
			)
			( pin "@baseboard_fab2_lib.baseboard_fab2(sch_1):page214_i134:b"
				( attribute "PN" "2"
					( Origin gPackager )
				)
				( objectStatus "CT61.2" )
			)
			( pin "@baseboard_fab2_lib.baseboard_fab2(sch_1):page214_i137:a"
				( attribute "PN" "1"
					( Origin gPackager )
				)
				( objectStatus "CT63.1" )
			)
			( pin "@baseboard_fab2_lib.baseboard_fab2(sch_1):page214_i137:b"
				( attribute "PN" "2"
					( Origin gPackager )
				)
				( objectStatus "CT63.2" )
			)
			( pin "@baseboard_fab2_lib.baseboard_fab2(sch_1):page242_i91:a"
				( attribute "PN" "1"
					( Origin gPackager )
				)
				( objectStatus "C5G78.1" )
			)
			( pin "@baseboard_fab2_lib.baseboard_fab2(sch_1):page242_i91:b"
				( attribute "PN" "2"
					( Origin gPackager )
				)
				( objectStatus "C5G78.2" )
			)
			( pin "@baseboard_fab2_lib.baseboard_fab2(sch_1):page236_i124:a"
				( attribute "PN" "1"
					( Origin gPackager )
				)
				( objectStatus "CT67.1" )
			)
			( pin "@baseboard_fab2_lib.baseboard_fab2(sch_1):page236_i124:b"
				( attribute "PN" "2"
					( Origin gPackager )
				)
				( objectStatus "CT67.2" )
			)
			( pin "@baseboard_fab2_lib.baseboard_fab2(sch_1):page236_i127:a"
				( attribute "PN" "1"
					( Origin gPackager )
				)
				( objectStatus "CT66.1" )
			)
			( pin "@baseboard_fab2_lib.baseboard_fab2(sch_1):page236_i127:b"
				( attribute "PN" "2"
					( Origin gPackager )
				)
				( objectStatus "CT66.2" )
			)
			( pin "@baseboard_fab2_lib.baseboard_fab2(sch_1):page216_i139:a"
				( attribute "PN" "1"
					( Origin gPackager )
				)
				( objectStatus "RT33.1" )
			)
			( pin "@baseboard_fab2_lib.baseboard_fab2(sch_1):page216_i139:b"
				( attribute "PN" "2"
					( Origin gPackager )
				)
				( objectStatus "RT33.2" )
			)
			( pin "@baseboard_fab2_lib.baseboard_fab2(sch_1):page227_i150:\1\"
				( attribute "PN" "1"
					( Origin gPackager )
				)
				( objectStatus "RT7.1" )
			)
			( pin "@baseboard_fab2_lib.baseboard_fab2(sch_1):page227_i150:\2\"
				( attribute "PN" "2"
					( Origin gPackager )
				)
				( objectStatus "RT7.2" )
			)
			( pin "@baseboard_fab2_lib.baseboard_fab2(sch_1):page236_i134:a"
				( attribute "PN" "1"
					( Origin gPackager )
				)
				( objectStatus "CT69.1" )
			)
			( pin "@baseboard_fab2_lib.baseboard_fab2(sch_1):page236_i134:b"
				( attribute "PN" "2"
					( Origin gPackager )
				)
				( objectStatus "CT69.2" )
			)
			( pin "@baseboard_fab2_lib.baseboard_fab2(sch_1):page236_i136:a"
				( attribute "PN" "1"
					( Origin gPackager )
				)
				( objectStatus "CT64.1" )
			)
			( pin "@baseboard_fab2_lib.baseboard_fab2(sch_1):page236_i136:b"
				( attribute "PN" "2"
					( Origin gPackager )
				)
				( objectStatus "CT64.2" )
			)
			( pin "@baseboard_fab2_lib.baseboard_fab2(sch_1):page242_i92:a"
				( attribute "PN" "1"
					( Origin gPackager )
				)
				( objectStatus "C5G21.1" )
			)
			( pin "@baseboard_fab2_lib.baseboard_fab2(sch_1):page242_i92:b"
				( attribute "PN" "2"
					( Origin gPackager )
				)
				( objectStatus "C5G21.2" )
			)
			( pin "@baseboard_fab2_lib.baseboard_fab2(sch_1):page212_i106:a"
				( attribute "PN" "1"
					( Origin gPackager )
				)
				( objectStatus "CT70.1" )
			)
			( pin "@baseboard_fab2_lib.baseboard_fab2(sch_1):page212_i106:b"
				( attribute "PN" "2"
					( Origin gPackager )
				)
				( objectStatus "CT70.2" )
			)
			( pin "@baseboard_fab2_lib.baseboard_fab2(sch_1):page158_i148:a"
				( attribute "PN" "1"
					( Origin gPackager )
				)
				( objectStatus "R9F65.1" )
			)
			( pin "@baseboard_fab2_lib.baseboard_fab2(sch_1):page158_i148:b"
				( attribute "PN" "2"
					( Origin gPackager )
				)
				( objectStatus "R9F65.2" )
			)
			( pin "@baseboard_fab2_lib.baseboard_fab2(sch_1):page212_i109:a"
				( attribute "PN" "1"
					( Origin gPackager )
				)
				( objectStatus "CT71.1" )
			)
			( pin "@baseboard_fab2_lib.baseboard_fab2(sch_1):page212_i109:b"
				( attribute "PN" "2"
					( Origin gPackager )
				)
				( objectStatus "CT71.2" )
			)
			( pin "@baseboard_fab2_lib.baseboard_fab2(sch_1):page216_i135:a"
				( attribute "PN" "1"
					( Origin gPackager )
				)
				( objectStatus "CT50.1" )
			)
			( pin "@baseboard_fab2_lib.baseboard_fab2(sch_1):page216_i135:b"
				( attribute "PN" "2"
					( Origin gPackager )
				)
				( objectStatus "CT50.2" )
			)
			( pin "@baseboard_fab2_lib.baseboard_fab2(sch_1):page225_i246:\1\"
				( attribute "PN" "1"
					( Origin gPackager )
				)
				( objectStatus "C22W1.1" )
			)
			( pin "@baseboard_fab2_lib.baseboard_fab2(sch_1):page225_i246:\2\"
				( attribute "PN" "2"
					( Origin gPackager )
				)
				( objectStatus "C22W1.2" )
			)
			( pin "@baseboard_fab2_lib.baseboard_fab2(sch_1):page207_i81:a"
				( attribute "PN" "1"
					( Origin gPackager )
				)
				( objectStatus "CT25.1" )
			)
			( pin "@baseboard_fab2_lib.baseboard_fab2(sch_1):page207_i81:b"
				( attribute "PN" "2"
					( Origin gPackager )
				)
				( objectStatus "CT25.2" )
			)
			( pin "@baseboard_fab2_lib.baseboard_fab2(sch_1):page207_i82:a"
				( attribute "PN" "1"
					( Origin gPackager )
				)
				( objectStatus "CT26.1" )
			)
			( pin "@baseboard_fab2_lib.baseboard_fab2(sch_1):page207_i82:b"
				( attribute "PN" "2"
					( Origin gPackager )
				)
				( objectStatus "CT26.2" )
			)
			( pin "@baseboard_fab2_lib.baseboard_fab2(sch_1):page219_i137:a"
				( attribute "PN" "1"
					( Origin gPackager )
				)
				( objectStatus "CT44.1" )
			)
			( pin "@baseboard_fab2_lib.baseboard_fab2(sch_1):page219_i137:b"
				( attribute "PN" "2"
					( Origin gPackager )
				)
				( objectStatus "CT44.2" )
			)
			( pin "@baseboard_fab2_lib.baseboard_fab2(sch_1):page236_i182:\1\"
				( attribute "PN" "1"
					( Origin gPackager )
				)
				( objectStatus "RT43.1" )
			)
			( pin "@baseboard_fab2_lib.baseboard_fab2(sch_1):page236_i182:\2\"
				( attribute "PN" "2"
					( Origin gPackager )
				)
				( objectStatus "RT43.2" )
			)
			( pin "@baseboard_fab2_lib.baseboard_fab2(sch_1):page202_i87:a"
				( attribute "PN" "1"
					( Origin gPackager )
				)
				( objectStatus "CT4.1" )
			)
			( pin "@baseboard_fab2_lib.baseboard_fab2(sch_1):page202_i87:b"
				( attribute "PN" "2"
					( Origin gPackager )
				)
				( objectStatus "CT4.2" )
			)
			( pin "@baseboard_fab2_lib.baseboard_fab2(sch_1):page244_i2:a"
				( attribute "PN" "1"
					( Origin gPackager )
				)
				( objectStatus "C831.1" )
			)
			( pin "@baseboard_fab2_lib.baseboard_fab2(sch_1):page244_i2:b"
				( attribute "PN" "2"
					( Origin gPackager )
				)
				( objectStatus "C831.2" )
			)
			( pin "@baseboard_fab2_lib.baseboard_fab2(sch_1):page244_i5:a"
				( attribute "PN" "1"
					( Origin gPackager )
				)
				( objectStatus "C829.1" )
			)
			( pin "@baseboard_fab2_lib.baseboard_fab2(sch_1):page244_i5:b"
				( attribute "PN" "2"
					( Origin gPackager )
				)
				( objectStatus "C829.2" )
			)
			( pin "@baseboard_fab2_lib.baseboard_fab2(sch_1):page244_i8:a"
				( attribute "PN" "1"
					( Origin gPackager )
				)
				( objectStatus "C833.1" )
			)
			( pin "@baseboard_fab2_lib.baseboard_fab2(sch_1):page244_i8:b"
				( attribute "PN" "2"
					( Origin gPackager )
				)
				( objectStatus "C833.2" )
			)
			( pin "@baseboard_fab2_lib.baseboard_fab2(sch_1):page244_i12:a"
				( attribute "PN" "1"
					( Origin gPackager )
				)
				( objectStatus "C827.1" )
			)
			( pin "@baseboard_fab2_lib.baseboard_fab2(sch_1):page244_i12:b"
				( attribute "PN" "2"
					( Origin gPackager )
				)
				( objectStatus "C827.2" )
			)
			( pin "@baseboard_fab2_lib.baseboard_fab2(sch_1):page244_i17:a"
				( attribute "PN" "1"
					( Origin gPackager )
				)
				( objectStatus "C841.1" )
			)
			( pin "@baseboard_fab2_lib.baseboard_fab2(sch_1):page244_i17:b"
				( attribute "PN" "2"
					( Origin gPackager )
				)
				( objectStatus "C841.2" )
			)
			( pin "@baseboard_fab2_lib.baseboard_fab2(sch_1):page244_i23:a"
				( attribute "PN" "1"
					( Origin gPackager )
				)
				( objectStatus "C830.1" )
			)
			( pin "@baseboard_fab2_lib.baseboard_fab2(sch_1):page244_i23:b"
				( attribute "PN" "2"
					( Origin gPackager )
				)
				( objectStatus "C830.2" )
			)
			( pin "@baseboard_fab2_lib.baseboard_fab2(sch_1):page244_i24:a"
				( attribute "PN" "1"
					( Origin gPackager )
				)
				( objectStatus "C826.1" )
			)
			( pin "@baseboard_fab2_lib.baseboard_fab2(sch_1):page244_i24:b"
				( attribute "PN" "2"
					( Origin gPackager )
				)
				( objectStatus "C826.2" )
			)
			( pin "@baseboard_fab2_lib.baseboard_fab2(sch_1):page244_i28:a"
				( attribute "PN" "1"
					( Origin gPackager )
				)
				( objectStatus "C828.1" )
			)
			( pin "@baseboard_fab2_lib.baseboard_fab2(sch_1):page244_i28:b"
				( attribute "PN" "2"
					( Origin gPackager )
				)
				( objectStatus "C828.2" )
			)
			( pin "@baseboard_fab2_lib.baseboard_fab2(sch_1):page244_i29:a"
				( attribute "PN" "1"
					( Origin gPackager )
				)
				( objectStatus "C840.1" )
			)
			( pin "@baseboard_fab2_lib.baseboard_fab2(sch_1):page244_i29:b"
				( attribute "PN" "2"
					( Origin gPackager )
				)
				( objectStatus "C840.2" )
			)
			( pin "@baseboard_fab2_lib.baseboard_fab2(sch_1):page244_i30:a"
				( attribute "PN" "1"
					( Origin gPackager )
				)
				( objectStatus "C832.1" )
			)
			( pin "@baseboard_fab2_lib.baseboard_fab2(sch_1):page244_i30:b"
				( attribute "PN" "2"
					( Origin gPackager )
				)
				( objectStatus "C832.2" )
			)
			( pin "@baseboard_fab2_lib.baseboard_fab2(sch_1):page244_i35:a"
				( attribute "PN" "1"
					( Origin gPackager )
				)
				( objectStatus "C845.1" )
			)
			( pin "@baseboard_fab2_lib.baseboard_fab2(sch_1):page244_i35:b"
				( attribute "PN" "2"
					( Origin gPackager )
				)
				( objectStatus "C845.2" )
			)
			( pin "@baseboard_fab2_lib.baseboard_fab2(sch_1):page244_i39:a"
				( attribute "PN" "1"
					( Origin gPackager )
				)
				( objectStatus "R767.1" )
			)
			( pin "@baseboard_fab2_lib.baseboard_fab2(sch_1):page244_i39:b"
				( attribute "PN" "2"
					( Origin gPackager )
				)
				( objectStatus "R767.2" )
			)
			( pin "@baseboard_fab2_lib.baseboard_fab2(sch_1):page244_i41:a"
				( attribute "PN" "1"
					( Origin gPackager )
				)
				( objectStatus "C835.1" )
			)
			( pin "@baseboard_fab2_lib.baseboard_fab2(sch_1):page244_i41:b"
				( attribute "PN" "2"
					( Origin gPackager )
				)
				( objectStatus "C835.2" )
			)
			( pin "@baseboard_fab2_lib.baseboard_fab2(sch_1):page244_i47:a"
				( attribute "PN" "1"
					( Origin gPackager )
				)
				( objectStatus "C843.1" )
			)
			( pin "@baseboard_fab2_lib.baseboard_fab2(sch_1):page244_i47:b"
				( attribute "PN" "2"
					( Origin gPackager )
				)
				( objectStatus "C843.2" )
			)
			( pin "@baseboard_fab2_lib.baseboard_fab2(sch_1):page244_i50:a"
				( attribute "PN" "1"
					( Origin gPackager )
				)
				( objectStatus "C834.1" )
			)
			( pin "@baseboard_fab2_lib.baseboard_fab2(sch_1):page244_i50:b"
				( attribute "PN" "2"
					( Origin gPackager )
				)
				( objectStatus "C834.2" )
			)
			( pin "@baseboard_fab2_lib.baseboard_fab2(sch_1):page244_i51:a"
				( attribute "PN" "1"
					( Origin gPackager )
				)
				( objectStatus "C844.1" )
			)
			( pin "@baseboard_fab2_lib.baseboard_fab2(sch_1):page244_i51:b"
				( attribute "PN" "2"
					( Origin gPackager )
				)
				( objectStatus "C844.2" )
			)
			( pin "@baseboard_fab2_lib.baseboard_fab2(sch_1):page244_i52:a"
				( attribute "PN" "1"
					( Origin gPackager )
				)
				( objectStatus "C842.1" )
			)
			( pin "@baseboard_fab2_lib.baseboard_fab2(sch_1):page244_i52:b"
				( attribute "PN" "2"
					( Origin gPackager )
				)
				( objectStatus "C842.2" )
			)
			( pin "@baseboard_fab2_lib.baseboard_fab2(sch_1):page244_i58:a"
				( attribute "PN" "1"
					( Origin gPackager )
				)
				( objectStatus "R769.1" )
			)
			( pin "@baseboard_fab2_lib.baseboard_fab2(sch_1):page244_i58:b"
				( attribute "PN" "2"
					( Origin gPackager )
				)
				( objectStatus "R769.2" )
			)
			( pin "@baseboard_fab2_lib.baseboard_fab2(sch_1):page244_i64:a"
				( attribute "PN" "1"
					( Origin gPackager )
				)
				( objectStatus "R760.1" )
			)
			( pin "@baseboard_fab2_lib.baseboard_fab2(sch_1):page244_i64:b"
				( attribute "PN" "2"
					( Origin gPackager )
				)
				( objectStatus "R760.2" )
			)
			( pin "@baseboard_fab2_lib.baseboard_fab2(sch_1):page244_i65:a"
				( attribute "PN" "1"
					( Origin gPackager )
				)
				( objectStatus "R771.1" )
			)
			( pin "@baseboard_fab2_lib.baseboard_fab2(sch_1):page244_i65:b"
				( attribute "PN" "2"
					( Origin gPackager )
				)
				( objectStatus "R771.2" )
			)
			( pin "@baseboard_fab2_lib.baseboard_fab2(sch_1):page244_i66:a"
				( attribute "PN" "1"
					( Origin gPackager )
				)
				( objectStatus "R768.1" )
			)
			( pin "@baseboard_fab2_lib.baseboard_fab2(sch_1):page244_i66:b"
				( attribute "PN" "2"
					( Origin gPackager )
				)
				( objectStatus "R768.2" )
			)
			( pin "@baseboard_fab2_lib.baseboard_fab2(sch_1):page244_i72:a"
				( attribute "PN" "1"
					( Origin gPackager )
				)
				( objectStatus "R774.1" )
			)
			( pin "@baseboard_fab2_lib.baseboard_fab2(sch_1):page244_i72:b"
				( attribute "PN" "2"
					( Origin gPackager )
				)
				( objectStatus "R774.2" )
			)
			( pin "@baseboard_fab2_lib.baseboard_fab2(sch_1):page244_i74:a"
				( attribute "PN" "1"
					( Origin gPackager )
				)
				( objectStatus "R779.1" )
			)
			( pin "@baseboard_fab2_lib.baseboard_fab2(sch_1):page244_i74:b"
				( attribute "PN" "2"
					( Origin gPackager )
				)
				( objectStatus "R779.2" )
			)
			( pin "@baseboard_fab2_lib.baseboard_fab2(sch_1):page244_i77:a"
				( attribute "PN" "1"
					( Origin gPackager )
				)
				( objectStatus "R783.1" )
			)
			( pin "@baseboard_fab2_lib.baseboard_fab2(sch_1):page244_i77:b"
				( attribute "PN" "2"
					( Origin gPackager )
				)
				( objectStatus "R783.2" )
			)
			( pin "@baseboard_fab2_lib.baseboard_fab2(sch_1):page244_i80:a"
				( attribute "PN" "1"
					( Origin gPackager )
				)
				( objectStatus "R777.1" )
			)
			( pin "@baseboard_fab2_lib.baseboard_fab2(sch_1):page244_i80:b"
				( attribute "PN" "2"
					( Origin gPackager )
				)
				( objectStatus "R777.2" )
			)
			( pin "@baseboard_fab2_lib.baseboard_fab2(sch_1):page244_i86:a"
				( attribute "PN" "1"
					( Origin gPackager )
				)
				( objectStatus "R781.1" )
			)
			( pin "@baseboard_fab2_lib.baseboard_fab2(sch_1):page244_i86:b"
				( attribute "PN" "2"
					( Origin gPackager )
				)
				( objectStatus "R781.2" )
			)
			( pin "@baseboard_fab2_lib.baseboard_fab2(sch_1):page244_i93:a"
				( attribute "PN" "1"
					( Origin gPackager )
				)
				( objectStatus "R775.1" )
			)
			( pin "@baseboard_fab2_lib.baseboard_fab2(sch_1):page244_i93:b"
				( attribute "PN" "2"
					( Origin gPackager )
				)
				( objectStatus "R775.2" )
			)
			( pin "@baseboard_fab2_lib.baseboard_fab2(sch_1):page244_i94:a"
				( attribute "PN" "1"
					( Origin gPackager )
				)
				( objectStatus "R778.1" )
			)
			( pin "@baseboard_fab2_lib.baseboard_fab2(sch_1):page244_i94:b"
				( attribute "PN" "2"
					( Origin gPackager )
				)
				( objectStatus "R778.2" )
			)
			( pin "@baseboard_fab2_lib.baseboard_fab2(sch_1):page244_i97:a"
				( attribute "PN" "1"
					( Origin gPackager )
				)
				( objectStatus "R780.1" )
			)
			( pin "@baseboard_fab2_lib.baseboard_fab2(sch_1):page244_i97:b"
				( attribute "PN" "2"
					( Origin gPackager )
				)
				( objectStatus "R780.2" )
			)
			( pin "@baseboard_fab2_lib.baseboard_fab2(sch_1):page244_i98:a"
				( attribute "PN" "1"
					( Origin gPackager )
				)
				( objectStatus "R782.1" )
			)
			( pin "@baseboard_fab2_lib.baseboard_fab2(sch_1):page244_i98:b"
				( attribute "PN" "2"
					( Origin gPackager )
				)
				( objectStatus "R782.2" )
			)
			( pin "@baseboard_fab2_lib.baseboard_fab2(sch_1):page244_i99:a"
				( attribute "PN" "1"
					( Origin gPackager )
				)
				( objectStatus "R784.1" )
			)
			( pin "@baseboard_fab2_lib.baseboard_fab2(sch_1):page244_i99:b"
				( attribute "PN" "2"
					( Origin gPackager )
				)
				( objectStatus "R784.2" )
			)
			( pin "@baseboard_fab2_lib.baseboard_fab2(sch_1):page244_i103:a"
				( attribute "PN" "1"
					( Origin gPackager )
				)
				( objectStatus "R785.1" )
			)
			( pin "@baseboard_fab2_lib.baseboard_fab2(sch_1):page244_i103:b"
				( attribute "PN" "2"
					( Origin gPackager )
				)
				( objectStatus "R785.2" )
			)
			( pin "@baseboard_fab2_lib.baseboard_fab2(sch_1):page245_i48:\1\"
				( attribute "PN" "1"
					( Origin gPackager )
				)
				( objectStatus "CONX8.1" )
			)
			( pin "@baseboard_fab2_lib.baseboard_fab2(sch_1):page245_i48:\2\"
				( attribute "PN" "2"
					( Origin gPackager )
				)
				( objectStatus "CONX8.2" )
			)
			( pin "@baseboard_fab2_lib.baseboard_fab2(sch_1):page245_i48:\3\"
				( attribute "PN" "3"
					( Origin gPackager )
				)
				( objectStatus "CONX8.3" )
			)
			( pin "@baseboard_fab2_lib.baseboard_fab2(sch_1):page245_i48:\4\"
				( attribute "PN" "4"
					( Origin gPackager )
				)
				( objectStatus "CONX8.4" )
			)
			( pin "@baseboard_fab2_lib.baseboard_fab2(sch_1):page245_i48:\5\"
				( attribute "PN" "5"
					( Origin gPackager )
				)
				( objectStatus "CONX8.5" )
			)
			( pin "@baseboard_fab2_lib.baseboard_fab2(sch_1):page245_i48:\6\"
				( attribute "PN" "6"
					( Origin gPackager )
				)
				( objectStatus "CONX8.6" )
			)
			( pin "@baseboard_fab2_lib.baseboard_fab2(sch_1):page245_i48:\7\"
				( attribute "PN" "7"
					( Origin gPackager )
				)
				( objectStatus "CONX8.7" )
			)
			( pin "@baseboard_fab2_lib.baseboard_fab2(sch_1):page245_i48:\8\"
				( attribute "PN" "8"
					( Origin gPackager )
				)
				( objectStatus "CONX8.8" )
			)
			( pin "@baseboard_fab2_lib.baseboard_fab2(sch_1):page245_i48:\9\"
				( attribute "PN" "9"
					( Origin gPackager )
				)
				( objectStatus "CONX8.9" )
			)
			( pin "@baseboard_fab2_lib.baseboard_fab2(sch_1):page245_i48:\10\"
				( attribute "PN" "10"
					( Origin gPackager )
				)
				( objectStatus "CONX8.10" )
			)
			( pin "@baseboard_fab2_lib.baseboard_fab2(sch_1):page245_i48:\11\"
				( attribute "PN" "11"
					( Origin gPackager )
				)
				( objectStatus "CONX8.11" )
			)
			( pin "@baseboard_fab2_lib.baseboard_fab2(sch_1):page245_i48:\12\"
				( attribute "PN" "12"
					( Origin gPackager )
				)
				( objectStatus "CONX8.12" )
			)
			( pin "@baseboard_fab2_lib.baseboard_fab2(sch_1):page245_i48:\13\"
				( attribute "PN" "13"
					( Origin gPackager )
				)
				( objectStatus "CONX8.13" )
			)
			( pin "@baseboard_fab2_lib.baseboard_fab2(sch_1):page245_i48:\14\"
				( attribute "PN" "14"
					( Origin gPackager )
				)
				( objectStatus "CONX8.14" )
			)
			( pin "@baseboard_fab2_lib.baseboard_fab2(sch_1):page245_i48:\15\"
				( attribute "PN" "15"
					( Origin gPackager )
				)
				( objectStatus "CONX8.15" )
			)
			( pin "@baseboard_fab2_lib.baseboard_fab2(sch_1):page245_i48:\16\"
				( attribute "PN" "16"
					( Origin gPackager )
				)
				( objectStatus "CONX8.16" )
			)
			( pin "@baseboard_fab2_lib.baseboard_fab2(sch_1):page245_i48:\17\"
				( attribute "PN" "17"
					( Origin gPackager )
				)
				( objectStatus "CONX8.17" )
			)
			( pin "@baseboard_fab2_lib.baseboard_fab2(sch_1):page245_i48:\18\"
				( attribute "PN" "18"
					( Origin gPackager )
				)
				( objectStatus "CONX8.18" )
			)
			( pin "@baseboard_fab2_lib.baseboard_fab2(sch_1):page245_i48:\19\"
				( attribute "PN" "19"
					( Origin gPackager )
				)
				( objectStatus "CONX8.19" )
			)
			( pin "@baseboard_fab2_lib.baseboard_fab2(sch_1):page245_i48:\20\"
				( attribute "PN" "20"
					( Origin gPackager )
				)
				( objectStatus "CONX8.20" )
			)
			( pin "@baseboard_fab2_lib.baseboard_fab2(sch_1):page245_i48:\21\"
				( attribute "PN" "21"
					( Origin gPackager )
				)
				( objectStatus "CONX8.21" )
			)
			( pin "@baseboard_fab2_lib.baseboard_fab2(sch_1):page245_i48:\22\"
				( attribute "PN" "22"
					( Origin gPackager )
				)
				( objectStatus "CONX8.22" )
			)
			( pin "@baseboard_fab2_lib.baseboard_fab2(sch_1):page245_i48:\23\"
				( attribute "PN" "23"
					( Origin gPackager )
				)
				( objectStatus "CONX8.23" )
			)
			( pin "@baseboard_fab2_lib.baseboard_fab2(sch_1):page245_i48:\24\"
				( attribute "PN" "24"
					( Origin gPackager )
				)
				( objectStatus "CONX8.24" )
			)
			( pin "@baseboard_fab2_lib.baseboard_fab2(sch_1):page245_i48:\25\"
				( attribute "PN" "25"
					( Origin gPackager )
				)
				( objectStatus "CONX8.25" )
			)
			( pin "@baseboard_fab2_lib.baseboard_fab2(sch_1):page245_i48:\26\"
				( attribute "PN" "26"
					( Origin gPackager )
				)
				( objectStatus "CONX8.26" )
			)
			( pin "@baseboard_fab2_lib.baseboard_fab2(sch_1):page245_i48:\27\"
				( attribute "PN" "27"
					( Origin gPackager )
				)
				( objectStatus "CONX8.27" )
			)
			( pin "@baseboard_fab2_lib.baseboard_fab2(sch_1):page245_i48:\28\"
				( attribute "PN" "28"
					( Origin gPackager )
				)
				( objectStatus "CONX8.28" )
			)
			( pin "@baseboard_fab2_lib.baseboard_fab2(sch_1):page245_i48:\29\"
				( attribute "PN" "29"
					( Origin gPackager )
				)
				( objectStatus "CONX8.29" )
			)
			( pin "@baseboard_fab2_lib.baseboard_fab2(sch_1):page245_i48:\30\"
				( attribute "PN" "30"
					( Origin gPackager )
				)
				( objectStatus "CONX8.30" )
			)
			( pin "@baseboard_fab2_lib.baseboard_fab2(sch_1):page245_i48:\31\"
				( attribute "PN" "31"
					( Origin gPackager )
				)
				( objectStatus "CONX8.31" )
			)
			( pin "@baseboard_fab2_lib.baseboard_fab2(sch_1):page245_i48:\32\"
				( attribute "PN" "32"
					( Origin gPackager )
				)
				( objectStatus "CONX8.32" )
			)
			( pin "@baseboard_fab2_lib.baseboard_fab2(sch_1):page245_i48:\33\"
				( attribute "PN" "33"
					( Origin gPackager )
				)
				( objectStatus "CONX8.33" )
			)
			( pin "@baseboard_fab2_lib.baseboard_fab2(sch_1):page245_i48:\34\"
				( attribute "PN" "34"
					( Origin gPackager )
				)
				( objectStatus "CONX8.34" )
			)
			( pin "@baseboard_fab2_lib.baseboard_fab2(sch_1):page245_i48:\35\"
				( attribute "PN" "35"
					( Origin gPackager )
				)
				( objectStatus "CONX8.35" )
			)
			( pin "@baseboard_fab2_lib.baseboard_fab2(sch_1):page245_i48:\36\"
				( attribute "PN" "36"
					( Origin gPackager )
				)
				( objectStatus "CONX8.36" )
			)
			( pin "@baseboard_fab2_lib.baseboard_fab2(sch_1):page245_i48:\37\"
				( attribute "PN" "37"
					( Origin gPackager )
				)
				( objectStatus "CONX8.37" )
			)
			( pin "@baseboard_fab2_lib.baseboard_fab2(sch_1):page245_i48:\38\"
				( attribute "PN" "38"
					( Origin gPackager )
				)
				( objectStatus "CONX8.38" )
			)
			( pin "@baseboard_fab2_lib.baseboard_fab2(sch_1):page245_i48:\39\"
				( attribute "PN" "39"
					( Origin gPackager )
				)
				( objectStatus "CONX8.39" )
			)
			( pin "@baseboard_fab2_lib.baseboard_fab2(sch_1):page245_i48:\40\"
				( attribute "PN" "40"
					( Origin gPackager )
				)
				( objectStatus "CONX8.40" )
			)
			( pin "@baseboard_fab2_lib.baseboard_fab2(sch_1):page245_i48:\41\"
				( attribute "PN" "41"
					( Origin gPackager )
				)
				( objectStatus "CONX8.41" )
			)
			( pin "@baseboard_fab2_lib.baseboard_fab2(sch_1):page245_i48:\42\"
				( attribute "PN" "42"
					( Origin gPackager )
				)
				( objectStatus "CONX8.42" )
			)
			( pin "@baseboard_fab2_lib.baseboard_fab2(sch_1):page245_i48:\43\"
				( attribute "PN" "43"
					( Origin gPackager )
				)
				( objectStatus "CONX8.43" )
			)
			( pin "@baseboard_fab2_lib.baseboard_fab2(sch_1):page245_i48:\44\"
				( attribute "PN" "44"
					( Origin gPackager )
				)
				( objectStatus "CONX8.44" )
			)
			( pin "@baseboard_fab2_lib.baseboard_fab2(sch_1):page245_i48:\45\"
				( attribute "PN" "45"
					( Origin gPackager )
				)
				( objectStatus "CONX8.45" )
			)
			( pin "@baseboard_fab2_lib.baseboard_fab2(sch_1):page245_i48:\46\"
				( attribute "PN" "46"
					( Origin gPackager )
				)
				( objectStatus "CONX8.46" )
			)
			( pin "@baseboard_fab2_lib.baseboard_fab2(sch_1):page245_i48:\47\"
				( attribute "PN" "47"
					( Origin gPackager )
				)
				( objectStatus "CONX8.47" )
			)
			( pin "@baseboard_fab2_lib.baseboard_fab2(sch_1):page245_i48:\48\"
				( attribute "PN" "48"
					( Origin gPackager )
				)
				( objectStatus "CONX8.48" )
			)
			( pin "@baseboard_fab2_lib.baseboard_fab2(sch_1):page245_i48:\49\"
				( attribute "PN" "49"
					( Origin gPackager )
				)
				( objectStatus "CONX8.49" )
			)
			( pin "@baseboard_fab2_lib.baseboard_fab2(sch_1):page245_i48:\50\"
				( attribute "PN" "50"
					( Origin gPackager )
				)
				( objectStatus "CONX8.50" )
			)
			( pin "@baseboard_fab2_lib.baseboard_fab2(sch_1):page245_i48:\51\"
				( attribute "PN" "51"
					( Origin gPackager )
				)
				( objectStatus "CONX8.51" )
			)
			( pin "@baseboard_fab2_lib.baseboard_fab2(sch_1):page245_i48:\52\"
				( attribute "PN" "52"
					( Origin gPackager )
				)
				( objectStatus "CONX8.52" )
			)
			( pin "@baseboard_fab2_lib.baseboard_fab2(sch_1):page245_i48:\53\"
				( attribute "PN" "53"
					( Origin gPackager )
				)
				( objectStatus "CONX8.53" )
			)
			( pin "@baseboard_fab2_lib.baseboard_fab2(sch_1):page245_i48:\54\"
				( attribute "PN" "54"
					( Origin gPackager )
				)
				( objectStatus "CONX8.54" )
			)
			( pin "@baseboard_fab2_lib.baseboard_fab2(sch_1):page245_i48:\55\"
				( attribute "PN" "55"
					( Origin gPackager )
				)
				( objectStatus "CONX8.55" )
			)
			( pin "@baseboard_fab2_lib.baseboard_fab2(sch_1):page245_i48:\56\"
				( attribute "PN" "56"
					( Origin gPackager )
				)
				( objectStatus "CONX8.56" )
			)
			( pin "@baseboard_fab2_lib.baseboard_fab2(sch_1):page245_i48:\57\"
				( attribute "PN" "57"
					( Origin gPackager )
				)
				( objectStatus "CONX8.57" )
			)
			( pin "@baseboard_fab2_lib.baseboard_fab2(sch_1):page245_i48:\58\"
				( attribute "PN" "58"
					( Origin gPackager )
				)
				( objectStatus "CONX8.58" )
			)
			( pin "@baseboard_fab2_lib.baseboard_fab2(sch_1):page245_i48:\59\"
				( attribute "PN" "59"
					( Origin gPackager )
				)
				( objectStatus "CONX8.59" )
			)
			( pin "@baseboard_fab2_lib.baseboard_fab2(sch_1):page245_i48:\60\"
				( attribute "PN" "60"
					( Origin gPackager )
				)
				( objectStatus "CONX8.60" )
			)
			( pin "@baseboard_fab2_lib.baseboard_fab2(sch_1):page245_i48:np1"
				( attribute "PN" "NP1"
					( Origin gPackager )
				)
				( objectStatus "CONX8.NP1" )
			)
			( pin "@baseboard_fab2_lib.baseboard_fab2(sch_1):page245_i48:np2"
				( attribute "PN" "NP2"
					( Origin gPackager )
				)
				( objectStatus "CONX8.NP2" )
			)
			( pin "@baseboard_fab2_lib.baseboard_fab2(sch_1):page245_i48:pth1"
				( attribute "PN" "PTH1"
					( Origin gPackager )
				)
				( objectStatus "CONX8.PTH1" )
			)
			( pin "@baseboard_fab2_lib.baseboard_fab2(sch_1):page245_i48:pth2"
				( attribute "PN" "PTH2"
					( Origin gPackager )
				)
				( objectStatus "CONX8.PTH2" )
			)
			( pin "@baseboard_fab2_lib.baseboard_fab2(sch_1):page109_i78:io101"
				( attribute "PN" "101"
					( Origin gPackager )
				)
				( objectStatus "J8G1.101" )
			)
			( pin "@baseboard_fab2_lib.baseboard_fab2(sch_1):page109_i78:io102"
				( attribute "PN" "102"
					( Origin gPackager )
				)
				( objectStatus "J8G1.102" )
			)
			( pin "@baseboard_fab2_lib.baseboard_fab2(sch_1):page109_i78:io103"
				( attribute "PN" "103"
					( Origin gPackager )
				)
				( objectStatus "J8G1.103" )
			)
			( pin "@baseboard_fab2_lib.baseboard_fab2(sch_1):page109_i78:io104"
				( attribute "PN" "104"
					( Origin gPackager )
				)
				( objectStatus "J8G1.104" )
			)
			( pin "@baseboard_fab2_lib.baseboard_fab2(sch_1):page109_i78:io105"
				( attribute "PN" "105"
					( Origin gPackager )
				)
				( objectStatus "J8G1.105" )
			)
			( pin "@baseboard_fab2_lib.baseboard_fab2(sch_1):page109_i78:io106"
				( attribute "PN" "106"
					( Origin gPackager )
				)
				( objectStatus "J8G1.106" )
			)
			( pin "@baseboard_fab2_lib.baseboard_fab2(sch_1):page109_i78:io107"
				( attribute "PN" "107"
					( Origin gPackager )
				)
				( objectStatus "J8G1.107" )
			)
			( pin "@baseboard_fab2_lib.baseboard_fab2(sch_1):page109_i78:io108"
				( attribute "PN" "108"
					( Origin gPackager )
				)
				( objectStatus "J8G1.108" )
			)
			( pin "@baseboard_fab2_lib.baseboard_fab2(sch_1):page109_i78:io109"
				( attribute "PN" "109"
					( Origin gPackager )
				)
				( objectStatus "J8G1.109" )
			)
			( pin "@baseboard_fab2_lib.baseboard_fab2(sch_1):page109_i78:io110"
				( attribute "PN" "110"
					( Origin gPackager )
				)
				( objectStatus "J8G1.110" )
			)
			( pin "@baseboard_fab2_lib.baseboard_fab2(sch_1):page109_i78:io111"
				( attribute "PN" "111"
					( Origin gPackager )
				)
				( objectStatus "J8G1.111" )
			)
			( pin "@baseboard_fab2_lib.baseboard_fab2(sch_1):page109_i78:io112"
				( attribute "PN" "112"
					( Origin gPackager )
				)
				( objectStatus "J8G1.112" )
			)
			( pin "@baseboard_fab2_lib.baseboard_fab2(sch_1):page109_i78:io113"
				( attribute "PN" "113"
					( Origin gPackager )
				)
				( objectStatus "J8G1.113" )
			)
			( pin "@baseboard_fab2_lib.baseboard_fab2(sch_1):page109_i78:io114"
				( attribute "PN" "114"
					( Origin gPackager )
				)
				( objectStatus "J8G1.114" )
			)
			( pin "@baseboard_fab2_lib.baseboard_fab2(sch_1):page109_i78:io115"
				( attribute "PN" "115"
					( Origin gPackager )
				)
				( objectStatus "J8G1.115" )
			)
			( pin "@baseboard_fab2_lib.baseboard_fab2(sch_1):page109_i78:io116"
				( attribute "PN" "116"
					( Origin gPackager )
				)
				( objectStatus "J8G1.116" )
			)
			( pin "@baseboard_fab2_lib.baseboard_fab2(sch_1):page109_i78:io117"
				( attribute "PN" "117"
					( Origin gPackager )
				)
				( objectStatus "J8G1.117" )
			)
			( pin "@baseboard_fab2_lib.baseboard_fab2(sch_1):page109_i78:io118"
				( attribute "PN" "118"
					( Origin gPackager )
				)
				( objectStatus "J8G1.118" )
			)
			( pin "@baseboard_fab2_lib.baseboard_fab2(sch_1):page109_i78:io119"
				( attribute "PN" "119"
					( Origin gPackager )
				)
				( objectStatus "J8G1.119" )
			)
			( pin "@baseboard_fab2_lib.baseboard_fab2(sch_1):page109_i78:io120"
				( attribute "PN" "120"
					( Origin gPackager )
				)
				( objectStatus "J8G1.120" )
			)
			( pin "@baseboard_fab2_lib.baseboard_fab2(sch_1):page109_i78:io121"
				( attribute "PN" "121"
					( Origin gPackager )
				)
				( objectStatus "J8G1.121" )
			)
			( pin "@baseboard_fab2_lib.baseboard_fab2(sch_1):page109_i78:io122"
				( attribute "PN" "122"
					( Origin gPackager )
				)
				( objectStatus "J8G1.122" )
			)
			( pin "@baseboard_fab2_lib.baseboard_fab2(sch_1):page109_i78:io123"
				( attribute "PN" "123"
					( Origin gPackager )
				)
				( objectStatus "J8G1.123" )
			)
			( pin "@baseboard_fab2_lib.baseboard_fab2(sch_1):page109_i78:io124"
				( attribute "PN" "124"
					( Origin gPackager )
				)
				( objectStatus "J8G1.124" )
			)
			( pin "@baseboard_fab2_lib.baseboard_fab2(sch_1):page109_i78:io125"
				( attribute "PN" "125"
					( Origin gPackager )
				)
				( objectStatus "J8G1.125" )
			)
			( pin "@baseboard_fab2_lib.baseboard_fab2(sch_1):page109_i78:io126"
				( attribute "PN" "126"
					( Origin gPackager )
				)
				( objectStatus "J8G1.126" )
			)
			( pin "@baseboard_fab2_lib.baseboard_fab2(sch_1):page109_i78:io127"
				( attribute "PN" "127"
					( Origin gPackager )
				)
				( objectStatus "J8G1.127" )
			)
			( pin "@baseboard_fab2_lib.baseboard_fab2(sch_1):page109_i78:io128"
				( attribute "PN" "128"
					( Origin gPackager )
				)
				( objectStatus "J8G1.128" )
			)
			( pin "@baseboard_fab2_lib.baseboard_fab2(sch_1):page109_i78:io129"
				( attribute "PN" "129"
					( Origin gPackager )
				)
				( objectStatus "J8G1.129" )
			)
			( pin "@baseboard_fab2_lib.baseboard_fab2(sch_1):page109_i78:io130"
				( attribute "PN" "130"
					( Origin gPackager )
				)
				( objectStatus "J8G1.130" )
			)
			( pin "@baseboard_fab2_lib.baseboard_fab2(sch_1):page109_i78:io131"
				( attribute "PN" "131"
					( Origin gPackager )
				)
				( objectStatus "J8G1.131" )
			)
			( pin "@baseboard_fab2_lib.baseboard_fab2(sch_1):page109_i78:io132"
				( attribute "PN" "132"
					( Origin gPackager )
				)
				( objectStatus "J8G1.132" )
			)
			( pin "@baseboard_fab2_lib.baseboard_fab2(sch_1):page109_i78:io133"
				( attribute "PN" "133"
					( Origin gPackager )
				)
				( objectStatus "J8G1.133" )
			)
			( pin "@baseboard_fab2_lib.baseboard_fab2(sch_1):page109_i78:io134"
				( attribute "PN" "134"
					( Origin gPackager )
				)
				( objectStatus "J8G1.134" )
			)
			( pin "@baseboard_fab2_lib.baseboard_fab2(sch_1):page109_i78:io135"
				( attribute "PN" "135"
					( Origin gPackager )
				)
				( objectStatus "J8G1.135" )
			)
			( pin "@baseboard_fab2_lib.baseboard_fab2(sch_1):page109_i78:io136"
				( attribute "PN" "136"
					( Origin gPackager )
				)
				( objectStatus "J8G1.136" )
			)
			( pin "@baseboard_fab2_lib.baseboard_fab2(sch_1):page109_i78:io137"
				( attribute "PN" "137"
					( Origin gPackager )
				)
				( objectStatus "J8G1.137" )
			)
			( pin "@baseboard_fab2_lib.baseboard_fab2(sch_1):page109_i78:io138"
				( attribute "PN" "138"
					( Origin gPackager )
				)
				( objectStatus "J8G1.138" )
			)
			( pin "@baseboard_fab2_lib.baseboard_fab2(sch_1):page109_i78:io139"
				( attribute "PN" "139"
					( Origin gPackager )
				)
				( objectStatus "J8G1.139" )
			)
			( pin "@baseboard_fab2_lib.baseboard_fab2(sch_1):page109_i78:io140"
				( attribute "PN" "140"
					( Origin gPackager )
				)
				( objectStatus "J8G1.140" )
			)
			( pin "@baseboard_fab2_lib.baseboard_fab2(sch_1):page109_i78:io141"
				( attribute "PN" "141"
					( Origin gPackager )
				)
				( objectStatus "J8G1.141" )
			)
			( pin "@baseboard_fab2_lib.baseboard_fab2(sch_1):page109_i78:io142"
				( attribute "PN" "142"
					( Origin gPackager )
				)
				( objectStatus "J8G1.142" )
			)
			( pin "@baseboard_fab2_lib.baseboard_fab2(sch_1):page109_i78:io143"
				( attribute "PN" "143"
					( Origin gPackager )
				)
				( objectStatus "J8G1.143" )
			)
			( pin "@baseboard_fab2_lib.baseboard_fab2(sch_1):page109_i78:io144"
				( attribute "PN" "144"
					( Origin gPackager )
				)
				( objectStatus "J8G1.144" )
			)
			( pin "@baseboard_fab2_lib.baseboard_fab2(sch_1):page109_i78:io145"
				( attribute "PN" "145"
					( Origin gPackager )
				)
				( objectStatus "J8G1.145" )
			)
			( pin "@baseboard_fab2_lib.baseboard_fab2(sch_1):page109_i78:io146"
				( attribute "PN" "146"
					( Origin gPackager )
				)
				( objectStatus "J8G1.146" )
			)
			( pin "@baseboard_fab2_lib.baseboard_fab2(sch_1):page109_i78:io147"
				( attribute "PN" "147"
					( Origin gPackager )
				)
				( objectStatus "J8G1.147" )
			)
			( pin "@baseboard_fab2_lib.baseboard_fab2(sch_1):page109_i78:io148"
				( attribute "PN" "148"
					( Origin gPackager )
				)
				( objectStatus "J8G1.148" )
			)
			( pin "@baseboard_fab2_lib.baseboard_fab2(sch_1):page109_i78:io149"
				( attribute "PN" "149"
					( Origin gPackager )
				)
				( objectStatus "J8G1.149" )
			)
			( pin "@baseboard_fab2_lib.baseboard_fab2(sch_1):page109_i78:io150"
				( attribute "PN" "150"
					( Origin gPackager )
				)
				( objectStatus "J8G1.150" )
			)
			( pin "@baseboard_fab2_lib.baseboard_fab2(sch_1):page109_i78:io151"
				( attribute "PN" "151"
					( Origin gPackager )
				)
				( objectStatus "J8G1.151" )
			)
			( pin "@baseboard_fab2_lib.baseboard_fab2(sch_1):page109_i78:io152"
				( attribute "PN" "152"
					( Origin gPackager )
				)
				( objectStatus "J8G1.152" )
			)
			( pin "@baseboard_fab2_lib.baseboard_fab2(sch_1):page109_i78:io153"
				( attribute "PN" "153"
					( Origin gPackager )
				)
				( objectStatus "J8G1.153" )
			)
			( pin "@baseboard_fab2_lib.baseboard_fab2(sch_1):page109_i78:io154"
				( attribute "PN" "154"
					( Origin gPackager )
				)
				( objectStatus "J8G1.154" )
			)
			( pin "@baseboard_fab2_lib.baseboard_fab2(sch_1):page109_i78:io155"
				( attribute "PN" "155"
					( Origin gPackager )
				)
				( objectStatus "J8G1.155" )
			)
			( pin "@baseboard_fab2_lib.baseboard_fab2(sch_1):page109_i78:io156"
				( attribute "PN" "156"
					( Origin gPackager )
				)
				( objectStatus "J8G1.156" )
			)
			( pin "@baseboard_fab2_lib.baseboard_fab2(sch_1):page109_i78:io157"
				( attribute "PN" "157"
					( Origin gPackager )
				)
				( objectStatus "J8G1.157" )
			)
			( pin "@baseboard_fab2_lib.baseboard_fab2(sch_1):page109_i78:io158"
				( attribute "PN" "158"
					( Origin gPackager )
				)
				( objectStatus "J8G1.158" )
			)
			( pin "@baseboard_fab2_lib.baseboard_fab2(sch_1):page109_i78:io159"
				( attribute "PN" "159"
					( Origin gPackager )
				)
				( objectStatus "J8G1.159" )
			)
			( pin "@baseboard_fab2_lib.baseboard_fab2(sch_1):page109_i78:io160"
				( attribute "PN" "160"
					( Origin gPackager )
				)
				( objectStatus "J8G1.160" )
			)
			( pin "@baseboard_fab2_lib.baseboard_fab2(sch_1):page109_i78:io161"
				( attribute "PN" "161"
					( Origin gPackager )
				)
				( objectStatus "J8G1.161" )
			)
			( pin "@baseboard_fab2_lib.baseboard_fab2(sch_1):page109_i78:io162"
				( attribute "PN" "162"
					( Origin gPackager )
				)
				( objectStatus "J8G1.162" )
			)
			( pin "@baseboard_fab2_lib.baseboard_fab2(sch_1):page109_i78:io163"
				( attribute "PN" "163"
					( Origin gPackager )
				)
				( objectStatus "J8G1.163" )
			)
			( pin "@baseboard_fab2_lib.baseboard_fab2(sch_1):page109_i78:io164"
				( attribute "PN" "164"
					( Origin gPackager )
				)
				( objectStatus "J8G1.164" )
			)
			( pin "@baseboard_fab2_lib.baseboard_fab2(sch_1):page109_i78:io165"
				( attribute "PN" "165"
					( Origin gPackager )
				)
				( objectStatus "J8G1.165" )
			)
			( pin "@baseboard_fab2_lib.baseboard_fab2(sch_1):page109_i78:io166"
				( attribute "PN" "166"
					( Origin gPackager )
				)
				( objectStatus "J8G1.166" )
			)
			( pin "@baseboard_fab2_lib.baseboard_fab2(sch_1):page109_i78:io167"
				( attribute "PN" "167"
					( Origin gPackager )
				)
				( objectStatus "J8G1.167" )
			)
			( pin "@baseboard_fab2_lib.baseboard_fab2(sch_1):page109_i78:io168"
				( attribute "PN" "168"
					( Origin gPackager )
				)
				( objectStatus "J8G1.168" )
			)
			( pin "@baseboard_fab2_lib.baseboard_fab2(sch_1):page109_i78:io169"
				( attribute "PN" "169"
					( Origin gPackager )
				)
				( objectStatus "J8G1.169" )
			)
			( pin "@baseboard_fab2_lib.baseboard_fab2(sch_1):page109_i78:io170"
				( attribute "PN" "170"
					( Origin gPackager )
				)
				( objectStatus "J8G1.170" )
			)
			( pin "@baseboard_fab2_lib.baseboard_fab2(sch_1):page109_i78:io171"
				( attribute "PN" "171"
					( Origin gPackager )
				)
				( objectStatus "J8G1.171" )
			)
			( pin "@baseboard_fab2_lib.baseboard_fab2(sch_1):page109_i78:io172"
				( attribute "PN" "172"
					( Origin gPackager )
				)
				( objectStatus "J8G1.172" )
			)
			( pin "@baseboard_fab2_lib.baseboard_fab2(sch_1):page109_i78:io173"
				( attribute "PN" "173"
					( Origin gPackager )
				)
				( objectStatus "J8G1.173" )
			)
			( pin "@baseboard_fab2_lib.baseboard_fab2(sch_1):page109_i78:io174"
				( attribute "PN" "174"
					( Origin gPackager )
				)
				( objectStatus "J8G1.174" )
			)
			( pin "@baseboard_fab2_lib.baseboard_fab2(sch_1):page109_i78:io175"
				( attribute "PN" "175"
					( Origin gPackager )
				)
				( objectStatus "J8G1.175" )
			)
			( pin "@baseboard_fab2_lib.baseboard_fab2(sch_1):page109_i78:io176"
				( attribute "PN" "176"
					( Origin gPackager )
				)
				( objectStatus "J8G1.176" )
			)
			( pin "@baseboard_fab2_lib.baseboard_fab2(sch_1):page109_i78:io177"
				( attribute "PN" "177"
					( Origin gPackager )
				)
				( objectStatus "J8G1.177" )
			)
			( pin "@baseboard_fab2_lib.baseboard_fab2(sch_1):page109_i78:io178"
				( attribute "PN" "178"
					( Origin gPackager )
				)
				( objectStatus "J8G1.178" )
			)
			( pin "@baseboard_fab2_lib.baseboard_fab2(sch_1):page109_i78:io179"
				( attribute "PN" "179"
					( Origin gPackager )
				)
				( objectStatus "J8G1.179" )
			)
			( pin "@baseboard_fab2_lib.baseboard_fab2(sch_1):page109_i78:io180"
				( attribute "PN" "180"
					( Origin gPackager )
				)
				( objectStatus "J8G1.180" )
			)
			( pin "@baseboard_fab2_lib.baseboard_fab2(sch_1):page109_i78:io181"
				( attribute "PN" "181"
					( Origin gPackager )
				)
				( objectStatus "J8G1.181" )
			)
			( pin "@baseboard_fab2_lib.baseboard_fab2(sch_1):page109_i78:io182"
				( attribute "PN" "182"
					( Origin gPackager )
				)
				( objectStatus "J8G1.182" )
			)
			( pin "@baseboard_fab2_lib.baseboard_fab2(sch_1):page109_i78:io183"
				( attribute "PN" "183"
					( Origin gPackager )
				)
				( objectStatus "J8G1.183" )
			)
			( pin "@baseboard_fab2_lib.baseboard_fab2(sch_1):page109_i78:io184"
				( attribute "PN" "184"
					( Origin gPackager )
				)
				( objectStatus "J8G1.184" )
			)
			( pin "@baseboard_fab2_lib.baseboard_fab2(sch_1):page109_i78:io185"
				( attribute "PN" "185"
					( Origin gPackager )
				)
				( objectStatus "J8G1.185" )
			)
			( pin "@baseboard_fab2_lib.baseboard_fab2(sch_1):page109_i78:io186"
				( attribute "PN" "186"
					( Origin gPackager )
				)
				( objectStatus "J8G1.186" )
			)
			( pin "@baseboard_fab2_lib.baseboard_fab2(sch_1):page109_i78:io187"
				( attribute "PN" "187"
					( Origin gPackager )
				)
				( objectStatus "J8G1.187" )
			)
			( pin "@baseboard_fab2_lib.baseboard_fab2(sch_1):page109_i78:io188"
				( attribute "PN" "188"
					( Origin gPackager )
				)
				( objectStatus "J8G1.188" )
			)
			( pin "@baseboard_fab2_lib.baseboard_fab2(sch_1):page109_i78:io189"
				( attribute "PN" "189"
					( Origin gPackager )
				)
				( objectStatus "J8G1.189" )
			)
			( pin "@baseboard_fab2_lib.baseboard_fab2(sch_1):page109_i78:io190"
				( attribute "PN" "190"
					( Origin gPackager )
				)
				( objectStatus "J8G1.190" )
			)
			( pin "@baseboard_fab2_lib.baseboard_fab2(sch_1):page109_i78:io191"
				( attribute "PN" "191"
					( Origin gPackager )
				)
				( objectStatus "J8G1.191" )
			)
			( pin "@baseboard_fab2_lib.baseboard_fab2(sch_1):page109_i78:io192"
				( attribute "PN" "192"
					( Origin gPackager )
				)
				( objectStatus "J8G1.192" )
			)
			( pin "@baseboard_fab2_lib.baseboard_fab2(sch_1):page109_i78:io193"
				( attribute "PN" "193"
					( Origin gPackager )
				)
				( objectStatus "J8G1.193" )
			)
			( pin "@baseboard_fab2_lib.baseboard_fab2(sch_1):page109_i78:io194"
				( attribute "PN" "194"
					( Origin gPackager )
				)
				( objectStatus "J8G1.194" )
			)
			( pin "@baseboard_fab2_lib.baseboard_fab2(sch_1):page109_i78:io195"
				( attribute "PN" "195"
					( Origin gPackager )
				)
				( objectStatus "J8G1.195" )
			)
			( pin "@baseboard_fab2_lib.baseboard_fab2(sch_1):page109_i78:io196"
				( attribute "PN" "196"
					( Origin gPackager )
				)
				( objectStatus "J8G1.196" )
			)
			( pin "@baseboard_fab2_lib.baseboard_fab2(sch_1):page109_i78:io197"
				( attribute "PN" "197"
					( Origin gPackager )
				)
				( objectStatus "J8G1.197" )
			)
			( pin "@baseboard_fab2_lib.baseboard_fab2(sch_1):page109_i78:io198"
				( attribute "PN" "198"
					( Origin gPackager )
				)
				( objectStatus "J8G1.198" )
			)
			( pin "@baseboard_fab2_lib.baseboard_fab2(sch_1):page109_i78:io199"
				( attribute "PN" "199"
					( Origin gPackager )
				)
				( objectStatus "J8G1.199" )
			)
			( pin "@baseboard_fab2_lib.baseboard_fab2(sch_1):page109_i78:io200"
				( attribute "PN" "200"
					( Origin gPackager )
				)
				( objectStatus "J8G1.200" )
			)
			( pin "@baseboard_fab2_lib.baseboard_fab2(sch_1):page246_i9:a"
				( attribute "PN" "1"
					( Origin gPackager )
				)
				( objectStatus "RN8F5.1" )
			)
			( pin "@baseboard_fab2_lib.baseboard_fab2(sch_1):page246_i9:b"
				( attribute "PN" "2"
					( Origin gPackager )
				)
				( objectStatus "RN8F5.2" )
			)
			( pin "@baseboard_fab2_lib.baseboard_fab2(sch_1):page246_i11:a"
				( attribute "PN" "1"
					( Origin gPackager )
				)
				( objectStatus "RN8F3.1" )
			)
			( pin "@baseboard_fab2_lib.baseboard_fab2(sch_1):page246_i11:b"
				( attribute "PN" "2"
					( Origin gPackager )
				)
				( objectStatus "RN8F3.2" )
			)
			( pin "@baseboard_fab2_lib.baseboard_fab2(sch_1):page246_i12:a"
				( attribute "PN" "1"
					( Origin gPackager )
				)
				( objectStatus "RN8F4.1" )
			)
			( pin "@baseboard_fab2_lib.baseboard_fab2(sch_1):page246_i12:b"
				( attribute "PN" "2"
					( Origin gPackager )
				)
				( objectStatus "RN8F4.2" )
			)
			( pin "@baseboard_fab2_lib.baseboard_fab2(sch_1):page151_i212:a"
				( attribute "PN" "1"
					( Origin gPackager )
				)
				( objectStatus "C25W12.1" )
			)
			( pin "@baseboard_fab2_lib.baseboard_fab2(sch_1):page151_i212:b"
				( attribute "PN" "2"
					( Origin gPackager )
				)
				( objectStatus "C25W12.2" )
			)
			( pin "@baseboard_fab2_lib.baseboard_fab2(sch_1):page151_i213:a"
				( attribute "PN" "1"
					( Origin gPackager )
				)
				( objectStatus "C25W10.1" )
			)
			( pin "@baseboard_fab2_lib.baseboard_fab2(sch_1):page151_i213:b"
				( attribute "PN" "2"
					( Origin gPackager )
				)
				( objectStatus "C25W10.2" )
			)
			( pin "@baseboard_fab2_lib.baseboard_fab2(sch_1):page246_i17:clk"
				( attribute "PN" "16"
					( Origin gPackager )
				)
				( objectStatus "UN8F2.16" )
			)
			( pin "@baseboard_fab2_lib.baseboard_fab2(sch_1):page246_i17:cs_n"
				( attribute "PN" "7"
					( Origin gPackager )
				)
				( objectStatus "UN8F2.7" )
			)
			( pin "@baseboard_fab2_lib.baseboard_fab2(sch_1):page246_i17:di_io(0)"
				( attribute "PN" "15"
					( Origin gPackager )
				)
				( objectStatus "UN8F2.15" )
			)
			( pin "@baseboard_fab2_lib.baseboard_fab2(sch_1):page246_i17:do_io(1)"
				( attribute "PN" "8"
					( Origin gPackager )
				)
				( objectStatus "UN8F2.8" )
			)
			( pin "@baseboard_fab2_lib.baseboard_fab2(sch_1):page246_i17:gnd"
				( attribute "PN" "10"
					( Origin gPackager )
				)
				( objectStatus "UN8F2.10" )
			)
			( pin "@baseboard_fab2_lib.baseboard_fab2(sch_1):page246_i17:hold_n_io(3)"
				( attribute "PN" "1"
					( Origin gPackager )
				)
				( objectStatus "UN8F2.1" )
			)
			( pin "@baseboard_fab2_lib.baseboard_fab2(sch_1):page246_i17:nc(0)"
				( attribute "PN" "14"
					( Origin gPackager )
				)
				( objectStatus "UN8F2.14" )
			)
			( pin "@baseboard_fab2_lib.baseboard_fab2(sch_1):page246_i17:nc(1)"
				( attribute "PN" "13"
					( Origin gPackager )
				)
				( objectStatus "UN8F2.13" )
			)
			( pin "@baseboard_fab2_lib.baseboard_fab2(sch_1):page246_i17:nc(2)"
				( attribute "PN" "12"
					( Origin gPackager )
				)
				( objectStatus "UN8F2.12" )
			)
			( pin "@baseboard_fab2_lib.baseboard_fab2(sch_1):page246_i17:nc(3)"
				( attribute "PN" "11"
					( Origin gPackager )
				)
				( objectStatus "UN8F2.11" )
			)
			( pin "@baseboard_fab2_lib.baseboard_fab2(sch_1):page246_i17:nc(4)"
				( attribute "PN" "6"
					( Origin gPackager )
				)
				( objectStatus "UN8F2.6" )
			)
			( pin "@baseboard_fab2_lib.baseboard_fab2(sch_1):page246_i17:nc(5)"
				( attribute "PN" "5"
					( Origin gPackager )
				)
				( objectStatus "UN8F2.5" )
			)
			( pin "@baseboard_fab2_lib.baseboard_fab2(sch_1):page246_i17:nc(6)"
				( attribute "PN" "4"
					( Origin gPackager )
				)
				( objectStatus "UN8F2.4" )
			)
			( pin "@baseboard_fab2_lib.baseboard_fab2(sch_1):page246_i17:reset_n"
				( attribute "PN" "3"
					( Origin gPackager )
				)
				( objectStatus "UN8F2.3" )
			)
			( pin "@baseboard_fab2_lib.baseboard_fab2(sch_1):page246_i17:vcc"
				( attribute "PN" "2"
					( Origin gPackager )
				)
				( objectStatus "UN8F2.2" )
			)
			( pin "@baseboard_fab2_lib.baseboard_fab2(sch_1):page246_i17:wp_n_io(2)"
				( attribute "PN" "9"
					( Origin gPackager )
				)
				( objectStatus "UN8F2.9" )
			)
			( pin "@baseboard_fab2_lib.baseboard_fab2(sch_1):page200_i225:drn"
				( attribute "PN" "3"
					( Origin gPackager )
				)
				( objectStatus "Q6W1.3" )
			)
			( pin "@baseboard_fab2_lib.baseboard_fab2(sch_1):page200_i225:gate"
				( attribute "PN" "1"
					( Origin gPackager )
				)
				( objectStatus "Q6W1.1" )
			)
			( pin "@baseboard_fab2_lib.baseboard_fab2(sch_1):page200_i225:src"
				( attribute "PN" "2"
					( Origin gPackager )
				)
				( objectStatus "Q6W1.2" )
			)
			( pin "@baseboard_fab2_lib.baseboard_fab2(sch_1):page247_i1:a"
				( attribute "PN" "1"
					( Origin gPackager )
				)
				( objectStatus "R6W10.1" )
			)
			( pin "@baseboard_fab2_lib.baseboard_fab2(sch_1):page247_i1:b"
				( attribute "PN" "2"
					( Origin gPackager )
				)
				( objectStatus "R6W10.2" )
			)
			( pin "@baseboard_fab2_lib.baseboard_fab2(sch_1):page215_i13:a"
				( attribute "PN" "1"
					( Origin gPackager )
				)
				( objectStatus "R7F21.1" )
			)
			( pin "@baseboard_fab2_lib.baseboard_fab2(sch_1):page215_i13:b"
				( attribute "PN" "2"
					( Origin gPackager )
				)
				( objectStatus "R7F21.2" )
			)
			( pin "@baseboard_fab2_lib.baseboard_fab2(sch_1):page215_i12:a"
				( attribute "PN" "1"
					( Origin gPackager )
				)
				( objectStatus "R7G9.1" )
			)
			( pin "@baseboard_fab2_lib.baseboard_fab2(sch_1):page215_i12:b"
				( attribute "PN" "2"
					( Origin gPackager )
				)
				( objectStatus "R7G9.2" )
			)
			( pin "@baseboard_fab2_lib.baseboard_fab2(sch_1):page249_i37:a"
				( attribute "PN" "1"
					( Origin gPackager )
				)
				( objectStatus "C8W2.1" )
			)
			( pin "@baseboard_fab2_lib.baseboard_fab2(sch_1):page249_i37:b"
				( attribute "PN" "2"
					( Origin gPackager )
				)
				( objectStatus "C8W2.2" )
			)
			( pin "@baseboard_fab2_lib.baseboard_fab2(sch_1):page251_i31:a"
				( attribute "PN" "1"
					( Origin gPackager )
				)
				( objectStatus "R10W7.1" )
			)
			( pin "@baseboard_fab2_lib.baseboard_fab2(sch_1):page251_i31:b"
				( attribute "PN" "2"
					( Origin gPackager )
				)
				( objectStatus "R10W7.2" )
			)
			( pin "@baseboard_fab2_lib.baseboard_fab2(sch_1):page251_i29:a"
				( attribute "PN" "1"
					( Origin gPackager )
				)
				( objectStatus "C10W5.1" )
			)
			( pin "@baseboard_fab2_lib.baseboard_fab2(sch_1):page251_i29:b"
				( attribute "PN" "2"
					( Origin gPackager )
				)
				( objectStatus "C10W5.2" )
			)
			( pin "@baseboard_fab2_lib.baseboard_fab2(sch_1):page251_i27:a"
				( attribute "PN" "1"
					( Origin gPackager )
				)
				( objectStatus "R10W6.1" )
			)
			( pin "@baseboard_fab2_lib.baseboard_fab2(sch_1):page251_i27:b"
				( attribute "PN" "2"
					( Origin gPackager )
				)
				( objectStatus "R10W6.2" )
			)
			( pin "@baseboard_fab2_lib.baseboard_fab2(sch_1):page251_i25:io1"
				( attribute "PN" "1"
					( Origin gPackager )
				)
				( objectStatus "J1B2.1" )
			)
			( pin "@baseboard_fab2_lib.baseboard_fab2(sch_1):page251_i25:io2"
				( attribute "PN" "2"
					( Origin gPackager )
				)
				( objectStatus "J1B2.2" )
			)
			( pin "@baseboard_fab2_lib.baseboard_fab2(sch_1):page251_i25:io3"
				( attribute "PN" "3"
					( Origin gPackager )
				)
				( objectStatus "J1B2.3" )
			)
			( pin "@baseboard_fab2_lib.baseboard_fab2(sch_1):page251_i25:io4"
				( attribute "PN" "4"
					( Origin gPackager )
				)
				( objectStatus "J1B2.4" )
			)
			( pin "@baseboard_fab2_lib.baseboard_fab2(sch_1):page251_i25:io5"
				( attribute "PN" "5"
					( Origin gPackager )
				)
				( objectStatus "J1B2.5" )
			)
			( pin "@baseboard_fab2_lib.baseboard_fab2(sch_1):page251_i25:io6"
				( attribute "PN" "6"
					( Origin gPackager )
				)
				( objectStatus "J1B2.6" )
			)
			( pin "@baseboard_fab2_lib.baseboard_fab2(sch_1):page146_i65:a"
				( attribute "PN" "1"
					( Origin gPackager )
				)
				( objectStatus "R25W63.1" )
			)
			( pin "@baseboard_fab2_lib.baseboard_fab2(sch_1):page146_i65:b"
				( attribute "PN" "2"
					( Origin gPackager )
				)
				( objectStatus "R25W63.2" )
			)
			( pin "@baseboard_fab2_lib.baseboard_fab2(sch_1):page168_i47:b"
				( attribute "PN" "1"
					( Origin gPackager )
				)
				( objectStatus "Q6W2.1" )
			)
			( pin "@baseboard_fab2_lib.baseboard_fab2(sch_1):page168_i47:c"
				( attribute "PN" "3"
					( Origin gPackager )
				)
				( objectStatus "Q6W2.3" )
			)
			( pin "@baseboard_fab2_lib.baseboard_fab2(sch_1):page168_i47:e"
				( attribute "PN" "2"
					( Origin gPackager )
				)
				( objectStatus "Q6W2.2" )
			)
			( pin "@baseboard_fab2_lib.baseboard_fab2(sch_1):page164_i97:a0"
				( attribute "PN" "1"
					( Origin gPackager )
				)
				( objectStatus "U6W11.1" )
			)
			( pin "@baseboard_fab2_lib.baseboard_fab2(sch_1):page164_i97:a1"
				( attribute "PN" "2"
					( Origin gPackager )
				)
				( objectStatus "U6W11.2" )
			)
			( pin "@baseboard_fab2_lib.baseboard_fab2(sch_1):page164_i97:a2"
				( attribute "PN" "3"
					( Origin gPackager )
				)
				( objectStatus "U6W11.3" )
			)
			( pin "@baseboard_fab2_lib.baseboard_fab2(sch_1):page164_i97:gnd"
				( attribute "PN" "8"
					( Origin gPackager )
				)
				( objectStatus "U6W11.8" )
			)
			( pin "@baseboard_fab2_lib.baseboard_fab2(sch_1):page164_i97:\int#\"
				( attribute "PN" "13"
					( Origin gPackager )
				)
				( objectStatus "U6W11.13" )
			)
			( pin "@baseboard_fab2_lib.baseboard_fab2(sch_1):page164_i97:p0"
				( attribute "PN" "4"
					( Origin gPackager )
				)
				( objectStatus "U6W11.4" )
			)
			( pin "@baseboard_fab2_lib.baseboard_fab2(sch_1):page164_i97:p1"
				( attribute "PN" "5"
					( Origin gPackager )
				)
				( objectStatus "U6W11.5" )
			)
			( pin "@baseboard_fab2_lib.baseboard_fab2(sch_1):page164_i97:p2"
				( attribute "PN" "6"
					( Origin gPackager )
				)
				( objectStatus "U6W11.6" )
			)
			( pin "@baseboard_fab2_lib.baseboard_fab2(sch_1):page164_i97:p3"
				( attribute "PN" "7"
					( Origin gPackager )
				)
				( objectStatus "U6W11.7" )
			)
			( pin "@baseboard_fab2_lib.baseboard_fab2(sch_1):page164_i97:p4"
				( attribute "PN" "9"
					( Origin gPackager )
				)
				( objectStatus "U6W11.9" )
			)
			( pin "@baseboard_fab2_lib.baseboard_fab2(sch_1):page164_i97:p5"
				( attribute "PN" "10"
					( Origin gPackager )
				)
				( objectStatus "U6W11.10" )
			)
			( pin "@baseboard_fab2_lib.baseboard_fab2(sch_1):page164_i97:p6"
				( attribute "PN" "11"
					( Origin gPackager )
				)
				( objectStatus "U6W11.11" )
			)
			( pin "@baseboard_fab2_lib.baseboard_fab2(sch_1):page164_i97:p7"
				( attribute "PN" "12"
					( Origin gPackager )
				)
				( objectStatus "U6W11.12" )
			)
			( pin "@baseboard_fab2_lib.baseboard_fab2(sch_1):page164_i97:scl"
				( attribute "PN" "14"
					( Origin gPackager )
				)
				( objectStatus "U6W11.14" )
			)
			( pin "@baseboard_fab2_lib.baseboard_fab2(sch_1):page164_i97:sda"
				( attribute "PN" "15"
					( Origin gPackager )
				)
				( objectStatus "U6W11.15" )
			)
			( pin "@baseboard_fab2_lib.baseboard_fab2(sch_1):page164_i97:vcc"
				( attribute "PN" "16"
					( Origin gPackager )
				)
				( objectStatus "U6W11.16" )
			)
			( pin "@baseboard_fab2_lib.baseboard_fab2(sch_1):page144_i150:\1\"
				( attribute "PN" "1"
					( Origin gPackager )
				)
				( objectStatus "R25W58.1" )
			)
			( pin "@baseboard_fab2_lib.baseboard_fab2(sch_1):page144_i150:\2\"
				( attribute "PN" "2"
					( Origin gPackager )
				)
				( objectStatus "R25W58.2" )
			)
			( pin "@baseboard_fab2_lib.baseboard_fab2(sch_1):page249_i2:a"
				( attribute "PN" "1"
					( Origin gPackager )
				)
				( objectStatus "R3W1.1" )
			)
			( pin "@baseboard_fab2_lib.baseboard_fab2(sch_1):page249_i2:b"
				( attribute "PN" "2"
					( Origin gPackager )
				)
				( objectStatus "R3W1.2" )
			)
			( pin "@baseboard_fab2_lib.baseboard_fab2(sch_1):page249_i7:a"
				( attribute "PN" "1"
					( Origin gPackager )
				)
				( objectStatus "R3W9.1" )
			)
			( pin "@baseboard_fab2_lib.baseboard_fab2(sch_1):page249_i7:b"
				( attribute "PN" "2"
					( Origin gPackager )
				)
				( objectStatus "R3W9.2" )
			)
			( pin "@baseboard_fab2_lib.baseboard_fab2(sch_1):page249_i8:a"
				( attribute "PN" "1"
					( Origin gPackager )
				)
				( objectStatus "R3W7.1" )
			)
			( pin "@baseboard_fab2_lib.baseboard_fab2(sch_1):page249_i8:b"
				( attribute "PN" "2"
					( Origin gPackager )
				)
				( objectStatus "R3W7.2" )
			)
			( pin "@baseboard_fab2_lib.baseboard_fab2(sch_1):page249_i31:\1\"
				( attribute "PN" "1"
					( Origin gPackager )
				)
				( objectStatus "R3W4.1" )
			)
			( pin "@baseboard_fab2_lib.baseboard_fab2(sch_1):page249_i31:\2\"
				( attribute "PN" "2"
					( Origin gPackager )
				)
				( objectStatus "R3W4.2" )
			)
			( pin "@baseboard_fab2_lib.baseboard_fab2(sch_1):page249_i15:\+in\"
				( attribute "PN" "1"
					( Origin gPackager )
				)
				( objectStatus "Q9W4.1" )
			)
			( pin "@baseboard_fab2_lib.baseboard_fab2(sch_1):page249_i15:\-in\"
				( attribute "PN" "3"
					( Origin gPackager )
				)
				( objectStatus "Q9W4.3" )
			)
			( pin "@baseboard_fab2_lib.baseboard_fab2(sch_1):page249_i15:gnd"
				( attribute "PN" "2"
					( Origin gPackager )
				)
				( objectStatus "Q9W4.2" )
			)
			( pin "@baseboard_fab2_lib.baseboard_fab2(sch_1):page249_i15:\out\"
				( attribute "PN" "4"
					( Origin gPackager )
				)
				( objectStatus "Q9W4.4" )
			)
			( pin "@baseboard_fab2_lib.baseboard_fab2(sch_1):page249_i15:vcc"
				( attribute "PN" "5"
					( Origin gPackager )
				)
				( objectStatus "Q9W4.5" )
			)
			( pin "@baseboard_fab2_lib.baseboard_fab2(sch_1):page133_i365:a"
				( attribute "PN" "1"
					( Origin gPackager )
				)
				( objectStatus "R3P53.1" )
			)
			( pin "@baseboard_fab2_lib.baseboard_fab2(sch_1):page133_i365:b"
				( attribute "PN" "2"
					( Origin gPackager )
				)
				( objectStatus "R3P53.2" )
			)
			( pin "@baseboard_fab2_lib.baseboard_fab2(sch_1):page151_i217:a"
				( attribute "PN" "1"
					( Origin gPackager )
				)
				( objectStatus "C25W13.1" )
			)
			( pin "@baseboard_fab2_lib.baseboard_fab2(sch_1):page151_i217:b"
				( attribute "PN" "2"
					( Origin gPackager )
				)
				( objectStatus "C25W13.2" )
			)
			( pin "@baseboard_fab2_lib.baseboard_fab2(sch_1):page249_i48:a"
				( attribute "PN" "1"
					( Origin gPackager )
				)
				( objectStatus "R3W6.1" )
			)
			( pin "@baseboard_fab2_lib.baseboard_fab2(sch_1):page249_i48:b"
				( attribute "PN" "2"
					( Origin gPackager )
				)
				( objectStatus "R3W6.2" )
			)
			( pin "@baseboard_fab2_lib.baseboard_fab2(sch_1):page249_i57:a"
				( attribute "PN" "1"
					( Origin gPackager )
				)
				( objectStatus "C3W2.1" )
			)
			( pin "@baseboard_fab2_lib.baseboard_fab2(sch_1):page249_i57:b"
				( attribute "PN" "2"
					( Origin gPackager )
				)
				( objectStatus "C3W2.2" )
			)
			( pin "@baseboard_fab2_lib.baseboard_fab2(sch_1):page249_i29:b"
				( attribute "PN" "1"
					( Origin gPackager )
				)
				( objectStatus "Q9W2.1" )
			)
			( pin "@baseboard_fab2_lib.baseboard_fab2(sch_1):page249_i29:c"
				( attribute "PN" "3"
					( Origin gPackager )
				)
				( objectStatus "Q9W2.3" )
			)
			( pin "@baseboard_fab2_lib.baseboard_fab2(sch_1):page249_i29:e"
				( attribute "PN" "2"
					( Origin gPackager )
				)
				( objectStatus "Q9W2.2" )
			)
			( pin "@baseboard_fab2_lib.baseboard_fab2(sch_1):page248_i11:a(0)"
				( attribute "PN" "1"
					( Origin gPackager )
				)
				( objectStatus "U14E2.1" )
			)
			( pin "@baseboard_fab2_lib.baseboard_fab2(sch_1):page248_i11:b(0)"
				( attribute "PN" "2"
					( Origin gPackager )
				)
				( objectStatus "U14E2.2" )
			)
			( pin "@baseboard_fab2_lib.baseboard_fab2(sch_1):page248_i11:y(0)"
				( attribute "PN" "4"
					( Origin gPackager )
				)
				( objectStatus "U14E2.4" )
			)
			( pin "@baseboard_fab2_lib.baseboard_fab2(sch_1):page145_i120:a"
				( attribute "PN" "1"
					( Origin gPackager )
				)
				( objectStatus "R6W17.1" )
			)
			( pin "@baseboard_fab2_lib.baseboard_fab2(sch_1):page145_i120:b"
				( attribute "PN" "2"
					( Origin gPackager )
				)
				( objectStatus "R6W17.2" )
			)
			( pin "@baseboard_fab2_lib.baseboard_fab2(sch_1):page145_i38:a"
				( attribute "PN" "1"
					( Origin gPackager )
				)
				( objectStatus "R25W65.1" )
			)
			( pin "@baseboard_fab2_lib.baseboard_fab2(sch_1):page145_i38:b"
				( attribute "PN" "2"
					( Origin gPackager )
				)
				( objectStatus "R25W65.2" )
			)
			( pin "@baseboard_fab2_lib.baseboard_fab2(sch_1):page145_i36:a"
				( attribute "PN" "1"
					( Origin gPackager )
				)
				( objectStatus "R25W64.1" )
			)
			( pin "@baseboard_fab2_lib.baseboard_fab2(sch_1):page145_i36:b"
				( attribute "PN" "2"
					( Origin gPackager )
				)
				( objectStatus "R25W64.2" )
			)
			( pin "@baseboard_fab2_lib.baseboard_fab2(sch_1):page151_i269:\1\"
				( attribute "PN" "1"
					( Origin gPackager )
				)
				( objectStatus "R25W23.1" )
			)
			( pin "@baseboard_fab2_lib.baseboard_fab2(sch_1):page151_i269:\2\"
				( attribute "PN" "2"
					( Origin gPackager )
				)
				( objectStatus "R25W23.2" )
			)
			( pin "@baseboard_fab2_lib.baseboard_fab2(sch_1):page151_i138:a"
				( attribute "PN" "1"
					( Origin gPackager )
				)
				( objectStatus "R9E24.1" )
			)
			( pin "@baseboard_fab2_lib.baseboard_fab2(sch_1):page151_i138:b"
				( attribute "PN" "2"
					( Origin gPackager )
				)
				( objectStatus "R9E24.2" )
			)
			( pin "@baseboard_fab2_lib.baseboard_fab2(sch_1):page145_i15:a"
				( attribute "PN" "1"
					( Origin gPackager )
				)
				( objectStatus "C9F23.1" )
			)
			( pin "@baseboard_fab2_lib.baseboard_fab2(sch_1):page145_i15:b"
				( attribute "PN" "2"
					( Origin gPackager )
				)
				( objectStatus "C9F23.2" )
			)
			( pin "@baseboard_fab2_lib.baseboard_fab2(sch_1):page145_i20:a"
				( attribute "PN" "1"
					( Origin gPackager )
				)
				( objectStatus "R9F33.1" )
			)
			( pin "@baseboard_fab2_lib.baseboard_fab2(sch_1):page145_i20:b"
				( attribute "PN" "2"
					( Origin gPackager )
				)
				( objectStatus "R9F33.2" )
			)
			( pin "@baseboard_fab2_lib.baseboard_fab2(sch_1):page197_i111:\1\"
				( attribute "PN" "1"
					( Origin gPackager )
				)
				( objectStatus "R12W5.1" )
			)
			( pin "@baseboard_fab2_lib.baseboard_fab2(sch_1):page197_i111:\2\"
				( attribute "PN" "2"
					( Origin gPackager )
				)
				( objectStatus "R12W5.2" )
			)
			( pin "@baseboard_fab2_lib.baseboard_fab2(sch_1):page147_i162:a"
				( attribute "PN" "1"
					( Origin gPackager )
				)
				( objectStatus "C25W8.1" )
			)
			( pin "@baseboard_fab2_lib.baseboard_fab2(sch_1):page147_i162:b"
				( attribute "PN" "2"
					( Origin gPackager )
				)
				( objectStatus "C25W8.2" )
			)
			( pin "@baseboard_fab2_lib.baseboard_fab2(sch_1):page145_i30:a"
				( attribute "PN" "1"
					( Origin gPackager )
				)
				( objectStatus "R25W61.1" )
			)
			( pin "@baseboard_fab2_lib.baseboard_fab2(sch_1):page145_i30:b"
				( attribute "PN" "2"
					( Origin gPackager )
				)
				( objectStatus "R25W61.2" )
			)
			( pin "@baseboard_fab2_lib.baseboard_fab2(sch_1):page145_i31:a"
				( attribute "PN" "1"
					( Origin gPackager )
				)
				( objectStatus "R25W62.1" )
			)
			( pin "@baseboard_fab2_lib.baseboard_fab2(sch_1):page145_i31:b"
				( attribute "PN" "2"
					( Origin gPackager )
				)
				( objectStatus "R25W62.2" )
			)
			( pin "@baseboard_fab2_lib.baseboard_fab2(sch_1):page247_i100:a"
				( attribute "PN" "1"
					( Origin gPackager )
				)
				( objectStatus "R6W24.1" )
			)
			( pin "@baseboard_fab2_lib.baseboard_fab2(sch_1):page247_i100:b"
				( attribute "PN" "2"
					( Origin gPackager )
				)
				( objectStatus "R6W24.2" )
			)
			( pin "@baseboard_fab2_lib.baseboard_fab2(sch_1):page150_i190:a"
				( attribute "PN" "1"
					( Origin gPackager )
				)
				( objectStatus "R25W107.1" )
			)
			( pin "@baseboard_fab2_lib.baseboard_fab2(sch_1):page150_i190:b"
				( attribute "PN" "2"
					( Origin gPackager )
				)
				( objectStatus "R25W107.2" )
			)
			( pin "@baseboard_fab2_lib.baseboard_fab2(sch_1):page157_i393:a"
				( attribute "PN" "1"
					( Origin gPackager )
				)
				( objectStatus "R9E14.1" )
			)
			( pin "@baseboard_fab2_lib.baseboard_fab2(sch_1):page157_i393:b"
				( attribute "PN" "2"
					( Origin gPackager )
				)
				( objectStatus "R9E14.2" )
			)
			( pin "@baseboard_fab2_lib.baseboard_fab2(sch_1):page219_i153:\1\"
				( attribute "PN" "1"
					( Origin gPackager )
				)
				( objectStatus "RT29.1" )
			)
			( pin "@baseboard_fab2_lib.baseboard_fab2(sch_1):page219_i153:\2\"
				( attribute "PN" "2"
					( Origin gPackager )
				)
				( objectStatus "RT29.2" )
			)
			( pin "@baseboard_fab2_lib.baseboard_fab2(sch_1):page151_i55:a"
				( attribute "PN" "1"
					( Origin gPackager )
				)
				( objectStatus "R9F29.1" )
			)
			( pin "@baseboard_fab2_lib.baseboard_fab2(sch_1):page151_i55:b"
				( attribute "PN" "2"
					( Origin gPackager )
				)
				( objectStatus "R9F29.2" )
			)
			( pin "@baseboard_fab2_lib.baseboard_fab2(sch_1):page150_i144:a"
				( attribute "PN" "1"
					( Origin gPackager )
				)
				( objectStatus "R25W95.1" )
			)
			( pin "@baseboard_fab2_lib.baseboard_fab2(sch_1):page150_i144:b"
				( attribute "PN" "2"
					( Origin gPackager )
				)
				( objectStatus "R25W95.2" )
			)
			( pin "@baseboard_fab2_lib.baseboard_fab2(sch_1):page150_i145:a"
				( attribute "PN" "1"
					( Origin gPackager )
				)
				( objectStatus "R25W96.1" )
			)
			( pin "@baseboard_fab2_lib.baseboard_fab2(sch_1):page150_i145:b"
				( attribute "PN" "2"
					( Origin gPackager )
				)
				( objectStatus "R25W96.2" )
			)
			( pin "@baseboard_fab2_lib.baseboard_fab2(sch_1):page150_i146:a"
				( attribute "PN" "1"
					( Origin gPackager )
				)
				( objectStatus "R25W97.1" )
			)
			( pin "@baseboard_fab2_lib.baseboard_fab2(sch_1):page150_i146:b"
				( attribute "PN" "2"
					( Origin gPackager )
				)
				( objectStatus "R25W97.2" )
			)
			( pin "@baseboard_fab2_lib.baseboard_fab2(sch_1):page150_i232:a"
				( attribute "PN" "1"
					( Origin gPackager )
				)
				( objectStatus "R25W151.1" )
			)
			( pin "@baseboard_fab2_lib.baseboard_fab2(sch_1):page150_i232:b"
				( attribute "PN" "2"
					( Origin gPackager )
				)
				( objectStatus "R25W151.2" )
			)
			( pin "@baseboard_fab2_lib.baseboard_fab2(sch_1):page150_i230:a"
				( attribute "PN" "1"
					( Origin gPackager )
				)
				( objectStatus "R25W113.1" )
			)
			( pin "@baseboard_fab2_lib.baseboard_fab2(sch_1):page150_i230:b"
				( attribute "PN" "2"
					( Origin gPackager )
				)
				( objectStatus "R25W113.2" )
			)
			( pin "@baseboard_fab2_lib.baseboard_fab2(sch_1):page150_i228:a"
				( attribute "PN" "1"
					( Origin gPackager )
				)
				( objectStatus "R25W112.1" )
			)
			( pin "@baseboard_fab2_lib.baseboard_fab2(sch_1):page150_i228:b"
				( attribute "PN" "2"
					( Origin gPackager )
				)
				( objectStatus "R25W112.2" )
			)
			( pin "@baseboard_fab2_lib.baseboard_fab2(sch_1):page150_i239:a"
				( attribute "PN" "1"
					( Origin gPackager )
				)
				( objectStatus "R25W102.1" )
			)
			( pin "@baseboard_fab2_lib.baseboard_fab2(sch_1):page150_i239:b"
				( attribute "PN" "2"
					( Origin gPackager )
				)
				( objectStatus "R25W102.2" )
			)
			( pin "@baseboard_fab2_lib.baseboard_fab2(sch_1):page147_i156:a"
				( attribute "PN" "1"
					( Origin gPackager )
				)
				( objectStatus "R25W142.1" )
			)
			( pin "@baseboard_fab2_lib.baseboard_fab2(sch_1):page147_i156:b"
				( attribute "PN" "2"
					( Origin gPackager )
				)
				( objectStatus "R25W142.2" )
			)
			( pin "@baseboard_fab2_lib.baseboard_fab2(sch_1):page150_i175:a"
				( attribute "PN" "1"
					( Origin gPackager )
				)
				( objectStatus "R25W106.1" )
			)
			( pin "@baseboard_fab2_lib.baseboard_fab2(sch_1):page150_i175:b"
				( attribute "PN" "2"
					( Origin gPackager )
				)
				( objectStatus "R25W106.2" )
			)
			( pin "@baseboard_fab2_lib.baseboard_fab2(sch_1):page207_i112:\1\"
				( attribute "PN" "1"
					( Origin gPackager )
				)
				( objectStatus "RT18.1" )
			)
			( pin "@baseboard_fab2_lib.baseboard_fab2(sch_1):page207_i112:\2\"
				( attribute "PN" "2"
					( Origin gPackager )
				)
				( objectStatus "RT18.2" )
			)
			( pin "@baseboard_fab2_lib.baseboard_fab2(sch_1):page205_i84:\1\"
				( attribute "PN" "1"
					( Origin gPackager )
				)
				( objectStatus "RT39.1" )
			)
			( pin "@baseboard_fab2_lib.baseboard_fab2(sch_1):page205_i84:\2\"
				( attribute "PN" "2"
					( Origin gPackager )
				)
				( objectStatus "RT39.2" )
			)
			( pin "@baseboard_fab2_lib.baseboard_fab2(sch_1):page151_i49:a0"
				( attribute "PN" "P3"
					( Origin gPackager )
				)
				( objectStatus "U25W5.P3" )
			)
			( pin "@baseboard_fab2_lib.baseboard_fab2(sch_1):page151_i49:a1"
				( attribute "PN" "P7"
					( Origin gPackager )
				)
				( objectStatus "U25W5.P7" )
			)
			( pin "@baseboard_fab2_lib.baseboard_fab2(sch_1):page151_i49:a2"
				( attribute "PN" "R3"
					( Origin gPackager )
				)
				( objectStatus "U25W5.R3" )
			)
			( pin "@baseboard_fab2_lib.baseboard_fab2(sch_1):page151_i49:a3"
				( attribute "PN" "N7"
					( Origin gPackager )
				)
				( objectStatus "U25W5.N7" )
			)
			( pin "@baseboard_fab2_lib.baseboard_fab2(sch_1):page151_i49:a4"
				( attribute "PN" "N3"
					( Origin gPackager )
				)
				( objectStatus "U25W5.N3" )
			)
			( pin "@baseboard_fab2_lib.baseboard_fab2(sch_1):page151_i49:a5"
				( attribute "PN" "P8"
					( Origin gPackager )
				)
				( objectStatus "U25W5.P8" )
			)
			( pin "@baseboard_fab2_lib.baseboard_fab2(sch_1):page151_i49:a6"
				( attribute "PN" "P2"
					( Origin gPackager )
				)
				( objectStatus "U25W5.P2" )
			)
			( pin "@baseboard_fab2_lib.baseboard_fab2(sch_1):page151_i49:a7"
				( attribute "PN" "R8"
					( Origin gPackager )
				)
				( objectStatus "U25W5.R8" )
			)
			( pin "@baseboard_fab2_lib.baseboard_fab2(sch_1):page151_i49:a8"
				( attribute "PN" "R2"
					( Origin gPackager )
				)
				( objectStatus "U25W5.R2" )
			)
			( pin "@baseboard_fab2_lib.baseboard_fab2(sch_1):page151_i49:a9"
				( attribute "PN" "R7"
					( Origin gPackager )
				)
				( objectStatus "U25W5.R7" )
			)
			( pin "@baseboard_fab2_lib.baseboard_fab2(sch_1):page151_i49:\a10/ap\"
				( attribute "PN" "M3"
					( Origin gPackager )
				)
				( objectStatus "U25W5.M3" )
			)
			( pin "@baseboard_fab2_lib.baseboard_fab2(sch_1):page151_i49:a11"
				( attribute "PN" "T2"
					( Origin gPackager )
				)
				( objectStatus "U25W5.T2" )
			)
			( pin "@baseboard_fab2_lib.baseboard_fab2(sch_1):page151_i49:\a12/bc#\"
				( attribute "PN" "M7"
					( Origin gPackager )
				)
				( objectStatus "U25W5.M7" )
			)
			( pin "@baseboard_fab2_lib.baseboard_fab2(sch_1):page151_i49:a13"
				( attribute "PN" "T8"
					( Origin gPackager )
				)
				( objectStatus "U25W5.T8" )
			)
			( pin "@baseboard_fab2_lib.baseboard_fab2(sch_1):page151_i49:\act#\"
				( attribute "PN" "L3"
					( Origin gPackager )
				)
				( objectStatus "U25W5.L3" )
			)
			( pin "@baseboard_fab2_lib.baseboard_fab2(sch_1):page151_i49:\alert#\"
				( attribute "PN" "P9"
					( Origin gPackager )
				)
				( objectStatus "U25W5.P9" )
			)
			( pin "@baseboard_fab2_lib.baseboard_fab2(sch_1):page151_i49:ba0"
				( attribute "PN" "N2"
					( Origin gPackager )
				)
				( objectStatus "U25W5.N2" )
			)
			( pin "@baseboard_fab2_lib.baseboard_fab2(sch_1):page151_i49:ba1"
				( attribute "PN" "N8"
					( Origin gPackager )
				)
				( objectStatus "U25W5.N8" )
			)
			( pin "@baseboard_fab2_lib.baseboard_fab2(sch_1):page151_i49:bg0"
				( attribute "PN" "M2"
					( Origin gPackager )
				)
				( objectStatus "U25W5.M2" )
			)
			( pin "@baseboard_fab2_lib.baseboard_fab2(sch_1):page151_i49:\cas#/a15\"
				( attribute "PN" "M8"
					( Origin gPackager )
				)
				( objectStatus "U25W5.M8" )
			)
			( pin "@baseboard_fab2_lib.baseboard_fab2(sch_1):page151_i49:ck_c"
				( attribute "PN" "K8"
					( Origin gPackager )
				)
				( objectStatus "U25W5.K8" )
			)
			( pin "@baseboard_fab2_lib.baseboard_fab2(sch_1):page151_i49:ck_t"
				( attribute "PN" "K7"
					( Origin gPackager )
				)
				( objectStatus "U25W5.K7" )
			)
			( pin "@baseboard_fab2_lib.baseboard_fab2(sch_1):page151_i49:cke"
				( attribute "PN" "K2"
					( Origin gPackager )
				)
				( objectStatus "U25W5.K2" )
			)
			( pin "@baseboard_fab2_lib.baseboard_fab2(sch_1):page151_i49:\cs#\"
				( attribute "PN" "L7"
					( Origin gPackager )
				)
				( objectStatus "U25W5.L7" )
			)
			( pin "@baseboard_fab2_lib.baseboard_fab2(sch_1):page151_i49:\dml#/dbil#\"
				( attribute "PN" "E7"
					( Origin gPackager )
				)
				( objectStatus "U25W5.E7" )
			)
			( pin "@baseboard_fab2_lib.baseboard_fab2(sch_1):page151_i49:\dmu#/dbiu#\"
				( attribute "PN" "E2"
					( Origin gPackager )
				)
				( objectStatus "U25W5.E2" )
			)
			( pin "@baseboard_fab2_lib.baseboard_fab2(sch_1):page151_i49:dql0"
				( attribute "PN" "G2"
					( Origin gPackager )
				)
				( objectStatus "U25W5.G2" )
			)
			( pin "@baseboard_fab2_lib.baseboard_fab2(sch_1):page151_i49:dql1"
				( attribute "PN" "F7"
					( Origin gPackager )
				)
				( objectStatus "U25W5.F7" )
			)
			( pin "@baseboard_fab2_lib.baseboard_fab2(sch_1):page151_i49:dql2"
				( attribute "PN" "H3"
					( Origin gPackager )
				)
				( objectStatus "U25W5.H3" )
			)
			( pin "@baseboard_fab2_lib.baseboard_fab2(sch_1):page151_i49:dql3"
				( attribute "PN" "H7"
					( Origin gPackager )
				)
				( objectStatus "U25W5.H7" )
			)
			( pin "@baseboard_fab2_lib.baseboard_fab2(sch_1):page151_i49:dql4"
				( attribute "PN" "H2"
					( Origin gPackager )
				)
				( objectStatus "U25W5.H2" )
			)
			( pin "@baseboard_fab2_lib.baseboard_fab2(sch_1):page151_i49:dql5"
				( attribute "PN" "H8"
					( Origin gPackager )
				)
				( objectStatus "U25W5.H8" )
			)
			( pin "@baseboard_fab2_lib.baseboard_fab2(sch_1):page151_i49:dql6"
				( attribute "PN" "J3"
					( Origin gPackager )
				)
				( objectStatus "U25W5.J3" )
			)
			( pin "@baseboard_fab2_lib.baseboard_fab2(sch_1):page151_i49:dql7"
				( attribute "PN" "J7"
					( Origin gPackager )
				)
				( objectStatus "U25W5.J7" )
			)
			( pin "@baseboard_fab2_lib.baseboard_fab2(sch_1):page151_i49:dqsl_c"
				( attribute "PN" "F3"
					( Origin gPackager )
				)
				( objectStatus "U25W5.F3" )
			)
			( pin "@baseboard_fab2_lib.baseboard_fab2(sch_1):page151_i49:dqsl_t"
				( attribute "PN" "G3"
					( Origin gPackager )
				)
				( objectStatus "U25W5.G3" )
			)
			( pin "@baseboard_fab2_lib.baseboard_fab2(sch_1):page151_i49:dqsu_c"
				( attribute "PN" "A7"
					( Origin gPackager )
				)
				( objectStatus "U25W5.A7" )
			)
			( pin "@baseboard_fab2_lib.baseboard_fab2(sch_1):page151_i49:dqsu_t"
				( attribute "PN" "B7"
					( Origin gPackager )
				)
				( objectStatus "U25W5.B7" )
			)
			( pin "@baseboard_fab2_lib.baseboard_fab2(sch_1):page151_i49:dqu0"
				( attribute "PN" "A3"
					( Origin gPackager )
				)
				( objectStatus "U25W5.A3" )
			)
			( pin "@baseboard_fab2_lib.baseboard_fab2(sch_1):page151_i49:dqu1"
				( attribute "PN" "B8"
					( Origin gPackager )
				)
				( objectStatus "U25W5.B8" )
			)
			( pin "@baseboard_fab2_lib.baseboard_fab2(sch_1):page151_i49:dqu2"
				( attribute "PN" "C3"
					( Origin gPackager )
				)
				( objectStatus "U25W5.C3" )
			)
			( pin "@baseboard_fab2_lib.baseboard_fab2(sch_1):page151_i49:dqu3"
				( attribute "PN" "C7"
					( Origin gPackager )
				)
				( objectStatus "U25W5.C7" )
			)
			( pin "@baseboard_fab2_lib.baseboard_fab2(sch_1):page151_i49:dqu4"
				( attribute "PN" "C2"
					( Origin gPackager )
				)
				( objectStatus "U25W5.C2" )
			)
			( pin "@baseboard_fab2_lib.baseboard_fab2(sch_1):page151_i49:dqu5"
				( attribute "PN" "C8"
					( Origin gPackager )
				)
				( objectStatus "U25W5.C8" )
			)
			( pin "@baseboard_fab2_lib.baseboard_fab2(sch_1):page151_i49:dqu6"
				( attribute "PN" "D3"
					( Origin gPackager )
				)
				( objectStatus "U25W5.D3" )
			)
			( pin "@baseboard_fab2_lib.baseboard_fab2(sch_1):page151_i49:dqu7"
				( attribute "PN" "D7"
					( Origin gPackager )
				)
				( objectStatus "U25W5.D7" )
			)
			( pin "@baseboard_fab2_lib.baseboard_fab2(sch_1):page151_i49:\nc#t7\"
				( attribute "PN" "T7"
					( Origin gPackager )
				)
				( objectStatus "U25W5.T7" )
			)
			( pin "@baseboard_fab2_lib.baseboard_fab2(sch_1):page151_i49:odt"
				( attribute "PN" "K3"
					( Origin gPackager )
				)
				( objectStatus "U25W5.K3" )
			)
			( pin "@baseboard_fab2_lib.baseboard_fab2(sch_1):page151_i49:par"
				( attribute "PN" "T3"
					( Origin gPackager )
				)
				( objectStatus "U25W5.T3" )
			)
			( pin "@baseboard_fab2_lib.baseboard_fab2(sch_1):page151_i49:\ras#/a16\"
				( attribute "PN" "L8"
					( Origin gPackager )
				)
				( objectStatus "U25W5.L8" )
			)
			( pin "@baseboard_fab2_lib.baseboard_fab2(sch_1):page151_i49:\reset#\"
				( attribute "PN" "P1"
					( Origin gPackager )
				)
				( objectStatus "U25W5.P1" )
			)
			( pin "@baseboard_fab2_lib.baseboard_fab2(sch_1):page151_i49:ten"
				( attribute "PN" "N9"
					( Origin gPackager )
				)
				( objectStatus "U25W5.N9" )
			)
			( pin "@baseboard_fab2_lib.baseboard_fab2(sch_1):page151_i49:vdd(0)"
				( attribute "PN" "B3"
					( Origin gPackager )
				)
				( objectStatus "U25W5.B3" )
			)
			( pin "@baseboard_fab2_lib.baseboard_fab2(sch_1):page151_i49:vdd(1)"
				( attribute "PN" "B9"
					( Origin gPackager )
				)
				( objectStatus "U25W5.B9" )
			)
			( pin "@baseboard_fab2_lib.baseboard_fab2(sch_1):page151_i49:vdd(2)"
				( attribute "PN" "D1"
					( Origin gPackager )
				)
				( objectStatus "U25W5.D1" )
			)
			( pin "@baseboard_fab2_lib.baseboard_fab2(sch_1):page151_i49:vdd(3)"
				( attribute "PN" "G7"
					( Origin gPackager )
				)
				( objectStatus "U25W5.G7" )
			)
			( pin "@baseboard_fab2_lib.baseboard_fab2(sch_1):page151_i49:vdd(4)"
				( attribute "PN" "J1"
					( Origin gPackager )
				)
				( objectStatus "U25W5.J1" )
			)
			( pin "@baseboard_fab2_lib.baseboard_fab2(sch_1):page151_i49:vdd(5)"
				( attribute "PN" "J9"
					( Origin gPackager )
				)
				( objectStatus "U25W5.J9" )
			)
			( pin "@baseboard_fab2_lib.baseboard_fab2(sch_1):page151_i49:vdd(6)"
				( attribute "PN" "L1"
					( Origin gPackager )
				)
				( objectStatus "U25W5.L1" )
			)
			( pin "@baseboard_fab2_lib.baseboard_fab2(sch_1):page151_i49:vdd(7)"
				( attribute "PN" "L9"
					( Origin gPackager )
				)
				( objectStatus "U25W5.L9" )
			)
			( pin "@baseboard_fab2_lib.baseboard_fab2(sch_1):page151_i49:vdd(8)"
				( attribute "PN" "R1"
					( Origin gPackager )
				)
				( objectStatus "U25W5.R1" )
			)
			( pin "@baseboard_fab2_lib.baseboard_fab2(sch_1):page151_i49:vdd(9)"
				( attribute "PN" "T9"
					( Origin gPackager )
				)
				( objectStatus "U25W5.T9" )
			)
			( pin "@baseboard_fab2_lib.baseboard_fab2(sch_1):page151_i49:vddq(0)"
				( attribute "PN" "A1"
					( Origin gPackager )
				)
				( objectStatus "U25W5.A1" )
			)
			( pin "@baseboard_fab2_lib.baseboard_fab2(sch_1):page151_i49:vddq(1)"
				( attribute "PN" "A9"
					( Origin gPackager )
				)
				( objectStatus "U25W5.A9" )
			)
			( pin "@baseboard_fab2_lib.baseboard_fab2(sch_1):page151_i49:vddq(2)"
				( attribute "PN" "C1"
					( Origin gPackager )
				)
				( objectStatus "U25W5.C1" )
			)
			( pin "@baseboard_fab2_lib.baseboard_fab2(sch_1):page151_i49:vddq(3)"
				( attribute "PN" "D9"
					( Origin gPackager )
				)
				( objectStatus "U25W5.D9" )
			)
			( pin "@baseboard_fab2_lib.baseboard_fab2(sch_1):page151_i49:vddq(4)"
				( attribute "PN" "F2"
					( Origin gPackager )
				)
				( objectStatus "U25W5.F2" )
			)
			( pin "@baseboard_fab2_lib.baseboard_fab2(sch_1):page151_i49:vddq(5)"
				( attribute "PN" "F8"
					( Origin gPackager )
				)
				( objectStatus "U25W5.F8" )
			)
			( pin "@baseboard_fab2_lib.baseboard_fab2(sch_1):page151_i49:vddq(6)"
				( attribute "PN" "G1"
					( Origin gPackager )
				)
				( objectStatus "U25W5.G1" )
			)
			( pin "@baseboard_fab2_lib.baseboard_fab2(sch_1):page151_i49:vddq(7)"
				( attribute "PN" "G9"
					( Origin gPackager )
				)
				( objectStatus "U25W5.G9" )
			)
			( pin "@baseboard_fab2_lib.baseboard_fab2(sch_1):page151_i49:vddq(8)"
				( attribute "PN" "J2"
					( Origin gPackager )
				)
				( objectStatus "U25W5.J2" )
			)
			( pin "@baseboard_fab2_lib.baseboard_fab2(sch_1):page151_i49:vddq(9)"
				( attribute "PN" "J8"
					( Origin gPackager )
				)
				( objectStatus "U25W5.J8" )
			)
			( pin "@baseboard_fab2_lib.baseboard_fab2(sch_1):page151_i49:vpp(0)"
				( attribute "PN" "B1"
					( Origin gPackager )
				)
				( objectStatus "U25W5.B1" )
			)
			( pin "@baseboard_fab2_lib.baseboard_fab2(sch_1):page151_i49:vpp(1)"
				( attribute "PN" "R9"
					( Origin gPackager )
				)
				( objectStatus "U25W5.R9" )
			)
			( pin "@baseboard_fab2_lib.baseboard_fab2(sch_1):page151_i49:vrefca"
				( attribute "PN" "M1"
					( Origin gPackager )
				)
				( objectStatus "U25W5.M1" )
			)
			( pin "@baseboard_fab2_lib.baseboard_fab2(sch_1):page151_i49:vss(0)"
				( attribute "PN" "B2"
					( Origin gPackager )
				)
				( objectStatus "U25W5.B2" )
			)
			( pin "@baseboard_fab2_lib.baseboard_fab2(sch_1):page151_i49:vss(1)"
				( attribute "PN" "E1"
					( Origin gPackager )
				)
				( objectStatus "U25W5.E1" )
			)
			( pin "@baseboard_fab2_lib.baseboard_fab2(sch_1):page151_i49:vss(2)"
				( attribute "PN" "E9"
					( Origin gPackager )
				)
				( objectStatus "U25W5.E9" )
			)
			( pin "@baseboard_fab2_lib.baseboard_fab2(sch_1):page151_i49:vss(3)"
				( attribute "PN" "G8"
					( Origin gPackager )
				)
				( objectStatus "U25W5.G8" )
			)
			( pin "@baseboard_fab2_lib.baseboard_fab2(sch_1):page151_i49:vss(4)"
				( attribute "PN" "K1"
					( Origin gPackager )
				)
				( objectStatus "U25W5.K1" )
			)
			( pin "@baseboard_fab2_lib.baseboard_fab2(sch_1):page151_i49:vss(5)"
				( attribute "PN" "K9"
					( Origin gPackager )
				)
				( objectStatus "U25W5.K9" )
			)
			( pin "@baseboard_fab2_lib.baseboard_fab2(sch_1):page151_i49:vss(6)"
				( attribute "PN" "M9"
					( Origin gPackager )
				)
				( objectStatus "U25W5.M9" )
			)
			( pin "@baseboard_fab2_lib.baseboard_fab2(sch_1):page151_i49:vss(7)"
				( attribute "PN" "N1"
					( Origin gPackager )
				)
				( objectStatus "U25W5.N1" )
			)
			( pin "@baseboard_fab2_lib.baseboard_fab2(sch_1):page151_i49:vss(8)"
				( attribute "PN" "T1"
					( Origin gPackager )
				)
				( objectStatus "U25W5.T1" )
			)
			( pin "@baseboard_fab2_lib.baseboard_fab2(sch_1):page151_i49:vssq(0)"
				( attribute "PN" "A2"
					( Origin gPackager )
				)
				( objectStatus "U25W5.A2" )
			)
			( pin "@baseboard_fab2_lib.baseboard_fab2(sch_1):page151_i49:vssq(1)"
				( attribute "PN" "A8"
					( Origin gPackager )
				)
				( objectStatus "U25W5.A8" )
			)
			( pin "@baseboard_fab2_lib.baseboard_fab2(sch_1):page151_i49:vssq(2)"
				( attribute "PN" "C9"
					( Origin gPackager )
				)
				( objectStatus "U25W5.C9" )
			)
			( pin "@baseboard_fab2_lib.baseboard_fab2(sch_1):page151_i49:vssq(3)"
				( attribute "PN" "D2"
					( Origin gPackager )
				)
				( objectStatus "U25W5.D2" )
			)
			( pin "@baseboard_fab2_lib.baseboard_fab2(sch_1):page151_i49:vssq(4)"
				( attribute "PN" "D8"
					( Origin gPackager )
				)
				( objectStatus "U25W5.D8" )
			)
			( pin "@baseboard_fab2_lib.baseboard_fab2(sch_1):page151_i49:vssq(5)"
				( attribute "PN" "E3"
					( Origin gPackager )
				)
				( objectStatus "U25W5.E3" )
			)
			( pin "@baseboard_fab2_lib.baseboard_fab2(sch_1):page151_i49:vssq(6)"
				( attribute "PN" "E8"
					( Origin gPackager )
				)
				( objectStatus "U25W5.E8" )
			)
			( pin "@baseboard_fab2_lib.baseboard_fab2(sch_1):page151_i49:vssq(7)"
				( attribute "PN" "F1"
					( Origin gPackager )
				)
				( objectStatus "U25W5.F1" )
			)
			( pin "@baseboard_fab2_lib.baseboard_fab2(sch_1):page151_i49:vssq(8)"
				( attribute "PN" "H1"
					( Origin gPackager )
				)
				( objectStatus "U25W5.H1" )
			)
			( pin "@baseboard_fab2_lib.baseboard_fab2(sch_1):page151_i49:vssq(9)"
				( attribute "PN" "H9"
					( Origin gPackager )
				)
				( objectStatus "U25W5.H9" )
			)
			( pin "@baseboard_fab2_lib.baseboard_fab2(sch_1):page151_i49:\we#/a14\"
				( attribute "PN" "L2"
					( Origin gPackager )
				)
				( objectStatus "U25W5.L2" )
			)
			( pin "@baseboard_fab2_lib.baseboard_fab2(sch_1):page151_i49:zq"
				( attribute "PN" "F9"
					( Origin gPackager )
				)
				( objectStatus "U25W5.F9" )
			)
			( pin "@baseboard_fab2_lib.baseboard_fab2(sch_1):page155_i196:a"
				( attribute "PN" "1"
					( Origin gPackager )
				)
				( objectStatus "R6W19.1" )
			)
			( pin "@baseboard_fab2_lib.baseboard_fab2(sch_1):page155_i196:b"
				( attribute "PN" "2"
					( Origin gPackager )
				)
				( objectStatus "R6W19.2" )
			)
			( pin "@baseboard_fab2_lib.baseboard_fab2(sch_1):page146_i68:a"
				( attribute "PN" "1"
					( Origin gPackager )
				)
				( objectStatus "R25W82.1" )
			)
			( pin "@baseboard_fab2_lib.baseboard_fab2(sch_1):page146_i68:b"
				( attribute "PN" "2"
					( Origin gPackager )
				)
				( objectStatus "R25W82.2" )
			)
			( pin "@baseboard_fab2_lib.baseboard_fab2(sch_1):page149_i1:a"
				( attribute "PN" "1"
					( Origin gPackager )
				)
				( objectStatus "C25W30.1" )
			)
			( pin "@baseboard_fab2_lib.baseboard_fab2(sch_1):page149_i1:b"
				( attribute "PN" "2"
					( Origin gPackager )
				)
				( objectStatus "C25W30.2" )
			)
			( pin "@baseboard_fab2_lib.baseboard_fab2(sch_1):page239_i73:adj_nc"
				( attribute "PN" "4"
					( Origin gPackager )
				)
				( objectStatus "EU25F2.4" )
			)
			( pin "@baseboard_fab2_lib.baseboard_fab2(sch_1):page239_i73:en"
				( attribute "PN" "6"
					( Origin gPackager )
				)
				( objectStatus "EU25F2.6" )
			)
			( pin "@baseboard_fab2_lib.baseboard_fab2(sch_1):page239_i73:gnd"
				( attribute "PN" "11"
					( Origin gPackager )
				)
				( objectStatus "EU25F2.11" )
			)
			( pin "@baseboard_fab2_lib.baseboard_fab2(sch_1):page239_i73:pgood"
				( attribute "PN" "5"
					( Origin gPackager )
				)
				( objectStatus "EU25F2.5" )
			)
			( pin "@baseboard_fab2_lib.baseboard_fab2(sch_1):page239_i73:vdd"
				( attribute "PN" "10"
					( Origin gPackager )
				)
				( objectStatus "EU25F2.10" )
			)
			( pin "@baseboard_fab2_lib.baseboard_fab2(sch_1):page239_i73:vin(0)"
				( attribute "PN" "7"
					( Origin gPackager )
				)
				( objectStatus "EU25F2.7" )
			)
			( pin "@baseboard_fab2_lib.baseboard_fab2(sch_1):page239_i73:vin(1)"
				( attribute "PN" "8"
					( Origin gPackager )
				)
				( objectStatus "EU25F2.8" )
			)
			( pin "@baseboard_fab2_lib.baseboard_fab2(sch_1):page239_i73:vin(2)"
				( attribute "PN" "9"
					( Origin gPackager )
				)
				( objectStatus "EU25F2.9" )
			)
			( pin "@baseboard_fab2_lib.baseboard_fab2(sch_1):page239_i73:vout(0)"
				( attribute "PN" "1"
					( Origin gPackager )
				)
				( objectStatus "EU25F2.1" )
			)
			( pin "@baseboard_fab2_lib.baseboard_fab2(sch_1):page239_i73:vout(1)"
				( attribute "PN" "2"
					( Origin gPackager )
				)
				( objectStatus "EU25F2.2" )
			)
			( pin "@baseboard_fab2_lib.baseboard_fab2(sch_1):page239_i73:vout(2)"
				( attribute "PN" "3"
					( Origin gPackager )
				)
				( objectStatus "EU25F2.3" )
			)
			( pin "@baseboard_fab2_lib.baseboard_fab2(sch_1):page239_i77:a"
				( attribute "PN" "1"
					( Origin gPackager )
				)
				( objectStatus "R1W9.1" )
			)
			( pin "@baseboard_fab2_lib.baseboard_fab2(sch_1):page239_i77:b"
				( attribute "PN" "2"
					( Origin gPackager )
				)
				( objectStatus "R1W9.2" )
			)
			( pin "@baseboard_fab2_lib.baseboard_fab2(sch_1):page239_i79:a"
				( attribute "PN" "1"
					( Origin gPackager )
				)
				( objectStatus "R9W12.1" )
			)
			( pin "@baseboard_fab2_lib.baseboard_fab2(sch_1):page239_i79:b"
				( attribute "PN" "2"
					( Origin gPackager )
				)
				( objectStatus "R9W12.2" )
			)
			( pin "@baseboard_fab2_lib.baseboard_fab2(sch_1):page239_i81:a"
				( attribute "PN" "1"
					( Origin gPackager )
				)
				( objectStatus "C9W13.1" )
			)
			( pin "@baseboard_fab2_lib.baseboard_fab2(sch_1):page239_i81:b"
				( attribute "PN" "2"
					( Origin gPackager )
				)
				( objectStatus "C9W13.2" )
			)
			( pin "@baseboard_fab2_lib.baseboard_fab2(sch_1):page239_i83:a"
				( attribute "PN" "1"
					( Origin gPackager )
				)
				( objectStatus "C1W15.1" )
			)
			( pin "@baseboard_fab2_lib.baseboard_fab2(sch_1):page239_i83:b"
				( attribute "PN" "2"
					( Origin gPackager )
				)
				( objectStatus "C1W15.2" )
			)
			( pin "@baseboard_fab2_lib.baseboard_fab2(sch_1):page239_i84:a"
				( attribute "PN" "1"
					( Origin gPackager )
				)
				( objectStatus "C9W10.1" )
			)
			( pin "@baseboard_fab2_lib.baseboard_fab2(sch_1):page239_i84:b"
				( attribute "PN" "2"
					( Origin gPackager )
				)
				( objectStatus "C9W10.2" )
			)
			( pin "@baseboard_fab2_lib.baseboard_fab2(sch_1):page239_i90:a"
				( attribute "PN" "1"
					( Origin gPackager )
				)
				( objectStatus "C9W5.1" )
			)
			( pin "@baseboard_fab2_lib.baseboard_fab2(sch_1):page239_i90:b"
				( attribute "PN" "2"
					( Origin gPackager )
				)
				( objectStatus "C9W5.2" )
			)
			( pin "@baseboard_fab2_lib.baseboard_fab2(sch_1):page239_i91:a"
				( attribute "PN" "1"
					( Origin gPackager )
				)
				( objectStatus "C9W6.1" )
			)
			( pin "@baseboard_fab2_lib.baseboard_fab2(sch_1):page239_i91:b"
				( attribute "PN" "2"
					( Origin gPackager )
				)
				( objectStatus "C9W6.2" )
			)
			( pin "@baseboard_fab2_lib.baseboard_fab2(sch_1):page239_i92:a"
				( attribute "PN" "1"
					( Origin gPackager )
				)
				( objectStatus "C1W7.1" )
			)
			( pin "@baseboard_fab2_lib.baseboard_fab2(sch_1):page239_i92:b"
				( attribute "PN" "2"
					( Origin gPackager )
				)
				( objectStatus "C1W7.2" )
			)
			( pin "@baseboard_fab2_lib.baseboard_fab2(sch_1):page144_i95:dacb"
				( attribute "PN" "J2"
					( Origin gPackager )
				)
				( objectStatus "U25W4.J2" )
			)
			( pin "@baseboard_fab2_lib.baseboard_fab2(sch_1):page144_i95:dacg"
				( attribute "PN" "J3"
					( Origin gPackager )
				)
				( objectStatus "U25W4.J3" )
			)
			( pin "@baseboard_fab2_lib.baseboard_fab2(sch_1):page144_i95:dacr"
				( attribute "PN" "J4"
					( Origin gPackager )
				)
				( objectStatus "U25W4.J4" )
			)
			( pin "@baseboard_fab2_lib.baseboard_fab2(sch_1):page144_i95:dacrset"
				( attribute "PN" "K4"
					( Origin gPackager )
				)
				( objectStatus "U25W4.K4" )
			)
			( pin "@baseboard_fab2_lib.baseboard_fab2(sch_1):page144_i95:gpioa4_timer5_scl9"
				( attribute "PN" "C14"
					( Origin gPackager )
				)
				( objectStatus "U25W4.C14" )
			)
			( pin "@baseboard_fab2_lib.baseboard_fab2(sch_1):page144_i95:gpioa5_timer6_sda9"
				( attribute "PN" "A13"
					( Origin gPackager )
				)
				( objectStatus "U25W4.A13" )
			)
			( pin "@baseboard_fab2_lib.baseboard_fab2(sch_1):page144_i95:gpiob0"
				( attribute "PN" "K19"
					( Origin gPackager )
				)
				( objectStatus "U25W4.K19" )
			)
			( pin "@baseboard_fab2_lib.baseboard_fab2(sch_1):page144_i95:gpiob1"
				( attribute "PN" "L19"
					( Origin gPackager )
				)
				( objectStatus "U25W4.L19" )
			)
			( pin "@baseboard_fab2_lib.baseboard_fab2(sch_1):page144_i95:gpiob2"
				( attribute "PN" "L18"
					( Origin gPackager )
				)
				( objectStatus "U25W4.L18" )
			)
			( pin "@baseboard_fab2_lib.baseboard_fab2(sch_1):page144_i95:gpiob3"
				( attribute "PN" "K18"
					( Origin gPackager )
				)
				( objectStatus "U25W4.K18" )
			)
			( pin "@baseboard_fab2_lib.baseboard_fab2(sch_1):page144_i95:gpiob4_usbcki"
				( attribute "PN" "J20"
					( Origin gPackager )
				)
				( objectStatus "U25W4.J20" )
			)
			( pin "@baseboard_fab2_lib.baseboard_fab2(sch_1):page144_i95:\gpiob5_lpcpd#_lpcsmi#\"
				( attribute "PN" "H21"
					( Origin gPackager )
				)
				( objectStatus "U25W4.H21" )
			)
			( pin "@baseboard_fab2_lib.baseboard_fab2(sch_1):page144_i95:\gpiob6_lpcpme#\"
				( attribute "PN" "H22"
					( Origin gPackager )
				)
				( objectStatus "U25W4.H22" )
			)
			( pin "@baseboard_fab2_lib.baseboard_fab2(sch_1):page144_i95:gpiob7"
				( attribute "PN" "H20"
					( Origin gPackager )
				)
				( objectStatus "U25W4.H20" )
			)
			( pin "@baseboard_fab2_lib.baseboard_fab2(sch_1):page144_i95:gpiog0_sgps1ck"
				( attribute "PN" "A19"
					( Origin gPackager )
				)
				( objectStatus "U25W4.A19" )
			)
			( pin "@baseboard_fab2_lib.baseboard_fab2(sch_1):page144_i95:gpiog1_sgps1ld"
				( attribute "PN" "E19"
					( Origin gPackager )
				)
				( objectStatus "U25W4.E19" )
			)
			( pin "@baseboard_fab2_lib.baseboard_fab2(sch_1):page144_i95:gpiog2_sgps1i0"
				( attribute "PN" "C19"
					( Origin gPackager )
				)
				( objectStatus "U25W4.C19" )
			)
			( pin "@baseboard_fab2_lib.baseboard_fab2(sch_1):page144_i95:gpiog3_sgps1i1"
				( attribute "PN" "E16"
					( Origin gPackager )
				)
				( objectStatus "U25W4.E16" )
			)
			( pin "@baseboard_fab2_lib.baseboard_fab2(sch_1):page144_i95:\gpioi0_syscs#\"
				( attribute "PN" "C18"
					( Origin gPackager )
				)
				( objectStatus "U25W4.C18" )
			)
			( pin "@baseboard_fab2_lib.baseboard_fab2(sch_1):page144_i95:gpioi1_sysck"
				( attribute "PN" "E15"
					( Origin gPackager )
				)
				( objectStatus "U25W4.E15" )
			)
			( pin "@baseboard_fab2_lib.baseboard_fab2(sch_1):page144_i95:gpioi2_sysmosi"
				( attribute "PN" "B16"
					( Origin gPackager )
				)
				( objectStatus "U25W4.B16" )
			)
			( pin "@baseboard_fab2_lib.baseboard_fab2(sch_1):page144_i95:gpioi3_sysmiso"
				( attribute "PN" "C16"
					( Origin gPackager )
				)
				( objectStatus "U25W4.C16" )
			)
			( pin "@baseboard_fab2_lib.baseboard_fab2(sch_1):page144_i95:\gpioi4_spi1cs0#_vbcs#\"
				( attribute "PN" "B15"
					( Origin gPackager )
				)
				( objectStatus "U25W4.B15" )
			)
			( pin "@baseboard_fab2_lib.baseboard_fab2(sch_1):page144_i95:gpioi5_spi1ck_vbck"
				( attribute "PN" "C15"
					( Origin gPackager )
				)
				( objectStatus "U25W4.C15" )
			)
			( pin "@baseboard_fab2_lib.baseboard_fab2(sch_1):page144_i95:gpioi6_spi1mosi_vbmosi"
				( attribute "PN" "A14"
					( Origin gPackager )
				)
				( objectStatus "U25W4.A14" )
			)
			( pin "@baseboard_fab2_lib.baseboard_fab2(sch_1):page144_i95:gpioi7_spi1miso_vbmiso"
				( attribute "PN" "A15"
					( Origin gPackager )
				)
				( objectStatus "U25W4.A15" )
			)
			( pin "@baseboard_fab2_lib.baseboard_fab2(sch_1):page144_i95:gpioj0_sgpmck"
				( attribute "PN" "R2"
					( Origin gPackager )
				)
				( objectStatus "U25W4.R2" )
			)
			( pin "@baseboard_fab2_lib.baseboard_fab2(sch_1):page144_i95:gpioj1_sgpmld"
				( attribute "PN" "L2"
					( Origin gPackager )
				)
				( objectStatus "U25W4.L2" )
			)
			( pin "@baseboard_fab2_lib.baseboard_fab2(sch_1):page144_i95:gpioj2_sgpmo"
				( attribute "PN" "N3"
					( Origin gPackager )
				)
				( objectStatus "U25W4.N3" )
			)
			( pin "@baseboard_fab2_lib.baseboard_fab2(sch_1):page144_i95:gpioj3_sgpmi"
				( attribute "PN" "N4"
					( Origin gPackager )
				)
				( objectStatus "U25W4.N4" )
			)
			( pin "@baseboard_fab2_lib.baseboard_fab2(sch_1):page144_i95:gpiok0_scl5"
				( attribute "PN" "L3"
					( Origin gPackager )
				)
				( objectStatus "U25W4.L3" )
			)
			( pin "@baseboard_fab2_lib.baseboard_fab2(sch_1):page144_i95:gpiok1_sda5"
				( attribute "PN" "L4"
					( Origin gPackager )
				)
				( objectStatus "U25W4.L4" )
			)
			( pin "@baseboard_fab2_lib.baseboard_fab2(sch_1):page144_i95:gpiok2_scl6"
				( attribute "PN" "L1"
					( Origin gPackager )
				)
				( objectStatus "U25W4.L1" )
			)
			( pin "@baseboard_fab2_lib.baseboard_fab2(sch_1):page144_i95:gpiok3_sda6"
				( attribute "PN" "N2"
					( Origin gPackager )
				)
				( objectStatus "U25W4.N2" )
			)
			( pin "@baseboard_fab2_lib.baseboard_fab2(sch_1):page144_i95:gpiok4_scl7"
				( attribute "PN" "N1"
					( Origin gPackager )
				)
				( objectStatus "U25W4.N1" )
			)
			( pin "@baseboard_fab2_lib.baseboard_fab2(sch_1):page144_i95:gpiok5_sda7"
				( attribute "PN" "P1"
					( Origin gPackager )
				)
				( objectStatus "U25W4.P1" )
			)
			( pin "@baseboard_fab2_lib.baseboard_fab2(sch_1):page144_i95:gpiok6_scl8"
				( attribute "PN" "P2"
					( Origin gPackager )
				)
				( objectStatus "U25W4.P2" )
			)
			( pin "@baseboard_fab2_lib.baseboard_fab2(sch_1):page144_i95:gpiok7_sda8"
				( attribute "PN" "R1"
					( Origin gPackager )
				)
				( objectStatus "U25W4.R1" )
			)
			( pin "@baseboard_fab2_lib.baseboard_fab2(sch_1):page144_i95:gpioq0_scl3"
				( attribute "PN" "A11"
					( Origin gPackager )
				)
				( objectStatus "U25W4.A11" )
			)
			( pin "@baseboard_fab2_lib.baseboard_fab2(sch_1):page144_i95:gpioq1_sda3"
				( attribute "PN" "A10"
					( Origin gPackager )
				)
				( objectStatus "U25W4.A10" )
			)
			( pin "@baseboard_fab2_lib.baseboard_fab2(sch_1):page144_i95:gpioq2_scl4"
				( attribute "PN" "A9"
					( Origin gPackager )
				)
				( objectStatus "U25W4.A9" )
			)
			( pin "@baseboard_fab2_lib.baseboard_fab2(sch_1):page144_i95:gpioq3_sda4"
				( attribute "PN" "B9"
					( Origin gPackager )
				)
				( objectStatus "U25W4.B9" )
			)
			( pin "@baseboard_fab2_lib.baseboard_fab2(sch_1):page144_i95:gpioq4_scl14"
				( attribute "PN" "N21"
					( Origin gPackager )
				)
				( objectStatus "U25W4.N21" )
			)
			( pin "@baseboard_fab2_lib.baseboard_fab2(sch_1):page144_i95:gpioq5_sda14"
				( attribute "PN" "N22"
					( Origin gPackager )
				)
				( objectStatus "U25W4.N22" )
			)
			( pin "@baseboard_fab2_lib.baseboard_fab2(sch_1):page144_i95:gpioy4_scl1"
				( attribute "PN" "M18"
					( Origin gPackager )
				)
				( objectStatus "U25W4.M18" )
			)
			( pin "@baseboard_fab2_lib.baseboard_fab2(sch_1):page144_i95:gpioy5_sda1"
				( attribute "PN" "M19"
					( Origin gPackager )
				)
				( objectStatus "U25W4.M19" )
			)
			( pin "@baseboard_fab2_lib.baseboard_fab2(sch_1):page144_i95:gpioy6_scl2"
				( attribute "PN" "M20"
					( Origin gPackager )
				)
				( objectStatus "U25W4.M20" )
			)
			( pin "@baseboard_fab2_lib.baseboard_fab2(sch_1):page144_i95:gpioy7_sda2"
				( attribute "PN" "P20"
					( Origin gPackager )
				)
				( objectStatus "U25W4.P20" )
			)
			( pin "@baseboard_fab2_lib.baseboard_fab2(sch_1):page144_i95:ntrst"
				( attribute "PN" "E11"
					( Origin gPackager )
				)
				( objectStatus "U25W4.E11" )
			)
			( pin "@baseboard_fab2_lib.baseboard_fab2(sch_1):page144_i95:rtck"
				( attribute "PN" "C9"
					( Origin gPackager )
				)
				( objectStatus "U25W4.C9" )
			)
			( pin "@baseboard_fab2_lib.baseboard_fab2(sch_1):page144_i95:tck"
				( attribute "PN" "C10"
					( Origin gPackager )
				)
				( objectStatus "U25W4.C10" )
			)
			( pin "@baseboard_fab2_lib.baseboard_fab2(sch_1):page144_i95:tdi"
				( attribute "PN" "D12"
					( Origin gPackager )
				)
				( objectStatus "U25W4.D12" )
			)
			( pin "@baseboard_fab2_lib.baseboard_fab2(sch_1):page144_i95:tdo"
				( attribute "PN" "D11"
					( Origin gPackager )
				)
				( objectStatus "U25W4.D11" )
			)
			( pin "@baseboard_fab2_lib.baseboard_fab2(sch_1):page144_i95:tms"
				( attribute "PN" "C8"
					( Origin gPackager )
				)
				( objectStatus "U25W4.C8" )
			)
			( pin "@baseboard_fab2_lib.baseboard_fab2(sch_1):page249_i30:drn"
				( attribute "PN" "3"
					( Origin gPackager )
				)
				( objectStatus "Q9W1.3" )
			)
			( pin "@baseboard_fab2_lib.baseboard_fab2(sch_1):page249_i30:gate"
				( attribute "PN" "1"
					( Origin gPackager )
				)
				( objectStatus "Q9W1.1" )
			)
			( pin "@baseboard_fab2_lib.baseboard_fab2(sch_1):page249_i30:src"
				( attribute "PN" "2"
					( Origin gPackager )
				)
				( objectStatus "Q9W1.2" )
			)
			( pin "@baseboard_fab2_lib.baseboard_fab2(sch_1):page247_i101:a"
				( attribute "PN" "1"
					( Origin gPackager )
				)
				( objectStatus "R6W25.1" )
			)
			( pin "@baseboard_fab2_lib.baseboard_fab2(sch_1):page247_i101:b"
				( attribute "PN" "2"
					( Origin gPackager )
				)
				( objectStatus "R6W25.2" )
			)
			( pin "@baseboard_fab2_lib.baseboard_fab2(sch_1):page146_i104:gpioaa0_vpor2_nord0_salt7"
				( attribute "PN" "Y21"
					( Origin gPackager )
				)
				( objectStatus "U25W4.Y21" )
			)
			( pin "@baseboard_fab2_lib.baseboard_fab2(sch_1):page146_i104:gpioaa1_vpor3_nord1_salt8"
				( attribute "PN" "V21"
					( Origin gPackager )
				)
				( objectStatus "U25W4.V21" )
			)
			( pin "@baseboard_fab2_lib.baseboard_fab2(sch_1):page146_i104:gpioaa2_vpor4_nord2_salt9"
				( attribute "PN" "Y22"
					( Origin gPackager )
				)
				( objectStatus "U25W4.Y22" )
			)
			( pin "@baseboard_fab2_lib.baseboard_fab2(sch_1):page146_i104:gpioaa3_vpor5_nord3_salt10"
				( attribute "PN" "AA22"
					( Origin gPackager )
				)
				( objectStatus "U25W4.AA22" )
			)
			( pin "@baseboard_fab2_lib.baseboard_fab2(sch_1):page146_i104:gpioaa4_vpor6_nord4_salt11"
				( attribute "PN" "U22"
					( Origin gPackager )
				)
				( objectStatus "U25W4.U22" )
			)
			( pin "@baseboard_fab2_lib.baseboard_fab2(sch_1):page146_i104:gpioaa5_vpor7_nord5_salt12"
				( attribute "PN" "T20"
					( Origin gPackager )
				)
				( objectStatus "U25W4.T20" )
			)
			( pin "@baseboard_fab2_lib.baseboard_fab2(sch_1):page146_i104:gpioaa6_vpor8_nord6_salt13"
				( attribute "PN" "N18"
					( Origin gPackager )
				)
				( objectStatus "U25W4.N18" )
			)
			( pin "@baseboard_fab2_lib.baseboard_fab2(sch_1):page146_i104:gpioaa7_vpor9_nord7_salt14"
				( attribute "PN" "P19"
					( Origin gPackager )
				)
				( objectStatus "U25W4.P19" )
			)
			( pin "@baseboard_fab2_lib.baseboard_fab2(sch_1):page146_i104:gpioh0_ncts6"
				( attribute "PN" "A18"
					( Origin gPackager )
				)
				( objectStatus "U25W4.A18" )
			)
			( pin "@baseboard_fab2_lib.baseboard_fab2(sch_1):page146_i104:gpioh1_ndcd6"
				( attribute "PN" "B18"
					( Origin gPackager )
				)
				( objectStatus "U25W4.B18" )
			)
			( pin "@baseboard_fab2_lib.baseboard_fab2(sch_1):page146_i104:gpioh2_ndsr6"
				( attribute "PN" "D17"
					( Origin gPackager )
				)
				( objectStatus "U25W4.D17" )
			)
			( pin "@baseboard_fab2_lib.baseboard_fab2(sch_1):page146_i104:gpioh3_nri6"
				( attribute "PN" "C17"
					( Origin gPackager )
				)
				( objectStatus "U25W4.C17" )
			)
			( pin "@baseboard_fab2_lib.baseboard_fab2(sch_1):page146_i104:gpioh4_ndtr6"
				( attribute "PN" "A17"
					( Origin gPackager )
				)
				( objectStatus "U25W4.A17" )
			)
			( pin "@baseboard_fab2_lib.baseboard_fab2(sch_1):page146_i104:gpioh5_nrts6"
				( attribute "PN" "B17"
					( Origin gPackager )
				)
				( objectStatus "U25W4.B17" )
			)
			( pin "@baseboard_fab2_lib.baseboard_fab2(sch_1):page146_i104:gpioh6_txd6"
				( attribute "PN" "A16"
					( Origin gPackager )
				)
				( objectStatus "U25W4.A16" )
			)
			( pin "@baseboard_fab2_lib.baseboard_fab2(sch_1):page146_i104:gpioh7_rxd6"
				( attribute "PN" "D18"
					( Origin gPackager )
				)
				( objectStatus "U25W4.D18" )
			)
			( pin "@baseboard_fab2_lib.baseboard_fab2(sch_1):page146_i104:\gpios0_vpob2_spi2cs1#\"
				( attribute "PN" "V20"
					( Origin gPackager )
				)
				( objectStatus "U25W4.V20" )
			)
			( pin "@baseboard_fab2_lib.baseboard_fab2(sch_1):page146_i104:gpios1_vpob3_bmcint"
				( attribute "PN" "U19"
					( Origin gPackager )
				)
				( objectStatus "U25W4.U19" )
			)
			( pin "@baseboard_fab2_lib.baseboard_fab2(sch_1):page146_i104:gpios2_vpob4_salt5"
				( attribute "PN" "R18"
					( Origin gPackager )
				)
				( objectStatus "U25W4.R18" )
			)
			( pin "@baseboard_fab2_lib.baseboard_fab2(sch_1):page146_i104:gpios3_vpob5_salt6"
				( attribute "PN" "P18"
					( Origin gPackager )
				)
				( objectStatus "U25W4.P18" )
			)
			( pin "@baseboard_fab2_lib.baseboard_fab2(sch_1):page146_i104:gpios4_vpob6"
				( attribute "PN" "R19"
					( Origin gPackager )
				)
				( objectStatus "U25W4.R19" )
			)
			( pin "@baseboard_fab2_lib.baseboard_fab2(sch_1):page146_i104:gpios5_vpob7"
				( attribute "PN" "W20"
					( Origin gPackager )
				)
				( objectStatus "U25W4.W20" )
			)
			( pin "@baseboard_fab2_lib.baseboard_fab2(sch_1):page146_i104:gpios6_vpob8"
				( attribute "PN" "U20"
					( Origin gPackager )
				)
				( objectStatus "U25W4.U20" )
			)
			( pin "@baseboard_fab2_lib.baseboard_fab2(sch_1):page146_i104:gpios7_vpob9"
				( attribute "PN" "AA20"
					( Origin gPackager )
				)
				( objectStatus "U25W4.AA20" )
			)
			( pin "@baseboard_fab2_lib.baseboard_fab2(sch_1):page146_i104:\gpioz0_vpog2_nora0_siopbi#\"
				( attribute "PN" "Y20"
					( Origin gPackager )
				)
				( objectStatus "U25W4.Y20" )
			)
			( pin "@baseboard_fab2_lib.baseboard_fab2(sch_1):page146_i104:gpioz1_vpog3_nora1_siopwrgd"
				( attribute "PN" "AB20"
					( Origin gPackager )
				)
				( objectStatus "U25W4.AB20" )
			)
			( pin "@baseboard_fab2_lib.baseboard_fab2(sch_1):page146_i104:\gpioz2_vpog4_nora2_siopbo#\"
				( attribute "PN" "AB21"
					( Origin gPackager )
				)
				( objectStatus "U25W4.AB21" )
			)
			( pin "@baseboard_fab2_lib.baseboard_fab2(sch_1):page146_i104:\gpioz3_vpog5_nora3_siosci#\"
				( attribute "PN" "AA21"
					( Origin gPackager )
				)
				( objectStatus "U25W4.AA21" )
			)
			( pin "@baseboard_fab2_lib.baseboard_fab2(sch_1):page146_i104:gpioz4_vpog6_nora4"
				( attribute "PN" "U21"
					( Origin gPackager )
				)
				( objectStatus "U25W4.U21" )
			)
			( pin "@baseboard_fab2_lib.baseboard_fab2(sch_1):page146_i104:gpioz5_vpog7_nora5"
				( attribute "PN" "W22"
					( Origin gPackager )
				)
				( objectStatus "U25W4.W22" )
			)
			( pin "@baseboard_fab2_lib.baseboard_fab2(sch_1):page146_i104:gpioz6_vpog8_nora6"
				( attribute "PN" "V22"
					( Origin gPackager )
				)
				( objectStatus "U25W4.V22" )
			)
			( pin "@baseboard_fab2_lib.baseboard_fab2(sch_1):page146_i104:gpioz7_vpog9_nora7"
				( attribute "PN" "W21"
					( Origin gPackager )
				)
				( objectStatus "U25W4.W21" )
			)
			( pin "@baseboard_fab2_lib.baseboard_fab2(sch_1):page146_i104:usb2a_dn"
				( attribute "PN" "A8"
					( Origin gPackager )
				)
				( objectStatus "U25W4.A8" )
			)
			( pin "@baseboard_fab2_lib.baseboard_fab2(sch_1):page146_i104:usb2a_dp"
				( attribute "PN" "A7"
					( Origin gPackager )
				)
				( objectStatus "U25W4.A7" )
			)
			( pin "@baseboard_fab2_lib.baseboard_fab2(sch_1):page146_i104:usb2avres"
				( attribute "PN" "B8"
					( Origin gPackager )
				)
				( objectStatus "U25W4.B8" )
			)
			( pin "@baseboard_fab2_lib.baseboard_fab2(sch_1):page146_i104:usb2b_dn"
				( attribute "PN" "A6"
					( Origin gPackager )
				)
				( objectStatus "U25W4.A6" )
			)
			( pin "@baseboard_fab2_lib.baseboard_fab2(sch_1):page146_i104:usb2b_dp"
				( attribute "PN" "B6"
					( Origin gPackager )
				)
				( objectStatus "U25W4.B6" )
			)
			( pin "@baseboard_fab2_lib.baseboard_fab2(sch_1):page146_i104:usb2bvres"
				( attribute "PN" "B7"
					( Origin gPackager )
				)
				( objectStatus "U25W4.B7" )
			)
			( pin "@baseboard_fab2_lib.baseboard_fab2(sch_1):page200_i235:\1\"
				( attribute "PN" "1"
					( Origin gPackager )
				)
				( objectStatus "C9W1.1" )
			)
			( pin "@baseboard_fab2_lib.baseboard_fab2(sch_1):page200_i235:\2\"
				( attribute "PN" "2"
					( Origin gPackager )
				)
				( objectStatus "C9W1.2" )
			)
			( pin "@baseboard_fab2_lib.baseboard_fab2(sch_1):page200_i236:\1\"
				( attribute "PN" "1"
					( Origin gPackager )
				)
				( objectStatus "C9W2.1" )
			)
			( pin "@baseboard_fab2_lib.baseboard_fab2(sch_1):page200_i236:\2\"
				( attribute "PN" "2"
					( Origin gPackager )
				)
				( objectStatus "C9W2.2" )
			)
			( pin "@baseboard_fab2_lib.baseboard_fab2(sch_1):page146_i67:a"
				( attribute "PN" "1"
					( Origin gPackager )
				)
				( objectStatus "R25W81.1" )
			)
			( pin "@baseboard_fab2_lib.baseboard_fab2(sch_1):page146_i67:b"
				( attribute "PN" "2"
					( Origin gPackager )
				)
				( objectStatus "R25W81.2" )
			)
			( pin "@baseboard_fab2_lib.baseboard_fab2(sch_1):page150_i180:a"
				( attribute "PN" "1"
					( Origin gPackager )
				)
				( objectStatus "R25W111.1" )
			)
			( pin "@baseboard_fab2_lib.baseboard_fab2(sch_1):page150_i180:b"
				( attribute "PN" "2"
					( Origin gPackager )
				)
				( objectStatus "R25W111.2" )
			)
			( pin "@baseboard_fab2_lib.baseboard_fab2(sch_1):page204_i99:a"
				( attribute "PN" "1"
					( Origin gPackager )
				)
				( objectStatus "RT23.1" )
			)
			( pin "@baseboard_fab2_lib.baseboard_fab2(sch_1):page204_i99:b"
				( attribute "PN" "2"
					( Origin gPackager )
				)
				( objectStatus "RT23.2" )
			)
			( pin "@baseboard_fab2_lib.baseboard_fab2(sch_1):page147_i151:a"
				( attribute "PN" "1"
					( Origin gPackager )
				)
				( objectStatus "R25W57.1" )
			)
			( pin "@baseboard_fab2_lib.baseboard_fab2(sch_1):page147_i151:b"
				( attribute "PN" "2"
					( Origin gPackager )
				)
				( objectStatus "R25W57.2" )
			)
			( pin "@baseboard_fab2_lib.baseboard_fab2(sch_1):page207_i99:a"
				( attribute "PN" "1"
					( Origin gPackager )
				)
				( objectStatus "RT15.1" )
			)
			( pin "@baseboard_fab2_lib.baseboard_fab2(sch_1):page207_i99:b"
				( attribute "PN" "2"
					( Origin gPackager )
				)
				( objectStatus "RT15.2" )
			)
			( pin "@baseboard_fab2_lib.baseboard_fab2(sch_1):page210_i68:a"
				( attribute "PN" "1"
					( Origin gPackager )
				)
				( objectStatus "RT37.1" )
			)
			( pin "@baseboard_fab2_lib.baseboard_fab2(sch_1):page210_i68:b"
				( attribute "PN" "2"
					( Origin gPackager )
				)
				( objectStatus "RT37.2" )
			)
			( pin "@baseboard_fab2_lib.baseboard_fab2(sch_1):page209_i75:a"
				( attribute "PN" "1"
					( Origin gPackager )
				)
				( objectStatus "RT9.1" )
			)
			( pin "@baseboard_fab2_lib.baseboard_fab2(sch_1):page209_i75:b"
				( attribute "PN" "2"
					( Origin gPackager )
				)
				( objectStatus "RT9.2" )
			)
			( pin "@baseboard_fab2_lib.baseboard_fab2(sch_1):page216_i140:a"
				( attribute "PN" "1"
					( Origin gPackager )
				)
				( objectStatus "RT36.1" )
			)
			( pin "@baseboard_fab2_lib.baseboard_fab2(sch_1):page216_i140:b"
				( attribute "PN" "2"
					( Origin gPackager )
				)
				( objectStatus "RT36.2" )
			)
			( pin "@baseboard_fab2_lib.baseboard_fab2(sch_1):page236_i153:a"
				( attribute "PN" "1"
					( Origin gPackager )
				)
				( objectStatus "RT44.1" )
			)
			( pin "@baseboard_fab2_lib.baseboard_fab2(sch_1):page236_i153:b"
				( attribute "PN" "2"
					( Origin gPackager )
				)
				( objectStatus "RT44.2" )
			)
			( pin "@baseboard_fab2_lib.baseboard_fab2(sch_1):page236_i154:a"
				( attribute "PN" "1"
					( Origin gPackager )
				)
				( objectStatus "RT46.1" )
			)
			( pin "@baseboard_fab2_lib.baseboard_fab2(sch_1):page236_i154:b"
				( attribute "PN" "2"
					( Origin gPackager )
				)
				( objectStatus "RT46.2" )
			)
			( pin "@baseboard_fab2_lib.baseboard_fab2(sch_1):page208_i109:a"
				( attribute "PN" "1"
					( Origin gPackager )
				)
				( objectStatus "RT14.1" )
			)
			( pin "@baseboard_fab2_lib.baseboard_fab2(sch_1):page208_i109:b"
				( attribute "PN" "2"
					( Origin gPackager )
				)
				( objectStatus "RT14.2" )
			)
			( pin "@baseboard_fab2_lib.baseboard_fab2(sch_1):page205_i78:a"
				( attribute "PN" "1"
					( Origin gPackager )
				)
				( objectStatus "RT40.1" )
			)
			( pin "@baseboard_fab2_lib.baseboard_fab2(sch_1):page205_i78:b"
				( attribute "PN" "2"
					( Origin gPackager )
				)
				( objectStatus "RT40.2" )
			)
			( pin "@baseboard_fab2_lib.baseboard_fab2(sch_1):page137_i140:a"
				( attribute "PN" "1"
					( Origin gPackager )
				)
				( objectStatus "R25W94.1" )
			)
			( pin "@baseboard_fab2_lib.baseboard_fab2(sch_1):page137_i140:b"
				( attribute "PN" "2"
					( Origin gPackager )
				)
				( objectStatus "R25W94.2" )
			)
			( pin "@baseboard_fab2_lib.baseboard_fab2(sch_1):page137_i133:a"
				( attribute "PN" "1"
					( Origin gPackager )
				)
				( objectStatus "R25W154.1" )
			)
			( pin "@baseboard_fab2_lib.baseboard_fab2(sch_1):page137_i133:b"
				( attribute "PN" "2"
					( Origin gPackager )
				)
				( objectStatus "R25W154.2" )
			)
			( pin "@baseboard_fab2_lib.baseboard_fab2(sch_1):page158_i152:a"
				( attribute "PN" "1"
					( Origin gPackager )
				)
				( objectStatus "R9F66.1" )
			)
			( pin "@baseboard_fab2_lib.baseboard_fab2(sch_1):page158_i152:b"
				( attribute "PN" "2"
					( Origin gPackager )
				)
				( objectStatus "R9F66.2" )
			)
			( pin "@baseboard_fab2_lib.baseboard_fab2(sch_1):page144_i58:a"
				( attribute "PN" "1"
					( Origin gPackager )
				)
				( objectStatus "R1U13.1" )
			)
			( pin "@baseboard_fab2_lib.baseboard_fab2(sch_1):page144_i58:b"
				( attribute "PN" "2"
					( Origin gPackager )
				)
				( objectStatus "R1U13.2" )
			)
			( pin "@baseboard_fab2_lib.baseboard_fab2(sch_1):page144_i57:a"
				( attribute "PN" "1"
					( Origin gPackager )
				)
				( objectStatus "R1U14.1" )
			)
			( pin "@baseboard_fab2_lib.baseboard_fab2(sch_1):page144_i57:b"
				( attribute "PN" "2"
					( Origin gPackager )
				)
				( objectStatus "R1U14.2" )
			)
			( pin "@baseboard_fab2_lib.baseboard_fab2(sch_1):page148_i28:adcav33"
				( attribute "PN" "J6"
					( Origin gPackager )
				)
				( objectStatus "U25W4.J6" )
			)
			( pin "@baseboard_fab2_lib.baseboard_fab2(sch_1):page148_i28:batvdd"
				( attribute "PN" "E4"
					( Origin gPackager )
				)
				( objectStatus "U25W4.E4" )
			)
			( pin "@baseboard_fab2_lib.baseboard_fab2(sch_1):page148_i28:dacav33"
				( attribute "PN" "K6"
					( Origin gPackager )
				)
				( objectStatus "U25W4.K6" )
			)
			( pin "@baseboard_fab2_lib.baseboard_fab2(sch_1):page148_i28:dacdv33"
				( attribute "PN" "K5"
					( Origin gPackager )
				)
				( objectStatus "U25W4.K5" )
			)
			( pin "@baseboard_fab2_lib.baseboard_fab2(sch_1):page148_i28:gnd0"
				( attribute "PN" "A1"
					( Origin gPackager )
				)
				( objectStatus "U25W4.A1" )
			)
			( pin "@baseboard_fab2_lib.baseboard_fab2(sch_1):page148_i28:gnd1"
				( attribute "PN" "A22"
					( Origin gPackager )
				)
				( objectStatus "U25W4.A22" )
			)
			( pin "@baseboard_fab2_lib.baseboard_fab2(sch_1):page148_i28:gnd2"
				( attribute "PN" "AA11"
					( Origin gPackager )
				)
				( objectStatus "U25W4.AA11" )
			)
			( pin "@baseboard_fab2_lib.baseboard_fab2(sch_1):page148_i28:gnd3"
				( attribute "PN" "AA13"
					( Origin gPackager )
				)
				( objectStatus "U25W4.AA13" )
			)
			( pin "@baseboard_fab2_lib.baseboard_fab2(sch_1):page148_i28:gnd4"
				( attribute "PN" "AA15"
					( Origin gPackager )
				)
				( objectStatus "U25W4.AA15" )
			)
			( pin "@baseboard_fab2_lib.baseboard_fab2(sch_1):page148_i28:gnd5"
				( attribute "PN" "AA7"
					( Origin gPackager )
				)
				( objectStatus "U25W4.AA7" )
			)
			( pin "@baseboard_fab2_lib.baseboard_fab2(sch_1):page148_i28:gnd6"
				( attribute "PN" "AA9"
					( Origin gPackager )
				)
				( objectStatus "U25W4.AA9" )
			)
			( pin "@baseboard_fab2_lib.baseboard_fab2(sch_1):page148_i28:gnd7"
				( attribute "PN" "AB1"
					( Origin gPackager )
				)
				( objectStatus "U25W4.AB1" )
			)
			( pin "@baseboard_fab2_lib.baseboard_fab2(sch_1):page148_i28:gnd8"
				( attribute "PN" "AB22"
					( Origin gPackager )
				)
				( objectStatus "U25W4.AB22" )
			)
			( pin "@baseboard_fab2_lib.baseboard_fab2(sch_1):page148_i28:gnd9"
				( attribute "PN" "C6"
					( Origin gPackager )
				)
				( objectStatus "U25W4.C6" )
			)
			( pin "@baseboard_fab2_lib.baseboard_fab2(sch_1):page148_i28:gnd10"
				( attribute "PN" "E8"
					( Origin gPackager )
				)
				( objectStatus "U25W4.E8" )
			)
			( pin "@baseboard_fab2_lib.baseboard_fab2(sch_1):page148_i28:gnd11"
				( attribute "PN" "F16"
					( Origin gPackager )
				)
				( objectStatus "U25W4.F16" )
			)
			( pin "@baseboard_fab2_lib.baseboard_fab2(sch_1):page148_i28:gnd12"
				( attribute "PN" "G19"
					( Origin gPackager )
				)
				( objectStatus "U25W4.G19" )
			)
			( pin "@baseboard_fab2_lib.baseboard_fab2(sch_1):page148_i28:gnd13"
				( attribute "PN" "G6"
					( Origin gPackager )
				)
				( objectStatus "U25W4.G6" )
			)
			( pin "@baseboard_fab2_lib.baseboard_fab2(sch_1):page148_i28:gnd14"
				( attribute "PN" "H6"
					( Origin gPackager )
				)
				( objectStatus "U25W4.H6" )
			)
			( pin "@baseboard_fab2_lib.baseboard_fab2(sch_1):page148_i28:gnd15"
				( attribute "PN" "J10"
					( Origin gPackager )
				)
				( objectStatus "U25W4.J10" )
			)
			( pin "@baseboard_fab2_lib.baseboard_fab2(sch_1):page148_i28:gnd16"
				( attribute "PN" "J11"
					( Origin gPackager )
				)
				( objectStatus "U25W4.J11" )
			)
			( pin "@baseboard_fab2_lib.baseboard_fab2(sch_1):page148_i28:gnd17"
				( attribute "PN" "J12"
					( Origin gPackager )
				)
				( objectStatus "U25W4.J12" )
			)
			( pin "@baseboard_fab2_lib.baseboard_fab2(sch_1):page148_i28:gnd18"
				( attribute "PN" "J13"
					( Origin gPackager )
				)
				( objectStatus "U25W4.J13" )
			)
			( pin "@baseboard_fab2_lib.baseboard_fab2(sch_1):page148_i28:gnd19"
				( attribute "PN" "J14"
					( Origin gPackager )
				)
				( objectStatus "U25W4.J14" )
			)
			( pin "@baseboard_fab2_lib.baseboard_fab2(sch_1):page148_i28:gnd20"
				( attribute "PN" "J21"
					( Origin gPackager )
				)
				( objectStatus "U25W4.J21" )
			)
			( pin "@baseboard_fab2_lib.baseboard_fab2(sch_1):page148_i28:gnd21"
				( attribute "PN" "J22"
					( Origin gPackager )
				)
				( objectStatus "U25W4.J22" )
			)
			( pin "@baseboard_fab2_lib.baseboard_fab2(sch_1):page148_i28:gnd22"
				( attribute "PN" "J5"
					( Origin gPackager )
				)
				( objectStatus "U25W4.J5" )
			)
			( pin "@baseboard_fab2_lib.baseboard_fab2(sch_1):page148_i28:gnd23"
				( attribute "PN" "J9"
					( Origin gPackager )
				)
				( objectStatus "U25W4.J9" )
			)
			( pin "@baseboard_fab2_lib.baseboard_fab2(sch_1):page148_i28:gnd24"
				( attribute "PN" "K10"
					( Origin gPackager )
				)
				( objectStatus "U25W4.K10" )
			)
			( pin "@baseboard_fab2_lib.baseboard_fab2(sch_1):page148_i28:gnd25"
				( attribute "PN" "K11"
					( Origin gPackager )
				)
				( objectStatus "U25W4.K11" )
			)
			( pin "@baseboard_fab2_lib.baseboard_fab2(sch_1):page148_i28:gnd26"
				( attribute "PN" "K12"
					( Origin gPackager )
				)
				( objectStatus "U25W4.K12" )
			)
			( pin "@baseboard_fab2_lib.baseboard_fab2(sch_1):page148_i28:gnd27"
				( attribute "PN" "K13"
					( Origin gPackager )
				)
				( objectStatus "U25W4.K13" )
			)
			( pin "@baseboard_fab2_lib.baseboard_fab2(sch_1):page148_i28:gnd28"
				( attribute "PN" "K14"
					( Origin gPackager )
				)
				( objectStatus "U25W4.K14" )
			)
			( pin "@baseboard_fab2_lib.baseboard_fab2(sch_1):page148_i28:gnd29"
				( attribute "PN" "K16"
					( Origin gPackager )
				)
				( objectStatus "U25W4.K16" )
			)
			( pin "@baseboard_fab2_lib.baseboard_fab2(sch_1):page148_i28:gnd30"
				( attribute "PN" "K9"
					( Origin gPackager )
				)
				( objectStatus "U25W4.K9" )
			)
			( pin "@baseboard_fab2_lib.baseboard_fab2(sch_1):page148_i28:gnd31"
				( attribute "PN" "L10"
					( Origin gPackager )
				)
				( objectStatus "U25W4.L10" )
			)
			( pin "@baseboard_fab2_lib.baseboard_fab2(sch_1):page148_i28:gnd32"
				( attribute "PN" "L11"
					( Origin gPackager )
				)
				( objectStatus "U25W4.L11" )
			)
			( pin "@baseboard_fab2_lib.baseboard_fab2(sch_1):page148_i28:gnd33"
				( attribute "PN" "L12"
					( Origin gPackager )
				)
				( objectStatus "U25W4.L12" )
			)
			( pin "@baseboard_fab2_lib.baseboard_fab2(sch_1):page148_i28:gnd34"
				( attribute "PN" "L13"
					( Origin gPackager )
				)
				( objectStatus "U25W4.L13" )
			)
			( pin "@baseboard_fab2_lib.baseboard_fab2(sch_1):page148_i28:gnd35"
				( attribute "PN" "L14"
					( Origin gPackager )
				)
				( objectStatus "U25W4.L14" )
			)
			( pin "@baseboard_fab2_lib.baseboard_fab2(sch_1):page148_i28:gnd36"
				( attribute "PN" "L9"
					( Origin gPackager )
				)
				( objectStatus "U25W4.L9" )
			)
			( pin "@baseboard_fab2_lib.baseboard_fab2(sch_1):page148_i28:gnd37"
				( attribute "PN" "M1"
					( Origin gPackager )
				)
				( objectStatus "U25W4.M1" )
			)
			( pin "@baseboard_fab2_lib.baseboard_fab2(sch_1):page148_i28:gnd38"
				( attribute "PN" "M10"
					( Origin gPackager )
				)
				( objectStatus "U25W4.M10" )
			)
			( pin "@baseboard_fab2_lib.baseboard_fab2(sch_1):page148_i28:gnd39"
				( attribute "PN" "M11"
					( Origin gPackager )
				)
				( objectStatus "U25W4.M11" )
			)
			( pin "@baseboard_fab2_lib.baseboard_fab2(sch_1):page148_i28:gnd40"
				( attribute "PN" "M12"
					( Origin gPackager )
				)
				( objectStatus "U25W4.M12" )
			)
			( pin "@baseboard_fab2_lib.baseboard_fab2(sch_1):page148_i28:gnd41"
				( attribute "PN" "M13"
					( Origin gPackager )
				)
				( objectStatus "U25W4.M13" )
			)
			( pin "@baseboard_fab2_lib.baseboard_fab2(sch_1):page148_i28:gnd42"
				( attribute "PN" "M14"
					( Origin gPackager )
				)
				( objectStatus "U25W4.M14" )
			)
			( pin "@baseboard_fab2_lib.baseboard_fab2(sch_1):page148_i28:gnd43"
				( attribute "PN" "M16"
					( Origin gPackager )
				)
				( objectStatus "U25W4.M16" )
			)
			( pin "@baseboard_fab2_lib.baseboard_fab2(sch_1):page148_i28:gnd44"
				( attribute "PN" "M17"
					( Origin gPackager )
				)
				( objectStatus "U25W4.M17" )
			)
			( pin "@baseboard_fab2_lib.baseboard_fab2(sch_1):page148_i28:gnd45"
				( attribute "PN" "M2"
					( Origin gPackager )
				)
				( objectStatus "U25W4.M2" )
			)
			( pin "@baseboard_fab2_lib.baseboard_fab2(sch_1):page148_i28:gnd46"
				( attribute "PN" "M3"
					( Origin gPackager )
				)
				( objectStatus "U25W4.M3" )
			)
			( pin "@baseboard_fab2_lib.baseboard_fab2(sch_1):page148_i28:gnd47"
				( attribute "PN" "M4"
					( Origin gPackager )
				)
				( objectStatus "U25W4.M4" )
			)
			( pin "@baseboard_fab2_lib.baseboard_fab2(sch_1):page148_i28:gnd48"
				( attribute "PN" "M5"
					( Origin gPackager )
				)
				( objectStatus "U25W4.M5" )
			)
			( pin "@baseboard_fab2_lib.baseboard_fab2(sch_1):page148_i28:gnd49"
				( attribute "PN" "M6"
					( Origin gPackager )
				)
				( objectStatus "U25W4.M6" )
			)
			( pin "@baseboard_fab2_lib.baseboard_fab2(sch_1):page148_i28:gnd50"
				( attribute "PN" "M7"
					( Origin gPackager )
				)
				( objectStatus "U25W4.M7" )
			)
			( pin "@baseboard_fab2_lib.baseboard_fab2(sch_1):page148_i28:gnd51"
				( attribute "PN" "M9"
					( Origin gPackager )
				)
				( objectStatus "U25W4.M9" )
			)
			( pin "@baseboard_fab2_lib.baseboard_fab2(sch_1):page148_i28:gnd52"
				( attribute "PN" "N10"
					( Origin gPackager )
				)
				( objectStatus "U25W4.N10" )
			)
			( pin "@baseboard_fab2_lib.baseboard_fab2(sch_1):page148_i28:gnd53"
				( attribute "PN" "N11"
					( Origin gPackager )
				)
				( objectStatus "U25W4.N11" )
			)
			( pin "@baseboard_fab2_lib.baseboard_fab2(sch_1):page148_i28:gnd54"
				( attribute "PN" "N12"
					( Origin gPackager )
				)
				( objectStatus "U25W4.N12" )
			)
			( pin "@baseboard_fab2_lib.baseboard_fab2(sch_1):page148_i28:gnd55"
				( attribute "PN" "N13"
					( Origin gPackager )
				)
				( objectStatus "U25W4.N13" )
			)
			( pin "@baseboard_fab2_lib.baseboard_fab2(sch_1):page148_i28:gnd56"
				( attribute "PN" "N14"
					( Origin gPackager )
				)
				( objectStatus "U25W4.N14" )
			)
			( pin "@baseboard_fab2_lib.baseboard_fab2(sch_1):page148_i28:gnd57"
				( attribute "PN" "N9"
					( Origin gPackager )
				)
				( objectStatus "U25W4.N9" )
			)
			( pin "@baseboard_fab2_lib.baseboard_fab2(sch_1):page148_i28:gnd58"
				( attribute "PN" "T16"
					( Origin gPackager )
				)
				( objectStatus "U25W4.T16" )
			)
			( pin "@baseboard_fab2_lib.baseboard_fab2(sch_1):page148_i28:gnd59"
				( attribute "PN" "T6"
					( Origin gPackager )
				)
				( objectStatus "U25W4.T6" )
			)
			( pin "@baseboard_fab2_lib.baseboard_fab2(sch_1):page148_i28:gnd60"
				( attribute "PN" "T7"
					( Origin gPackager )
				)
				( objectStatus "U25W4.T7" )
			)
			( pin "@baseboard_fab2_lib.baseboard_fab2(sch_1):page148_i28:gnd61"
				( attribute "PN" "U11"
					( Origin gPackager )
				)
				( objectStatus "U25W4.U11" )
			)
			( pin "@baseboard_fab2_lib.baseboard_fab2(sch_1):page148_i28:gnd62"
				( attribute "PN" "U6"
					( Origin gPackager )
				)
				( objectStatus "U25W4.U6" )
			)
			( pin "@baseboard_fab2_lib.baseboard_fab2(sch_1):page148_i28:gnd63"
				( attribute "PN" "V10"
					( Origin gPackager )
				)
				( objectStatus "U25W4.V10" )
			)
			( pin "@baseboard_fab2_lib.baseboard_fab2(sch_1):page148_i28:gnd64"
				( attribute "PN" "V12"
					( Origin gPackager )
				)
				( objectStatus "U25W4.V12" )
			)
			( pin "@baseboard_fab2_lib.baseboard_fab2(sch_1):page148_i28:gnd65"
				( attribute "PN" "V14"
					( Origin gPackager )
				)
				( objectStatus "U25W4.V14" )
			)
			( pin "@baseboard_fab2_lib.baseboard_fab2(sch_1):page148_i28:gnd66"
				( attribute "PN" "V16"
					( Origin gPackager )
				)
				( objectStatus "U25W4.V16" )
			)
			( pin "@baseboard_fab2_lib.baseboard_fab2(sch_1):page148_i28:gnd67"
				( attribute "PN" "V8"
					( Origin gPackager )
				)
				( objectStatus "U25W4.V8" )
			)
			( pin "@baseboard_fab2_lib.baseboard_fab2(sch_1):page148_i28:gnd68"
				( attribute "PN" "E5"
					( Origin gPackager )
				)
				( objectStatus "U25W4.E5" )
			)
			( pin "@baseboard_fab2_lib.baseboard_fab2(sch_1):page148_i28:\gpioy0_sios3#\"
				( attribute "PN" "R22"
					( Origin gPackager )
				)
				( objectStatus "U25W4.R22" )
			)
			( pin "@baseboard_fab2_lib.baseboard_fab2(sch_1):page148_i28:\gpioy1_sios5#\"
				( attribute "PN" "R21"
					( Origin gPackager )
				)
				( objectStatus "U25W4.R21" )
			)
			( pin "@baseboard_fab2_lib.baseboard_fab2(sch_1):page148_i28:\gpioy2_siopwreq#\"
				( attribute "PN" "P22"
					( Origin gPackager )
				)
				( objectStatus "U25W4.P22" )
			)
			( pin "@baseboard_fab2_lib.baseboard_fab2(sch_1):page148_i28:iv11d0"
				( attribute "PN" "F6"
					( Origin gPackager )
				)
				( objectStatus "U25W4.F6" )
			)
			( pin "@baseboard_fab2_lib.baseboard_fab2(sch_1):page148_i28:iv11d1"
				( attribute "PN" "G10"
					( Origin gPackager )
				)
				( objectStatus "U25W4.G10" )
			)
			( pin "@baseboard_fab2_lib.baseboard_fab2(sch_1):page148_i28:iv11d2"
				( attribute "PN" "G11"
					( Origin gPackager )
				)
				( objectStatus "U25W4.G11" )
			)
			( pin "@baseboard_fab2_lib.baseboard_fab2(sch_1):page148_i28:iv11d3"
				( attribute "PN" "G12"
					( Origin gPackager )
				)
				( objectStatus "U25W4.G12" )
			)
			( pin "@baseboard_fab2_lib.baseboard_fab2(sch_1):page148_i28:iv11d4"
				( attribute "PN" "G13"
					( Origin gPackager )
				)
				( objectStatus "U25W4.G13" )
			)
			( pin "@baseboard_fab2_lib.baseboard_fab2(sch_1):page148_i28:iv11d5"
				( attribute "PN" "G14"
					( Origin gPackager )
				)
				( objectStatus "U25W4.G14" )
			)
			( pin "@baseboard_fab2_lib.baseboard_fab2(sch_1):page148_i28:iv11d6"
				( attribute "PN" "G15"
					( Origin gPackager )
				)
				( objectStatus "U25W4.G15" )
			)
			( pin "@baseboard_fab2_lib.baseboard_fab2(sch_1):page148_i28:iv11d7"
				( attribute "PN" "G7"
					( Origin gPackager )
				)
				( objectStatus "U25W4.G7" )
			)
			( pin "@baseboard_fab2_lib.baseboard_fab2(sch_1):page148_i28:iv11d8"
				( attribute "PN" "G8"
					( Origin gPackager )
				)
				( objectStatus "U25W4.G8" )
			)
			( pin "@baseboard_fab2_lib.baseboard_fab2(sch_1):page148_i28:iv11d9"
				( attribute "PN" "G9"
					( Origin gPackager )
				)
				( objectStatus "U25W4.G9" )
			)
			( pin "@baseboard_fab2_lib.baseboard_fab2(sch_1):page148_i28:iv11d10"
				( attribute "PN" "H16"
					( Origin gPackager )
				)
				( objectStatus "U25W4.H16" )
			)
			( pin "@baseboard_fab2_lib.baseboard_fab2(sch_1):page148_i28:iv11d11"
				( attribute "PN" "J16"
					( Origin gPackager )
				)
				( objectStatus "U25W4.J16" )
			)
			( pin "@baseboard_fab2_lib.baseboard_fab2(sch_1):page148_i28:iv11d12"
				( attribute "PN" "L7"
					( Origin gPackager )
				)
				( objectStatus "U25W4.L7" )
			)
			( pin "@baseboard_fab2_lib.baseboard_fab2(sch_1):page148_i28:iv11d13"
				( attribute "PN" "N16"
					( Origin gPackager )
				)
				( objectStatus "U25W4.N16" )
			)
			( pin "@baseboard_fab2_lib.baseboard_fab2(sch_1):page148_i28:iv11d14"
				( attribute "PN" "N7"
					( Origin gPackager )
				)
				( objectStatus "U25W4.N7" )
			)
			( pin "@baseboard_fab2_lib.baseboard_fab2(sch_1):page148_i28:iv11d15"
				( attribute "PN" "P10"
					( Origin gPackager )
				)
				( objectStatus "U25W4.P10" )
			)
			( pin "@baseboard_fab2_lib.baseboard_fab2(sch_1):page148_i28:iv11d16"
				( attribute "PN" "P11"
					( Origin gPackager )
				)
				( objectStatus "U25W4.P11" )
			)
			( pin "@baseboard_fab2_lib.baseboard_fab2(sch_1):page148_i28:iv11d17"
				( attribute "PN" "P12"
					( Origin gPackager )
				)
				( objectStatus "U25W4.P12" )
			)
			( pin "@baseboard_fab2_lib.baseboard_fab2(sch_1):page148_i28:iv11d18"
				( attribute "PN" "P13"
					( Origin gPackager )
				)
				( objectStatus "U25W4.P13" )
			)
			( pin "@baseboard_fab2_lib.baseboard_fab2(sch_1):page148_i28:iv11d19"
				( attribute "PN" "P14"
					( Origin gPackager )
				)
				( objectStatus "U25W4.P14" )
			)
			( pin "@baseboard_fab2_lib.baseboard_fab2(sch_1):page148_i28:iv11d20"
				( attribute "PN" "P16"
					( Origin gPackager )
				)
				( objectStatus "U25W4.P16" )
			)
			( pin "@baseboard_fab2_lib.baseboard_fab2(sch_1):page148_i28:iv11d21"
				( attribute "PN" "P7"
					( Origin gPackager )
				)
				( objectStatus "U25W4.P7" )
			)
			( pin "@baseboard_fab2_lib.baseboard_fab2(sch_1):page148_i28:iv11d22"
				( attribute "PN" "P9"
					( Origin gPackager )
				)
				( objectStatus "U25W4.P9" )
			)
			( pin "@baseboard_fab2_lib.baseboard_fab2(sch_1):page148_i28:iv11d23"
				( attribute "PN" "R16"
					( Origin gPackager )
				)
				( objectStatus "U25W4.R16" )
			)
			( pin "@baseboard_fab2_lib.baseboard_fab2(sch_1):page148_i28:iv11d24"
				( attribute "PN" "R7"
					( Origin gPackager )
				)
				( objectStatus "U25W4.R7" )
			)
			( pin "@baseboard_fab2_lib.baseboard_fab2(sch_1):page148_i28:lpvdd0"
				( attribute "PN" "J17"
					( Origin gPackager )
				)
				( objectStatus "U25W4.J17" )
			)
			( pin "@baseboard_fab2_lib.baseboard_fab2(sch_1):page148_i28:lpvdd1"
				( attribute "PN" "K17"
					( Origin gPackager )
				)
				( objectStatus "U25W4.K17" )
			)
			( pin "@baseboard_fab2_lib.baseboard_fab2(sch_1):page148_i28:mvdd0"
				( attribute "PN" "T10"
					( Origin gPackager )
				)
				( objectStatus "U25W4.T10" )
			)
			( pin "@baseboard_fab2_lib.baseboard_fab2(sch_1):page148_i28:mvdd1"
				( attribute "PN" "T12"
					( Origin gPackager )
				)
				( objectStatus "U25W4.T12" )
			)
			( pin "@baseboard_fab2_lib.baseboard_fab2(sch_1):page148_i28:mvdd2"
				( attribute "PN" "T13"
					( Origin gPackager )
				)
				( objectStatus "U25W4.T13" )
			)
			( pin "@baseboard_fab2_lib.baseboard_fab2(sch_1):page148_i28:mvdd3"
				( attribute "PN" "T14"
					( Origin gPackager )
				)
				( objectStatus "U25W4.T14" )
			)
			( pin "@baseboard_fab2_lib.baseboard_fab2(sch_1):page148_i28:mvdd4"
				( attribute "PN" "T8"
					( Origin gPackager )
				)
				( objectStatus "U25W4.T8" )
			)
			( pin "@baseboard_fab2_lib.baseboard_fab2(sch_1):page148_i28:peav11"
				( attribute "PN" "L17"
					( Origin gPackager )
				)
				( objectStatus "U25W4.L17" )
			)
			( pin "@baseboard_fab2_lib.baseboard_fab2(sch_1):page148_i28:peav33"
				( attribute "PN" "L16"
					( Origin gPackager )
				)
				( objectStatus "U25W4.L16" )
			)
			( pin "@baseboard_fab2_lib.baseboard_fab2(sch_1):page148_i28:pecivdd"
				( attribute "PN" "AA17"
					( Origin gPackager )
				)
				( objectStatus "U25W4.AA17" )
			)
			( pin "@baseboard_fab2_lib.baseboard_fab2(sch_1):page148_i28:pllav330"
				( attribute "PN" "Y17"
					( Origin gPackager )
				)
				( objectStatus "U25W4.Y17" )
			)
			( pin "@baseboard_fab2_lib.baseboard_fab2(sch_1):page148_i28:pllav331"
				( attribute "PN" "W17"
					( Origin gPackager )
				)
				( objectStatus "U25W4.W17" )
			)
			( pin "@baseboard_fab2_lib.baseboard_fab2(sch_1):page148_i28:plldv11"
				( attribute "PN" "V17"
					( Origin gPackager )
				)
				( objectStatus "U25W4.V17" )
			)
			( pin "@baseboard_fab2_lib.baseboard_fab2(sch_1):page148_i28:pv33d0"
				( attribute "PN" "F12"
					( Origin gPackager )
				)
				( objectStatus "U25W4.F12" )
			)
			( pin "@baseboard_fab2_lib.baseboard_fab2(sch_1):page148_i28:pv33d1"
				( attribute "PN" "F13"
					( Origin gPackager )
				)
				( objectStatus "U25W4.F13" )
			)
			( pin "@baseboard_fab2_lib.baseboard_fab2(sch_1):page148_i28:pv33d2"
				( attribute "PN" "F14"
					( Origin gPackager )
				)
				( objectStatus "U25W4.F14" )
			)
			( pin "@baseboard_fab2_lib.baseboard_fab2(sch_1):page148_i28:pv33d3"
				( attribute "PN" "F15"
					( Origin gPackager )
				)
				( objectStatus "U25W4.F15" )
			)
			( pin "@baseboard_fab2_lib.baseboard_fab2(sch_1):page148_i28:pv33d4"
				( attribute "PN" "G16"
					( Origin gPackager )
				)
				( objectStatus "U25W4.G16" )
			)
			( pin "@baseboard_fab2_lib.baseboard_fab2(sch_1):page148_i28:pv33d5"
				( attribute "PN" "H17"
					( Origin gPackager )
				)
				( objectStatus "U25W4.H17" )
			)
			( pin "@baseboard_fab2_lib.baseboard_fab2(sch_1):page148_i28:pv33d6"
				( attribute "PN" "K7"
					( Origin gPackager )
				)
				( objectStatus "U25W4.K7" )
			)
			( pin "@baseboard_fab2_lib.baseboard_fab2(sch_1):page148_i28:pv33d7"
				( attribute "PN" "N17"
					( Origin gPackager )
				)
				( objectStatus "U25W4.N17" )
			)
			( pin "@baseboard_fab2_lib.baseboard_fab2(sch_1):page148_i28:pv33d8"
				( attribute "PN" "N6"
					( Origin gPackager )
				)
				( objectStatus "U25W4.N6" )
			)
			( pin "@baseboard_fab2_lib.baseboard_fab2(sch_1):page148_i28:pv33d9"
				( attribute "PN" "P17"
					( Origin gPackager )
				)
				( objectStatus "U25W4.P17" )
			)
			( pin "@baseboard_fab2_lib.baseboard_fab2(sch_1):page148_i28:pv33d10"
				( attribute "PN" "P6"
					( Origin gPackager )
				)
				( objectStatus "U25W4.P6" )
			)
			( pin "@baseboard_fab2_lib.baseboard_fab2(sch_1):page148_i28:pv33d11"
				( attribute "PN" "R17"
					( Origin gPackager )
				)
				( objectStatus "U25W4.R17" )
			)
			( pin "@baseboard_fab2_lib.baseboard_fab2(sch_1):page148_i28:pv33d12"
				( attribute "PN" "R6"
					( Origin gPackager )
				)
				( objectStatus "U25W4.R6" )
			)
			( pin "@baseboard_fab2_lib.baseboard_fab2(sch_1):page148_i28:pv33d13"
				( attribute "PN" "T11"
					( Origin gPackager )
				)
				( objectStatus "U25W4.T11" )
			)
			( pin "@baseboard_fab2_lib.baseboard_fab2(sch_1):page148_i28:pv33d14"
				( attribute "PN" "T15"
					( Origin gPackager )
				)
				( objectStatus "U25W4.T15" )
			)
			( pin "@baseboard_fab2_lib.baseboard_fab2(sch_1):page148_i28:r1vdd0"
				( attribute "PN" "F10"
					( Origin gPackager )
				)
				( objectStatus "U25W4.F10" )
			)
			( pin "@baseboard_fab2_lib.baseboard_fab2(sch_1):page148_i28:r1vdd1"
				( attribute "PN" "F11"
					( Origin gPackager )
				)
				( objectStatus "U25W4.F11" )
			)
			( pin "@baseboard_fab2_lib.baseboard_fab2(sch_1):page148_i28:r2vdd0"
				( attribute "PN" "F7"
					( Origin gPackager )
				)
				( objectStatus "U25W4.F7" )
			)
			( pin "@baseboard_fab2_lib.baseboard_fab2(sch_1):page148_i28:r2vdd1"
				( attribute "PN" "F8"
					( Origin gPackager )
				)
				( objectStatus "U25W4.F8" )
			)
			( pin "@baseboard_fab2_lib.baseboard_fab2(sch_1):page148_i28:usb2av33"
				( attribute "PN" "C7"
					( Origin gPackager )
				)
				( objectStatus "U25W4.C7" )
			)
			( pin "@baseboard_fab2_lib.baseboard_fab2(sch_1):page148_i28:vpllav110"
				( attribute "PN" "L5"
					( Origin gPackager )
				)
				( objectStatus "U25W4.L5" )
			)
			( pin "@baseboard_fab2_lib.baseboard_fab2(sch_1):page148_i28:vpllav111"
				( attribute "PN" "L6"
					( Origin gPackager )
				)
				( objectStatus "U25W4.L6" )
			)
			( pin "@baseboard_fab2_lib.baseboard_fab2(sch_1):page148_i28:vpllav330"
				( attribute "PN" "J7"
					( Origin gPackager )
				)
				( objectStatus "U25W4.J7" )
			)
			( pin "@baseboard_fab2_lib.baseboard_fab2(sch_1):page148_i28:vpllav331"
				( attribute "PN" "H7"
					( Origin gPackager )
				)
				( objectStatus "U25W4.H7" )
			)
			( pin "@baseboard_fab2_lib.baseboard_fab2(sch_1):page149_i123:a"
				( attribute "PN" "1"
					( Origin gPackager )
				)
				( objectStatus "C25W49.1" )
			)
			( pin "@baseboard_fab2_lib.baseboard_fab2(sch_1):page149_i123:b"
				( attribute "PN" "2"
					( Origin gPackager )
				)
				( objectStatus "C25W49.2" )
			)
			( pin "@baseboard_fab2_lib.baseboard_fab2(sch_1):page148_i20:a"
				( attribute "PN" "1"
					( Origin gPackager )
				)
				( objectStatus "C1T21.1" )
			)
			( pin "@baseboard_fab2_lib.baseboard_fab2(sch_1):page148_i20:b"
				( attribute "PN" "2"
					( Origin gPackager )
				)
				( objectStatus "C1T21.2" )
			)
			( pin "@baseboard_fab2_lib.baseboard_fab2(sch_1):page144_i59:a"
				( attribute "PN" "1"
					( Origin gPackager )
				)
				( objectStatus "R1U12.1" )
			)
			( pin "@baseboard_fab2_lib.baseboard_fab2(sch_1):page144_i59:b"
				( attribute "PN" "2"
					( Origin gPackager )
				)
				( objectStatus "R1U12.2" )
			)
			( pin "@baseboard_fab2_lib.baseboard_fab2(sch_1):page148_i16:a"
				( attribute "PN" "1"
					( Origin gPackager )
				)
				( objectStatus "R25W59.1" )
			)
			( pin "@baseboard_fab2_lib.baseboard_fab2(sch_1):page148_i16:b"
				( attribute "PN" "2"
					( Origin gPackager )
				)
				( objectStatus "R25W59.2" )
			)
			( pin "@baseboard_fab2_lib.baseboard_fab2(sch_1):page147_i62:a"
				( attribute "PN" "1"
					( Origin gPackager )
				)
				( objectStatus "R1U2.1" )
			)
			( pin "@baseboard_fab2_lib.baseboard_fab2(sch_1):page147_i62:b"
				( attribute "PN" "2"
					( Origin gPackager )
				)
				( objectStatus "R1U2.2" )
			)
			( pin "@baseboard_fab2_lib.baseboard_fab2(sch_1):page145_i34:a"
				( attribute "PN" "1"
					( Origin gPackager )
				)
				( objectStatus "R25W60.1" )
			)
			( pin "@baseboard_fab2_lib.baseboard_fab2(sch_1):page145_i34:b"
				( attribute "PN" "2"
					( Origin gPackager )
				)
				( objectStatus "R25W60.2" )
			)
			( pin "@baseboard_fab2_lib.baseboard_fab2(sch_1):page147_i106:adc0_gpiw0"
				( attribute "PN" "F4"
					( Origin gPackager )
				)
				( objectStatus "U25W4.F4" )
			)
			( pin "@baseboard_fab2_lib.baseboard_fab2(sch_1):page147_i106:adc1_gpiw1"
				( attribute "PN" "F5"
					( Origin gPackager )
				)
				( objectStatus "U25W4.F5" )
			)
			( pin "@baseboard_fab2_lib.baseboard_fab2(sch_1):page147_i106:adc2_gpiw2"
				( attribute "PN" "E2"
					( Origin gPackager )
				)
				( objectStatus "U25W4.E2" )
			)
			( pin "@baseboard_fab2_lib.baseboard_fab2(sch_1):page147_i106:adc3_gpiw3"
				( attribute "PN" "E1"
					( Origin gPackager )
				)
				( objectStatus "U25W4.E1" )
			)
			( pin "@baseboard_fab2_lib.baseboard_fab2(sch_1):page147_i106:adc4_gpiw4"
				( attribute "PN" "F3"
					( Origin gPackager )
				)
				( objectStatus "U25W4.F3" )
			)
			( pin "@baseboard_fab2_lib.baseboard_fab2(sch_1):page147_i106:adc5_gpiw5"
				( attribute "PN" "E3"
					( Origin gPackager )
				)
				( objectStatus "U25W4.E3" )
			)
			( pin "@baseboard_fab2_lib.baseboard_fab2(sch_1):page147_i106:adc6_gpiw6"
				( attribute "PN" "G5"
					( Origin gPackager )
				)
				( objectStatus "U25W4.G5" )
			)
			( pin "@baseboard_fab2_lib.baseboard_fab2(sch_1):page147_i106:adc7_gpiw7"
				( attribute "PN" "G4"
					( Origin gPackager )
				)
				( objectStatus "U25W4.G4" )
			)
			( pin "@baseboard_fab2_lib.baseboard_fab2(sch_1):page147_i106:adc8_gpix0"
				( attribute "PN" "F2"
					( Origin gPackager )
				)
				( objectStatus "U25W4.F2" )
			)
			( pin "@baseboard_fab2_lib.baseboard_fab2(sch_1):page147_i106:adc9_gpix1"
				( attribute "PN" "G3"
					( Origin gPackager )
				)
				( objectStatus "U25W4.G3" )
			)
			( pin "@baseboard_fab2_lib.baseboard_fab2(sch_1):page147_i106:adc10_gpix2"
				( attribute "PN" "G2"
					( Origin gPackager )
				)
				( objectStatus "U25W4.G2" )
			)
			( pin "@baseboard_fab2_lib.baseboard_fab2(sch_1):page147_i106:adc11_gpix3"
				( attribute "PN" "F1"
					( Origin gPackager )
				)
				( objectStatus "U25W4.F1" )
			)
			( pin "@baseboard_fab2_lib.baseboard_fab2(sch_1):page147_i106:adc12_gpix4"
				( attribute "PN" "H5"
					( Origin gPackager )
				)
				( objectStatus "U25W4.H5" )
			)
			( pin "@baseboard_fab2_lib.baseboard_fab2(sch_1):page147_i106:adc13_gpix5"
				( attribute "PN" "G1"
					( Origin gPackager )
				)
				( objectStatus "U25W4.G1" )
			)
			( pin "@baseboard_fab2_lib.baseboard_fab2(sch_1):page147_i106:adc14_gpix6"
				( attribute "PN" "H3"
					( Origin gPackager )
				)
				( objectStatus "U25W4.H3" )
			)
			( pin "@baseboard_fab2_lib.baseboard_fab2(sch_1):page147_i106:adc15_gpix7"
				( attribute "PN" "H4"
					( Origin gPackager )
				)
				( objectStatus "U25W4.H4" )
			)
			( pin "@baseboard_fab2_lib.baseboard_fab2(sch_1):page147_i106:adcrext"
				( attribute "PN" "J1"
					( Origin gPackager )
				)
				( objectStatus "U25W4.J1" )
			)
			( pin "@baseboard_fab2_lib.baseboard_fab2(sch_1):page147_i106:adcvrefn"
				( attribute "PN" "H1"
					( Origin gPackager )
				)
				( objectStatus "U25W4.H1" )
			)
			( pin "@baseboard_fab2_lib.baseboard_fab2(sch_1):page147_i106:adcvrefp"
				( attribute "PN" "H2"
					( Origin gPackager )
				)
				( objectStatus "U25W4.H2" )
			)
			( pin "@baseboard_fab2_lib.baseboard_fab2(sch_1):page147_i106:gpioa6_timer7_mdc2"
				( attribute "PN" "C13"
					( Origin gPackager )
				)
				( objectStatus "U25W4.C13" )
			)
			( pin "@baseboard_fab2_lib.baseboard_fab2(sch_1):page147_i106:gpioa7_timer8_mdio2"
				( attribute "PN" "B13"
					( Origin gPackager )
				)
				( objectStatus "U25W4.B13" )
			)
			( pin "@baseboard_fab2_lib.baseboard_fab2(sch_1):page147_i106:gpion0_pwm0"
				( attribute "PN" "V2"
					( Origin gPackager )
				)
				( objectStatus "U25W4.V2" )
			)
			( pin "@baseboard_fab2_lib.baseboard_fab2(sch_1):page147_i106:gpion1_pwm1"
				( attribute "PN" "W2"
					( Origin gPackager )
				)
				( objectStatus "U25W4.W2" )
			)
			( pin "@baseboard_fab2_lib.baseboard_fab2(sch_1):page147_i106:gpion2_pwm2_vpig2"
				( attribute "PN" "V3"
					( Origin gPackager )
				)
				( objectStatus "U25W4.V3" )
			)
			( pin "@baseboard_fab2_lib.baseboard_fab2(sch_1):page147_i106:gpion3_pwm3_vpig3"
				( attribute "PN" "U3"
					( Origin gPackager )
				)
				( objectStatus "U25W4.U3" )
			)
			( pin "@baseboard_fab2_lib.baseboard_fab2(sch_1):page147_i106:gpion4_pwm4_vpig4"
				( attribute "PN" "W3"
					( Origin gPackager )
				)
				( objectStatus "U25W4.W3" )
			)
			( pin "@baseboard_fab2_lib.baseboard_fab2(sch_1):page147_i106:gpion5_pwm5_vpig5"
				( attribute "PN" "AA3"
					( Origin gPackager )
				)
				( objectStatus "U25W4.AA3" )
			)
			( pin "@baseboard_fab2_lib.baseboard_fab2(sch_1):page147_i106:gpion6_pwm6_vpig6"
				( attribute "PN" "Y3"
					( Origin gPackager )
				)
				( objectStatus "U25W4.Y3" )
			)
			( pin "@baseboard_fab2_lib.baseboard_fab2(sch_1):page147_i106:gpion7_pwm7_vpig7"
				( attribute "PN" "T4"
					( Origin gPackager )
				)
				( objectStatus "U25W4.T4" )
			)
			( pin "@baseboard_fab2_lib.baseboard_fab2(sch_1):page147_i106:gpioo0_tach0_vpig8"
				( attribute "PN" "U5"
					( Origin gPackager )
				)
				( objectStatus "U25W4.U5" )
			)
			( pin "@baseboard_fab2_lib.baseboard_fab2(sch_1):page147_i106:gpioo1_tach1_vpig9"
				( attribute "PN" "U4"
					( Origin gPackager )
				)
				( objectStatus "U25W4.U4" )
			)
			( pin "@baseboard_fab2_lib.baseboard_fab2(sch_1):page147_i106:gpioo2_tach2"
				( attribute "PN" "V5"
					( Origin gPackager )
				)
				( objectStatus "U25W4.V5" )
			)
			( pin "@baseboard_fab2_lib.baseboard_fab2(sch_1):page147_i106:gpioo3_tach3"
				( attribute "PN" "AB4"
					( Origin gPackager )
				)
				( objectStatus "U25W4.AB4" )
			)
			( pin "@baseboard_fab2_lib.baseboard_fab2(sch_1):page147_i106:gpioo4_tach4_vpir2"
				( attribute "PN" "AB3"
					( Origin gPackager )
				)
				( objectStatus "U25W4.AB3" )
			)
			( pin "@baseboard_fab2_lib.baseboard_fab2(sch_1):page147_i106:gpioo5_tach5_vpir3"
				( attribute "PN" "Y4"
					( Origin gPackager )
				)
				( objectStatus "U25W4.Y4" )
			)
			( pin "@baseboard_fab2_lib.baseboard_fab2(sch_1):page147_i106:gpioo6_tach6_vpir4"
				( attribute "PN" "AA4"
					( Origin gPackager )
				)
				( objectStatus "U25W4.AA4" )
			)
			( pin "@baseboard_fab2_lib.baseboard_fab2(sch_1):page147_i106:gpioo7_tach7_vpir5"
				( attribute "PN" "W4"
					( Origin gPackager )
				)
				( objectStatus "U25W4.W4" )
			)
			( pin "@baseboard_fab2_lib.baseboard_fab2(sch_1):page147_i106:gpiop0_tach8_vpir6"
				( attribute "PN" "V4"
					( Origin gPackager )
				)
				( objectStatus "U25W4.V4" )
			)
			( pin "@baseboard_fab2_lib.baseboard_fab2(sch_1):page147_i106:gpiop1_tach9_vpir7"
				( attribute "PN" "W5"
					( Origin gPackager )
				)
				( objectStatus "U25W4.W5" )
			)
			( pin "@baseboard_fab2_lib.baseboard_fab2(sch_1):page147_i106:gpiop2_tach10_vpir8"
				( attribute "PN" "AA5"
					( Origin gPackager )
				)
				( objectStatus "U25W4.AA5" )
			)
			( pin "@baseboard_fab2_lib.baseboard_fab2(sch_1):page147_i106:gpiop3_tach11_vpir9"
				( attribute "PN" "AB5"
					( Origin gPackager )
				)
				( objectStatus "U25W4.AB5" )
			)
			( pin "@baseboard_fab2_lib.baseboard_fab2(sch_1):page147_i106:gpiop4_tach12"
				( attribute "PN" "Y6"
					( Origin gPackager )
				)
				( objectStatus "U25W4.Y6" )
			)
			( pin "@baseboard_fab2_lib.baseboard_fab2(sch_1):page147_i106:gpiop5_tach13"
				( attribute "PN" "Y5"
					( Origin gPackager )
				)
				( objectStatus "U25W4.Y5" )
			)
			( pin "@baseboard_fab2_lib.baseboard_fab2(sch_1):page147_i106:gpiop6_tach14"
				( attribute "PN" "W6"
					( Origin gPackager )
				)
				( objectStatus "U25W4.W6" )
			)
			( pin "@baseboard_fab2_lib.baseboard_fab2(sch_1):page147_i106:gpiop7_tach15"
				( attribute "PN" "V6"
					( Origin gPackager )
				)
				( objectStatus "U25W4.V6" )
			)
			( pin "@baseboard_fab2_lib.baseboard_fab2(sch_1):page147_i106:gpior6_mdc1"
				( attribute "PN" "D8"
					( Origin gPackager )
				)
				( objectStatus "U25W4.D8" )
			)
			( pin "@baseboard_fab2_lib.baseboard_fab2(sch_1):page147_i106:gpior7_mdio1"
				( attribute "PN" "E10"
					( Origin gPackager )
				)
				( objectStatus "U25W4.E10" )
			)
			( pin "@baseboard_fab2_lib.baseboard_fab2(sch_1):page147_i106:rgmii1rxck_rmii1rclki_gpiou4"
				( attribute "PN" "B4"
					( Origin gPackager )
				)
				( objectStatus "U25W4.B4" )
			)
			( pin "@baseboard_fab2_lib.baseboard_fab2(sch_1):page147_i106:rgmii1rxctl_gpiou5"
				( attribute "PN" "A4"
					( Origin gPackager )
				)
				( objectStatus "U25W4.A4" )
			)
			( pin "@baseboard_fab2_lib.baseboard_fab2(sch_1):page147_i106:rgmii1rxd0_rmii1rxd0_gpiou6"
				( attribute "PN" "A3"
					( Origin gPackager )
				)
				( objectStatus "U25W4.A3" )
			)
			( pin "@baseboard_fab2_lib.baseboard_fab2(sch_1):page147_i106:rgmii1rxd1_rmii1rxd1_gpiou7"
				( attribute "PN" "D6"
					( Origin gPackager )
				)
				( objectStatus "U25W4.D6" )
			)
			( pin "@baseboard_fab2_lib.baseboard_fab2(sch_1):page147_i106:rgmii1rxd2_rmii1crsdv_gpiov0"
				( attribute "PN" "C5"
					( Origin gPackager )
				)
				( objectStatus "U25W4.C5" )
			)
			( pin "@baseboard_fab2_lib.baseboard_fab2(sch_1):page147_i106:rgmii1rxd3_rmii1rxer_gpiov1"
				( attribute "PN" "C4"
					( Origin gPackager )
				)
				( objectStatus "U25W4.C4" )
			)
			( pin "@baseboard_fab2_lib.baseboard_fab2(sch_1):page147_i106:rgmii1txck_rmii1rclko_gpiot0"
				( attribute "PN" "B5"
					( Origin gPackager )
				)
				( objectStatus "U25W4.B5" )
			)
			( pin "@baseboard_fab2_lib.baseboard_fab2(sch_1):page147_i106:rgmii1txctl_rmii1txen_gpiot1"
				( attribute "PN" "E9"
					( Origin gPackager )
				)
				( objectStatus "U25W4.E9" )
			)
			( pin "@baseboard_fab2_lib.baseboard_fab2(sch_1):page147_i106:rgmii1txd0_rmii1txd0_gpiot2"
				( attribute "PN" "F9"
					( Origin gPackager )
				)
				( objectStatus "U25W4.F9" )
			)
			( pin "@baseboard_fab2_lib.baseboard_fab2(sch_1):page147_i106:rgmii1txd1_rmii1txd1_gpiot3"
				( attribute "PN" "A5"
					( Origin gPackager )
				)
				( objectStatus "U25W4.A5" )
			)
			( pin "@baseboard_fab2_lib.baseboard_fab2(sch_1):page147_i106:rgmii1txd2_gpiot4"
				( attribute "PN" "E7"
					( Origin gPackager )
				)
				( objectStatus "U25W4.E7" )
			)
			( pin "@baseboard_fab2_lib.baseboard_fab2(sch_1):page147_i106:rgmii1txd3_gpiot5"
				( attribute "PN" "D7"
					( Origin gPackager )
				)
				( objectStatus "U25W4.D7" )
			)
			( pin "@baseboard_fab2_lib.baseboard_fab2(sch_1):page147_i106:rgmii2rxck_rmii2rclki_gpiov2"
				( attribute "PN" "C2"
					( Origin gPackager )
				)
				( objectStatus "U25W4.C2" )
			)
			( pin "@baseboard_fab2_lib.baseboard_fab2(sch_1):page147_i106:rgmii2rxctl_gpiov3"
				( attribute "PN" "C1"
					( Origin gPackager )
				)
				( objectStatus "U25W4.C1" )
			)
			( pin "@baseboard_fab2_lib.baseboard_fab2(sch_1):page147_i106:rgmii2rxd0_rmii2rxd0_gpiov4"
				( attribute "PN" "C3"
					( Origin gPackager )
				)
				( objectStatus "U25W4.C3" )
			)
			( pin "@baseboard_fab2_lib.baseboard_fab2(sch_1):page147_i106:rgmii2rxd1_rmii2rxd1_gpiov5"
				( attribute "PN" "D1"
					( Origin gPackager )
				)
				( objectStatus "U25W4.D1" )
			)
			( pin "@baseboard_fab2_lib.baseboard_fab2(sch_1):page147_i106:rgmii2rxd2_rmii2crsdv_gpiov6"
				( attribute "PN" "D2"
					( Origin gPackager )
				)
				( objectStatus "U25W4.D2" )
			)
			( pin "@baseboard_fab2_lib.baseboard_fab2(sch_1):page147_i106:rgmii2rxd3_rmii2rxer_gpiov7"
				( attribute "PN" "E6"
					( Origin gPackager )
				)
				( objectStatus "U25W4.E6" )
			)
			( pin "@baseboard_fab2_lib.baseboard_fab2(sch_1):page147_i106:rgmii2txck_rmii2rclko_gpiot6"
				( attribute "PN" "B2"
					( Origin gPackager )
				)
				( objectStatus "U25W4.B2" )
			)
			( pin "@baseboard_fab2_lib.baseboard_fab2(sch_1):page147_i106:rgmii2txctl_rmii2txen_gpiot7"
				( attribute "PN" "B1"
					( Origin gPackager )
				)
				( objectStatus "U25W4.B1" )
			)
			( pin "@baseboard_fab2_lib.baseboard_fab2(sch_1):page147_i106:rgmii2txd0_rmii2txd0_gpiou0"
				( attribute "PN" "A2"
					( Origin gPackager )
				)
				( objectStatus "U25W4.A2" )
			)
			( pin "@baseboard_fab2_lib.baseboard_fab2(sch_1):page147_i106:rgmii2txd1_rmii2txd1_gpiou1"
				( attribute "PN" "B3"
					( Origin gPackager )
				)
				( objectStatus "U25W4.B3" )
			)
			( pin "@baseboard_fab2_lib.baseboard_fab2(sch_1):page147_i106:rgmii2txd2_gpiou2"
				( attribute "PN" "D5"
					( Origin gPackager )
				)
				( objectStatus "U25W4.D5" )
			)
			( pin "@baseboard_fab2_lib.baseboard_fab2(sch_1):page147_i106:rgmii2txd3_gpiou3"
				( attribute "PN" "D4"
					( Origin gPackager )
				)
				( objectStatus "U25W4.D4" )
			)
			( pin "@baseboard_fab2_lib.baseboard_fab2(sch_1):page147_i106:rgmiick"
				( attribute "PN" "D3"
					( Origin gPackager )
				)
				( objectStatus "U25W4.D3" )
			)
			( pin "@baseboard_fab2_lib.baseboard_fab2(sch_1):page147_i61:a"
				( attribute "PN" "1"
					( Origin gPackager )
				)
				( objectStatus "R1U1.1" )
			)
			( pin "@baseboard_fab2_lib.baseboard_fab2(sch_1):page147_i61:b"
				( attribute "PN" "2"
					( Origin gPackager )
				)
				( objectStatus "R1U1.2" )
			)
			( pin "@baseboard_fab2_lib.baseboard_fab2(sch_1):page146_i37:a"
				( attribute "PN" "1"
					( Origin gPackager )
				)
				( objectStatus "R1T26.1" )
			)
			( pin "@baseboard_fab2_lib.baseboard_fab2(sch_1):page146_i37:b"
				( attribute "PN" "2"
					( Origin gPackager )
				)
				( objectStatus "R1T26.2" )
			)
			( pin "@baseboard_fab2_lib.baseboard_fab2(sch_1):page146_i35:a"
				( attribute "PN" "1"
					( Origin gPackager )
				)
				( objectStatus "R1T25.1" )
			)
			( pin "@baseboard_fab2_lib.baseboard_fab2(sch_1):page146_i35:b"
				( attribute "PN" "2"
					( Origin gPackager )
				)
				( objectStatus "R1T25.2" )
			)
			( pin "@baseboard_fab2_lib.baseboard_fab2(sch_1):page146_i26:a"
				( attribute "PN" "1"
					( Origin gPackager )
				)
				( objectStatus "R25W83.1" )
			)
			( pin "@baseboard_fab2_lib.baseboard_fab2(sch_1):page146_i26:b"
				( attribute "PN" "2"
					( Origin gPackager )
				)
				( objectStatus "R25W83.2" )
			)
			( pin "@baseboard_fab2_lib.baseboard_fab2(sch_1):page149_i5:a"
				( attribute "PN" "1"
					( Origin gPackager )
				)
				( objectStatus "C25W70.1" )
			)
			( pin "@baseboard_fab2_lib.baseboard_fab2(sch_1):page149_i5:b"
				( attribute "PN" "2"
					( Origin gPackager )
				)
				( objectStatus "C25W70.2" )
			)
			( pin "@baseboard_fab2_lib.baseboard_fab2(sch_1):page147_i21:a"
				( attribute "PN" "1"
					( Origin gPackager )
				)
				( objectStatus "R25W90.1" )
			)
			( pin "@baseboard_fab2_lib.baseboard_fab2(sch_1):page147_i21:b"
				( attribute "PN" "2"
					( Origin gPackager )
				)
				( objectStatus "R25W90.2" )
			)
			( pin "@baseboard_fab2_lib.baseboard_fab2(sch_1):page149_i124:a"
				( attribute "PN" "1"
					( Origin gPackager )
				)
				( objectStatus "C25W55.1" )
			)
			( pin "@baseboard_fab2_lib.baseboard_fab2(sch_1):page149_i124:b"
				( attribute "PN" "2"
					( Origin gPackager )
				)
				( objectStatus "C25W55.2" )
			)
			( pin "@baseboard_fab2_lib.baseboard_fab2(sch_1):page208_i120:\1\"
				( attribute "PN" "1"
					( Origin gPackager )
				)
				( objectStatus "RT12.1" )
			)
			( pin "@baseboard_fab2_lib.baseboard_fab2(sch_1):page208_i120:\2\"
				( attribute "PN" "2"
					( Origin gPackager )
				)
				( objectStatus "RT12.2" )
			)
			( pin "@baseboard_fab2_lib.baseboard_fab2(sch_1):page145_i14:a"
				( attribute "PN" "1"
					( Origin gPackager )
				)
				( objectStatus "R9F61.1" )
			)
			( pin "@baseboard_fab2_lib.baseboard_fab2(sch_1):page145_i14:b"
				( attribute "PN" "2"
					( Origin gPackager )
				)
				( objectStatus "R9F61.2" )
			)
			( pin "@baseboard_fab2_lib.baseboard_fab2(sch_1):page145_i11:a"
				( attribute "PN" "1"
					( Origin gPackager )
				)
				( objectStatus "R9F62.1" )
			)
			( pin "@baseboard_fab2_lib.baseboard_fab2(sch_1):page145_i11:b"
				( attribute "PN" "2"
					( Origin gPackager )
				)
				( objectStatus "R9F62.2" )
			)
			( pin "@baseboard_fab2_lib.baseboard_fab2(sch_1):page145_i10:a"
				( attribute "PN" "1"
					( Origin gPackager )
				)
				( objectStatus "R9F60.1" )
			)
			( pin "@baseboard_fab2_lib.baseboard_fab2(sch_1):page145_i10:b"
				( attribute "PN" "2"
					( Origin gPackager )
				)
				( objectStatus "R9F60.2" )
			)
			( pin "@baseboard_fab2_lib.baseboard_fab2(sch_1):page145_i8:enable_control"
				( attribute "PN" "1"
					( Origin gPackager )
				)
				( objectStatus "Y9F2.1" )
			)
			( pin "@baseboard_fab2_lib.baseboard_fab2(sch_1):page145_i8:gnd"
				( attribute "PN" "2"
					( Origin gPackager )
				)
				( objectStatus "Y9F2.2" )
			)
			( pin "@baseboard_fab2_lib.baseboard_fab2(sch_1):page145_i8:\out\"
				( attribute "PN" "3"
					( Origin gPackager )
				)
				( objectStatus "Y9F2.3" )
			)
			( pin "@baseboard_fab2_lib.baseboard_fab2(sch_1):page145_i8:vdd"
				( attribute "PN" "4"
					( Origin gPackager )
				)
				( objectStatus "Y9F2.4" )
			)
			( pin "@baseboard_fab2_lib.baseboard_fab2(sch_1):page197_i112:\1\"
				( attribute "PN" "1"
					( Origin gPackager )
				)
				( objectStatus "R12W15.1" )
			)
			( pin "@baseboard_fab2_lib.baseboard_fab2(sch_1):page197_i112:\2\"
				( attribute "PN" "2"
					( Origin gPackager )
				)
				( objectStatus "R12W15.2" )
			)
			( pin "@baseboard_fab2_lib.baseboard_fab2(sch_1):page151_i228:\1\"
				( attribute "PN" "1"
					( Origin gPackager )
				)
				( objectStatus "R25W33.1" )
			)
			( pin "@baseboard_fab2_lib.baseboard_fab2(sch_1):page151_i228:\2\"
				( attribute "PN" "2"
					( Origin gPackager )
				)
				( objectStatus "R25W33.2" )
			)
			( pin "@baseboard_fab2_lib.baseboard_fab2(sch_1):page151_i125:a"
				( attribute "PN" "1"
					( Origin gPackager )
				)
				( objectStatus "C25W1.1" )
			)
			( pin "@baseboard_fab2_lib.baseboard_fab2(sch_1):page151_i125:b"
				( attribute "PN" "2"
					( Origin gPackager )
				)
				( objectStatus "C25W1.2" )
			)
			( pin "@baseboard_fab2_lib.baseboard_fab2(sch_1):page151_i123:a"
				( attribute "PN" "1"
					( Origin gPackager )
				)
				( objectStatus "C25W19.1" )
			)
			( pin "@baseboard_fab2_lib.baseboard_fab2(sch_1):page151_i123:b"
				( attribute "PN" "2"
					( Origin gPackager )
				)
				( objectStatus "C25W19.2" )
			)
			( pin "@baseboard_fab2_lib.baseboard_fab2(sch_1):page151_i121:\1\"
				( attribute "PN" "1"
					( Origin gPackager )
				)
				( objectStatus "C25W18.1" )
			)
			( pin "@baseboard_fab2_lib.baseboard_fab2(sch_1):page151_i121:\2\"
				( attribute "PN" "2"
					( Origin gPackager )
				)
				( objectStatus "C25W18.2" )
			)
			( pin "@baseboard_fab2_lib.baseboard_fab2(sch_1):page151_i120:\1\"
				( attribute "PN" "1"
					( Origin gPackager )
				)
				( objectStatus "C25W17.1" )
			)
			( pin "@baseboard_fab2_lib.baseboard_fab2(sch_1):page151_i120:\2\"
				( attribute "PN" "2"
					( Origin gPackager )
				)
				( objectStatus "C25W17.2" )
			)
			( pin "@baseboard_fab2_lib.baseboard_fab2(sch_1):page146_i160:a"
				( attribute "PN" "1"
					( Origin gPackager )
				)
				( objectStatus "C1W21.1" )
			)
			( pin "@baseboard_fab2_lib.baseboard_fab2(sch_1):page146_i160:b"
				( attribute "PN" "2"
					( Origin gPackager )
				)
				( objectStatus "C1W21.2" )
			)
			( pin "@baseboard_fab2_lib.baseboard_fab2(sch_1):page99_i115:a"
				( attribute "PN" "1"
					( Origin gPackager )
				)
				( objectStatus "R6U14.1" )
			)
			( pin "@baseboard_fab2_lib.baseboard_fab2(sch_1):page99_i115:b"
				( attribute "PN" "2"
					( Origin gPackager )
				)
				( objectStatus "R6U14.2" )
			)
			( pin "@baseboard_fab2_lib.baseboard_fab2(sch_1):page151_i101:a"
				( attribute "PN" "1"
					( Origin gPackager )
				)
				( objectStatus "R25W117.1" )
			)
			( pin "@baseboard_fab2_lib.baseboard_fab2(sch_1):page151_i101:b"
				( attribute "PN" "2"
					( Origin gPackager )
				)
				( objectStatus "R25W117.2" )
			)
			( pin "@baseboard_fab2_lib.baseboard_fab2(sch_1):page149_i119:a"
				( attribute "PN" "1"
					( Origin gPackager )
				)
				( objectStatus "C25W31.1" )
			)
			( pin "@baseboard_fab2_lib.baseboard_fab2(sch_1):page149_i119:b"
				( attribute "PN" "2"
					( Origin gPackager )
				)
				( objectStatus "C25W31.2" )
			)
			( pin "@baseboard_fab2_lib.baseboard_fab2(sch_1):page149_i120:a"
				( attribute "PN" "1"
					( Origin gPackager )
				)
				( objectStatus "C25W34.1" )
			)
			( pin "@baseboard_fab2_lib.baseboard_fab2(sch_1):page149_i120:b"
				( attribute "PN" "2"
					( Origin gPackager )
				)
				( objectStatus "C25W34.2" )
			)
			( pin "@baseboard_fab2_lib.baseboard_fab2(sch_1):page151_i248:\1\"
				( attribute "PN" "1"
					( Origin gPackager )
				)
				( objectStatus "R25W1.1" )
			)
			( pin "@baseboard_fab2_lib.baseboard_fab2(sch_1):page151_i248:\2\"
				( attribute "PN" "2"
					( Origin gPackager )
				)
				( objectStatus "R25W1.2" )
			)
			( pin "@baseboard_fab2_lib.baseboard_fab2(sch_1):page151_i56:a"
				( attribute "PN" "2"
					( Origin gPackager )
				)
				( objectStatus "U9F3.2" )
			)
			( pin "@baseboard_fab2_lib.baseboard_fab2(sch_1):page151_i56:y"
				( attribute "PN" "4"
					( Origin gPackager )
				)
				( objectStatus "U9F3.4" )
			)
			( pin "@baseboard_fab2_lib.baseboard_fab2(sch_1):page147_i129:a"
				( attribute "PN" "1"
					( Origin gPackager )
				)
				( objectStatus "R1T24.1" )
			)
			( pin "@baseboard_fab2_lib.baseboard_fab2(sch_1):page147_i129:b"
				( attribute "PN" "2"
					( Origin gPackager )
				)
				( objectStatus "R1T24.2" )
			)
			( pin "@baseboard_fab2_lib.baseboard_fab2(sch_1):page147_i66:a"
				( attribute "PN" "1"
					( Origin gPackager )
				)
				( objectStatus "R1U5.1" )
			)
			( pin "@baseboard_fab2_lib.baseboard_fab2(sch_1):page147_i66:b"
				( attribute "PN" "2"
					( Origin gPackager )
				)
				( objectStatus "R1U5.2" )
			)
			( pin "@baseboard_fab2_lib.baseboard_fab2(sch_1):page147_i65:a"
				( attribute "PN" "1"
					( Origin gPackager )
				)
				( objectStatus "R1U4.1" )
			)
			( pin "@baseboard_fab2_lib.baseboard_fab2(sch_1):page147_i65:b"
				( attribute "PN" "2"
					( Origin gPackager )
				)
				( objectStatus "R1U4.2" )
			)
			( pin "@baseboard_fab2_lib.baseboard_fab2(sch_1):page147_i43:a"
				( attribute "PN" "1"
					( Origin gPackager )
				)
				( objectStatus "R25W80.1" )
			)
			( pin "@baseboard_fab2_lib.baseboard_fab2(sch_1):page147_i43:b"
				( attribute "PN" "2"
					( Origin gPackager )
				)
				( objectStatus "R25W80.2" )
			)
			( pin "@baseboard_fab2_lib.baseboard_fab2(sch_1):page147_i42:a"
				( attribute "PN" "1"
					( Origin gPackager )
				)
				( objectStatus "R25W79.1" )
			)
			( pin "@baseboard_fab2_lib.baseboard_fab2(sch_1):page147_i42:b"
				( attribute "PN" "2"
					( Origin gPackager )
				)
				( objectStatus "R25W79.2" )
			)
			( pin "@baseboard_fab2_lib.baseboard_fab2(sch_1):page147_i161:a"
				( attribute "PN" "1"
					( Origin gPackager )
				)
				( objectStatus "C25W7.1" )
			)
			( pin "@baseboard_fab2_lib.baseboard_fab2(sch_1):page147_i161:b"
				( attribute "PN" "2"
					( Origin gPackager )
				)
				( objectStatus "C25W7.2" )
			)
			( pin "@baseboard_fab2_lib.baseboard_fab2(sch_1):page147_i25:a"
				( attribute "PN" "1"
					( Origin gPackager )
				)
				( objectStatus "R25W87.1" )
			)
			( pin "@baseboard_fab2_lib.baseboard_fab2(sch_1):page147_i25:b"
				( attribute "PN" "2"
					( Origin gPackager )
				)
				( objectStatus "R25W87.2" )
			)
			( pin "@baseboard_fab2_lib.baseboard_fab2(sch_1):page147_i24:a"
				( attribute "PN" "1"
					( Origin gPackager )
				)
				( objectStatus "R25W86.1" )
			)
			( pin "@baseboard_fab2_lib.baseboard_fab2(sch_1):page147_i24:b"
				( attribute "PN" "2"
					( Origin gPackager )
				)
				( objectStatus "R25W86.2" )
			)
			( pin "@baseboard_fab2_lib.baseboard_fab2(sch_1):page147_i23:a"
				( attribute "PN" "1"
					( Origin gPackager )
				)
				( objectStatus "R25W85.1" )
			)
			( pin "@baseboard_fab2_lib.baseboard_fab2(sch_1):page147_i23:b"
				( attribute "PN" "2"
					( Origin gPackager )
				)
				( objectStatus "R25W85.2" )
			)
			( pin "@baseboard_fab2_lib.baseboard_fab2(sch_1):page147_i22:a"
				( attribute "PN" "1"
					( Origin gPackager )
				)
				( objectStatus "R25W89.1" )
			)
			( pin "@baseboard_fab2_lib.baseboard_fab2(sch_1):page147_i22:b"
				( attribute "PN" "2"
					( Origin gPackager )
				)
				( objectStatus "R25W89.2" )
			)
			( pin "@baseboard_fab2_lib.baseboard_fab2(sch_1):page147_i8:a"
				( attribute "PN" "1"
					( Origin gPackager )
				)
				( objectStatus "R25W88.1" )
			)
			( pin "@baseboard_fab2_lib.baseboard_fab2(sch_1):page147_i8:b"
				( attribute "PN" "2"
					( Origin gPackager )
				)
				( objectStatus "R25W88.2" )
			)
			( pin "@baseboard_fab2_lib.baseboard_fab2(sch_1):page146_i85:a"
				( attribute "PN" "1"
					( Origin gPackager )
				)
				( objectStatus "R25W69.1" )
			)
			( pin "@baseboard_fab2_lib.baseboard_fab2(sch_1):page146_i85:b"
				( attribute "PN" "2"
					( Origin gPackager )
				)
				( objectStatus "R25W69.2" )
			)
			( pin "@baseboard_fab2_lib.baseboard_fab2(sch_1):page146_i84:a"
				( attribute "PN" "1"
					( Origin gPackager )
				)
				( objectStatus "R25W68.1" )
			)
			( pin "@baseboard_fab2_lib.baseboard_fab2(sch_1):page146_i84:b"
				( attribute "PN" "2"
					( Origin gPackager )
				)
				( objectStatus "R25W68.2" )
			)
			( pin "@baseboard_fab2_lib.baseboard_fab2(sch_1):page146_i78:a"
				( attribute "PN" "1"
					( Origin gPackager )
				)
				( objectStatus "R1U7.1" )
			)
			( pin "@baseboard_fab2_lib.baseboard_fab2(sch_1):page146_i78:b"
				( attribute "PN" "2"
					( Origin gPackager )
				)
				( objectStatus "R1U7.2" )
			)
			( pin "@baseboard_fab2_lib.baseboard_fab2(sch_1):page146_i76:a"
				( attribute "PN" "1"
					( Origin gPackager )
				)
				( objectStatus "R25W66.1" )
			)
			( pin "@baseboard_fab2_lib.baseboard_fab2(sch_1):page146_i76:b"
				( attribute "PN" "2"
					( Origin gPackager )
				)
				( objectStatus "R25W66.2" )
			)
			( pin "@baseboard_fab2_lib.baseboard_fab2(sch_1):page146_i75:a"
				( attribute "PN" "1"
					( Origin gPackager )
				)
				( objectStatus "R3N26.1" )
			)
			( pin "@baseboard_fab2_lib.baseboard_fab2(sch_1):page146_i75:b"
				( attribute "PN" "2"
					( Origin gPackager )
				)
				( objectStatus "R3N26.2" )
			)
			( pin "@baseboard_fab2_lib.baseboard_fab2(sch_1):page146_i74:a"
				( attribute "PN" "1"
					( Origin gPackager )
				)
				( objectStatus "R3N24.1" )
			)
			( pin "@baseboard_fab2_lib.baseboard_fab2(sch_1):page146_i74:b"
				( attribute "PN" "2"
					( Origin gPackager )
				)
				( objectStatus "R3N24.2" )
			)
			( pin "@baseboard_fab2_lib.baseboard_fab2(sch_1):page146_i73:a"
				( attribute "PN" "1"
					( Origin gPackager )
				)
				( objectStatus "R25W73.1" )
			)
			( pin "@baseboard_fab2_lib.baseboard_fab2(sch_1):page146_i73:b"
				( attribute "PN" "2"
					( Origin gPackager )
				)
				( objectStatus "R25W73.2" )
			)
			( pin "@baseboard_fab2_lib.baseboard_fab2(sch_1):page201_i185:a"
				( attribute "PN" "1"
					( Origin gPackager )
				)
				( objectStatus "RF4.1" )
			)
			( pin "@baseboard_fab2_lib.baseboard_fab2(sch_1):page201_i185:b"
				( attribute "PN" "2"
					( Origin gPackager )
				)
				( objectStatus "RF4.2" )
			)
			( pin "@baseboard_fab2_lib.baseboard_fab2(sch_1):page146_i71:a"
				( attribute "PN" "1"
					( Origin gPackager )
				)
				( objectStatus "R25W72.1" )
			)
			( pin "@baseboard_fab2_lib.baseboard_fab2(sch_1):page146_i71:b"
				( attribute "PN" "2"
					( Origin gPackager )
				)
				( objectStatus "R25W72.2" )
			)
			( pin "@baseboard_fab2_lib.baseboard_fab2(sch_1):page146_i70:a"
				( attribute "PN" "1"
					( Origin gPackager )
				)
				( objectStatus "R25W74.1" )
			)
			( pin "@baseboard_fab2_lib.baseboard_fab2(sch_1):page146_i70:b"
				( attribute "PN" "2"
					( Origin gPackager )
				)
				( objectStatus "R25W74.2" )
			)
			( pin "@baseboard_fab2_lib.baseboard_fab2(sch_1):page151_i173:a"
				( attribute "PN" "1"
					( Origin gPackager )
				)
				( objectStatus "R9E21.1" )
			)
			( pin "@baseboard_fab2_lib.baseboard_fab2(sch_1):page151_i173:b"
				( attribute "PN" "2"
					( Origin gPackager )
				)
				( objectStatus "R9E21.2" )
			)
			( pin "@baseboard_fab2_lib.baseboard_fab2(sch_1):page151_i249:\1\"
				( attribute "PN" "1"
					( Origin gPackager )
				)
				( objectStatus "R25W2.1" )
			)
			( pin "@baseboard_fab2_lib.baseboard_fab2(sch_1):page151_i249:\2\"
				( attribute "PN" "2"
					( Origin gPackager )
				)
				( objectStatus "R25W2.2" )
			)
			( pin "@baseboard_fab2_lib.baseboard_fab2(sch_1):page151_i250:\1\"
				( attribute "PN" "1"
					( Origin gPackager )
				)
				( objectStatus "R25W3.1" )
			)
			( pin "@baseboard_fab2_lib.baseboard_fab2(sch_1):page151_i250:\2\"
				( attribute "PN" "2"
					( Origin gPackager )
				)
				( objectStatus "R25W3.2" )
			)
			( pin "@baseboard_fab2_lib.baseboard_fab2(sch_1):page151_i251:\1\"
				( attribute "PN" "1"
					( Origin gPackager )
				)
				( objectStatus "R25W4.1" )
			)
			( pin "@baseboard_fab2_lib.baseboard_fab2(sch_1):page151_i251:\2\"
				( attribute "PN" "2"
					( Origin gPackager )
				)
				( objectStatus "R25W4.2" )
			)
			( pin "@baseboard_fab2_lib.baseboard_fab2(sch_1):page151_i252:\1\"
				( attribute "PN" "1"
					( Origin gPackager )
				)
				( objectStatus "R25W5.1" )
			)
			( pin "@baseboard_fab2_lib.baseboard_fab2(sch_1):page151_i252:\2\"
				( attribute "PN" "2"
					( Origin gPackager )
				)
				( objectStatus "R25W5.2" )
			)
			( pin "@baseboard_fab2_lib.baseboard_fab2(sch_1):page151_i253:\1\"
				( attribute "PN" "1"
					( Origin gPackager )
				)
				( objectStatus "R25W6.1" )
			)
			( pin "@baseboard_fab2_lib.baseboard_fab2(sch_1):page151_i253:\2\"
				( attribute "PN" "2"
					( Origin gPackager )
				)
				( objectStatus "R25W6.2" )
			)
			( pin "@baseboard_fab2_lib.baseboard_fab2(sch_1):page151_i254:\1\"
				( attribute "PN" "1"
					( Origin gPackager )
				)
				( objectStatus "R25W7.1" )
			)
			( pin "@baseboard_fab2_lib.baseboard_fab2(sch_1):page151_i254:\2\"
				( attribute "PN" "2"
					( Origin gPackager )
				)
				( objectStatus "R25W7.2" )
			)
			( pin "@baseboard_fab2_lib.baseboard_fab2(sch_1):page151_i255:\1\"
				( attribute "PN" "1"
					( Origin gPackager )
				)
				( objectStatus "R25W8.1" )
			)
			( pin "@baseboard_fab2_lib.baseboard_fab2(sch_1):page151_i255:\2\"
				( attribute "PN" "2"
					( Origin gPackager )
				)
				( objectStatus "R25W8.2" )
			)
			( pin "@baseboard_fab2_lib.baseboard_fab2(sch_1):page151_i256:\1\"
				( attribute "PN" "1"
					( Origin gPackager )
				)
				( objectStatus "R25W12.1" )
			)
			( pin "@baseboard_fab2_lib.baseboard_fab2(sch_1):page151_i256:\2\"
				( attribute "PN" "2"
					( Origin gPackager )
				)
				( objectStatus "R25W12.2" )
			)
			( pin "@baseboard_fab2_lib.baseboard_fab2(sch_1):page151_i257:\1\"
				( attribute "PN" "1"
					( Origin gPackager )
				)
				( objectStatus "R25W11.1" )
			)
			( pin "@baseboard_fab2_lib.baseboard_fab2(sch_1):page151_i257:\2\"
				( attribute "PN" "2"
					( Origin gPackager )
				)
				( objectStatus "R25W11.2" )
			)
			( pin "@baseboard_fab2_lib.baseboard_fab2(sch_1):page151_i258:\1\"
				( attribute "PN" "1"
					( Origin gPackager )
				)
				( objectStatus "R25W9.1" )
			)
			( pin "@baseboard_fab2_lib.baseboard_fab2(sch_1):page151_i258:\2\"
				( attribute "PN" "2"
					( Origin gPackager )
				)
				( objectStatus "R25W9.2" )
			)
			( pin "@baseboard_fab2_lib.baseboard_fab2(sch_1):page151_i259:\1\"
				( attribute "PN" "1"
					( Origin gPackager )
				)
				( objectStatus "R25W10.1" )
			)
			( pin "@baseboard_fab2_lib.baseboard_fab2(sch_1):page151_i259:\2\"
				( attribute "PN" "2"
					( Origin gPackager )
				)
				( objectStatus "R25W10.2" )
			)
			( pin "@baseboard_fab2_lib.baseboard_fab2(sch_1):page151_i260:\1\"
				( attribute "PN" "1"
					( Origin gPackager )
				)
				( objectStatus "R25W13.1" )
			)
			( pin "@baseboard_fab2_lib.baseboard_fab2(sch_1):page151_i260:\2\"
				( attribute "PN" "2"
					( Origin gPackager )
				)
				( objectStatus "R25W13.2" )
			)
			( pin "@baseboard_fab2_lib.baseboard_fab2(sch_1):page151_i261:\1\"
				( attribute "PN" "1"
					( Origin gPackager )
				)
				( objectStatus "R25W16.1" )
			)
			( pin "@baseboard_fab2_lib.baseboard_fab2(sch_1):page151_i261:\2\"
				( attribute "PN" "2"
					( Origin gPackager )
				)
				( objectStatus "R25W16.2" )
			)
			( pin "@baseboard_fab2_lib.baseboard_fab2(sch_1):page151_i262:\1\"
				( attribute "PN" "1"
					( Origin gPackager )
				)
				( objectStatus "R25W15.1" )
			)
			( pin "@baseboard_fab2_lib.baseboard_fab2(sch_1):page151_i262:\2\"
				( attribute "PN" "2"
					( Origin gPackager )
				)
				( objectStatus "R25W15.2" )
			)
			( pin "@baseboard_fab2_lib.baseboard_fab2(sch_1):page151_i263:\1\"
				( attribute "PN" "1"
					( Origin gPackager )
				)
				( objectStatus "R25W14.1" )
			)
			( pin "@baseboard_fab2_lib.baseboard_fab2(sch_1):page151_i263:\2\"
				( attribute "PN" "2"
					( Origin gPackager )
				)
				( objectStatus "R25W14.2" )
			)
			( pin "@baseboard_fab2_lib.baseboard_fab2(sch_1):page151_i264:\1\"
				( attribute "PN" "1"
					( Origin gPackager )
				)
				( objectStatus "R25W17.1" )
			)
			( pin "@baseboard_fab2_lib.baseboard_fab2(sch_1):page151_i264:\2\"
				( attribute "PN" "2"
					( Origin gPackager )
				)
				( objectStatus "R25W17.2" )
			)
			( pin "@baseboard_fab2_lib.baseboard_fab2(sch_1):page151_i265:\1\"
				( attribute "PN" "1"
					( Origin gPackager )
				)
				( objectStatus "R25W18.1" )
			)
			( pin "@baseboard_fab2_lib.baseboard_fab2(sch_1):page151_i265:\2\"
				( attribute "PN" "2"
					( Origin gPackager )
				)
				( objectStatus "R25W18.2" )
			)
			( pin "@baseboard_fab2_lib.baseboard_fab2(sch_1):page151_i266:\1\"
				( attribute "PN" "1"
					( Origin gPackager )
				)
				( objectStatus "R25W20.1" )
			)
			( pin "@baseboard_fab2_lib.baseboard_fab2(sch_1):page151_i266:\2\"
				( attribute "PN" "2"
					( Origin gPackager )
				)
				( objectStatus "R25W20.2" )
			)
			( pin "@baseboard_fab2_lib.baseboard_fab2(sch_1):page151_i267:\1\"
				( attribute "PN" "1"
					( Origin gPackager )
				)
				( objectStatus "R25W19.1" )
			)
			( pin "@baseboard_fab2_lib.baseboard_fab2(sch_1):page151_i267:\2\"
				( attribute "PN" "2"
					( Origin gPackager )
				)
				( objectStatus "R25W19.2" )
			)
			( pin "@baseboard_fab2_lib.baseboard_fab2(sch_1):page151_i268:\1\"
				( attribute "PN" "1"
					( Origin gPackager )
				)
				( objectStatus "R25W24.1" )
			)
			( pin "@baseboard_fab2_lib.baseboard_fab2(sch_1):page151_i268:\2\"
				( attribute "PN" "2"
					( Origin gPackager )
				)
				( objectStatus "R25W24.2" )
			)
			( pin "@baseboard_fab2_lib.baseboard_fab2(sch_1):page151_i211:a"
				( attribute "PN" "1"
					( Origin gPackager )
				)
				( objectStatus "R25W118.1" )
			)
			( pin "@baseboard_fab2_lib.baseboard_fab2(sch_1):page151_i211:b"
				( attribute "PN" "2"
					( Origin gPackager )
				)
				( objectStatus "R25W118.2" )
			)
			( pin "@baseboard_fab2_lib.baseboard_fab2(sch_1):page151_i145:drain(0)"
				( attribute "PN" "3"
					( Origin gPackager )
				)
				( objectStatus "Q9E1.3" )
			)
			( pin "@baseboard_fab2_lib.baseboard_fab2(sch_1):page151_i145:gate(0)"
				( attribute "PN" "5"
					( Origin gPackager )
				)
				( objectStatus "Q9E1.5" )
			)
			( pin "@baseboard_fab2_lib.baseboard_fab2(sch_1):page151_i145:source(0)"
				( attribute "PN" "4"
					( Origin gPackager )
				)
				( objectStatus "Q9E1.4" )
			)
			( pin "@baseboard_fab2_lib.baseboard_fab2(sch_1):page151_i144:a"
				( attribute "PN" "1"
					( Origin gPackager )
				)
				( objectStatus "DS9E1.1" )
			)
			( pin "@baseboard_fab2_lib.baseboard_fab2(sch_1):page151_i144:c"
				( attribute "PN" "2"
					( Origin gPackager )
				)
				( objectStatus "DS9E1.2" )
			)
			( pin "@baseboard_fab2_lib.baseboard_fab2(sch_1):page151_i58:a"
				( attribute "PN" "1"
					( Origin gPackager )
				)
				( objectStatus "C25W16.1" )
			)
			( pin "@baseboard_fab2_lib.baseboard_fab2(sch_1):page151_i58:b"
				( attribute "PN" "2"
					( Origin gPackager )
				)
				( objectStatus "C25W16.2" )
			)
			( pin "@baseboard_fab2_lib.baseboard_fab2(sch_1):page147_i75:a"
				( attribute "PN" "1"
					( Origin gPackager )
				)
				( objectStatus "R2N13.1" )
			)
			( pin "@baseboard_fab2_lib.baseboard_fab2(sch_1):page147_i75:b"
				( attribute "PN" "2"
					( Origin gPackager )
				)
				( objectStatus "R2N13.2" )
			)
			( pin "@baseboard_fab2_lib.baseboard_fab2(sch_1):page146_i123:a"
				( attribute "PN" "1"
					( Origin gPackager )
				)
				( objectStatus "R25W78.1" )
			)
			( pin "@baseboard_fab2_lib.baseboard_fab2(sch_1):page146_i123:b"
				( attribute "PN" "2"
					( Origin gPackager )
				)
				( objectStatus "R25W78.2" )
			)
			( pin "@baseboard_fab2_lib.baseboard_fab2(sch_1):page145_i100:a"
				( attribute "PN" "1"
					( Origin gPackager )
				)
				( objectStatus "R1T15.1" )
			)
			( pin "@baseboard_fab2_lib.baseboard_fab2(sch_1):page145_i100:b"
				( attribute "PN" "2"
					( Origin gPackager )
				)
				( objectStatus "R1T15.2" )
			)
			( pin "@baseboard_fab2_lib.baseboard_fab2(sch_1):page145_i101:a"
				( attribute "PN" "1"
					( Origin gPackager )
				)
				( objectStatus "R1T23.1" )
			)
			( pin "@baseboard_fab2_lib.baseboard_fab2(sch_1):page145_i101:b"
				( attribute "PN" "2"
					( Origin gPackager )
				)
				( objectStatus "R1T23.2" )
			)
			( pin "@baseboard_fab2_lib.baseboard_fab2(sch_1):page247_i85:a"
				( attribute "PN" "1"
					( Origin gPackager )
				)
				( objectStatus "C6W3.1" )
			)
			( pin "@baseboard_fab2_lib.baseboard_fab2(sch_1):page247_i85:b"
				( attribute "PN" "2"
					( Origin gPackager )
				)
				( objectStatus "C6W3.2" )
			)
			( pin "@baseboard_fab2_lib.baseboard_fab2(sch_1):page247_i87:a"
				( attribute "PN" "1"
					( Origin gPackager )
				)
				( objectStatus "R6W20.1" )
			)
			( pin "@baseboard_fab2_lib.baseboard_fab2(sch_1):page247_i87:b"
				( attribute "PN" "2"
					( Origin gPackager )
				)
				( objectStatus "R6W20.2" )
			)
			( pin "@baseboard_fab2_lib.baseboard_fab2(sch_1):page247_i89:a0"
				( attribute "PN" "1"
					( Origin gPackager )
				)
				( objectStatus "U6W3.1" )
			)
			( pin "@baseboard_fab2_lib.baseboard_fab2(sch_1):page247_i89:a1"
				( attribute "PN" "2"
					( Origin gPackager )
				)
				( objectStatus "U6W3.2" )
			)
			( pin "@baseboard_fab2_lib.baseboard_fab2(sch_1):page247_i89:a2"
				( attribute "PN" "3"
					( Origin gPackager )
				)
				( objectStatus "U6W3.3" )
			)
			( pin "@baseboard_fab2_lib.baseboard_fab2(sch_1):page247_i89:scl"
				( attribute "PN" "6"
					( Origin gPackager )
				)
				( objectStatus "U6W3.6" )
			)
			( pin "@baseboard_fab2_lib.baseboard_fab2(sch_1):page247_i89:sda"
				( attribute "PN" "5"
					( Origin gPackager )
				)
				( objectStatus "U6W3.5" )
			)
			( pin "@baseboard_fab2_lib.baseboard_fab2(sch_1):page247_i89:wp"
				( attribute "PN" "7"
					( Origin gPackager )
				)
				( objectStatus "U6W3.7" )
			)
			( pin "@baseboard_fab2_lib.baseboard_fab2(sch_1):page247_i90:a"
				( attribute "PN" "1"
					( Origin gPackager )
				)
				( objectStatus "R6W21.1" )
			)
			( pin "@baseboard_fab2_lib.baseboard_fab2(sch_1):page247_i90:b"
				( attribute "PN" "2"
					( Origin gPackager )
				)
				( objectStatus "R6W21.2" )
			)
			( pin "@baseboard_fab2_lib.baseboard_fab2(sch_1):page247_i92:a"
				( attribute "PN" "1"
					( Origin gPackager )
				)
				( objectStatus "R6W23.1" )
			)
			( pin "@baseboard_fab2_lib.baseboard_fab2(sch_1):page247_i92:b"
				( attribute "PN" "2"
					( Origin gPackager )
				)
				( objectStatus "R6W23.2" )
			)
			( pin "@baseboard_fab2_lib.baseboard_fab2(sch_1):page247_i94:a"
				( attribute "PN" "1"
					( Origin gPackager )
				)
				( objectStatus "R6W22.1" )
			)
			( pin "@baseboard_fab2_lib.baseboard_fab2(sch_1):page247_i94:b"
				( attribute "PN" "2"
					( Origin gPackager )
				)
				( objectStatus "R6W22.2" )
			)
			( pin "@baseboard_fab2_lib.baseboard_fab2(sch_1):page143_i63:ma0"
				( attribute "PN" "V13"
					( Origin gPackager )
				)
				( objectStatus "U25W4.V13" )
			)
			( pin "@baseboard_fab2_lib.baseboard_fab2(sch_1):page143_i63:ma1"
				( attribute "PN" "AB14"
					( Origin gPackager )
				)
				( objectStatus "U25W4.AB14" )
			)
			( pin "@baseboard_fab2_lib.baseboard_fab2(sch_1):page143_i63:ma2"
				( attribute "PN" "W14"
					( Origin gPackager )
				)
				( objectStatus "U25W4.W14" )
			)
			( pin "@baseboard_fab2_lib.baseboard_fab2(sch_1):page143_i63:ma3"
				( attribute "PN" "U14"
					( Origin gPackager )
				)
				( objectStatus "U25W4.U14" )
			)
			( pin "@baseboard_fab2_lib.baseboard_fab2(sch_1):page143_i63:ma4"
				( attribute "PN" "W15"
					( Origin gPackager )
				)
				( objectStatus "U25W4.W15" )
			)
			( pin "@baseboard_fab2_lib.baseboard_fab2(sch_1):page143_i63:ma5"
				( attribute "PN" "V15"
					( Origin gPackager )
				)
				( objectStatus "U25W4.V15" )
			)
			( pin "@baseboard_fab2_lib.baseboard_fab2(sch_1):page143_i63:ma6"
				( attribute "PN" "AB16"
					( Origin gPackager )
				)
				( objectStatus "U25W4.AB16" )
			)
			( pin "@baseboard_fab2_lib.baseboard_fab2(sch_1):page143_i63:ma7"
				( attribute "PN" "AA16"
					( Origin gPackager )
				)
				( objectStatus "U25W4.AA16" )
			)
			( pin "@baseboard_fab2_lib.baseboard_fab2(sch_1):page143_i63:ma8"
				( attribute "PN" "W16"
					( Origin gPackager )
				)
				( objectStatus "U25W4.W16" )
			)
			( pin "@baseboard_fab2_lib.baseboard_fab2(sch_1):page143_i63:ma9"
				( attribute "PN" "Y16"
					( Origin gPackager )
				)
				( objectStatus "U25W4.Y16" )
			)
			( pin "@baseboard_fab2_lib.baseboard_fab2(sch_1):page143_i63:ma10"
				( attribute "PN" "U13"
					( Origin gPackager )
				)
				( objectStatus "U25W4.U13" )
			)
			( pin "@baseboard_fab2_lib.baseboard_fab2(sch_1):page143_i63:ma11"
				( attribute "PN" "AA14"
					( Origin gPackager )
				)
				( objectStatus "U25W4.AA14" )
			)
			( pin "@baseboard_fab2_lib.baseboard_fab2(sch_1):page143_i63:ma12"
				( attribute "PN" "Y14"
					( Origin gPackager )
				)
				( objectStatus "U25W4.Y14" )
			)
			( pin "@baseboard_fab2_lib.baseboard_fab2(sch_1):page143_i63:ma13"
				( attribute "PN" "AB15"
					( Origin gPackager )
				)
				( objectStatus "U25W4.AB15" )
			)
			( pin "@baseboard_fab2_lib.baseboard_fab2(sch_1):page143_i63:\ma14_mact#\"
				( attribute "PN" "Y15"
					( Origin gPackager )
				)
				( objectStatus "U25W4.Y15" )
			)
			( pin "@baseboard_fab2_lib.baseboard_fab2(sch_1):page143_i63:ma15"
				( attribute "PN" "U15"
					( Origin gPackager )
				)
				( objectStatus "U25W4.U15" )
			)
			( pin "@baseboard_fab2_lib.baseboard_fab2(sch_1):page143_i63:mba0"
				( attribute "PN" "U12"
					( Origin gPackager )
				)
				( objectStatus "U25W4.U12" )
			)
			( pin "@baseboard_fab2_lib.baseboard_fab2(sch_1):page143_i63:mba1"
				( attribute "PN" "Y13"
					( Origin gPackager )
				)
				( objectStatus "U25W4.Y13" )
			)
			( pin "@baseboard_fab2_lib.baseboard_fab2(sch_1):page143_i63:mba2_mbg0"
				( attribute "PN" "W13"
					( Origin gPackager )
				)
				( objectStatus "U25W4.W13" )
			)
			( pin "@baseboard_fab2_lib.baseboard_fab2(sch_1):page143_i63:\mcas#\"
				( attribute "PN" "AB13"
					( Origin gPackager )
				)
				( objectStatus "U25W4.AB13" )
			)
			( pin "@baseboard_fab2_lib.baseboard_fab2(sch_1):page143_i63:mcke"
				( attribute "PN" "Y11"
					( Origin gPackager )
				)
				( objectStatus "U25W4.Y11" )
			)
			( pin "@baseboard_fab2_lib.baseboard_fab2(sch_1):page143_i63:mckn"
				( attribute "PN" "AB12"
					( Origin gPackager )
				)
				( objectStatus "U25W4.AB12" )
			)
			( pin "@baseboard_fab2_lib.baseboard_fab2(sch_1):page143_i63:mckp"
				( attribute "PN" "AB11"
					( Origin gPackager )
				)
				( objectStatus "U25W4.AB11" )
			)
			( pin "@baseboard_fab2_lib.baseboard_fab2(sch_1):page143_i63:\mcs#\"
				( attribute "PN" "AA12"
					( Origin gPackager )
				)
				( objectStatus "U25W4.AA12" )
			)
			( pin "@baseboard_fab2_lib.baseboard_fab2(sch_1):page143_i63:mdm0"
				( attribute "PN" "U8"
					( Origin gPackager )
				)
				( objectStatus "U25W4.U8" )
			)
			( pin "@baseboard_fab2_lib.baseboard_fab2(sch_1):page143_i63:mdm1"
				( attribute "PN" "AB8"
					( Origin gPackager )
				)
				( objectStatus "U25W4.AB8" )
			)
			( pin "@baseboard_fab2_lib.baseboard_fab2(sch_1):page143_i63:mdq0"
				( attribute "PN" "U10"
					( Origin gPackager )
				)
				( objectStatus "U25W4.U10" )
			)
			( pin "@baseboard_fab2_lib.baseboard_fab2(sch_1):page143_i63:mdq1"
				( attribute "PN" "W10"
					( Origin gPackager )
				)
				( objectStatus "U25W4.W10" )
			)
			( pin "@baseboard_fab2_lib.baseboard_fab2(sch_1):page143_i63:mdq2"
				( attribute "PN" "Y10"
					( Origin gPackager )
				)
				( objectStatus "U25W4.Y10" )
			)
			( pin "@baseboard_fab2_lib.baseboard_fab2(sch_1):page143_i63:mdq3"
				( attribute "PN" "AA10"
					( Origin gPackager )
				)
				( objectStatus "U25W4.AA10" )
			)
			( pin "@baseboard_fab2_lib.baseboard_fab2(sch_1):page143_i63:mdq4"
				( attribute "PN" "U9"
					( Origin gPackager )
				)
				( objectStatus "U25W4.U9" )
			)
			( pin "@baseboard_fab2_lib.baseboard_fab2(sch_1):page143_i63:mdq5"
				( attribute "PN" "Y9"
					( Origin gPackager )
				)
				( objectStatus "U25W4.Y9" )
			)
			( pin "@baseboard_fab2_lib.baseboard_fab2(sch_1):page143_i63:mdq6"
				( attribute "PN" "W9"
					( Origin gPackager )
				)
				( objectStatus "U25W4.W9" )
			)
			( pin "@baseboard_fab2_lib.baseboard_fab2(sch_1):page143_i63:mdq7"
				( attribute "PN" "V9"
					( Origin gPackager )
				)
				( objectStatus "U25W4.V9" )
			)
			( pin "@baseboard_fab2_lib.baseboard_fab2(sch_1):page143_i63:mdq8"
				( attribute "PN" "AA8"
					( Origin gPackager )
				)
				( objectStatus "U25W4.AA8" )
			)
			( pin "@baseboard_fab2_lib.baseboard_fab2(sch_1):page143_i63:mdq9"
				( attribute "PN" "Y8"
					( Origin gPackager )
				)
				( objectStatus "U25W4.Y8" )
			)
			( pin "@baseboard_fab2_lib.baseboard_fab2(sch_1):page143_i63:mdq10"
				( attribute "PN" "Y7"
					( Origin gPackager )
				)
				( objectStatus "U25W4.Y7" )
			)
			( pin "@baseboard_fab2_lib.baseboard_fab2(sch_1):page143_i63:mdq11"
				( attribute "PN" "W8"
					( Origin gPackager )
				)
				( objectStatus "U25W4.W8" )
			)
			( pin "@baseboard_fab2_lib.baseboard_fab2(sch_1):page143_i63:mdq12"
				( attribute "PN" "AA6"
					( Origin gPackager )
				)
				( objectStatus "U25W4.AA6" )
			)
			( pin "@baseboard_fab2_lib.baseboard_fab2(sch_1):page143_i63:mdq13"
				( attribute "PN" "W7"
					( Origin gPackager )
				)
				( objectStatus "U25W4.W7" )
			)
			( pin "@baseboard_fab2_lib.baseboard_fab2(sch_1):page143_i63:mdq14"
				( attribute "PN" "V7"
					( Origin gPackager )
				)
				( objectStatus "U25W4.V7" )
			)
			( pin "@baseboard_fab2_lib.baseboard_fab2(sch_1):page143_i63:mdq15"
				( attribute "PN" "U7"
					( Origin gPackager )
				)
				( objectStatus "U25W4.U7" )
			)
			( pin "@baseboard_fab2_lib.baseboard_fab2(sch_1):page143_i63:mdqs0n"
				( attribute "PN" "AB10"
					( Origin gPackager )
				)
				( objectStatus "U25W4.AB10" )
			)
			( pin "@baseboard_fab2_lib.baseboard_fab2(sch_1):page143_i63:mdqs0p"
				( attribute "PN" "AB9"
					( Origin gPackager )
				)
				( objectStatus "U25W4.AB9" )
			)
			( pin "@baseboard_fab2_lib.baseboard_fab2(sch_1):page143_i63:mdqs1n"
				( attribute "PN" "AB6"
					( Origin gPackager )
				)
				( objectStatus "U25W4.AB6" )
			)
			( pin "@baseboard_fab2_lib.baseboard_fab2(sch_1):page143_i63:mdqs1p"
				( attribute "PN" "AB7"
					( Origin gPackager )
				)
				( objectStatus "U25W4.AB7" )
			)
			( pin "@baseboard_fab2_lib.baseboard_fab2(sch_1):page143_i63:mioz"
				( attribute "PN" "W11"
					( Origin gPackager )
				)
				( objectStatus "U25W4.W11" )
			)
			( pin "@baseboard_fab2_lib.baseboard_fab2(sch_1):page143_i63:modt"
				( attribute "PN" "V11"
					( Origin gPackager )
				)
				( objectStatus "U25W4.V11" )
			)
			( pin "@baseboard_fab2_lib.baseboard_fab2(sch_1):page143_i63:\mras#\"
				( attribute "PN" "W12"
					( Origin gPackager )
				)
				( objectStatus "U25W4.W12" )
			)
			( pin "@baseboard_fab2_lib.baseboard_fab2(sch_1):page143_i63:mvref"
				( attribute "PN" "T9"
					( Origin gPackager )
				)
				( objectStatus "U25W4.T9" )
			)
			( pin "@baseboard_fab2_lib.baseboard_fab2(sch_1):page143_i63:\mwe#\"
				( attribute "PN" "Y12"
					( Origin gPackager )
				)
				( objectStatus "U25W4.Y12" )
			)
			( pin "@baseboard_fab2_lib.baseboard_fab2(sch_1):page146_i105:entest"
				( attribute "PN" "K3"
					( Origin gPackager )
				)
				( objectStatus "U25W4.K3" )
			)
			( pin "@baseboard_fab2_lib.baseboard_fab2(sch_1):page146_i105:\extrst#\"
				( attribute "PN" "V18"
					( Origin gPackager )
				)
				( objectStatus "U25W4.V18" )
			)
			( pin "@baseboard_fab2_lib.baseboard_fab2(sch_1):page146_i105:fwspick"
				( attribute "PN" "AA18"
					( Origin gPackager )
				)
				( objectStatus "U25W4.AA18" )
			)
			( pin "@baseboard_fab2_lib.baseboard_fab2(sch_1):page146_i105:\fwspics0#\"
				( attribute "PN" "AB19"
					( Origin gPackager )
				)
				( objectStatus "U25W4.AB19" )
			)
			( pin "@baseboard_fab2_lib.baseboard_fab2(sch_1):page146_i105:fwspimiso"
				( attribute "PN" "T18"
					( Origin gPackager )
				)
				( objectStatus "U25W4.T18" )
			)
			( pin "@baseboard_fab2_lib.baseboard_fab2(sch_1):page146_i105:fwspimosi"
				( attribute "PN" "U17"
					( Origin gPackager )
				)
				( objectStatus "U25W4.U17" )
			)
			( pin "@baseboard_fab2_lib.baseboard_fab2(sch_1):page146_i105:\gpioab0_vpode_noroe#\"
				( attribute "PN" "N19"
					( Origin gPackager )
				)
				( objectStatus "U25W4.N19" )
			)
			( pin "@baseboard_fab2_lib.baseboard_fab2(sch_1):page146_i105:\gpioab1_vpohs_norwe#\"
				( attribute "PN" "T21"
					( Origin gPackager )
				)
				( objectStatus "U25W4.T21" )
			)
			( pin "@baseboard_fab2_lib.baseboard_fab2(sch_1):page146_i105:gpioab2_vpovs_wdtrst1"
				( attribute "PN" "T22"
					( Origin gPackager )
				)
				( objectStatus "U25W4.T22" )
			)
			( pin "@baseboard_fab2_lib.baseboard_fab2(sch_1):page146_i105:gpioab3_vpoclk_wdtrst2"
				( attribute "PN" "R20"
					( Origin gPackager )
				)
				( objectStatus "U25W4.R20" )
			)
			( pin "@baseboard_fab2_lib.baseboard_fab2(sch_1):page146_i105:gpioac0_espid0_lad0"
				( attribute "PN" "G21"
					( Origin gPackager )
				)
				( objectStatus "U25W4.G21" )
			)
			( pin "@baseboard_fab2_lib.baseboard_fab2(sch_1):page146_i105:gpioac1_espid1_lad1"
				( attribute "PN" "G20"
					( Origin gPackager )
				)
				( objectStatus "U25W4.G20" )
			)
			( pin "@baseboard_fab2_lib.baseboard_fab2(sch_1):page146_i105:gpioac2_espid2_lad2"
				( attribute "PN" "D22"
					( Origin gPackager )
				)
				( objectStatus "U25W4.D22" )
			)
			( pin "@baseboard_fab2_lib.baseboard_fab2(sch_1):page146_i105:gpioac3_espid3_lad3"
				( attribute "PN" "E22"
					( Origin gPackager )
				)
				( objectStatus "U25W4.E22" )
			)
			( pin "@baseboard_fab2_lib.baseboard_fab2(sch_1):page146_i105:gpioac4_espick_lclk"
				( attribute "PN" "C22"
					( Origin gPackager )
				)
				( objectStatus "U25W4.C22" )
			)
			( pin "@baseboard_fab2_lib.baseboard_fab2(sch_1):page146_i105:\gpioac5_espics#_lframe#\"
				( attribute "PN" "F21"
					( Origin gPackager )
				)
				( objectStatus "U25W4.F21" )
			)
			( pin "@baseboard_fab2_lib.baseboard_fab2(sch_1):page146_i105:\gpioac6_espialt#_lsirq#\"
				( attribute "PN" "F22"
					( Origin gPackager )
				)
				( objectStatus "U25W4.F22" )
			)
			( pin "@baseboard_fab2_lib.baseboard_fab2(sch_1):page146_i105:\gpioac7_espirst#_lpcrst#\"
				( attribute "PN" "G22"
					( Origin gPackager )
				)
				( objectStatus "U25W4.G22" )
			)
			( pin "@baseboard_fab2_lib.baseboard_fab2(sch_1):page146_i105:gpioj4_vgahs"
				( attribute "PN" "N5"
					( Origin gPackager )
				)
				( objectStatus "U25W4.N5" )
			)
			( pin "@baseboard_fab2_lib.baseboard_fab2(sch_1):page146_i105:gpioj5_vgavs"
				( attribute "PN" "R4"
					( Origin gPackager )
				)
				( objectStatus "U25W4.R4" )
			)
			( pin "@baseboard_fab2_lib.baseboard_fab2(sch_1):page146_i105:gpioj6_ddcclk"
				( attribute "PN" "R3"
					( Origin gPackager )
				)
				( objectStatus "U25W4.R3" )
			)
			( pin "@baseboard_fab2_lib.baseboard_fab2(sch_1):page146_i105:gpioj7_ddcdat"
				( attribute "PN" "T3"
					( Origin gPackager )
				)
				( objectStatus "U25W4.T3" )
			)
			( pin "@baseboard_fab2_lib.baseboard_fab2(sch_1):page146_i105:gpioq6_oscclk"
				( attribute "PN" "B10"
					( Origin gPackager )
				)
				( objectStatus "U25W4.B10" )
			)
			( pin "@baseboard_fab2_lib.baseboard_fab2(sch_1):page146_i105:\gpioq7_pewake#\"
				( attribute "PN" "N20"
					( Origin gPackager )
				)
				( objectStatus "U25W4.N20" )
			)
			( pin "@baseboard_fab2_lib.baseboard_fab2(sch_1):page146_i105:\gpior0_fwspics1#\"
				( attribute "PN" "AA19"
					( Origin gPackager )
				)
				( objectStatus "U25W4.AA19" )
			)
			( pin "@baseboard_fab2_lib.baseboard_fab2(sch_1):page146_i105:\gpior1_fwspics2#\"
				( attribute "PN" "T19"
					( Origin gPackager )
				)
				( objectStatus "U25W4.T19" )
			)
			( pin "@baseboard_fab2_lib.baseboard_fab2(sch_1):page146_i105:\gpior2_spi2cs0#\"
				( attribute "PN" "T17"
					( Origin gPackager )
				)
				( objectStatus "U25W4.T17" )
			)
			( pin "@baseboard_fab2_lib.baseboard_fab2(sch_1):page146_i105:gpior3_spi2ck"
				( attribute "PN" "Y19"
					( Origin gPackager )
				)
				( objectStatus "U25W4.Y19" )
			)
			( pin "@baseboard_fab2_lib.baseboard_fab2(sch_1):page146_i105:gpior4_spi2mosi"
				( attribute "PN" "W19"
					( Origin gPackager )
				)
				( objectStatus "U25W4.W19" )
			)
			( pin "@baseboard_fab2_lib.baseboard_fab2(sch_1):page146_i105:gpior5_spi2miso"
				( attribute "PN" "V19"
					( Origin gPackager )
				)
				( objectStatus "U25W4.V19" )
			)
			( pin "@baseboard_fab2_lib.baseboard_fab2(sch_1):page146_i105:\hbled#\"
				( attribute "PN" "Y18"
					( Origin gPackager )
				)
				( objectStatus "U25W4.Y18" )
			)
			( pin "@baseboard_fab2_lib.baseboard_fab2(sch_1):page146_i105:\malert#\"
				( attribute "PN" "U16"
					( Origin gPackager )
				)
				( objectStatus "U25W4.U16" )
			)
			( pin "@baseboard_fab2_lib.baseboard_fab2(sch_1):page146_i105:\mreset#\"
				( attribute "PN" "AB17"
					( Origin gPackager )
				)
				( objectStatus "U25W4.AB17" )
			)
			( pin "@baseboard_fab2_lib.baseboard_fab2(sch_1):page255_i89:\1\"
				( attribute "PN" "1"
					( Origin gPackager )
				)
				( objectStatus "F25W1.1" )
			)
			( pin "@baseboard_fab2_lib.baseboard_fab2(sch_1):page255_i89:\2\"
				( attribute "PN" "2"
					( Origin gPackager )
				)
				( objectStatus "F25W1.2" )
			)
			( pin "@baseboard_fab2_lib.baseboard_fab2(sch_1):page247_i98:a"
				( attribute "PN" "1"
					( Origin gPackager )
				)
				( objectStatus "R6W11.1" )
			)
			( pin "@baseboard_fab2_lib.baseboard_fab2(sch_1):page247_i98:b"
				( attribute "PN" "2"
					( Origin gPackager )
				)
				( objectStatus "R6W11.2" )
			)
			( pin "@baseboard_fab2_lib.baseboard_fab2(sch_1):page247_i107:a"
				( attribute "PN" "1"
					( Origin gPackager )
				)
				( objectStatus "C6W2.1" )
			)
			( pin "@baseboard_fab2_lib.baseboard_fab2(sch_1):page247_i107:b"
				( attribute "PN" "2"
					( Origin gPackager )
				)
				( objectStatus "C6W2.2" )
			)
			( pin "@baseboard_fab2_lib.baseboard_fab2(sch_1):page105_i257:a"
				( attribute "PN" "1"
					( Origin gPackager )
				)
				( objectStatus "C7G19.1" )
			)
			( pin "@baseboard_fab2_lib.baseboard_fab2(sch_1):page105_i257:b"
				( attribute "PN" "2"
					( Origin gPackager )
				)
				( objectStatus "C7G19.2" )
			)
			( pin "@baseboard_fab2_lib.baseboard_fab2(sch_1):page105_i258:a"
				( attribute "PN" "1"
					( Origin gPackager )
				)
				( objectStatus "C7G20.1" )
			)
			( pin "@baseboard_fab2_lib.baseboard_fab2(sch_1):page105_i258:b"
				( attribute "PN" "2"
					( Origin gPackager )
				)
				( objectStatus "C7G20.2" )
			)
			( pin "@baseboard_fab2_lib.baseboard_fab2(sch_1):page145_i118:\1\"
				( attribute "PN" "1"
					( Origin gPackager )
				)
				( objectStatus "R25W67.1" )
			)
			( pin "@baseboard_fab2_lib.baseboard_fab2(sch_1):page145_i118:\2\"
				( attribute "PN" "2"
					( Origin gPackager )
				)
				( objectStatus "R25W67.2" )
			)
			( pin "@baseboard_fab2_lib.baseboard_fab2(sch_1):page145_i119:a"
				( attribute "PN" "1"
					( Origin gPackager )
				)
				( objectStatus "R6W18.1" )
			)
			( pin "@baseboard_fab2_lib.baseboard_fab2(sch_1):page145_i119:b"
				( attribute "PN" "2"
					( Origin gPackager )
				)
				( objectStatus "R6W18.2" )
			)
			( pin "@baseboard_fab2_lib.baseboard_fab2(sch_1):page201_i172:\1\"
				( attribute "PN" "1"
					( Origin gPackager )
				)
				( objectStatus "CF5.1" )
			)
			( pin "@baseboard_fab2_lib.baseboard_fab2(sch_1):page201_i172:\2\"
				( attribute "PN" "2"
					( Origin gPackager )
				)
				( objectStatus "CF5.2" )
			)
			( pin "@baseboard_fab2_lib.baseboard_fab2(sch_1):page201_i171:\1\"
				( attribute "PN" "1"
					( Origin gPackager )
				)
				( objectStatus "CF4.1" )
			)
			( pin "@baseboard_fab2_lib.baseboard_fab2(sch_1):page201_i171:\2\"
				( attribute "PN" "2"
					( Origin gPackager )
				)
				( objectStatus "CF4.2" )
			)
			( pin "@baseboard_fab2_lib.baseboard_fab2(sch_1):page201_i170:\1\"
				( attribute "PN" "1"
					( Origin gPackager )
				)
				( objectStatus "CF3.1" )
			)
			( pin "@baseboard_fab2_lib.baseboard_fab2(sch_1):page201_i170:\2\"
				( attribute "PN" "2"
					( Origin gPackager )
				)
				( objectStatus "CF3.2" )
			)
			( pin "@baseboard_fab2_lib.baseboard_fab2(sch_1):page201_i169:\1\"
				( attribute "PN" "1"
					( Origin gPackager )
				)
				( objectStatus "CF2.1" )
			)
			( pin "@baseboard_fab2_lib.baseboard_fab2(sch_1):page201_i169:\2\"
				( attribute "PN" "2"
					( Origin gPackager )
				)
				( objectStatus "CF2.2" )
			)
			( pin "@baseboard_fab2_lib.baseboard_fab2(sch_1):page201_i168:\1\"
				( attribute "PN" "1"
					( Origin gPackager )
				)
				( objectStatus "CF1.1" )
			)
			( pin "@baseboard_fab2_lib.baseboard_fab2(sch_1):page201_i168:\2\"
				( attribute "PN" "2"
					( Origin gPackager )
				)
				( objectStatus "CF1.2" )
			)
			( pin "@baseboard_fab2_lib.baseboard_fab2(sch_1):page206_i149:a"
				( attribute "PN" "1"
					( Origin gPackager )
				)
				( objectStatus "RF12.1" )
			)
			( pin "@baseboard_fab2_lib.baseboard_fab2(sch_1):page206_i149:b"
				( attribute "PN" "2"
					( Origin gPackager )
				)
				( objectStatus "RF12.2" )
			)
			( pin "@baseboard_fab2_lib.baseboard_fab2(sch_1):page206_i150:a"
				( attribute "PN" "1"
					( Origin gPackager )
				)
				( objectStatus "RF7.1" )
			)
			( pin "@baseboard_fab2_lib.baseboard_fab2(sch_1):page206_i150:b"
				( attribute "PN" "2"
					( Origin gPackager )
				)
				( objectStatus "RF7.2" )
			)
			( pin "@baseboard_fab2_lib.baseboard_fab2(sch_1):page206_i151:a"
				( attribute "PN" "1"
					( Origin gPackager )
				)
				( objectStatus "RF8.1" )
			)
			( pin "@baseboard_fab2_lib.baseboard_fab2(sch_1):page206_i151:b"
				( attribute "PN" "2"
					( Origin gPackager )
				)
				( objectStatus "RF8.2" )
			)
			( pin "@baseboard_fab2_lib.baseboard_fab2(sch_1):page206_i152:a"
				( attribute "PN" "1"
					( Origin gPackager )
				)
				( objectStatus "RF9.1" )
			)
			( pin "@baseboard_fab2_lib.baseboard_fab2(sch_1):page206_i152:b"
				( attribute "PN" "2"
					( Origin gPackager )
				)
				( objectStatus "RF9.2" )
			)
			( pin "@baseboard_fab2_lib.baseboard_fab2(sch_1):page206_i153:a"
				( attribute "PN" "1"
					( Origin gPackager )
				)
				( objectStatus "RF10.1" )
			)
			( pin "@baseboard_fab2_lib.baseboard_fab2(sch_1):page206_i153:b"
				( attribute "PN" "2"
					( Origin gPackager )
				)
				( objectStatus "RF10.2" )
			)
			( pin "@baseboard_fab2_lib.baseboard_fab2(sch_1):page206_i154:a"
				( attribute "PN" "1"
					( Origin gPackager )
				)
				( objectStatus "RF11.1" )
			)
			( pin "@baseboard_fab2_lib.baseboard_fab2(sch_1):page206_i154:b"
				( attribute "PN" "2"
					( Origin gPackager )
				)
				( objectStatus "RF11.2" )
			)
			( pin "@baseboard_fab2_lib.baseboard_fab2(sch_1):page213_i99:a"
				( attribute "PN" "1"
					( Origin gPackager )
				)
				( objectStatus "RF14.1" )
			)
			( pin "@baseboard_fab2_lib.baseboard_fab2(sch_1):page213_i99:b"
				( attribute "PN" "2"
					( Origin gPackager )
				)
				( objectStatus "RF14.2" )
			)
			( pin "@baseboard_fab2_lib.baseboard_fab2(sch_1):page221_i4:a"
				( attribute "PN" "1"
					( Origin gPackager )
				)
				( objectStatus "R4G23.1" )
			)
			( pin "@baseboard_fab2_lib.baseboard_fab2(sch_1):page221_i4:b"
				( attribute "PN" "2"
					( Origin gPackager )
				)
				( objectStatus "R4G23.2" )
			)
			( pin "@baseboard_fab2_lib.baseboard_fab2(sch_1):page222_i2:a"
				( attribute "PN" "1"
					( Origin gPackager )
				)
				( objectStatus "C4A2.1" )
			)
			( pin "@baseboard_fab2_lib.baseboard_fab2(sch_1):page222_i2:b"
				( attribute "PN" "2"
					( Origin gPackager )
				)
				( objectStatus "C4A2.2" )
			)
			( pin "@baseboard_fab2_lib.baseboard_fab2(sch_1):page222_i4:a"
				( attribute "PN" "1"
					( Origin gPackager )
				)
				( objectStatus "R4A2.1" )
			)
			( pin "@baseboard_fab2_lib.baseboard_fab2(sch_1):page222_i4:b"
				( attribute "PN" "2"
					( Origin gPackager )
				)
				( objectStatus "R4A2.2" )
			)
			( pin "@baseboard_fab2_lib.baseboard_fab2(sch_1):page229_i2:a"
				( attribute "PN" "1"
					( Origin gPackager )
				)
				( objectStatus "C4G12.1" )
			)
			( pin "@baseboard_fab2_lib.baseboard_fab2(sch_1):page229_i2:b"
				( attribute "PN" "2"
					( Origin gPackager )
				)
				( objectStatus "C4G12.2" )
			)
			( pin "@baseboard_fab2_lib.baseboard_fab2(sch_1):page229_i4:a"
				( attribute "PN" "1"
					( Origin gPackager )
				)
				( objectStatus "R4G16.1" )
			)
			( pin "@baseboard_fab2_lib.baseboard_fab2(sch_1):page229_i4:b"
				( attribute "PN" "2"
					( Origin gPackager )
				)
				( objectStatus "R4G16.2" )
			)
			( pin "@baseboard_fab2_lib.baseboard_fab2(sch_1):page197_i1:a"
				( attribute "PN" "1"
					( Origin gPackager )
				)
				( objectStatus "C12W2.1" )
			)
			( pin "@baseboard_fab2_lib.baseboard_fab2(sch_1):page197_i1:b"
				( attribute "PN" "2"
					( Origin gPackager )
				)
				( objectStatus "C12W2.2" )
			)
			( pin "@baseboard_fab2_lib.baseboard_fab2(sch_1):page235_i242:a"
				( attribute "PN" "1"
					( Origin gPackager )
				)
				( objectStatus "RF24.1" )
			)
			( pin "@baseboard_fab2_lib.baseboard_fab2(sch_1):page235_i242:b"
				( attribute "PN" "2"
					( Origin gPackager )
				)
				( objectStatus "RF24.2" )
			)
			( pin "@baseboard_fab2_lib.baseboard_fab2(sch_1):page235_i241:a"
				( attribute "PN" "1"
					( Origin gPackager )
				)
				( objectStatus "RF23.1" )
			)
			( pin "@baseboard_fab2_lib.baseboard_fab2(sch_1):page235_i241:b"
				( attribute "PN" "2"
					( Origin gPackager )
				)
				( objectStatus "RF23.2" )
			)
			( pin "@baseboard_fab2_lib.baseboard_fab2(sch_1):page247_i99:a"
				( attribute "PN" "1"
					( Origin gPackager )
				)
				( objectStatus "R6W12.1" )
			)
			( pin "@baseboard_fab2_lib.baseboard_fab2(sch_1):page247_i99:b"
				( attribute "PN" "2"
					( Origin gPackager )
				)
				( objectStatus "R6W12.2" )
			)
			( pin "@baseboard_fab2_lib.baseboard_fab2(sch_1):page248_i13:a"
				( attribute "PN" "1"
					( Origin gPackager )
				)
				( objectStatus "C14W1.1" )
			)
			( pin "@baseboard_fab2_lib.baseboard_fab2(sch_1):page248_i13:b"
				( attribute "PN" "2"
					( Origin gPackager )
				)
				( objectStatus "C14W1.2" )
			)
			( pin "@baseboard_fab2_lib.baseboard_fab2(sch_1):page248_i17:a"
				( attribute "PN" "1"
					( Origin gPackager )
				)
				( objectStatus "C14W2.1" )
			)
			( pin "@baseboard_fab2_lib.baseboard_fab2(sch_1):page248_i17:b"
				( attribute "PN" "2"
					( Origin gPackager )
				)
				( objectStatus "C14W2.2" )
			)
			( pin "@baseboard_fab2_lib.baseboard_fab2(sch_1):page175_i92:pin1"
				( attribute "PN" "1"
					( Origin gPackager )
				)
				( objectStatus "S9A2.1" )
			)
			( pin "@baseboard_fab2_lib.baseboard_fab2(sch_1):page175_i92:pin2"
				( attribute "PN" "2"
					( Origin gPackager )
				)
				( objectStatus "S9A2.2" )
			)
			( pin "@baseboard_fab2_lib.baseboard_fab2(sch_1):page175_i92:pin3"
				( attribute "PN" "3"
					( Origin gPackager )
				)
				( objectStatus "S9A2.3" )
			)
			( pin "@baseboard_fab2_lib.baseboard_fab2(sch_1):page175_i92:pin4"
				( attribute "PN" "4"
					( Origin gPackager )
				)
				( objectStatus "S9A2.4" )
			)
			( pin "@baseboard_fab2_lib.baseboard_fab2(sch_1):page201_i186:a"
				( attribute "PN" "1"
					( Origin gPackager )
				)
				( objectStatus "RF5.1" )
			)
			( pin "@baseboard_fab2_lib.baseboard_fab2(sch_1):page201_i186:b"
				( attribute "PN" "2"
					( Origin gPackager )
				)
				( objectStatus "RF5.2" )
			)
			( pin "@baseboard_fab2_lib.baseboard_fab2(sch_1):page201_i184:a"
				( attribute "PN" "1"
					( Origin gPackager )
				)
				( objectStatus "RF3.1" )
			)
			( pin "@baseboard_fab2_lib.baseboard_fab2(sch_1):page201_i184:b"
				( attribute "PN" "2"
					( Origin gPackager )
				)
				( objectStatus "RF3.2" )
			)
			( pin "@baseboard_fab2_lib.baseboard_fab2(sch_1):page201_i183:a"
				( attribute "PN" "1"
					( Origin gPackager )
				)
				( objectStatus "RF2.1" )
			)
			( pin "@baseboard_fab2_lib.baseboard_fab2(sch_1):page201_i183:b"
				( attribute "PN" "2"
					( Origin gPackager )
				)
				( objectStatus "RF2.2" )
			)
			( pin "@baseboard_fab2_lib.baseboard_fab2(sch_1):page201_i182:a"
				( attribute "PN" "1"
					( Origin gPackager )
				)
				( objectStatus "RF1.1" )
			)
			( pin "@baseboard_fab2_lib.baseboard_fab2(sch_1):page201_i182:b"
				( attribute "PN" "2"
					( Origin gPackager )
				)
				( objectStatus "RF1.2" )
			)
			( pin "@baseboard_fab2_lib.baseboard_fab2(sch_1):page201_i180:a"
				( attribute "PN" "1"
					( Origin gPackager )
				)
				( objectStatus "RF6.1" )
			)
			( pin "@baseboard_fab2_lib.baseboard_fab2(sch_1):page201_i180:b"
				( attribute "PN" "2"
					( Origin gPackager )
				)
				( objectStatus "RF6.2" )
			)
			( pin "@baseboard_fab2_lib.baseboard_fab2(sch_1):page201_i173:\1\"
				( attribute "PN" "1"
					( Origin gPackager )
				)
				( objectStatus "CF6.1" )
			)
			( pin "@baseboard_fab2_lib.baseboard_fab2(sch_1):page201_i173:\2\"
				( attribute "PN" "2"
					( Origin gPackager )
				)
				( objectStatus "CF6.2" )
			)
			( pin "@baseboard_fab2_lib.baseboard_fab2(sch_1):page206_i137:\1\"
				( attribute "PN" "1"
					( Origin gPackager )
				)
				( objectStatus "CF7.1" )
			)
			( pin "@baseboard_fab2_lib.baseboard_fab2(sch_1):page206_i137:\2\"
				( attribute "PN" "2"
					( Origin gPackager )
				)
				( objectStatus "CF7.2" )
			)
			( pin "@baseboard_fab2_lib.baseboard_fab2(sch_1):page206_i138:\1\"
				( attribute "PN" "1"
					( Origin gPackager )
				)
				( objectStatus "CF8.1" )
			)
			( pin "@baseboard_fab2_lib.baseboard_fab2(sch_1):page206_i138:\2\"
				( attribute "PN" "2"
					( Origin gPackager )
				)
				( objectStatus "CF8.2" )
			)
			( pin "@baseboard_fab2_lib.baseboard_fab2(sch_1):page206_i139:\1\"
				( attribute "PN" "1"
					( Origin gPackager )
				)
				( objectStatus "CF9.1" )
			)
			( pin "@baseboard_fab2_lib.baseboard_fab2(sch_1):page206_i139:\2\"
				( attribute "PN" "2"
					( Origin gPackager )
				)
				( objectStatus "CF9.2" )
			)
			( pin "@baseboard_fab2_lib.baseboard_fab2(sch_1):page206_i140:\1\"
				( attribute "PN" "1"
					( Origin gPackager )
				)
				( objectStatus "CF10.1" )
			)
			( pin "@baseboard_fab2_lib.baseboard_fab2(sch_1):page206_i140:\2\"
				( attribute "PN" "2"
					( Origin gPackager )
				)
				( objectStatus "CF10.2" )
			)
			( pin "@baseboard_fab2_lib.baseboard_fab2(sch_1):page206_i141:\1\"
				( attribute "PN" "1"
					( Origin gPackager )
				)
				( objectStatus "CF11.1" )
			)
			( pin "@baseboard_fab2_lib.baseboard_fab2(sch_1):page206_i141:\2\"
				( attribute "PN" "2"
					( Origin gPackager )
				)
				( objectStatus "CF11.2" )
			)
			( pin "@baseboard_fab2_lib.baseboard_fab2(sch_1):page206_i142:\1\"
				( attribute "PN" "1"
					( Origin gPackager )
				)
				( objectStatus "CF12.1" )
			)
			( pin "@baseboard_fab2_lib.baseboard_fab2(sch_1):page206_i142:\2\"
				( attribute "PN" "2"
					( Origin gPackager )
				)
				( objectStatus "CF12.2" )
			)
			( pin "@baseboard_fab2_lib.baseboard_fab2(sch_1):page211_i95:\1\"
				( attribute "PN" "1"
					( Origin gPackager )
				)
				( objectStatus "CF13.1" )
			)
			( pin "@baseboard_fab2_lib.baseboard_fab2(sch_1):page211_i95:\2\"
				( attribute "PN" "2"
					( Origin gPackager )
				)
				( objectStatus "CF13.2" )
			)
			( pin "@baseboard_fab2_lib.baseboard_fab2(sch_1):page221_i6:a"
				( attribute "PN" "1"
					( Origin gPackager )
				)
				( objectStatus "R6U5.1" )
			)
			( pin "@baseboard_fab2_lib.baseboard_fab2(sch_1):page221_i6:b"
				( attribute "PN" "2"
					( Origin gPackager )
				)
				( objectStatus "R6U5.2" )
			)
			( pin "@baseboard_fab2_lib.baseboard_fab2(sch_1):page221_i5:a"
				( attribute "PN" "1"
					( Origin gPackager )
				)
				( objectStatus "R6U15.1" )
			)
			( pin "@baseboard_fab2_lib.baseboard_fab2(sch_1):page221_i5:b"
				( attribute "PN" "2"
					( Origin gPackager )
				)
				( objectStatus "R6U15.2" )
			)
			( pin "@baseboard_fab2_lib.baseboard_fab2(sch_1):page213_i98:\1\"
				( attribute "PN" "1"
					( Origin gPackager )
				)
				( objectStatus "CF14.1" )
			)
			( pin "@baseboard_fab2_lib.baseboard_fab2(sch_1):page213_i98:\2\"
				( attribute "PN" "2"
					( Origin gPackager )
				)
				( objectStatus "CF14.2" )
			)
			( pin "@baseboard_fab2_lib.baseboard_fab2(sch_1):page222_i6:a"
				( attribute "PN" "1"
					( Origin gPackager )
				)
				( objectStatus "R6L10.1" )
			)
			( pin "@baseboard_fab2_lib.baseboard_fab2(sch_1):page222_i6:b"
				( attribute "PN" "2"
					( Origin gPackager )
				)
				( objectStatus "R6L10.2" )
			)
			( pin "@baseboard_fab2_lib.baseboard_fab2(sch_1):page222_i5:a"
				( attribute "PN" "1"
					( Origin gPackager )
				)
				( objectStatus "R6L4.1" )
			)
			( pin "@baseboard_fab2_lib.baseboard_fab2(sch_1):page222_i5:b"
				( attribute "PN" "2"
					( Origin gPackager )
				)
				( objectStatus "R6L4.2" )
			)
			( pin "@baseboard_fab2_lib.baseboard_fab2(sch_1):page229_i6:a"
				( attribute "PN" "1"
					( Origin gPackager )
				)
				( objectStatus "R6U6.1" )
			)
			( pin "@baseboard_fab2_lib.baseboard_fab2(sch_1):page229_i6:b"
				( attribute "PN" "2"
					( Origin gPackager )
				)
				( objectStatus "R6U6.2" )
			)
			( pin "@baseboard_fab2_lib.baseboard_fab2(sch_1):page229_i5:a"
				( attribute "PN" "1"
					( Origin gPackager )
				)
				( objectStatus "R6U3.1" )
			)
			( pin "@baseboard_fab2_lib.baseboard_fab2(sch_1):page229_i5:b"
				( attribute "PN" "2"
					( Origin gPackager )
				)
				( objectStatus "R6U3.2" )
			)
			( pin "@baseboard_fab2_lib.baseboard_fab2(sch_1):page197_i116:\1\"
				( attribute "PN" "1"
					( Origin gPackager )
				)
				( objectStatus "R12W13.1" )
			)
			( pin "@baseboard_fab2_lib.baseboard_fab2(sch_1):page197_i116:\2\"
				( attribute "PN" "2"
					( Origin gPackager )
				)
				( objectStatus "R12W13.2" )
			)
			( pin "@baseboard_fab2_lib.baseboard_fab2(sch_1):page235_i239:\1\"
				( attribute "PN" "1"
					( Origin gPackager )
				)
				( objectStatus "CF23.1" )
			)
			( pin "@baseboard_fab2_lib.baseboard_fab2(sch_1):page235_i239:\2\"
				( attribute "PN" "2"
					( Origin gPackager )
				)
				( objectStatus "CF23.2" )
			)
			( pin "@baseboard_fab2_lib.baseboard_fab2(sch_1):page235_i240:\1\"
				( attribute "PN" "1"
					( Origin gPackager )
				)
				( objectStatus "CF24.1" )
			)
			( pin "@baseboard_fab2_lib.baseboard_fab2(sch_1):page235_i240:\2\"
				( attribute "PN" "2"
					( Origin gPackager )
				)
				( objectStatus "CF24.2" )
			)
			( pin "@baseboard_fab2_lib.baseboard_fab2(sch_1):page151_i223:\1\"
				( attribute "PN" "1"
					( Origin gPackager )
				)
				( objectStatus "R25W27.1" )
			)
			( pin "@baseboard_fab2_lib.baseboard_fab2(sch_1):page151_i223:\2\"
				( attribute "PN" "2"
					( Origin gPackager )
				)
				( objectStatus "R25W27.2" )
			)
			( pin "@baseboard_fab2_lib.baseboard_fab2(sch_1):page144_i114:a"
				( attribute "PN" "1"
					( Origin gPackager )
				)
				( objectStatus "R25W70.1" )
			)
			( pin "@baseboard_fab2_lib.baseboard_fab2(sch_1):page144_i114:b"
				( attribute "PN" "2"
					( Origin gPackager )
				)
				( objectStatus "R25W70.2" )
			)
			( pin "@baseboard_fab2_lib.baseboard_fab2(sch_1):page144_i118:a"
				( attribute "PN" "1"
					( Origin gPackager )
				)
				( objectStatus "R25W75.1" )
			)
			( pin "@baseboard_fab2_lib.baseboard_fab2(sch_1):page144_i118:b"
				( attribute "PN" "2"
					( Origin gPackager )
				)
				( objectStatus "R25W75.2" )
			)
			( pin "@baseboard_fab2_lib.baseboard_fab2(sch_1):page228_i313:a"
				( attribute "PN" "1"
					( Origin gPackager )
				)
				( objectStatus "C2A16.1" )
			)
			( pin "@baseboard_fab2_lib.baseboard_fab2(sch_1):page228_i313:b"
				( attribute "PN" "2"
					( Origin gPackager )
				)
				( objectStatus "C2A16.2" )
			)
			( pin "@baseboard_fab2_lib.baseboard_fab2(sch_1):page228_i304:a"
				( attribute "PN" "1"
					( Origin gPackager )
				)
				( objectStatus "C8P1.1" )
			)
			( pin "@baseboard_fab2_lib.baseboard_fab2(sch_1):page228_i304:b"
				( attribute "PN" "2"
					( Origin gPackager )
				)
				( objectStatus "C8P1.2" )
			)
			( pin "@baseboard_fab2_lib.baseboard_fab2(sch_1):page149_i17:a"
				( attribute "PN" "1"
					( Origin gPackager )
				)
				( objectStatus "C25W69.1" )
			)
			( pin "@baseboard_fab2_lib.baseboard_fab2(sch_1):page149_i17:b"
				( attribute "PN" "2"
					( Origin gPackager )
				)
				( objectStatus "C25W69.2" )
			)
			( pin "@baseboard_fab2_lib.baseboard_fab2(sch_1):page247_i151:a"
				( attribute "PN" "1"
					( Origin gPackager )
				)
				( objectStatus "C6W1.1" )
			)
			( pin "@baseboard_fab2_lib.baseboard_fab2(sch_1):page247_i151:b"
				( attribute "PN" "2"
					( Origin gPackager )
				)
				( objectStatus "C6W1.2" )
			)
			( pin "@baseboard_fab2_lib.baseboard_fab2(sch_1):page149_i22:\1\"
				( attribute "PN" "1"
					( Origin gPackager )
				)
				( objectStatus "FB2T1.1" )
			)
			( pin "@baseboard_fab2_lib.baseboard_fab2(sch_1):page149_i22:\2\"
				( attribute "PN" "2"
					( Origin gPackager )
				)
				( objectStatus "FB2T1.2" )
			)
			( pin "@baseboard_fab2_lib.baseboard_fab2(sch_1):page149_i25:a"
				( attribute "PN" "1"
					( Origin gPackager )
				)
				( objectStatus "C25W39.1" )
			)
			( pin "@baseboard_fab2_lib.baseboard_fab2(sch_1):page149_i25:b"
				( attribute "PN" "2"
					( Origin gPackager )
				)
				( objectStatus "C25W39.2" )
			)
			( pin "@baseboard_fab2_lib.baseboard_fab2(sch_1):page149_i31:a"
				( attribute "PN" "1"
					( Origin gPackager )
				)
				( objectStatus "C25W50.1" )
			)
			( pin "@baseboard_fab2_lib.baseboard_fab2(sch_1):page149_i31:b"
				( attribute "PN" "2"
					( Origin gPackager )
				)
				( objectStatus "C25W50.2" )
			)
			( pin "@baseboard_fab2_lib.baseboard_fab2(sch_1):page149_i40:a"
				( attribute "PN" "1"
					( Origin gPackager )
				)
				( objectStatus "C25W62.1" )
			)
			( pin "@baseboard_fab2_lib.baseboard_fab2(sch_1):page149_i40:b"
				( attribute "PN" "2"
					( Origin gPackager )
				)
				( objectStatus "C25W62.2" )
			)
			( pin "@baseboard_fab2_lib.baseboard_fab2(sch_1):page149_i42:\1\"
				( attribute "PN" "1"
					( Origin gPackager )
				)
				( objectStatus "FB2T7.1" )
			)
			( pin "@baseboard_fab2_lib.baseboard_fab2(sch_1):page149_i42:\2\"
				( attribute "PN" "2"
					( Origin gPackager )
				)
				( objectStatus "FB2T7.2" )
			)
			( pin "@baseboard_fab2_lib.baseboard_fab2(sch_1):page149_i46:a"
				( attribute "PN" "1"
					( Origin gPackager )
				)
				( objectStatus "C25W36.1" )
			)
			( pin "@baseboard_fab2_lib.baseboard_fab2(sch_1):page149_i46:b"
				( attribute "PN" "2"
					( Origin gPackager )
				)
				( objectStatus "C25W36.2" )
			)
			( pin "@baseboard_fab2_lib.baseboard_fab2(sch_1):page149_i126:a"
				( attribute "PN" "1"
					( Origin gPackager )
				)
				( objectStatus "C25W61.1" )
			)
			( pin "@baseboard_fab2_lib.baseboard_fab2(sch_1):page149_i126:b"
				( attribute "PN" "2"
					( Origin gPackager )
				)
				( objectStatus "C25W61.2" )
			)
			( pin "@baseboard_fab2_lib.baseboard_fab2(sch_1):page149_i50:a"
				( attribute "PN" "1"
					( Origin gPackager )
				)
				( objectStatus "C25W47.1" )
			)
			( pin "@baseboard_fab2_lib.baseboard_fab2(sch_1):page149_i50:b"
				( attribute "PN" "2"
					( Origin gPackager )
				)
				( objectStatus "C25W47.2" )
			)
			( pin "@baseboard_fab2_lib.baseboard_fab2(sch_1):page149_i51:a"
				( attribute "PN" "1"
					( Origin gPackager )
				)
				( objectStatus "C25W46.1" )
			)
			( pin "@baseboard_fab2_lib.baseboard_fab2(sch_1):page149_i51:b"
				( attribute "PN" "2"
					( Origin gPackager )
				)
				( objectStatus "C25W46.2" )
			)
			( pin "@baseboard_fab2_lib.baseboard_fab2(sch_1):page149_i128:a"
				( attribute "PN" "1"
					( Origin gPackager )
				)
				( objectStatus "C25W68.1" )
			)
			( pin "@baseboard_fab2_lib.baseboard_fab2(sch_1):page149_i128:b"
				( attribute "PN" "2"
					( Origin gPackager )
				)
				( objectStatus "C25W68.2" )
			)
			( pin "@baseboard_fab2_lib.baseboard_fab2(sch_1):page268_i36:\1\"
				( attribute "PN" "1"
					( Origin gPackager )
				)
				( objectStatus "R25W183.1" )
			)
			( pin "@baseboard_fab2_lib.baseboard_fab2(sch_1):page268_i36:\2\"
				( attribute "PN" "2"
					( Origin gPackager )
				)
				( objectStatus "R25W183.2" )
			)
			( pin "@baseboard_fab2_lib.baseboard_fab2(sch_1):page149_i125:a"
				( attribute "PN" "1"
					( Origin gPackager )
				)
				( objectStatus "C25W58.1" )
			)
			( pin "@baseboard_fab2_lib.baseboard_fab2(sch_1):page149_i125:b"
				( attribute "PN" "2"
					( Origin gPackager )
				)
				( objectStatus "C25W58.2" )
			)
			( pin "@baseboard_fab2_lib.baseboard_fab2(sch_1):page149_i79:a"
				( attribute "PN" "1"
					( Origin gPackager )
				)
				( objectStatus "C25W59.1" )
			)
			( pin "@baseboard_fab2_lib.baseboard_fab2(sch_1):page149_i79:b"
				( attribute "PN" "2"
					( Origin gPackager )
				)
				( objectStatus "C25W59.2" )
			)
			( pin "@baseboard_fab2_lib.baseboard_fab2(sch_1):page143_i67:a"
				( attribute "PN" "1"
					( Origin gPackager )
				)
				( objectStatus "C25W22.1" )
			)
			( pin "@baseboard_fab2_lib.baseboard_fab2(sch_1):page143_i67:b"
				( attribute "PN" "2"
					( Origin gPackager )
				)
				( objectStatus "C25W22.2" )
			)
			( pin "@baseboard_fab2_lib.baseboard_fab2(sch_1):page250_i12:drain(0)"
				( attribute "PN" "3"
					( Origin gPackager )
				)
				( objectStatus "Q1W2.3" )
			)
			( pin "@baseboard_fab2_lib.baseboard_fab2(sch_1):page250_i12:gate(0)"
				( attribute "PN" "5"
					( Origin gPackager )
				)
				( objectStatus "Q1W2.5" )
			)
			( pin "@baseboard_fab2_lib.baseboard_fab2(sch_1):page250_i12:source(0)"
				( attribute "PN" "4"
					( Origin gPackager )
				)
				( objectStatus "Q1W2.4" )
			)
			( pin "@baseboard_fab2_lib.baseboard_fab2(sch_1):page149_i85:\1\"
				( attribute "PN" "1"
					( Origin gPackager )
				)
				( objectStatus "FB2T3.1" )
			)
			( pin "@baseboard_fab2_lib.baseboard_fab2(sch_1):page149_i85:\2\"
				( attribute "PN" "2"
					( Origin gPackager )
				)
				( objectStatus "FB2T3.2" )
			)
			( pin "@baseboard_fab2_lib.baseboard_fab2(sch_1):page149_i86:\1\"
				( attribute "PN" "1"
					( Origin gPackager )
				)
				( objectStatus "FB2T4.1" )
			)
			( pin "@baseboard_fab2_lib.baseboard_fab2(sch_1):page149_i86:\2\"
				( attribute "PN" "2"
					( Origin gPackager )
				)
				( objectStatus "FB2T4.2" )
			)
			( pin "@baseboard_fab2_lib.baseboard_fab2(sch_1):page149_i88:\1\"
				( attribute "PN" "1"
					( Origin gPackager )
				)
				( objectStatus "FB2T5.1" )
			)
			( pin "@baseboard_fab2_lib.baseboard_fab2(sch_1):page149_i88:\2\"
				( attribute "PN" "2"
					( Origin gPackager )
				)
				( objectStatus "FB2T5.2" )
			)
			( pin "@baseboard_fab2_lib.baseboard_fab2(sch_1):page202_i115:\1\"
				( attribute "PN" "1"
					( Origin gPackager )
				)
				( objectStatus "RT4.1" )
			)
			( pin "@baseboard_fab2_lib.baseboard_fab2(sch_1):page202_i115:\2\"
				( attribute "PN" "2"
					( Origin gPackager )
				)
				( objectStatus "RT4.2" )
			)
			( pin "@baseboard_fab2_lib.baseboard_fab2(sch_1):page200_i249:\1\"
				( attribute "PN" "1"
					( Origin gPackager )
				)
				( objectStatus "R9P13.1" )
			)
			( pin "@baseboard_fab2_lib.baseboard_fab2(sch_1):page200_i249:\2\"
				( attribute "PN" "2"
					( Origin gPackager )
				)
				( objectStatus "R9P13.2" )
			)
			( pin "@baseboard_fab2_lib.baseboard_fab2(sch_1):page151_i198:drain(0)"
				( attribute "PN" "6"
					( Origin gPackager )
				)
				( objectStatus "Q9E1.6" )
			)
			( pin "@baseboard_fab2_lib.baseboard_fab2(sch_1):page151_i198:gate(0)"
				( attribute "PN" "2"
					( Origin gPackager )
				)
				( objectStatus "Q9E1.2" )
			)
			( pin "@baseboard_fab2_lib.baseboard_fab2(sch_1):page151_i198:source(0)"
				( attribute "PN" "1"
					( Origin gPackager )
				)
				( objectStatus "Q9E1.1" )
			)
			( pin "@baseboard_fab2_lib.baseboard_fab2(sch_1):page151_i201:a"
				( attribute "PN" "1"
					( Origin gPackager )
				)
				( objectStatus "R1T30.1" )
			)
			( pin "@baseboard_fab2_lib.baseboard_fab2(sch_1):page151_i201:b"
				( attribute "PN" "2"
					( Origin gPackager )
				)
				( objectStatus "R1T30.2" )
			)
			( pin "@baseboard_fab2_lib.baseboard_fab2(sch_1):page151_i202:a"
				( attribute "PN" "1"
					( Origin gPackager )
				)
				( objectStatus "R1T29.1" )
			)
			( pin "@baseboard_fab2_lib.baseboard_fab2(sch_1):page151_i202:b"
				( attribute "PN" "2"
					( Origin gPackager )
				)
				( objectStatus "R1T29.2" )
			)
			( pin "@baseboard_fab2_lib.baseboard_fab2(sch_1):page246_i22:a"
				( attribute "PN" "1"
					( Origin gPackager )
				)
				( objectStatus "CN8F2.1" )
			)
			( pin "@baseboard_fab2_lib.baseboard_fab2(sch_1):page246_i22:b"
				( attribute "PN" "2"
					( Origin gPackager )
				)
				( objectStatus "CN8F2.2" )
			)
			( pin "@baseboard_fab2_lib.baseboard_fab2(sch_1):page151_i216:a"
				( attribute "PN" "1"
					( Origin gPackager )
				)
				( objectStatus "C25W15.1" )
			)
			( pin "@baseboard_fab2_lib.baseboard_fab2(sch_1):page151_i216:b"
				( attribute "PN" "2"
					( Origin gPackager )
				)
				( objectStatus "C25W15.2" )
			)
			( pin "@baseboard_fab2_lib.baseboard_fab2(sch_1):page151_i215:a"
				( attribute "PN" "1"
					( Origin gPackager )
				)
				( objectStatus "C25W14.1" )
			)
			( pin "@baseboard_fab2_lib.baseboard_fab2(sch_1):page151_i215:b"
				( attribute "PN" "2"
					( Origin gPackager )
				)
				( objectStatus "C25W14.2" )
			)
			( pin "@baseboard_fab2_lib.baseboard_fab2(sch_1):page248_i19:a(0)"
				( attribute "PN" "1"
					( Origin gPackager )
				)
				( objectStatus "U14E3.1" )
			)
			( pin "@baseboard_fab2_lib.baseboard_fab2(sch_1):page248_i19:b(0)"
				( attribute "PN" "2"
					( Origin gPackager )
				)
				( objectStatus "U14E3.2" )
			)
			( pin "@baseboard_fab2_lib.baseboard_fab2(sch_1):page248_i19:y(0)"
				( attribute "PN" "4"
					( Origin gPackager )
				)
				( objectStatus "U14E3.4" )
			)
			( pin "@baseboard_fab2_lib.baseboard_fab2(sch_1):page207_i111:\1\"
				( attribute "PN" "1"
					( Origin gPackager )
				)
				( objectStatus "RT16.1" )
			)
			( pin "@baseboard_fab2_lib.baseboard_fab2(sch_1):page207_i111:\2\"
				( attribute "PN" "2"
					( Origin gPackager )
				)
				( objectStatus "RT16.2" )
			)
			( pin "@baseboard_fab2_lib.baseboard_fab2(sch_1):page248_i24:a"
				( attribute "PN" "1"
					( Origin gPackager )
				)
				( objectStatus "R6W26.1" )
			)
			( pin "@baseboard_fab2_lib.baseboard_fab2(sch_1):page248_i24:b"
				( attribute "PN" "2"
					( Origin gPackager )
				)
				( objectStatus "R6W26.2" )
			)
			( pin "@baseboard_fab2_lib.baseboard_fab2(sch_1):page248_i25:a"
				( attribute "PN" "1"
					( Origin gPackager )
				)
				( objectStatus "R6W27.1" )
			)
			( pin "@baseboard_fab2_lib.baseboard_fab2(sch_1):page248_i25:b"
				( attribute "PN" "2"
					( Origin gPackager )
				)
				( objectStatus "R6W27.2" )
			)
			( pin "@baseboard_fab2_lib.baseboard_fab2(sch_1):page248_i26:a"
				( attribute "PN" "1"
					( Origin gPackager )
				)
				( objectStatus "R9W19.1" )
			)
			( pin "@baseboard_fab2_lib.baseboard_fab2(sch_1):page248_i26:b"
				( attribute "PN" "2"
					( Origin gPackager )
				)
				( objectStatus "R9W19.2" )
			)
			( pin "@baseboard_fab2_lib.baseboard_fab2(sch_1):page248_i27:a"
				( attribute "PN" "1"
					( Origin gPackager )
				)
				( objectStatus "R9W18.1" )
			)
			( pin "@baseboard_fab2_lib.baseboard_fab2(sch_1):page248_i27:b"
				( attribute "PN" "2"
					( Origin gPackager )
				)
				( objectStatus "R9W18.2" )
			)
			( pin "@baseboard_fab2_lib.baseboard_fab2(sch_1):page248_i30:a"
				( attribute "PN" "1"
					( Origin gPackager )
				)
				( objectStatus "C9W8.1" )
			)
			( pin "@baseboard_fab2_lib.baseboard_fab2(sch_1):page248_i30:b"
				( attribute "PN" "2"
					( Origin gPackager )
				)
				( objectStatus "C9W8.2" )
			)
			( pin "@baseboard_fab2_lib.baseboard_fab2(sch_1):page248_i32:a"
				( attribute "PN" "1"
					( Origin gPackager )
				)
				( objectStatus "C9W7.1" )
			)
			( pin "@baseboard_fab2_lib.baseboard_fab2(sch_1):page248_i32:b"
				( attribute "PN" "2"
					( Origin gPackager )
				)
				( objectStatus "C9W7.2" )
			)
			( pin "@baseboard_fab2_lib.baseboard_fab2(sch_1):page248_i34:a"
				( attribute "PN" "1"
					( Origin gPackager )
				)
				( objectStatus "R9W16.1" )
			)
			( pin "@baseboard_fab2_lib.baseboard_fab2(sch_1):page248_i34:b"
				( attribute "PN" "2"
					( Origin gPackager )
				)
				( objectStatus "R9W16.2" )
			)
			( pin "@baseboard_fab2_lib.baseboard_fab2(sch_1):page248_i35:a"
				( attribute "PN" "1"
					( Origin gPackager )
				)
				( objectStatus "R9W17.1" )
			)
			( pin "@baseboard_fab2_lib.baseboard_fab2(sch_1):page248_i35:b"
				( attribute "PN" "2"
					( Origin gPackager )
				)
				( objectStatus "R9W17.2" )
			)
			( pin "@baseboard_fab2_lib.baseboard_fab2(sch_1):page248_i37:a"
				( attribute "PN" "1"
					( Origin gPackager )
				)
				( objectStatus "R9W14.1" )
			)
			( pin "@baseboard_fab2_lib.baseboard_fab2(sch_1):page248_i37:b"
				( attribute "PN" "2"
					( Origin gPackager )
				)
				( objectStatus "R9W14.2" )
			)
			( pin "@baseboard_fab2_lib.baseboard_fab2(sch_1):page248_i38:a"
				( attribute "PN" "1"
					( Origin gPackager )
				)
				( objectStatus "R9W13.1" )
			)
			( pin "@baseboard_fab2_lib.baseboard_fab2(sch_1):page248_i38:b"
				( attribute "PN" "2"
					( Origin gPackager )
				)
				( objectStatus "R9W13.2" )
			)
			( pin "@baseboard_fab2_lib.baseboard_fab2(sch_1):page249_i34:a"
				( attribute "PN" "1"
					( Origin gPackager )
				)
				( objectStatus "R8W1.1" )
			)
			( pin "@baseboard_fab2_lib.baseboard_fab2(sch_1):page249_i34:b"
				( attribute "PN" "2"
					( Origin gPackager )
				)
				( objectStatus "R8W1.2" )
			)
			( pin "@baseboard_fab2_lib.baseboard_fab2(sch_1):page216_i152:\1\"
				( attribute "PN" "1"
					( Origin gPackager )
				)
				( objectStatus "RT35.1" )
			)
			( pin "@baseboard_fab2_lib.baseboard_fab2(sch_1):page216_i152:\2\"
				( attribute "PN" "2"
					( Origin gPackager )
				)
				( objectStatus "RT35.2" )
			)
			( pin "@baseboard_fab2_lib.baseboard_fab2(sch_1):page250_i27:\1\"
				( attribute "PN" "1"
					( Origin gPackager )
				)
				( objectStatus "R1W3.1" )
			)
			( pin "@baseboard_fab2_lib.baseboard_fab2(sch_1):page250_i27:\2\"
				( attribute "PN" "2"
					( Origin gPackager )
				)
				( objectStatus "R1W3.2" )
			)
			( pin "@baseboard_fab2_lib.baseboard_fab2(sch_1):page250_i24:drain(0)"
				( attribute "PN" "6"
					( Origin gPackager )
				)
				( objectStatus "Q1W2.6" )
			)
			( pin "@baseboard_fab2_lib.baseboard_fab2(sch_1):page250_i24:gate(0)"
				( attribute "PN" "2"
					( Origin gPackager )
				)
				( objectStatus "Q1W2.2" )
			)
			( pin "@baseboard_fab2_lib.baseboard_fab2(sch_1):page250_i24:source(0)"
				( attribute "PN" "1"
					( Origin gPackager )
				)
				( objectStatus "Q1W2.1" )
			)
			( pin "@baseboard_fab2_lib.baseboard_fab2(sch_1):page250_i22:a"
				( attribute "PN" "1"
					( Origin gPackager )
				)
				( objectStatus "R1W4.1" )
			)
			( pin "@baseboard_fab2_lib.baseboard_fab2(sch_1):page250_i22:b"
				( attribute "PN" "2"
					( Origin gPackager )
				)
				( objectStatus "R1W4.2" )
			)
			( pin "@baseboard_fab2_lib.baseboard_fab2(sch_1):page199_i130:drn"
				( attribute "PN" "3"
					( Origin gPackager )
				)
				( objectStatus "Q1W5.3" )
			)
			( pin "@baseboard_fab2_lib.baseboard_fab2(sch_1):page199_i130:gate"
				( attribute "PN" "1"
					( Origin gPackager )
				)
				( objectStatus "Q1W5.1" )
			)
			( pin "@baseboard_fab2_lib.baseboard_fab2(sch_1):page199_i130:src"
				( attribute "PN" "2"
					( Origin gPackager )
				)
				( objectStatus "Q1W5.2" )
			)
			( pin "@baseboard_fab2_lib.baseboard_fab2(sch_1):page250_i18:\1\"
				( attribute "PN" "1"
					( Origin gPackager )
				)
				( objectStatus "R1W1.1" )
			)
			( pin "@baseboard_fab2_lib.baseboard_fab2(sch_1):page250_i18:\2\"
				( attribute "PN" "2"
					( Origin gPackager )
				)
				( objectStatus "R1W1.2" )
			)
			( pin "@baseboard_fab2_lib.baseboard_fab2(sch_1):page164_i34:a"
				( attribute "PN" "1"
					( Origin gPackager )
				)
				( objectStatus "R1U23.1" )
			)
			( pin "@baseboard_fab2_lib.baseboard_fab2(sch_1):page164_i34:b"
				( attribute "PN" "2"
					( Origin gPackager )
				)
				( objectStatus "R1U23.2" )
			)
			( pin "@baseboard_fab2_lib.baseboard_fab2(sch_1):page164_i37:a"
				( attribute "PN" "1"
					( Origin gPackager )
				)
				( objectStatus "R1U16.1" )
			)
			( pin "@baseboard_fab2_lib.baseboard_fab2(sch_1):page164_i37:b"
				( attribute "PN" "2"
					( Origin gPackager )
				)
				( objectStatus "R1U16.2" )
			)
			( pin "@baseboard_fab2_lib.baseboard_fab2(sch_1):page247_i112:a"
				( attribute "PN" "1"
					( Origin gPackager )
				)
				( objectStatus "R6W28.1" )
			)
			( pin "@baseboard_fab2_lib.baseboard_fab2(sch_1):page247_i112:b"
				( attribute "PN" "2"
					( Origin gPackager )
				)
				( objectStatus "R6W28.2" )
			)
			( pin "@baseboard_fab2_lib.baseboard_fab2(sch_1):page149_i91:a"
				( attribute "PN" "1"
					( Origin gPackager )
				)
				( objectStatus "R25W120.1" )
			)
			( pin "@baseboard_fab2_lib.baseboard_fab2(sch_1):page149_i91:b"
				( attribute "PN" "2"
					( Origin gPackager )
				)
				( objectStatus "R25W120.2" )
			)
			( pin "@baseboard_fab2_lib.baseboard_fab2(sch_1):page107_i500:a"
				( attribute "PN" "1"
					( Origin gPackager )
				)
				( objectStatus "R2U28.1" )
			)
			( pin "@baseboard_fab2_lib.baseboard_fab2(sch_1):page107_i500:b"
				( attribute "PN" "2"
					( Origin gPackager )
				)
				( objectStatus "R2U28.2" )
			)
			( pin "@baseboard_fab2_lib.baseboard_fab2(sch_1):page107_i499:a"
				( attribute "PN" "1"
					( Origin gPackager )
				)
				( objectStatus "R2U14.1" )
			)
			( pin "@baseboard_fab2_lib.baseboard_fab2(sch_1):page107_i499:b"
				( attribute "PN" "2"
					( Origin gPackager )
				)
				( objectStatus "R2U14.2" )
			)
			( pin "@baseboard_fab2_lib.baseboard_fab2(sch_1):page107_i498:a"
				( attribute "PN" "1"
					( Origin gPackager )
				)
				( objectStatus "R2U26.1" )
			)
			( pin "@baseboard_fab2_lib.baseboard_fab2(sch_1):page107_i498:b"
				( attribute "PN" "2"
					( Origin gPackager )
				)
				( objectStatus "R2U26.2" )
			)
			( pin "@baseboard_fab2_lib.baseboard_fab2(sch_1):page107_i481:a"
				( attribute "PN" "1"
					( Origin gPackager )
				)
				( objectStatus "C3P12.1" )
			)
			( pin "@baseboard_fab2_lib.baseboard_fab2(sch_1):page107_i481:b"
				( attribute "PN" "2"
					( Origin gPackager )
				)
				( objectStatus "C3P12.2" )
			)
			( pin "@baseboard_fab2_lib.baseboard_fab2(sch_1):page107_i480:a"
				( attribute "PN" "1"
					( Origin gPackager )
				)
				( objectStatus "C3P21.1" )
			)
			( pin "@baseboard_fab2_lib.baseboard_fab2(sch_1):page107_i480:b"
				( attribute "PN" "2"
					( Origin gPackager )
				)
				( objectStatus "C3P21.2" )
			)
			( pin "@baseboard_fab2_lib.baseboard_fab2(sch_1):page107_i479:a"
				( attribute "PN" "1"
					( Origin gPackager )
				)
				( objectStatus "C3P24.1" )
			)
			( pin "@baseboard_fab2_lib.baseboard_fab2(sch_1):page107_i479:b"
				( attribute "PN" "2"
					( Origin gPackager )
				)
				( objectStatus "C3P24.2" )
			)
			( pin "@baseboard_fab2_lib.baseboard_fab2(sch_1):page107_i478:a"
				( attribute "PN" "1"
					( Origin gPackager )
				)
				( objectStatus "C3P29.1" )
			)
			( pin "@baseboard_fab2_lib.baseboard_fab2(sch_1):page107_i478:b"
				( attribute "PN" "2"
					( Origin gPackager )
				)
				( objectStatus "C3P29.2" )
			)
			( pin "@baseboard_fab2_lib.baseboard_fab2(sch_1):page185_i142:a"
				( attribute "PN" "1"
					( Origin gPackager )
				)
				( objectStatus "C8F15.1" )
			)
			( pin "@baseboard_fab2_lib.baseboard_fab2(sch_1):page185_i142:b"
				( attribute "PN" "2"
					( Origin gPackager )
				)
				( objectStatus "C8F15.2" )
			)
			( pin "@baseboard_fab2_lib.baseboard_fab2(sch_1):page185_i141:a"
				( attribute "PN" "1"
					( Origin gPackager )
				)
				( objectStatus "C8F13.1" )
			)
			( pin "@baseboard_fab2_lib.baseboard_fab2(sch_1):page185_i141:b"
				( attribute "PN" "2"
					( Origin gPackager )
				)
				( objectStatus "C8F13.2" )
			)
			( pin "@baseboard_fab2_lib.baseboard_fab2(sch_1):page185_i140:a"
				( attribute "PN" "1"
					( Origin gPackager )
				)
				( objectStatus "C8F12.1" )
			)
			( pin "@baseboard_fab2_lib.baseboard_fab2(sch_1):page185_i140:b"
				( attribute "PN" "2"
					( Origin gPackager )
				)
				( objectStatus "C8F12.2" )
			)
			( pin "@baseboard_fab2_lib.baseboard_fab2(sch_1):page185_i138:a"
				( attribute "PN" "1"
					( Origin gPackager )
				)
				( objectStatus "C8F6.1" )
			)
			( pin "@baseboard_fab2_lib.baseboard_fab2(sch_1):page185_i138:b"
				( attribute "PN" "2"
					( Origin gPackager )
				)
				( objectStatus "C8F6.2" )
			)
			( pin "@baseboard_fab2_lib.baseboard_fab2(sch_1):page250_i8:drain(0)"
				( attribute "PN" "3"
					( Origin gPackager )
				)
				( objectStatus "Q1W4.3" )
			)
			( pin "@baseboard_fab2_lib.baseboard_fab2(sch_1):page250_i8:gate(0)"
				( attribute "PN" "5"
					( Origin gPackager )
				)
				( objectStatus "Q1W4.5" )
			)
			( pin "@baseboard_fab2_lib.baseboard_fab2(sch_1):page250_i8:source(0)"
				( attribute "PN" "4"
					( Origin gPackager )
				)
				( objectStatus "Q1W4.4" )
			)
			( pin "@baseboard_fab2_lib.baseboard_fab2(sch_1):page250_i6:a"
				( attribute "PN" "1"
					( Origin gPackager )
				)
				( objectStatus "R1W7.1" )
			)
			( pin "@baseboard_fab2_lib.baseboard_fab2(sch_1):page250_i6:b"
				( attribute "PN" "2"
					( Origin gPackager )
				)
				( objectStatus "R1W7.2" )
			)
			( pin "@baseboard_fab2_lib.baseboard_fab2(sch_1):page250_i3:drain(0)"
				( attribute "PN" "6"
					( Origin gPackager )
				)
				( objectStatus "Q1W4.6" )
			)
			( pin "@baseboard_fab2_lib.baseboard_fab2(sch_1):page250_i3:gate(0)"
				( attribute "PN" "2"
					( Origin gPackager )
				)
				( objectStatus "Q1W4.2" )
			)
			( pin "@baseboard_fab2_lib.baseboard_fab2(sch_1):page250_i3:source(0)"
				( attribute "PN" "1"
					( Origin gPackager )
				)
				( objectStatus "Q1W4.1" )
			)
			( pin "@baseboard_fab2_lib.baseboard_fab2(sch_1):page250_i2:\1\"
				( attribute "PN" "1"
					( Origin gPackager )
				)
				( objectStatus "R1W6.1" )
			)
			( pin "@baseboard_fab2_lib.baseboard_fab2(sch_1):page250_i2:\2\"
				( attribute "PN" "2"
					( Origin gPackager )
				)
				( objectStatus "R1W6.2" )
			)
			( pin "@baseboard_fab2_lib.baseboard_fab2(sch_1):page107_i501:a"
				( attribute "PN" "1"
					( Origin gPackager )
				)
				( objectStatus "R2U16.1" )
			)
			( pin "@baseboard_fab2_lib.baseboard_fab2(sch_1):page107_i501:b"
				( attribute "PN" "2"
					( Origin gPackager )
				)
				( objectStatus "R2U16.2" )
			)
			( pin "@baseboard_fab2_lib.baseboard_fab2(sch_1):page107_i502:a"
				( attribute "PN" "1"
					( Origin gPackager )
				)
				( objectStatus "R2U18.1" )
			)
			( pin "@baseboard_fab2_lib.baseboard_fab2(sch_1):page107_i502:b"
				( attribute "PN" "2"
					( Origin gPackager )
				)
				( objectStatus "R2U18.2" )
			)
			( pin "@baseboard_fab2_lib.baseboard_fab2(sch_1):page107_i503:a"
				( attribute "PN" "1"
					( Origin gPackager )
				)
				( objectStatus "R2U20.1" )
			)
			( pin "@baseboard_fab2_lib.baseboard_fab2(sch_1):page107_i503:b"
				( attribute "PN" "2"
					( Origin gPackager )
				)
				( objectStatus "R2U20.2" )
			)
			( pin "@baseboard_fab2_lib.baseboard_fab2(sch_1):page107_i504:a"
				( attribute "PN" "1"
					( Origin gPackager )
				)
				( objectStatus "R2U22.1" )
			)
			( pin "@baseboard_fab2_lib.baseboard_fab2(sch_1):page107_i504:b"
				( attribute "PN" "2"
					( Origin gPackager )
				)
				( objectStatus "R2U22.2" )
			)
			( pin "@baseboard_fab2_lib.baseboard_fab2(sch_1):page107_i505:a"
				( attribute "PN" "1"
					( Origin gPackager )
				)
				( objectStatus "R2U24.1" )
			)
			( pin "@baseboard_fab2_lib.baseboard_fab2(sch_1):page107_i505:b"
				( attribute "PN" "2"
					( Origin gPackager )
				)
				( objectStatus "R2U24.2" )
			)
			( pin "@baseboard_fab2_lib.baseboard_fab2(sch_1):page169_i171:\1\"
				( attribute "PN" "1"
					( Origin gPackager )
				)
				( objectStatus "R1U33.1" )
			)
			( pin "@baseboard_fab2_lib.baseboard_fab2(sch_1):page169_i171:\2\"
				( attribute "PN" "2"
					( Origin gPackager )
				)
				( objectStatus "R1U33.2" )
			)
			( pin "@baseboard_fab2_lib.baseboard_fab2(sch_1):page169_i172:a"
				( attribute "PN" "1"
					( Origin gPackager )
				)
				( objectStatus "R1U38.1" )
			)
			( pin "@baseboard_fab2_lib.baseboard_fab2(sch_1):page169_i172:b"
				( attribute "PN" "2"
					( Origin gPackager )
				)
				( objectStatus "R1U38.2" )
			)
			( pin "@baseboard_fab2_lib.baseboard_fab2(sch_1):page169_i173:a"
				( attribute "PN" "1"
					( Origin gPackager )
				)
				( objectStatus "R1U27.1" )
			)
			( pin "@baseboard_fab2_lib.baseboard_fab2(sch_1):page169_i173:b"
				( attribute "PN" "2"
					( Origin gPackager )
				)
				( objectStatus "R1U27.2" )
			)
			( pin "@baseboard_fab2_lib.baseboard_fab2(sch_1):page186_i358:\1\"
				( attribute "PN" "1"
					( Origin gPackager )
				)
				( objectStatus "R9B7.1" )
			)
			( pin "@baseboard_fab2_lib.baseboard_fab2(sch_1):page186_i358:\2\"
				( attribute "PN" "2"
					( Origin gPackager )
				)
				( objectStatus "R9B7.2" )
			)
			( pin "@baseboard_fab2_lib.baseboard_fab2(sch_1):page187_i175:\1\"
				( attribute "PN" "1"
					( Origin gPackager )
				)
				( objectStatus "R2R8.1" )
			)
			( pin "@baseboard_fab2_lib.baseboard_fab2(sch_1):page187_i175:\2\"
				( attribute "PN" "2"
					( Origin gPackager )
				)
				( objectStatus "R2R8.2" )
			)
			( pin "@baseboard_fab2_lib.baseboard_fab2(sch_1):page208_i105:a"
				( attribute "PN" "1"
					( Origin gPackager )
				)
				( objectStatus "CT20.1" )
			)
			( pin "@baseboard_fab2_lib.baseboard_fab2(sch_1):page208_i105:b"
				( attribute "PN" "2"
					( Origin gPackager )
				)
				( objectStatus "CT20.2" )
			)
			( pin "@baseboard_fab2_lib.baseboard_fab2(sch_1):page243_i89:a"
				( attribute "PN" "1"
					( Origin gPackager )
				)
				( objectStatus "C5G115.1" )
			)
			( pin "@baseboard_fab2_lib.baseboard_fab2(sch_1):page243_i89:b"
				( attribute "PN" "2"
					( Origin gPackager )
				)
				( objectStatus "C5G115.2" )
			)
			( pin "@baseboard_fab2_lib.baseboard_fab2(sch_1):page203_i123:a"
				( attribute "PN" "1"
					( Origin gPackager )
				)
				( objectStatus "RT28.1" )
			)
			( pin "@baseboard_fab2_lib.baseboard_fab2(sch_1):page203_i123:b"
				( attribute "PN" "2"
					( Origin gPackager )
				)
				( objectStatus "RT28.2" )
			)
			( pin "@baseboard_fab2_lib.baseboard_fab2(sch_1):page203_i122:a"
				( attribute "PN" "1"
					( Origin gPackager )
				)
				( objectStatus "RT25.1" )
			)
			( pin "@baseboard_fab2_lib.baseboard_fab2(sch_1):page203_i122:b"
				( attribute "PN" "2"
					( Origin gPackager )
				)
				( objectStatus "RT25.2" )
			)
			( pin "@baseboard_fab2_lib.baseboard_fab2(sch_1):page202_i98:a"
				( attribute "PN" "1"
					( Origin gPackager )
				)
				( objectStatus "CT5.1" )
			)
			( pin "@baseboard_fab2_lib.baseboard_fab2(sch_1):page202_i98:b"
				( attribute "PN" "2"
					( Origin gPackager )
				)
				( objectStatus "CT5.2" )
			)
			( pin "@baseboard_fab2_lib.baseboard_fab2(sch_1):page202_i97:a"
				( attribute "PN" "1"
					( Origin gPackager )
				)
				( objectStatus "CT3.1" )
			)
			( pin "@baseboard_fab2_lib.baseboard_fab2(sch_1):page202_i97:b"
				( attribute "PN" "2"
					( Origin gPackager )
				)
				( objectStatus "CT3.2" )
			)
			( pin "@baseboard_fab2_lib.baseboard_fab2(sch_1):page186_i356:a"
				( attribute "PN" "1"
					( Origin gPackager )
				)
				( objectStatus "R9W1.1" )
			)
			( pin "@baseboard_fab2_lib.baseboard_fab2(sch_1):page186_i356:b"
				( attribute "PN" "2"
					( Origin gPackager )
				)
				( objectStatus "R9W1.2" )
			)
			( pin "@baseboard_fab2_lib.baseboard_fab2(sch_1):page187_i174:a"
				( attribute "PN" "1"
					( Origin gPackager )
				)
				( objectStatus "R2W1.1" )
			)
			( pin "@baseboard_fab2_lib.baseboard_fab2(sch_1):page187_i174:b"
				( attribute "PN" "2"
					( Origin gPackager )
				)
				( objectStatus "R2W1.2" )
			)
			( pin "@baseboard_fab2_lib.baseboard_fab2(sch_1):page208_i121:\1\"
				( attribute "PN" "1"
					( Origin gPackager )
				)
				( objectStatus "RT13.1" )
			)
			( pin "@baseboard_fab2_lib.baseboard_fab2(sch_1):page208_i121:\2\"
				( attribute "PN" "2"
					( Origin gPackager )
				)
				( objectStatus "RT13.2" )
			)
			( pin "@baseboard_fab2_lib.baseboard_fab2(sch_1):page202_i101:a"
				( attribute "PN" "1"
					( Origin gPackager )
				)
				( objectStatus "RT1.1" )
			)
			( pin "@baseboard_fab2_lib.baseboard_fab2(sch_1):page202_i101:b"
				( attribute "PN" "2"
					( Origin gPackager )
				)
				( objectStatus "RT1.2" )
			)
			( pin "@baseboard_fab2_lib.baseboard_fab2(sch_1):page202_i102:a"
				( attribute "PN" "1"
					( Origin gPackager )
				)
				( objectStatus "RT3.1" )
			)
			( pin "@baseboard_fab2_lib.baseboard_fab2(sch_1):page202_i102:b"
				( attribute "PN" "2"
					( Origin gPackager )
				)
				( objectStatus "RT3.2" )
			)
			( pin "@baseboard_fab2_lib.baseboard_fab2(sch_1):page227_i149:\1\"
				( attribute "PN" "1"
					( Origin gPackager )
				)
				( objectStatus "RT6.1" )
			)
			( pin "@baseboard_fab2_lib.baseboard_fab2(sch_1):page227_i149:\2\"
				( attribute "PN" "2"
					( Origin gPackager )
				)
				( objectStatus "RT6.2" )
			)
			( pin "@baseboard_fab2_lib.baseboard_fab2(sch_1):page149_i92:a"
				( attribute "PN" "1"
					( Origin gPackager )
				)
				( objectStatus "C25W53.1" )
			)
			( pin "@baseboard_fab2_lib.baseboard_fab2(sch_1):page149_i92:b"
				( attribute "PN" "2"
					( Origin gPackager )
				)
				( objectStatus "C25W53.2" )
			)
			( pin "@baseboard_fab2_lib.baseboard_fab2(sch_1):page149_i93:a"
				( attribute "PN" "1"
					( Origin gPackager )
				)
				( objectStatus "C25W56.1" )
			)
			( pin "@baseboard_fab2_lib.baseboard_fab2(sch_1):page149_i93:b"
				( attribute "PN" "2"
					( Origin gPackager )
				)
				( objectStatus "C25W56.2" )
			)
			( pin "@baseboard_fab2_lib.baseboard_fab2(sch_1):page149_i95:a"
				( attribute "PN" "1"
					( Origin gPackager )
				)
				( objectStatus "C25W54.1" )
			)
			( pin "@baseboard_fab2_lib.baseboard_fab2(sch_1):page149_i95:b"
				( attribute "PN" "2"
					( Origin gPackager )
				)
				( objectStatus "C25W54.2" )
			)
			( pin "@baseboard_fab2_lib.baseboard_fab2(sch_1):page149_i96:a"
				( attribute "PN" "1"
					( Origin gPackager )
				)
				( objectStatus "C25W40.1" )
			)
			( pin "@baseboard_fab2_lib.baseboard_fab2(sch_1):page149_i96:b"
				( attribute "PN" "2"
					( Origin gPackager )
				)
				( objectStatus "C25W40.2" )
			)
			( pin "@baseboard_fab2_lib.baseboard_fab2(sch_1):page149_i97:a"
				( attribute "PN" "1"
					( Origin gPackager )
				)
				( objectStatus "C25W41.1" )
			)
			( pin "@baseboard_fab2_lib.baseboard_fab2(sch_1):page149_i97:b"
				( attribute "PN" "2"
					( Origin gPackager )
				)
				( objectStatus "C25W41.2" )
			)
			( pin "@baseboard_fab2_lib.baseboard_fab2(sch_1):page149_i98:a"
				( attribute "PN" "1"
					( Origin gPackager )
				)
				( objectStatus "C25W42.1" )
			)
			( pin "@baseboard_fab2_lib.baseboard_fab2(sch_1):page149_i98:b"
				( attribute "PN" "2"
					( Origin gPackager )
				)
				( objectStatus "C25W42.2" )
			)
			( pin "@baseboard_fab2_lib.baseboard_fab2(sch_1):page149_i99:a"
				( attribute "PN" "1"
					( Origin gPackager )
				)
				( objectStatus "C25W32.1" )
			)
			( pin "@baseboard_fab2_lib.baseboard_fab2(sch_1):page149_i99:b"
				( attribute "PN" "2"
					( Origin gPackager )
				)
				( objectStatus "C25W32.2" )
			)
			( pin "@baseboard_fab2_lib.baseboard_fab2(sch_1):page149_i100:a"
				( attribute "PN" "1"
					( Origin gPackager )
				)
				( objectStatus "C25W43.1" )
			)
			( pin "@baseboard_fab2_lib.baseboard_fab2(sch_1):page149_i100:b"
				( attribute "PN" "2"
					( Origin gPackager )
				)
				( objectStatus "C25W43.2" )
			)
			( pin "@baseboard_fab2_lib.baseboard_fab2(sch_1):page149_i101:a"
				( attribute "PN" "1"
					( Origin gPackager )
				)
				( objectStatus "C25W44.1" )
			)
			( pin "@baseboard_fab2_lib.baseboard_fab2(sch_1):page149_i101:b"
				( attribute "PN" "2"
					( Origin gPackager )
				)
				( objectStatus "C25W44.2" )
			)
			( pin "@baseboard_fab2_lib.baseboard_fab2(sch_1):page149_i102:a"
				( attribute "PN" "1"
					( Origin gPackager )
				)
				( objectStatus "C25W33.1" )
			)
			( pin "@baseboard_fab2_lib.baseboard_fab2(sch_1):page149_i102:b"
				( attribute "PN" "2"
					( Origin gPackager )
				)
				( objectStatus "C25W33.2" )
			)
			( pin "@baseboard_fab2_lib.baseboard_fab2(sch_1):page149_i103:a"
				( attribute "PN" "1"
					( Origin gPackager )
				)
				( objectStatus "C25W23.1" )
			)
			( pin "@baseboard_fab2_lib.baseboard_fab2(sch_1):page149_i103:b"
				( attribute "PN" "2"
					( Origin gPackager )
				)
				( objectStatus "C25W23.2" )
			)
			( pin "@baseboard_fab2_lib.baseboard_fab2(sch_1):page149_i104:a"
				( attribute "PN" "1"
					( Origin gPackager )
				)
				( objectStatus "C25W24.1" )
			)
			( pin "@baseboard_fab2_lib.baseboard_fab2(sch_1):page149_i104:b"
				( attribute "PN" "2"
					( Origin gPackager )
				)
				( objectStatus "C25W24.2" )
			)
			( pin "@baseboard_fab2_lib.baseboard_fab2(sch_1):page149_i105:a"
				( attribute "PN" "1"
					( Origin gPackager )
				)
				( objectStatus "C25W25.1" )
			)
			( pin "@baseboard_fab2_lib.baseboard_fab2(sch_1):page149_i105:b"
				( attribute "PN" "2"
					( Origin gPackager )
				)
				( objectStatus "C25W25.2" )
			)
			( pin "@baseboard_fab2_lib.baseboard_fab2(sch_1):page149_i106:a"
				( attribute "PN" "1"
					( Origin gPackager )
				)
				( objectStatus "C25W26.1" )
			)
			( pin "@baseboard_fab2_lib.baseboard_fab2(sch_1):page149_i106:b"
				( attribute "PN" "2"
					( Origin gPackager )
				)
				( objectStatus "C25W26.2" )
			)
			( pin "@baseboard_fab2_lib.baseboard_fab2(sch_1):page149_i107:a"
				( attribute "PN" "1"
					( Origin gPackager )
				)
				( objectStatus "C25W27.1" )
			)
			( pin "@baseboard_fab2_lib.baseboard_fab2(sch_1):page149_i107:b"
				( attribute "PN" "2"
					( Origin gPackager )
				)
				( objectStatus "C25W27.2" )
			)
			( pin "@baseboard_fab2_lib.baseboard_fab2(sch_1):page149_i108:a"
				( attribute "PN" "1"
					( Origin gPackager )
				)
				( objectStatus "C25W28.1" )
			)
			( pin "@baseboard_fab2_lib.baseboard_fab2(sch_1):page149_i108:b"
				( attribute "PN" "2"
					( Origin gPackager )
				)
				( objectStatus "C25W28.2" )
			)
			( pin "@baseboard_fab2_lib.baseboard_fab2(sch_1):page149_i109:a"
				( attribute "PN" "1"
					( Origin gPackager )
				)
				( objectStatus "C25W60.1" )
			)
			( pin "@baseboard_fab2_lib.baseboard_fab2(sch_1):page149_i109:b"
				( attribute "PN" "2"
					( Origin gPackager )
				)
				( objectStatus "C25W60.2" )
			)
			( pin "@baseboard_fab2_lib.baseboard_fab2(sch_1):page149_i110:a"
				( attribute "PN" "1"
					( Origin gPackager )
				)
				( objectStatus "C25W35.1" )
			)
			( pin "@baseboard_fab2_lib.baseboard_fab2(sch_1):page149_i110:b"
				( attribute "PN" "2"
					( Origin gPackager )
				)
				( objectStatus "C25W35.2" )
			)
			( pin "@baseboard_fab2_lib.baseboard_fab2(sch_1):page149_i112:a"
				( attribute "PN" "1"
					( Origin gPackager )
				)
				( objectStatus "C25W48.1" )
			)
			( pin "@baseboard_fab2_lib.baseboard_fab2(sch_1):page149_i112:b"
				( attribute "PN" "2"
					( Origin gPackager )
				)
				( objectStatus "C25W48.2" )
			)
			( pin "@baseboard_fab2_lib.baseboard_fab2(sch_1):page149_i113:a"
				( attribute "PN" "1"
					( Origin gPackager )
				)
				( objectStatus "C25W37.1" )
			)
			( pin "@baseboard_fab2_lib.baseboard_fab2(sch_1):page149_i113:b"
				( attribute "PN" "2"
					( Origin gPackager )
				)
				( objectStatus "C25W37.2" )
			)
			( pin "@baseboard_fab2_lib.baseboard_fab2(sch_1):page149_i114:a"
				( attribute "PN" "1"
					( Origin gPackager )
				)
				( objectStatus "C25W51.1" )
			)
			( pin "@baseboard_fab2_lib.baseboard_fab2(sch_1):page149_i114:b"
				( attribute "PN" "2"
					( Origin gPackager )
				)
				( objectStatus "C25W51.2" )
			)
			( pin "@baseboard_fab2_lib.baseboard_fab2(sch_1):page149_i115:a"
				( attribute "PN" "1"
					( Origin gPackager )
				)
				( objectStatus "C25W71.1" )
			)
			( pin "@baseboard_fab2_lib.baseboard_fab2(sch_1):page149_i115:b"
				( attribute "PN" "2"
					( Origin gPackager )
				)
				( objectStatus "C25W71.2" )
			)
			( pin "@baseboard_fab2_lib.baseboard_fab2(sch_1):page149_i116:a"
				( attribute "PN" "1"
					( Origin gPackager )
				)
				( objectStatus "C25W66.1" )
			)
			( pin "@baseboard_fab2_lib.baseboard_fab2(sch_1):page149_i116:b"
				( attribute "PN" "2"
					( Origin gPackager )
				)
				( objectStatus "C25W66.2" )
			)
			( pin "@baseboard_fab2_lib.baseboard_fab2(sch_1):page149_i117:a"
				( attribute "PN" "1"
					( Origin gPackager )
				)
				( objectStatus "C25W67.1" )
			)
			( pin "@baseboard_fab2_lib.baseboard_fab2(sch_1):page149_i117:b"
				( attribute "PN" "2"
					( Origin gPackager )
				)
				( objectStatus "C25W67.2" )
			)
			( pin "@baseboard_fab2_lib.baseboard_fab2(sch_1):page149_i118:a"
				( attribute "PN" "1"
					( Origin gPackager )
				)
				( objectStatus "C25W52.1" )
			)
			( pin "@baseboard_fab2_lib.baseboard_fab2(sch_1):page149_i118:b"
				( attribute "PN" "2"
					( Origin gPackager )
				)
				( objectStatus "C25W52.2" )
			)
			( pin "@baseboard_fab2_lib.baseboard_fab2(sch_1):page176_i132:a"
				( attribute "PN" "1"
					( Origin gPackager )
				)
				( objectStatus "R1W10.1" )
			)
			( pin "@baseboard_fab2_lib.baseboard_fab2(sch_1):page176_i132:b"
				( attribute "PN" "2"
					( Origin gPackager )
				)
				( objectStatus "R1W10.2" )
			)
			( pin "@baseboard_fab2_lib.baseboard_fab2(sch_1):page176_i133:a"
				( attribute "PN" "1"
					( Origin gPackager )
				)
				( objectStatus "R1W11.1" )
			)
			( pin "@baseboard_fab2_lib.baseboard_fab2(sch_1):page176_i133:b"
				( attribute "PN" "2"
					( Origin gPackager )
				)
				( objectStatus "R1W11.2" )
			)
			( pin "@baseboard_fab2_lib.baseboard_fab2(sch_1):page176_i137:a"
				( attribute "PN" "1"
					( Origin gPackager )
				)
				( objectStatus "R1W12.1" )
			)
			( pin "@baseboard_fab2_lib.baseboard_fab2(sch_1):page176_i137:b"
				( attribute "PN" "2"
					( Origin gPackager )
				)
				( objectStatus "R1W12.2" )
			)
			( pin "@baseboard_fab2_lib.baseboard_fab2(sch_1):page176_i138:a"
				( attribute "PN" "1"
					( Origin gPackager )
				)
				( objectStatus "R1W13.1" )
			)
			( pin "@baseboard_fab2_lib.baseboard_fab2(sch_1):page176_i138:b"
				( attribute "PN" "2"
					( Origin gPackager )
				)
				( objectStatus "R1W13.2" )
			)
			( pin "@baseboard_fab2_lib.baseboard_fab2(sch_1):page249_i36:a"
				( attribute "PN" "1"
					( Origin gPackager )
				)
				( objectStatus "R3W3.1" )
			)
			( pin "@baseboard_fab2_lib.baseboard_fab2(sch_1):page249_i36:b"
				( attribute "PN" "2"
					( Origin gPackager )
				)
				( objectStatus "R3W3.2" )
			)
			( pin "@baseboard_fab2_lib.baseboard_fab2(sch_1):page251_i19:a"
				( attribute "PN" "2"
					( Origin gPackager )
				)
				( objectStatus "U10W1.2" )
			)
			( pin "@baseboard_fab2_lib.baseboard_fab2(sch_1):page251_i19:y"
				( attribute "PN" "4"
					( Origin gPackager )
				)
				( objectStatus "U10W1.4" )
			)
			( pin "@baseboard_fab2_lib.baseboard_fab2(sch_1):page251_i16:a"
				( attribute "PN" "1"
					( Origin gPackager )
				)
				( objectStatus "C10W3.1" )
			)
			( pin "@baseboard_fab2_lib.baseboard_fab2(sch_1):page251_i16:b"
				( attribute "PN" "2"
					( Origin gPackager )
				)
				( objectStatus "C10W3.2" )
			)
			( pin "@baseboard_fab2_lib.baseboard_fab2(sch_1):page251_i15:a"
				( attribute "PN" "1"
					( Origin gPackager )
				)
				( objectStatus "R10W2.1" )
			)
			( pin "@baseboard_fab2_lib.baseboard_fab2(sch_1):page251_i15:b"
				( attribute "PN" "2"
					( Origin gPackager )
				)
				( objectStatus "R10W2.2" )
			)
			( pin "@baseboard_fab2_lib.baseboard_fab2(sch_1):page251_i14:a"
				( attribute "PN" "1"
					( Origin gPackager )
				)
				( objectStatus "R10W4.1" )
			)
			( pin "@baseboard_fab2_lib.baseboard_fab2(sch_1):page251_i14:b"
				( attribute "PN" "2"
					( Origin gPackager )
				)
				( objectStatus "R10W4.2" )
			)
			( pin "@baseboard_fab2_lib.baseboard_fab2(sch_1):page251_i13:a"
				( attribute "PN" "1"
					( Origin gPackager )
				)
				( objectStatus "R10W1.1" )
			)
			( pin "@baseboard_fab2_lib.baseboard_fab2(sch_1):page251_i13:b"
				( attribute "PN" "2"
					( Origin gPackager )
				)
				( objectStatus "R10W1.2" )
			)
			( pin "@baseboard_fab2_lib.baseboard_fab2(sch_1):page251_i12:a"
				( attribute "PN" "2"
					( Origin gPackager )
				)
				( objectStatus "CR10W1.2" )
			)
			( pin "@baseboard_fab2_lib.baseboard_fab2(sch_1):page251_i12:c"
				( attribute "PN" "1"
					( Origin gPackager )
				)
				( objectStatus "CR10W1.1" )
			)
			( pin "@baseboard_fab2_lib.baseboard_fab2(sch_1):page251_i11:a"
				( attribute "PN" "1"
					( Origin gPackager )
				)
				( objectStatus "R10W3.1" )
			)
			( pin "@baseboard_fab2_lib.baseboard_fab2(sch_1):page251_i11:b"
				( attribute "PN" "2"
					( Origin gPackager )
				)
				( objectStatus "R10W3.2" )
			)
			( pin "@baseboard_fab2_lib.baseboard_fab2(sch_1):page251_i5:a"
				( attribute "PN" "1"
					( Origin gPackager )
				)
				( objectStatus "R10W5.1" )
			)
			( pin "@baseboard_fab2_lib.baseboard_fab2(sch_1):page251_i5:b"
				( attribute "PN" "2"
					( Origin gPackager )
				)
				( objectStatus "R10W5.2" )
			)
			( pin "@baseboard_fab2_lib.baseboard_fab2(sch_1):page251_i3:a"
				( attribute "PN" "1"
					( Origin gPackager )
				)
				( objectStatus "C10W1.1" )
			)
			( pin "@baseboard_fab2_lib.baseboard_fab2(sch_1):page251_i3:b"
				( attribute "PN" "2"
					( Origin gPackager )
				)
				( objectStatus "C10W1.2" )
			)
			( pin "@baseboard_fab2_lib.baseboard_fab2(sch_1):page251_i1:a"
				( attribute "PN" "1"
					( Origin gPackager )
				)
				( objectStatus "C10W2.1" )
			)
			( pin "@baseboard_fab2_lib.baseboard_fab2(sch_1):page251_i1:b"
				( attribute "PN" "2"
					( Origin gPackager )
				)
				( objectStatus "C10W2.2" )
			)
			( pin "@baseboard_fab2_lib.baseboard_fab2(sch_1):page157_i390:\1a\"
				( attribute "PN" "1"
					( Origin gPackager )
				)
				( objectStatus "U2R1.1" )
			)
			( pin "@baseboard_fab2_lib.baseboard_fab2(sch_1):page157_i390:\1y\"
				( attribute "PN" "6"
					( Origin gPackager )
				)
				( objectStatus "U2R1.6" )
			)
			( pin "@baseboard_fab2_lib.baseboard_fab2(sch_1):page157_i390:\2a\"
				( attribute "PN" "3"
					( Origin gPackager )
				)
				( objectStatus "U2R1.3" )
			)
			( pin "@baseboard_fab2_lib.baseboard_fab2(sch_1):page157_i390:\2y\"
				( attribute "PN" "4"
					( Origin gPackager )
				)
				( objectStatus "U2R1.4" )
			)
			( pin "@baseboard_fab2_lib.baseboard_fab2(sch_1):page157_i390:gnd"
				( attribute "PN" "2"
					( Origin gPackager )
				)
				( objectStatus "U2R1.2" )
			)
			( pin "@baseboard_fab2_lib.baseboard_fab2(sch_1):page157_i390:vcc"
				( attribute "PN" "5"
					( Origin gPackager )
				)
				( objectStatus "U2R1.5" )
			)
			( pin "@baseboard_fab2_lib.baseboard_fab2(sch_1):page157_i391:a"
				( attribute "PN" "1"
					( Origin gPackager )
				)
				( objectStatus "R2R10.1" )
			)
			( pin "@baseboard_fab2_lib.baseboard_fab2(sch_1):page157_i391:b"
				( attribute "PN" "2"
					( Origin gPackager )
				)
				( objectStatus "R2R10.2" )
			)
			( pin "@baseboard_fab2_lib.baseboard_fab2(sch_1):page175_i95:a"
				( attribute "PN" "1"
					( Origin gPackager )
				)
				( objectStatus "R9A9.1" )
			)
			( pin "@baseboard_fab2_lib.baseboard_fab2(sch_1):page175_i95:b"
				( attribute "PN" "2"
					( Origin gPackager )
				)
				( objectStatus "R9A9.2" )
			)
			( pin "@baseboard_fab2_lib.baseboard_fab2(sch_1):page175_i97:\1a\"
				( attribute "PN" "1"
					( Origin gPackager )
				)
				( objectStatus "U9A4.1" )
			)
			( pin "@baseboard_fab2_lib.baseboard_fab2(sch_1):page175_i97:\1y\"
				( attribute "PN" "6"
					( Origin gPackager )
				)
				( objectStatus "U9A4.6" )
			)
			( pin "@baseboard_fab2_lib.baseboard_fab2(sch_1):page175_i97:\2a\"
				( attribute "PN" "3"
					( Origin gPackager )
				)
				( objectStatus "U9A4.3" )
			)
			( pin "@baseboard_fab2_lib.baseboard_fab2(sch_1):page175_i97:\2y\"
				( attribute "PN" "4"
					( Origin gPackager )
				)
				( objectStatus "U9A4.4" )
			)
			( pin "@baseboard_fab2_lib.baseboard_fab2(sch_1):page175_i97:gnd"
				( attribute "PN" "2"
					( Origin gPackager )
				)
				( objectStatus "U9A4.2" )
			)
			( pin "@baseboard_fab2_lib.baseboard_fab2(sch_1):page175_i97:vcc"
				( attribute "PN" "5"
					( Origin gPackager )
				)
				( objectStatus "U9A4.5" )
			)
			( pin "@baseboard_fab2_lib.baseboard_fab2(sch_1):page164_i40:a"
				( attribute "PN" "1"
					( Origin gPackager )
				)
				( objectStatus "R1U18.1" )
			)
			( pin "@baseboard_fab2_lib.baseboard_fab2(sch_1):page164_i40:b"
				( attribute "PN" "2"
					( Origin gPackager )
				)
				( objectStatus "R1U18.2" )
			)
			( pin "@baseboard_fab2_lib.baseboard_fab2(sch_1):page156_i340:\1a\"
				( attribute "PN" "1"
					( Origin gPackager )
				)
				( objectStatus "U8F3.1" )
			)
			( pin "@baseboard_fab2_lib.baseboard_fab2(sch_1):page156_i340:\1y\"
				( attribute "PN" "6"
					( Origin gPackager )
				)
				( objectStatus "U8F3.6" )
			)
			( pin "@baseboard_fab2_lib.baseboard_fab2(sch_1):page156_i340:\2a\"
				( attribute "PN" "3"
					( Origin gPackager )
				)
				( objectStatus "U8F3.3" )
			)
			( pin "@baseboard_fab2_lib.baseboard_fab2(sch_1):page156_i340:\2y\"
				( attribute "PN" "4"
					( Origin gPackager )
				)
				( objectStatus "U8F3.4" )
			)
			( pin "@baseboard_fab2_lib.baseboard_fab2(sch_1):page156_i340:gnd"
				( attribute "PN" "2"
					( Origin gPackager )
				)
				( objectStatus "U8F3.2" )
			)
			( pin "@baseboard_fab2_lib.baseboard_fab2(sch_1):page156_i340:vcc"
				( attribute "PN" "5"
					( Origin gPackager )
				)
				( objectStatus "U8F3.5" )
			)
			( pin "@baseboard_fab2_lib.baseboard_fab2(sch_1):page156_i342:\1a\"
				( attribute "PN" "1"
					( Origin gPackager )
				)
				( objectStatus "U8G1.1" )
			)
			( pin "@baseboard_fab2_lib.baseboard_fab2(sch_1):page156_i342:\1y\"
				( attribute "PN" "6"
					( Origin gPackager )
				)
				( objectStatus "U8G1.6" )
			)
			( pin "@baseboard_fab2_lib.baseboard_fab2(sch_1):page156_i342:\2a\"
				( attribute "PN" "3"
					( Origin gPackager )
				)
				( objectStatus "U8G1.3" )
			)
			( pin "@baseboard_fab2_lib.baseboard_fab2(sch_1):page156_i342:\2y\"
				( attribute "PN" "4"
					( Origin gPackager )
				)
				( objectStatus "U8G1.4" )
			)
			( pin "@baseboard_fab2_lib.baseboard_fab2(sch_1):page156_i342:gnd"
				( attribute "PN" "2"
					( Origin gPackager )
				)
				( objectStatus "U8G1.2" )
			)
			( pin "@baseboard_fab2_lib.baseboard_fab2(sch_1):page156_i342:vcc"
				( attribute "PN" "5"
					( Origin gPackager )
				)
				( objectStatus "U8G1.5" )
			)
			( pin "@baseboard_fab2_lib.baseboard_fab2(sch_1):page149_i130:a"
				( attribute "PN" "1"
					( Origin gPackager )
				)
				( objectStatus "C25W57.1" )
			)
			( pin "@baseboard_fab2_lib.baseboard_fab2(sch_1):page149_i130:b"
				( attribute "PN" "2"
					( Origin gPackager )
				)
				( objectStatus "C25W57.2" )
			)
			( pin "@baseboard_fab2_lib.baseboard_fab2(sch_1):page151_i209:a"
				( attribute "PN" "1"
					( Origin gPackager )
				)
				( objectStatus "R9F34.1" )
			)
			( pin "@baseboard_fab2_lib.baseboard_fab2(sch_1):page151_i209:b"
				( attribute "PN" "2"
					( Origin gPackager )
				)
				( objectStatus "R9F34.2" )
			)
			( pin "@baseboard_fab2_lib.baseboard_fab2(sch_1):page251_i21:a"
				( attribute "PN" "1"
					( Origin gPackager )
				)
				( objectStatus "C10W4.1" )
			)
			( pin "@baseboard_fab2_lib.baseboard_fab2(sch_1):page251_i21:b"
				( attribute "PN" "2"
					( Origin gPackager )
				)
				( objectStatus "C10W4.2" )
			)
			( pin "@baseboard_fab2_lib.baseboard_fab2(sch_1):page115_i118:a"
				( attribute "PN" "1"
					( Origin gPackager )
				)
				( objectStatus "R1W14.1" )
			)
			( pin "@baseboard_fab2_lib.baseboard_fab2(sch_1):page115_i118:b"
				( attribute "PN" "2"
					( Origin gPackager )
				)
				( objectStatus "R1W14.2" )
			)
			( pin "@baseboard_fab2_lib.baseboard_fab2(sch_1):page115_i119:a"
				( attribute "PN" "1"
					( Origin gPackager )
				)
				( objectStatus "R1W15.1" )
			)
			( pin "@baseboard_fab2_lib.baseboard_fab2(sch_1):page115_i119:b"
				( attribute "PN" "2"
					( Origin gPackager )
				)
				( objectStatus "R1W15.2" )
			)
			( pin "@baseboard_fab2_lib.baseboard_fab2(sch_1):page115_i120:a"
				( attribute "PN" "1"
					( Origin gPackager )
				)
				( objectStatus "R1W17.1" )
			)
			( pin "@baseboard_fab2_lib.baseboard_fab2(sch_1):page115_i120:b"
				( attribute "PN" "2"
					( Origin gPackager )
				)
				( objectStatus "R1W17.2" )
			)
			( pin "@baseboard_fab2_lib.baseboard_fab2(sch_1):page115_i121:a"
				( attribute "PN" "1"
					( Origin gPackager )
				)
				( objectStatus "R1W16.1" )
			)
			( pin "@baseboard_fab2_lib.baseboard_fab2(sch_1):page115_i121:b"
				( attribute "PN" "2"
					( Origin gPackager )
				)
				( objectStatus "R1W16.2" )
			)
			( pin "@baseboard_fab2_lib.baseboard_fab2(sch_1):page115_i122:a"
				( attribute "PN" "1"
					( Origin gPackager )
				)
				( objectStatus "R1W19.1" )
			)
			( pin "@baseboard_fab2_lib.baseboard_fab2(sch_1):page115_i122:b"
				( attribute "PN" "2"
					( Origin gPackager )
				)
				( objectStatus "R1W19.2" )
			)
			( pin "@baseboard_fab2_lib.baseboard_fab2(sch_1):page115_i123:a"
				( attribute "PN" "1"
					( Origin gPackager )
				)
				( objectStatus "R1W18.1" )
			)
			( pin "@baseboard_fab2_lib.baseboard_fab2(sch_1):page115_i123:b"
				( attribute "PN" "2"
					( Origin gPackager )
				)
				( objectStatus "R1W18.2" )
			)
			( pin "@baseboard_fab2_lib.baseboard_fab2(sch_1):page144_i139:a"
				( attribute "PN" "1"
					( Origin gPackager )
				)
				( objectStatus "R25W123.1" )
			)
			( pin "@baseboard_fab2_lib.baseboard_fab2(sch_1):page144_i139:b"
				( attribute "PN" "2"
					( Origin gPackager )
				)
				( objectStatus "R25W123.2" )
			)
			( pin "@baseboard_fab2_lib.baseboard_fab2(sch_1):page144_i140:a"
				( attribute "PN" "1"
					( Origin gPackager )
				)
				( objectStatus "R25W124.1" )
			)
			( pin "@baseboard_fab2_lib.baseboard_fab2(sch_1):page144_i140:b"
				( attribute "PN" "2"
					( Origin gPackager )
				)
				( objectStatus "R25W124.2" )
			)
			( pin "@baseboard_fab2_lib.baseboard_fab2(sch_1):page144_i141:a"
				( attribute "PN" "1"
					( Origin gPackager )
				)
				( objectStatus "R25W125.1" )
			)
			( pin "@baseboard_fab2_lib.baseboard_fab2(sch_1):page144_i141:b"
				( attribute "PN" "2"
					( Origin gPackager )
				)
				( objectStatus "R25W125.2" )
			)
			( pin "@baseboard_fab2_lib.baseboard_fab2(sch_1):page255_i7:a"
				( attribute "PN" "1"
					( Origin gPackager )
				)
				( objectStatus "C25W72.1" )
			)
			( pin "@baseboard_fab2_lib.baseboard_fab2(sch_1):page255_i7:b"
				( attribute "PN" "2"
					( Origin gPackager )
				)
				( objectStatus "C25W72.2" )
			)
			( pin "@baseboard_fab2_lib.baseboard_fab2(sch_1):page255_i11:a"
				( attribute "PN" "1"
					( Origin gPackager )
				)
				( objectStatus "C25W73.1" )
			)
			( pin "@baseboard_fab2_lib.baseboard_fab2(sch_1):page255_i11:b"
				( attribute "PN" "2"
					( Origin gPackager )
				)
				( objectStatus "C25W73.2" )
			)
			( pin "@baseboard_fab2_lib.baseboard_fab2(sch_1):page255_i12:a"
				( attribute "PN" "1"
					( Origin gPackager )
				)
				( objectStatus "C25W74.1" )
			)
			( pin "@baseboard_fab2_lib.baseboard_fab2(sch_1):page255_i12:b"
				( attribute "PN" "2"
					( Origin gPackager )
				)
				( objectStatus "C25W74.2" )
			)
			( pin "@baseboard_fab2_lib.baseboard_fab2(sch_1):page255_i16:a"
				( attribute "PN" "1"
					( Origin gPackager )
				)
				( objectStatus "C25W77.1" )
			)
			( pin "@baseboard_fab2_lib.baseboard_fab2(sch_1):page255_i16:b"
				( attribute "PN" "2"
					( Origin gPackager )
				)
				( objectStatus "C25W77.2" )
			)
			( pin "@baseboard_fab2_lib.baseboard_fab2(sch_1):page255_i18:a"
				( attribute "PN" "1"
					( Origin gPackager )
				)
				( objectStatus "C25W76.1" )
			)
			( pin "@baseboard_fab2_lib.baseboard_fab2(sch_1):page255_i18:b"
				( attribute "PN" "2"
					( Origin gPackager )
				)
				( objectStatus "C25W76.2" )
			)
			( pin "@baseboard_fab2_lib.baseboard_fab2(sch_1):page255_i21:a"
				( attribute "PN" "1"
					( Origin gPackager )
				)
				( objectStatus "C25W75.1" )
			)
			( pin "@baseboard_fab2_lib.baseboard_fab2(sch_1):page255_i21:b"
				( attribute "PN" "2"
					( Origin gPackager )
				)
				( objectStatus "C25W75.2" )
			)
			( pin "@baseboard_fab2_lib.baseboard_fab2(sch_1):page255_i22:a"
				( attribute "PN" "1"
					( Origin gPackager )
				)
				( objectStatus "R25W128.1" )
			)
			( pin "@baseboard_fab2_lib.baseboard_fab2(sch_1):page255_i22:b"
				( attribute "PN" "2"
					( Origin gPackager )
				)
				( objectStatus "R25W128.2" )
			)
			( pin "@baseboard_fab2_lib.baseboard_fab2(sch_1):page255_i24:a"
				( attribute "PN" "1"
					( Origin gPackager )
				)
				( objectStatus "R25W127.1" )
			)
			( pin "@baseboard_fab2_lib.baseboard_fab2(sch_1):page255_i24:b"
				( attribute "PN" "2"
					( Origin gPackager )
				)
				( objectStatus "R25W127.2" )
			)
			( pin "@baseboard_fab2_lib.baseboard_fab2(sch_1):page255_i26:a"
				( attribute "PN" "1"
					( Origin gPackager )
				)
				( objectStatus "R25W126.1" )
			)
			( pin "@baseboard_fab2_lib.baseboard_fab2(sch_1):page255_i26:b"
				( attribute "PN" "2"
					( Origin gPackager )
				)
				( objectStatus "R25W126.2" )
			)
			( pin "@baseboard_fab2_lib.baseboard_fab2(sch_1):page146_i152:a"
				( attribute "PN" "1"
					( Origin gPackager )
				)
				( objectStatus "R25W129.1" )
			)
			( pin "@baseboard_fab2_lib.baseboard_fab2(sch_1):page146_i152:b"
				( attribute "PN" "2"
					( Origin gPackager )
				)
				( objectStatus "R25W129.2" )
			)
			( pin "@baseboard_fab2_lib.baseboard_fab2(sch_1):page146_i153:a"
				( attribute "PN" "1"
					( Origin gPackager )
				)
				( objectStatus "R25W130.1" )
			)
			( pin "@baseboard_fab2_lib.baseboard_fab2(sch_1):page146_i153:b"
				( attribute "PN" "2"
					( Origin gPackager )
				)
				( objectStatus "R25W130.2" )
			)
			( pin "@baseboard_fab2_lib.baseboard_fab2(sch_1):page255_i30:a"
				( attribute "PN" "1"
					( Origin gPackager )
				)
				( objectStatus "R25W131.1" )
			)
			( pin "@baseboard_fab2_lib.baseboard_fab2(sch_1):page255_i30:b"
				( attribute "PN" "2"
					( Origin gPackager )
				)
				( objectStatus "R25W131.2" )
			)
			( pin "@baseboard_fab2_lib.baseboard_fab2(sch_1):page255_i31:a"
				( attribute "PN" "1"
					( Origin gPackager )
				)
				( objectStatus "R25W132.1" )
			)
			( pin "@baseboard_fab2_lib.baseboard_fab2(sch_1):page255_i31:b"
				( attribute "PN" "2"
					( Origin gPackager )
				)
				( objectStatus "R25W132.2" )
			)
			( pin "@baseboard_fab2_lib.baseboard_fab2(sch_1):page255_i34:a"
				( attribute "PN" "1"
					( Origin gPackager )
				)
				( objectStatus "R25W133.1" )
			)
			( pin "@baseboard_fab2_lib.baseboard_fab2(sch_1):page255_i34:b"
				( attribute "PN" "2"
					( Origin gPackager )
				)
				( objectStatus "R25W133.2" )
			)
			( pin "@baseboard_fab2_lib.baseboard_fab2(sch_1):page255_i35:a"
				( attribute "PN" "1"
					( Origin gPackager )
				)
				( objectStatus "C25W78.1" )
			)
			( pin "@baseboard_fab2_lib.baseboard_fab2(sch_1):page255_i35:b"
				( attribute "PN" "2"
					( Origin gPackager )
				)
				( objectStatus "C25W78.2" )
			)
			( pin "@baseboard_fab2_lib.baseboard_fab2(sch_1):page255_i38:a"
				( attribute "PN" "1"
					( Origin gPackager )
				)
				( objectStatus "R25W136.1" )
			)
			( pin "@baseboard_fab2_lib.baseboard_fab2(sch_1):page255_i38:b"
				( attribute "PN" "2"
					( Origin gPackager )
				)
				( objectStatus "R25W136.2" )
			)
			( pin "@baseboard_fab2_lib.baseboard_fab2(sch_1):page255_i39:a"
				( attribute "PN" "1"
					( Origin gPackager )
				)
				( objectStatus "C25W79.1" )
			)
			( pin "@baseboard_fab2_lib.baseboard_fab2(sch_1):page255_i39:b"
				( attribute "PN" "2"
					( Origin gPackager )
				)
				( objectStatus "C25W79.2" )
			)
			( pin "@baseboard_fab2_lib.baseboard_fab2(sch_1):page255_i43:a"
				( attribute "PN" "1"
					( Origin gPackager )
				)
				( objectStatus "R25W134.1" )
			)
			( pin "@baseboard_fab2_lib.baseboard_fab2(sch_1):page255_i43:b"
				( attribute "PN" "2"
					( Origin gPackager )
				)
				( objectStatus "R25W134.2" )
			)
			( pin "@baseboard_fab2_lib.baseboard_fab2(sch_1):page255_i44:a"
				( attribute "PN" "1"
					( Origin gPackager )
				)
				( objectStatus "R25W135.1" )
			)
			( pin "@baseboard_fab2_lib.baseboard_fab2(sch_1):page255_i44:b"
				( attribute "PN" "2"
					( Origin gPackager )
				)
				( objectStatus "R25W135.2" )
			)
			( pin "@baseboard_fab2_lib.baseboard_fab2(sch_1):page168_i48:a"
				( attribute "PN" "1"
					( Origin gPackager )
				)
				( objectStatus "R6W49.1" )
			)
			( pin "@baseboard_fab2_lib.baseboard_fab2(sch_1):page168_i48:b"
				( attribute "PN" "2"
					( Origin gPackager )
				)
				( objectStatus "R6W49.2" )
			)
			( pin "@baseboard_fab2_lib.baseboard_fab2(sch_1):page200_i243:a"
				( attribute "PN" "1"
					( Origin gPackager )
				)
				( objectStatus "R9P15.1" )
			)
			( pin "@baseboard_fab2_lib.baseboard_fab2(sch_1):page200_i243:b"
				( attribute "PN" "2"
					( Origin gPackager )
				)
				( objectStatus "R9P15.2" )
			)
			( pin "@baseboard_fab2_lib.baseboard_fab2(sch_1):page200_i244:a"
				( attribute "PN" "1"
					( Origin gPackager )
				)
				( objectStatus "R1D10.1" )
			)
			( pin "@baseboard_fab2_lib.baseboard_fab2(sch_1):page200_i244:b"
				( attribute "PN" "2"
					( Origin gPackager )
				)
				( objectStatus "R1D10.2" )
			)
			( pin "@baseboard_fab2_lib.baseboard_fab2(sch_1):page141_i129:\1\"
				( attribute "PN" "1"
					( Origin gPackager )
				)
				( objectStatus "JA9G1.1" )
			)
			( pin "@baseboard_fab2_lib.baseboard_fab2(sch_1):page141_i129:\2\"
				( attribute "PN" "2"
					( Origin gPackager )
				)
				( objectStatus "JA9G1.2" )
			)
			( pin "@baseboard_fab2_lib.baseboard_fab2(sch_1):page141_i129:l1"
				( attribute "PN" "L1"
					( Origin gPackager )
				)
				( objectStatus "JA9G1.L1" )
			)
			( pin "@baseboard_fab2_lib.baseboard_fab2(sch_1):page141_i129:l2"
				( attribute "PN" "L2"
					( Origin gPackager )
				)
				( objectStatus "JA9G1.L2" )
			)
			( pin "@baseboard_fab2_lib.baseboard_fab2(sch_1):page141_i129:l3"
				( attribute "PN" "L3"
					( Origin gPackager )
				)
				( objectStatus "JA9G1.L3" )
			)
			( pin "@baseboard_fab2_lib.baseboard_fab2(sch_1):page141_i129:l4"
				( attribute "PN" "L4"
					( Origin gPackager )
				)
				( objectStatus "JA9G1.L4" )
			)
			( pin "@baseboard_fab2_lib.baseboard_fab2(sch_1):page141_i129:r1"
				( attribute "PN" "R1"
					( Origin gPackager )
				)
				( objectStatus "JA9G1.R1" )
			)
			( pin "@baseboard_fab2_lib.baseboard_fab2(sch_1):page141_i129:r2"
				( attribute "PN" "R2"
					( Origin gPackager )
				)
				( objectStatus "JA9G1.R2" )
			)
			( pin "@baseboard_fab2_lib.baseboard_fab2(sch_1):page141_i129:r3"
				( attribute "PN" "R3"
					( Origin gPackager )
				)
				( objectStatus "JA9G1.R3" )
			)
			( pin "@baseboard_fab2_lib.baseboard_fab2(sch_1):page141_i129:r4"
				( attribute "PN" "R4"
					( Origin gPackager )
				)
				( objectStatus "JA9G1.R4" )
			)
			( pin "@baseboard_fab2_lib.baseboard_fab2(sch_1):page141_i129:r5"
				( attribute "PN" "R5"
					( Origin gPackager )
				)
				( objectStatus "JA9G1.R5" )
			)
			( pin "@baseboard_fab2_lib.baseboard_fab2(sch_1):page141_i129:r6"
				( attribute "PN" "R6"
					( Origin gPackager )
				)
				( objectStatus "JA9G1.R6" )
			)
			( pin "@baseboard_fab2_lib.baseboard_fab2(sch_1):page141_i129:r7"
				( attribute "PN" "R7"
					( Origin gPackager )
				)
				( objectStatus "JA9G1.R7" )
			)
			( pin "@baseboard_fab2_lib.baseboard_fab2(sch_1):page141_i129:r8"
				( attribute "PN" "R8"
					( Origin gPackager )
				)
				( objectStatus "JA9G1.R8" )
			)
			( pin "@baseboard_fab2_lib.baseboard_fab2(sch_1):page141_i129:r9"
				( attribute "PN" "R9"
					( Origin gPackager )
				)
				( objectStatus "JA9G1.R9" )
			)
			( pin "@baseboard_fab2_lib.baseboard_fab2(sch_1):page141_i129:r10"
				( attribute "PN" "R10"
					( Origin gPackager )
				)
				( objectStatus "JA9G1.R10" )
			)
			( pin "@baseboard_fab2_lib.baseboard_fab2(sch_1):page141_i129:r11"
				( attribute "PN" "R11"
					( Origin gPackager )
				)
				( objectStatus "JA9G1.R11" )
			)
			( pin "@baseboard_fab2_lib.baseboard_fab2(sch_1):page172_i66:a(0)"
				( attribute "PN" "1"
					( Origin gPackager )
				)
				( objectStatus "F9B1.1" )
			)
			( pin "@baseboard_fab2_lib.baseboard_fab2(sch_1):page172_i66:b(0)"
				( attribute "PN" "2"
					( Origin gPackager )
				)
				( objectStatus "F9B1.2" )
			)
			( pin "@baseboard_fab2_lib.baseboard_fab2(sch_1):page255_i49:a"
				( attribute "PN" "1"
					( Origin gPackager )
				)
				( objectStatus "R25W138.1" )
			)
			( pin "@baseboard_fab2_lib.baseboard_fab2(sch_1):page255_i49:b"
				( attribute "PN" "2"
					( Origin gPackager )
				)
				( objectStatus "R25W138.2" )
			)
			( pin "@baseboard_fab2_lib.baseboard_fab2(sch_1):page255_i60:a"
				( attribute "PN" "1"
					( Origin gPackager )
				)
				( objectStatus "C25W81.1" )
			)
			( pin "@baseboard_fab2_lib.baseboard_fab2(sch_1):page255_i60:b"
				( attribute "PN" "2"
					( Origin gPackager )
				)
				( objectStatus "C25W81.2" )
			)
			( pin "@baseboard_fab2_lib.baseboard_fab2(sch_1):page255_i59:a"
				( attribute "PN" "1"
					( Origin gPackager )
				)
				( objectStatus "R25W139.1" )
			)
			( pin "@baseboard_fab2_lib.baseboard_fab2(sch_1):page255_i59:b"
				( attribute "PN" "2"
					( Origin gPackager )
				)
				( objectStatus "R25W139.2" )
			)
			( pin "@baseboard_fab2_lib.baseboard_fab2(sch_1):page255_i62:a"
				( attribute "PN" "1"
					( Origin gPackager )
				)
				( objectStatus "C25W82.1" )
			)
			( pin "@baseboard_fab2_lib.baseboard_fab2(sch_1):page255_i62:b"
				( attribute "PN" "2"
					( Origin gPackager )
				)
				( objectStatus "C25W82.2" )
			)
			( pin "@baseboard_fab2_lib.baseboard_fab2(sch_1):page255_i74:a"
				( attribute "PN" "1"
					( Origin gPackager )
				)
				( objectStatus "C25P83.1" )
			)
			( pin "@baseboard_fab2_lib.baseboard_fab2(sch_1):page255_i74:b"
				( attribute "PN" "2"
					( Origin gPackager )
				)
				( objectStatus "C25P83.2" )
			)
			( pin "@baseboard_fab2_lib.baseboard_fab2(sch_1):page255_i76:\1\"
				( attribute "PN" "1"
					( Origin gPackager )
				)
				( objectStatus "L25W1.1" )
			)
			( pin "@baseboard_fab2_lib.baseboard_fab2(sch_1):page255_i76:\2\"
				( attribute "PN" "2"
					( Origin gPackager )
				)
				( objectStatus "L25W1.2" )
			)
			( pin "@baseboard_fab2_lib.baseboard_fab2(sch_1):page255_i77:\1\"
				( attribute "PN" "1"
					( Origin gPackager )
				)
				( objectStatus "L25W2.1" )
			)
			( pin "@baseboard_fab2_lib.baseboard_fab2(sch_1):page255_i77:\2\"
				( attribute "PN" "2"
					( Origin gPackager )
				)
				( objectStatus "L25W2.2" )
			)
			( pin "@baseboard_fab2_lib.baseboard_fab2(sch_1):page255_i78:\1\"
				( attribute "PN" "1"
					( Origin gPackager )
				)
				( objectStatus "L25W3.1" )
			)
			( pin "@baseboard_fab2_lib.baseboard_fab2(sch_1):page255_i78:\2\"
				( attribute "PN" "2"
					( Origin gPackager )
				)
				( objectStatus "L25W3.2" )
			)
			( pin "@baseboard_fab2_lib.baseboard_fab2(sch_1):page163_i28:en"
				( attribute "PN" "5"
					( Origin gPackager )
				)
				( objectStatus "U1B2.5" )
			)
			( pin "@baseboard_fab2_lib.baseboard_fab2(sch_1):page163_i28:gnd"
				( attribute "PN" "4"
					( Origin gPackager )
				)
				( objectStatus "U1B2.4" )
			)
			( pin "@baseboard_fab2_lib.baseboard_fab2(sch_1):page163_i28:scla"
				( attribute "PN" "2"
					( Origin gPackager )
				)
				( objectStatus "U1B2.2" )
			)
			( pin "@baseboard_fab2_lib.baseboard_fab2(sch_1):page163_i28:sclb"
				( attribute "PN" "7"
					( Origin gPackager )
				)
				( objectStatus "U1B2.7" )
			)
			( pin "@baseboard_fab2_lib.baseboard_fab2(sch_1):page163_i28:sdaa"
				( attribute "PN" "3"
					( Origin gPackager )
				)
				( objectStatus "U1B2.3" )
			)
			( pin "@baseboard_fab2_lib.baseboard_fab2(sch_1):page163_i28:sdab"
				( attribute "PN" "6"
					( Origin gPackager )
				)
				( objectStatus "U1B2.6" )
			)
			( pin "@baseboard_fab2_lib.baseboard_fab2(sch_1):page163_i28:vcca"
				( attribute "PN" "1"
					( Origin gPackager )
				)
				( objectStatus "U1B2.1" )
			)
			( pin "@baseboard_fab2_lib.baseboard_fab2(sch_1):page163_i28:vccb"
				( attribute "PN" "8"
					( Origin gPackager )
				)
				( objectStatus "U1B2.8" )
			)
			( pin "@baseboard_fab2_lib.baseboard_fab2(sch_1):page247_i118:en"
				( attribute "PN" "5"
					( Origin gPackager )
				)
				( objectStatus "U6W2.5" )
			)
			( pin "@baseboard_fab2_lib.baseboard_fab2(sch_1):page247_i118:gnd"
				( attribute "PN" "4"
					( Origin gPackager )
				)
				( objectStatus "U6W2.4" )
			)
			( pin "@baseboard_fab2_lib.baseboard_fab2(sch_1):page247_i118:scla"
				( attribute "PN" "2"
					( Origin gPackager )
				)
				( objectStatus "U6W2.2" )
			)
			( pin "@baseboard_fab2_lib.baseboard_fab2(sch_1):page247_i118:sclb"
				( attribute "PN" "7"
					( Origin gPackager )
				)
				( objectStatus "U6W2.7" )
			)
			( pin "@baseboard_fab2_lib.baseboard_fab2(sch_1):page247_i118:sdaa"
				( attribute "PN" "3"
					( Origin gPackager )
				)
				( objectStatus "U6W2.3" )
			)
			( pin "@baseboard_fab2_lib.baseboard_fab2(sch_1):page247_i118:sdab"
				( attribute "PN" "6"
					( Origin gPackager )
				)
				( objectStatus "U6W2.6" )
			)
			( pin "@baseboard_fab2_lib.baseboard_fab2(sch_1):page247_i118:vcca"
				( attribute "PN" "1"
					( Origin gPackager )
				)
				( objectStatus "U6W2.1" )
			)
			( pin "@baseboard_fab2_lib.baseboard_fab2(sch_1):page247_i118:vccb"
				( attribute "PN" "8"
					( Origin gPackager )
				)
				( objectStatus "U6W2.8" )
			)
			( pin "@baseboard_fab2_lib.baseboard_fab2(sch_1):page248_i49:en"
				( attribute "PN" "5"
					( Origin gPackager )
				)
				( objectStatus "U1W2.5" )
			)
			( pin "@baseboard_fab2_lib.baseboard_fab2(sch_1):page248_i49:gnd"
				( attribute "PN" "4"
					( Origin gPackager )
				)
				( objectStatus "U1W2.4" )
			)
			( pin "@baseboard_fab2_lib.baseboard_fab2(sch_1):page248_i49:scla"
				( attribute "PN" "2"
					( Origin gPackager )
				)
				( objectStatus "U1W2.2" )
			)
			( pin "@baseboard_fab2_lib.baseboard_fab2(sch_1):page248_i49:sclb"
				( attribute "PN" "7"
					( Origin gPackager )
				)
				( objectStatus "U1W2.7" )
			)
			( pin "@baseboard_fab2_lib.baseboard_fab2(sch_1):page248_i49:sdaa"
				( attribute "PN" "3"
					( Origin gPackager )
				)
				( objectStatus "U1W2.3" )
			)
			( pin "@baseboard_fab2_lib.baseboard_fab2(sch_1):page248_i49:sdab"
				( attribute "PN" "6"
					( Origin gPackager )
				)
				( objectStatus "U1W2.6" )
			)
			( pin "@baseboard_fab2_lib.baseboard_fab2(sch_1):page248_i49:vcca"
				( attribute "PN" "1"
					( Origin gPackager )
				)
				( objectStatus "U1W2.1" )
			)
			( pin "@baseboard_fab2_lib.baseboard_fab2(sch_1):page248_i49:vccb"
				( attribute "PN" "8"
					( Origin gPackager )
				)
				( objectStatus "U1W2.8" )
			)
			( pin "@baseboard_fab2_lib.baseboard_fab2(sch_1):page116_i238:a"
				( attribute "PN" "1"
					( Origin gPackager )
				)
				( objectStatus "C2M4.1" )
			)
			( pin "@baseboard_fab2_lib.baseboard_fab2(sch_1):page116_i238:b"
				( attribute "PN" "2"
					( Origin gPackager )
				)
				( objectStatus "C2M4.2" )
			)
			( pin "@baseboard_fab2_lib.baseboard_fab2(sch_1):page116_i239:a"
				( attribute "PN" "1"
					( Origin gPackager )
				)
				( objectStatus "C2M3.1" )
			)
			( pin "@baseboard_fab2_lib.baseboard_fab2(sch_1):page116_i239:b"
				( attribute "PN" "2"
					( Origin gPackager )
				)
				( objectStatus "C2M3.2" )
			)
			( pin "@baseboard_fab2_lib.baseboard_fab2(sch_1):page114_i191:a"
				( attribute "PN" "1"
					( Origin gPackager )
				)
				( objectStatus "R7C4.1" )
			)
			( pin "@baseboard_fab2_lib.baseboard_fab2(sch_1):page114_i191:b"
				( attribute "PN" "2"
					( Origin gPackager )
				)
				( objectStatus "R7C4.2" )
			)
			( pin "@baseboard_fab2_lib.baseboard_fab2(sch_1):page114_i192:a"
				( attribute "PN" "1"
					( Origin gPackager )
				)
				( objectStatus "R7C2.1" )
			)
			( pin "@baseboard_fab2_lib.baseboard_fab2(sch_1):page114_i192:b"
				( attribute "PN" "2"
					( Origin gPackager )
				)
				( objectStatus "R7C2.2" )
			)
			( pin "@baseboard_fab2_lib.baseboard_fab2(sch_1):page125_i85:a"
				( attribute "PN" "1"
					( Origin gPackager )
				)
				( objectStatus "R8D16.1" )
			)
			( pin "@baseboard_fab2_lib.baseboard_fab2(sch_1):page125_i85:b"
				( attribute "PN" "2"
					( Origin gPackager )
				)
				( objectStatus "R8D16.2" )
			)
			( pin "@baseboard_fab2_lib.baseboard_fab2(sch_1):page125_i86:a"
				( attribute "PN" "1"
					( Origin gPackager )
				)
				( objectStatus "R7D1.1" )
			)
			( pin "@baseboard_fab2_lib.baseboard_fab2(sch_1):page125_i86:b"
				( attribute "PN" "2"
					( Origin gPackager )
				)
				( objectStatus "R7D1.2" )
			)
			( pin "@baseboard_fab2_lib.baseboard_fab2(sch_1):page203_i135:\1\"
				( attribute "PN" "1"
					( Origin gPackager )
				)
				( objectStatus "RT27.1" )
			)
			( pin "@baseboard_fab2_lib.baseboard_fab2(sch_1):page203_i135:\2\"
				( attribute "PN" "2"
					( Origin gPackager )
				)
				( objectStatus "RT27.2" )
			)
			( pin "@baseboard_fab2_lib.baseboard_fab2(sch_1):page203_i134:\1\"
				( attribute "PN" "1"
					( Origin gPackager )
				)
				( objectStatus "RT26.1" )
			)
			( pin "@baseboard_fab2_lib.baseboard_fab2(sch_1):page203_i134:\2\"
				( attribute "PN" "2"
					( Origin gPackager )
				)
				( objectStatus "RT26.2" )
			)
			( pin "@baseboard_fab2_lib.baseboard_fab2(sch_1):page225_i247:\1\"
				( attribute "PN" "1"
					( Origin gPackager )
				)
				( objectStatus "C22W2.1" )
			)
			( pin "@baseboard_fab2_lib.baseboard_fab2(sch_1):page225_i247:\2\"
				( attribute "PN" "2"
					( Origin gPackager )
				)
				( objectStatus "C22W2.2" )
			)
			( pin "@baseboard_fab2_lib.baseboard_fab2(sch_1):page225_i251:\1\"
				( attribute "PN" "1"
					( Origin gPackager )
				)
				( objectStatus "C22W4.1" )
			)
			( pin "@baseboard_fab2_lib.baseboard_fab2(sch_1):page225_i251:\2\"
				( attribute "PN" "2"
					( Origin gPackager )
				)
				( objectStatus "C22W4.2" )
			)
			( pin "@baseboard_fab2_lib.baseboard_fab2(sch_1):page176_i178:a"
				( attribute "PN" "1"
					( Origin gPackager )
				)
				( objectStatus "R6W50.1" )
			)
			( pin "@baseboard_fab2_lib.baseboard_fab2(sch_1):page176_i178:b"
				( attribute "PN" "2"
					( Origin gPackager )
				)
				( objectStatus "R6W50.2" )
			)
			( pin "@baseboard_fab2_lib.baseboard_fab2(sch_1):page233_i280:\1\"
				( attribute "PN" "1"
					( Origin gPackager )
				)
				( objectStatus "C4G5.1" )
			)
			( pin "@baseboard_fab2_lib.baseboard_fab2(sch_1):page233_i280:\2\"
				( attribute "PN" "2"
					( Origin gPackager )
				)
				( objectStatus "C4G5.2" )
			)
			( pin "@baseboard_fab2_lib.baseboard_fab2(sch_1):page232_i311:\1\"
				( attribute "PN" "1"
					( Origin gPackager )
				)
				( objectStatus "C22W7.1" )
			)
			( pin "@baseboard_fab2_lib.baseboard_fab2(sch_1):page232_i311:\2\"
				( attribute "PN" "2"
					( Origin gPackager )
				)
				( objectStatus "C22W7.2" )
			)
			( pin "@baseboard_fab2_lib.baseboard_fab2(sch_1):page241_i95:\1\"
				( attribute "PN" "1"
					( Origin gPackager )
				)
				( objectStatus "C22W9.1" )
			)
			( pin "@baseboard_fab2_lib.baseboard_fab2(sch_1):page241_i95:\2\"
				( attribute "PN" "2"
					( Origin gPackager )
				)
				( objectStatus "C22W9.2" )
			)
			( pin "@baseboard_fab2_lib.baseboard_fab2(sch_1):page241_i96:\1\"
				( attribute "PN" "1"
					( Origin gPackager )
				)
				( objectStatus "C22W8.1" )
			)
			( pin "@baseboard_fab2_lib.baseboard_fab2(sch_1):page241_i96:\2\"
				( attribute "PN" "2"
					( Origin gPackager )
				)
				( objectStatus "C22W8.2" )
			)
			( pin "@baseboard_fab2_lib.baseboard_fab2(sch_1):page241_i98:\1\"
				( attribute "PN" "1"
					( Origin gPackager )
				)
				( objectStatus "C7E12.1" )
			)
			( pin "@baseboard_fab2_lib.baseboard_fab2(sch_1):page241_i98:\2\"
				( attribute "PN" "2"
					( Origin gPackager )
				)
				( objectStatus "C7E12.2" )
			)
			( pin "@baseboard_fab2_lib.baseboard_fab2(sch_1):page240_i181:\1\"
				( attribute "PN" "1"
					( Origin gPackager )
				)
				( objectStatus "C9F1.1" )
			)
			( pin "@baseboard_fab2_lib.baseboard_fab2(sch_1):page240_i181:\2\"
				( attribute "PN" "2"
					( Origin gPackager )
				)
				( objectStatus "C9F1.2" )
			)
			( pin "@baseboard_fab2_lib.baseboard_fab2(sch_1):page231_i225:\1\"
				( attribute "PN" "1"
					( Origin gPackager )
				)
				( objectStatus "C22W10.1" )
			)
			( pin "@baseboard_fab2_lib.baseboard_fab2(sch_1):page231_i225:\2\"
				( attribute "PN" "2"
					( Origin gPackager )
				)
				( objectStatus "C22W10.2" )
			)
			( pin "@baseboard_fab2_lib.baseboard_fab2(sch_1):page231_i226:\1\"
				( attribute "PN" "1"
					( Origin gPackager )
				)
				( objectStatus "C7F7.1" )
			)
			( pin "@baseboard_fab2_lib.baseboard_fab2(sch_1):page231_i226:\2\"
				( attribute "PN" "2"
					( Origin gPackager )
				)
				( objectStatus "C7F7.2" )
			)
			( pin "@baseboard_fab2_lib.baseboard_fab2(sch_1):page240_i186:\1\"
				( attribute "PN" "1"
					( Origin gPackager )
				)
				( objectStatus "C22W12.1" )
			)
			( pin "@baseboard_fab2_lib.baseboard_fab2(sch_1):page240_i186:\2\"
				( attribute "PN" "2"
					( Origin gPackager )
				)
				( objectStatus "C22W12.2" )
			)
			( pin "@baseboard_fab2_lib.baseboard_fab2(sch_1):page214_i152:\1\"
				( attribute "PN" "1"
					( Origin gPackager )
				)
				( objectStatus "C22W14.1" )
			)
			( pin "@baseboard_fab2_lib.baseboard_fab2(sch_1):page214_i152:\2\"
				( attribute "PN" "2"
					( Origin gPackager )
				)
				( objectStatus "C22W14.2" )
			)
			( pin "@baseboard_fab2_lib.baseboard_fab2(sch_1):page214_i154:\1\"
				( attribute "PN" "1"
					( Origin gPackager )
				)
				( objectStatus "C22W15.1" )
			)
			( pin "@baseboard_fab2_lib.baseboard_fab2(sch_1):page214_i154:\2\"
				( attribute "PN" "2"
					( Origin gPackager )
				)
				( objectStatus "C22W15.2" )
			)
			( pin "@baseboard_fab2_lib.baseboard_fab2(sch_1):page214_i156:\1\"
				( attribute "PN" "1"
					( Origin gPackager )
				)
				( objectStatus "C22W18.1" )
			)
			( pin "@baseboard_fab2_lib.baseboard_fab2(sch_1):page214_i156:\2\"
				( attribute "PN" "2"
					( Origin gPackager )
				)
				( objectStatus "C22W18.2" )
			)
			( pin "@baseboard_fab2_lib.baseboard_fab2(sch_1):page214_i158:\1\"
				( attribute "PN" "1"
					( Origin gPackager )
				)
				( objectStatus "C22W17.1" )
			)
			( pin "@baseboard_fab2_lib.baseboard_fab2(sch_1):page214_i158:\2\"
				( attribute "PN" "2"
					( Origin gPackager )
				)
				( objectStatus "C22W17.2" )
			)
			( pin "@baseboard_fab2_lib.baseboard_fab2(sch_1):page214_i160:\1\"
				( attribute "PN" "1"
					( Origin gPackager )
				)
				( objectStatus "C22W16.1" )
			)
			( pin "@baseboard_fab2_lib.baseboard_fab2(sch_1):page214_i160:\2\"
				( attribute "PN" "2"
					( Origin gPackager )
				)
				( objectStatus "C22W16.2" )
			)
			( pin "@baseboard_fab2_lib.baseboard_fab2(sch_1):page214_i161:\1\"
				( attribute "PN" "1"
					( Origin gPackager )
				)
				( objectStatus "C4E8.1" )
			)
			( pin "@baseboard_fab2_lib.baseboard_fab2(sch_1):page214_i161:\2\"
				( attribute "PN" "2"
					( Origin gPackager )
				)
				( objectStatus "C4E8.2" )
			)
			( pin "@baseboard_fab2_lib.baseboard_fab2(sch_1):page214_i164:\1\"
				( attribute "PN" "1"
					( Origin gPackager )
				)
				( objectStatus "C4E9.1" )
			)
			( pin "@baseboard_fab2_lib.baseboard_fab2(sch_1):page214_i164:\2\"
				( attribute "PN" "2"
					( Origin gPackager )
				)
				( objectStatus "C4E9.2" )
			)
			( pin "@baseboard_fab2_lib.baseboard_fab2(sch_1):page214_i166:\1\"
				( attribute "PN" "1"
					( Origin gPackager )
				)
				( objectStatus "C22W21.1" )
			)
			( pin "@baseboard_fab2_lib.baseboard_fab2(sch_1):page214_i166:\2\"
				( attribute "PN" "2"
					( Origin gPackager )
				)
				( objectStatus "C22W21.2" )
			)
			( pin "@baseboard_fab2_lib.baseboard_fab2(sch_1):page214_i168:\1\"
				( attribute "PN" "1"
					( Origin gPackager )
				)
				( objectStatus "C22W20.1" )
			)
			( pin "@baseboard_fab2_lib.baseboard_fab2(sch_1):page214_i168:\2\"
				( attribute "PN" "2"
					( Origin gPackager )
				)
				( objectStatus "C22W20.2" )
			)
			( pin "@baseboard_fab2_lib.baseboard_fab2(sch_1):page214_i169:\1\"
				( attribute "PN" "1"
					( Origin gPackager )
				)
				( objectStatus "C22W19.1" )
			)
			( pin "@baseboard_fab2_lib.baseboard_fab2(sch_1):page214_i169:\2\"
				( attribute "PN" "2"
					( Origin gPackager )
				)
				( objectStatus "C22W19.2" )
			)
			( pin "@baseboard_fab2_lib.baseboard_fab2(sch_1):page236_i162:\1\"
				( attribute "PN" "1"
					( Origin gPackager )
				)
				( objectStatus "C22W25.1" )
			)
			( pin "@baseboard_fab2_lib.baseboard_fab2(sch_1):page236_i162:\2\"
				( attribute "PN" "2"
					( Origin gPackager )
				)
				( objectStatus "C22W25.2" )
			)
			( pin "@baseboard_fab2_lib.baseboard_fab2(sch_1):page236_i163:\1\"
				( attribute "PN" "1"
					( Origin gPackager )
				)
				( objectStatus "C22W27.1" )
			)
			( pin "@baseboard_fab2_lib.baseboard_fab2(sch_1):page236_i163:\2\"
				( attribute "PN" "2"
					( Origin gPackager )
				)
				( objectStatus "C22W27.2" )
			)
			( pin "@baseboard_fab2_lib.baseboard_fab2(sch_1):page236_i165:\1\"
				( attribute "PN" "1"
					( Origin gPackager )
				)
				( objectStatus "C22W26.1" )
			)
			( pin "@baseboard_fab2_lib.baseboard_fab2(sch_1):page236_i165:\2\"
				( attribute "PN" "2"
					( Origin gPackager )
				)
				( objectStatus "C22W26.2" )
			)
			( pin "@baseboard_fab2_lib.baseboard_fab2(sch_1):page236_i171:\1\"
				( attribute "PN" "1"
					( Origin gPackager )
				)
				( objectStatus "C22W22.1" )
			)
			( pin "@baseboard_fab2_lib.baseboard_fab2(sch_1):page236_i171:\2\"
				( attribute "PN" "2"
					( Origin gPackager )
				)
				( objectStatus "C22W22.2" )
			)
			( pin "@baseboard_fab2_lib.baseboard_fab2(sch_1):page236_i172:\1\"
				( attribute "PN" "1"
					( Origin gPackager )
				)
				( objectStatus "C7A14.1" )
			)
			( pin "@baseboard_fab2_lib.baseboard_fab2(sch_1):page236_i172:\2\"
				( attribute "PN" "2"
					( Origin gPackager )
				)
				( objectStatus "C7A14.2" )
			)
			( pin "@baseboard_fab2_lib.baseboard_fab2(sch_1):page212_i129:\1\"
				( attribute "PN" "1"
					( Origin gPackager )
				)
				( objectStatus "C22W31.1" )
			)
			( pin "@baseboard_fab2_lib.baseboard_fab2(sch_1):page212_i129:\2\"
				( attribute "PN" "2"
					( Origin gPackager )
				)
				( objectStatus "C22W31.2" )
			)
			( pin "@baseboard_fab2_lib.baseboard_fab2(sch_1):page212_i130:\1\"
				( attribute "PN" "1"
					( Origin gPackager )
				)
				( objectStatus "C7C8.1" )
			)
			( pin "@baseboard_fab2_lib.baseboard_fab2(sch_1):page212_i130:\2\"
				( attribute "PN" "2"
					( Origin gPackager )
				)
				( objectStatus "C7C8.2" )
			)
			( pin "@baseboard_fab2_lib.baseboard_fab2(sch_1):page212_i132:\1\"
				( attribute "PN" "1"
					( Origin gPackager )
				)
				( objectStatus "C22W30.1" )
			)
			( pin "@baseboard_fab2_lib.baseboard_fab2(sch_1):page212_i132:\2\"
				( attribute "PN" "2"
					( Origin gPackager )
				)
				( objectStatus "C22W30.2" )
			)
			( pin "@baseboard_fab2_lib.baseboard_fab2(sch_1):page212_i134:\1\"
				( attribute "PN" "1"
					( Origin gPackager )
				)
				( objectStatus "C22W29.1" )
			)
			( pin "@baseboard_fab2_lib.baseboard_fab2(sch_1):page212_i134:\2\"
				( attribute "PN" "2"
					( Origin gPackager )
				)
				( objectStatus "C22W29.2" )
			)
			( pin "@baseboard_fab2_lib.baseboard_fab2(sch_1):page212_i136:\1\"
				( attribute "PN" "1"
					( Origin gPackager )
				)
				( objectStatus "C22W28.1" )
			)
			( pin "@baseboard_fab2_lib.baseboard_fab2(sch_1):page212_i136:\2\"
				( attribute "PN" "2"
					( Origin gPackager )
				)
				( objectStatus "C22W28.2" )
			)
			( pin "@baseboard_fab2_lib.baseboard_fab2(sch_1):page212_i138:\1\"
				( attribute "PN" "1"
					( Origin gPackager )
				)
				( objectStatus "C7C7.1" )
			)
			( pin "@baseboard_fab2_lib.baseboard_fab2(sch_1):page212_i138:\2\"
				( attribute "PN" "2"
					( Origin gPackager )
				)
				( objectStatus "C7C7.2" )
			)
			( pin "@baseboard_fab2_lib.baseboard_fab2(sch_1):page125_i87:a"
				( attribute "PN" "1"
					( Origin gPackager )
				)
				( objectStatus "R8D13.1" )
			)
			( pin "@baseboard_fab2_lib.baseboard_fab2(sch_1):page125_i87:b"
				( attribute "PN" "2"
					( Origin gPackager )
				)
				( objectStatus "R8D13.2" )
			)
			( pin "@baseboard_fab2_lib.baseboard_fab2(sch_1):page139_i244:\1\"
				( attribute "PN" "1"
					( Origin gPackager )
				)
				( objectStatus "C22W34.1" )
			)
			( pin "@baseboard_fab2_lib.baseboard_fab2(sch_1):page139_i244:\2\"
				( attribute "PN" "2"
					( Origin gPackager )
				)
				( objectStatus "C22W34.2" )
			)
			( pin "@baseboard_fab2_lib.baseboard_fab2(sch_1):page139_i245:\1\"
				( attribute "PN" "1"
					( Origin gPackager )
				)
				( objectStatus "C9F2.1" )
			)
			( pin "@baseboard_fab2_lib.baseboard_fab2(sch_1):page139_i245:\2\"
				( attribute "PN" "2"
					( Origin gPackager )
				)
				( objectStatus "C9F2.2" )
			)
			( pin "@baseboard_fab2_lib.baseboard_fab2(sch_1):page139_i246:\1\"
				( attribute "PN" "1"
					( Origin gPackager )
				)
				( objectStatus "C22W35.1" )
			)
			( pin "@baseboard_fab2_lib.baseboard_fab2(sch_1):page139_i246:\2\"
				( attribute "PN" "2"
					( Origin gPackager )
				)
				( objectStatus "C22W35.2" )
			)
			( pin "@baseboard_fab2_lib.baseboard_fab2(sch_1):page139_i248:\1\"
				( attribute "PN" "1"
					( Origin gPackager )
				)
				( objectStatus "C9E6.1" )
			)
			( pin "@baseboard_fab2_lib.baseboard_fab2(sch_1):page139_i248:\2\"
				( attribute "PN" "2"
					( Origin gPackager )
				)
				( objectStatus "C9E6.2" )
			)
			( pin "@baseboard_fab2_lib.baseboard_fab2(sch_1):page126_i27:a"
				( attribute "PN" "1"
					( Origin gPackager )
				)
				( objectStatus "R2N10.1" )
			)
			( pin "@baseboard_fab2_lib.baseboard_fab2(sch_1):page126_i27:b"
				( attribute "PN" "2"
					( Origin gPackager )
				)
				( objectStatus "R2N10.2" )
			)
			( pin "@baseboard_fab2_lib.baseboard_fab2(sch_1):page250_i29:drn"
				( attribute "PN" "3"
					( Origin gPackager )
				)
				( objectStatus "Q1W1.3" )
			)
			( pin "@baseboard_fab2_lib.baseboard_fab2(sch_1):page250_i29:gate"
				( attribute "PN" "1"
					( Origin gPackager )
				)
				( objectStatus "Q1W1.1" )
			)
			( pin "@baseboard_fab2_lib.baseboard_fab2(sch_1):page250_i29:src"
				( attribute "PN" "2"
					( Origin gPackager )
				)
				( objectStatus "Q1W1.2" )
			)
			( pin "@baseboard_fab2_lib.baseboard_fab2(sch_1):page197_i109:\1\"
				( attribute "PN" "1"
					( Origin gPackager )
				)
				( objectStatus "R12W10.1" )
			)
			( pin "@baseboard_fab2_lib.baseboard_fab2(sch_1):page197_i109:\2\"
				( attribute "PN" "2"
					( Origin gPackager )
				)
				( objectStatus "R12W10.2" )
			)
			( pin "@baseboard_fab2_lib.baseboard_fab2(sch_1):page247_i120:a0"
				( attribute "PN" "21"
					( Origin gPackager )
				)
				( objectStatus "U6W1.21" )
			)
			( pin "@baseboard_fab2_lib.baseboard_fab2(sch_1):page247_i120:a1"
				( attribute "PN" "2"
					( Origin gPackager )
				)
				( objectStatus "U6W1.2" )
			)
			( pin "@baseboard_fab2_lib.baseboard_fab2(sch_1):page247_i120:a2"
				( attribute "PN" "3"
					( Origin gPackager )
				)
				( objectStatus "U6W1.3" )
			)
			( pin "@baseboard_fab2_lib.baseboard_fab2(sch_1):page247_i120:gnd"
				( attribute "PN" "12"
					( Origin gPackager )
				)
				( objectStatus "U6W1.12" )
			)
			( pin "@baseboard_fab2_lib.baseboard_fab2(sch_1):page247_i120:\int#\"
				( attribute "PN" "1"
					( Origin gPackager )
				)
				( objectStatus "U6W1.1" )
			)
			( pin "@baseboard_fab2_lib.baseboard_fab2(sch_1):page247_i120:p00"
				( attribute "PN" "4"
					( Origin gPackager )
				)
				( objectStatus "U6W1.4" )
			)
			( pin "@baseboard_fab2_lib.baseboard_fab2(sch_1):page247_i120:p01"
				( attribute "PN" "5"
					( Origin gPackager )
				)
				( objectStatus "U6W1.5" )
			)
			( pin "@baseboard_fab2_lib.baseboard_fab2(sch_1):page247_i120:p02"
				( attribute "PN" "6"
					( Origin gPackager )
				)
				( objectStatus "U6W1.6" )
			)
			( pin "@baseboard_fab2_lib.baseboard_fab2(sch_1):page247_i120:p03"
				( attribute "PN" "7"
					( Origin gPackager )
				)
				( objectStatus "U6W1.7" )
			)
			( pin "@baseboard_fab2_lib.baseboard_fab2(sch_1):page247_i120:p04"
				( attribute "PN" "8"
					( Origin gPackager )
				)
				( objectStatus "U6W1.8" )
			)
			( pin "@baseboard_fab2_lib.baseboard_fab2(sch_1):page247_i120:p05"
				( attribute "PN" "9"
					( Origin gPackager )
				)
				( objectStatus "U6W1.9" )
			)
			( pin "@baseboard_fab2_lib.baseboard_fab2(sch_1):page247_i120:p06"
				( attribute "PN" "10"
					( Origin gPackager )
				)
				( objectStatus "U6W1.10" )
			)
			( pin "@baseboard_fab2_lib.baseboard_fab2(sch_1):page247_i120:p07"
				( attribute "PN" "11"
					( Origin gPackager )
				)
				( objectStatus "U6W1.11" )
			)
			( pin "@baseboard_fab2_lib.baseboard_fab2(sch_1):page247_i120:p10"
				( attribute "PN" "13"
					( Origin gPackager )
				)
				( objectStatus "U6W1.13" )
			)
			( pin "@baseboard_fab2_lib.baseboard_fab2(sch_1):page247_i120:p11"
				( attribute "PN" "14"
					( Origin gPackager )
				)
				( objectStatus "U6W1.14" )
			)
			( pin "@baseboard_fab2_lib.baseboard_fab2(sch_1):page247_i120:p12"
				( attribute "PN" "15"
					( Origin gPackager )
				)
				( objectStatus "U6W1.15" )
			)
			( pin "@baseboard_fab2_lib.baseboard_fab2(sch_1):page247_i120:p13"
				( attribute "PN" "16"
					( Origin gPackager )
				)
				( objectStatus "U6W1.16" )
			)
			( pin "@baseboard_fab2_lib.baseboard_fab2(sch_1):page247_i120:p14"
				( attribute "PN" "17"
					( Origin gPackager )
				)
				( objectStatus "U6W1.17" )
			)
			( pin "@baseboard_fab2_lib.baseboard_fab2(sch_1):page247_i120:p15"
				( attribute "PN" "18"
					( Origin gPackager )
				)
				( objectStatus "U6W1.18" )
			)
			( pin "@baseboard_fab2_lib.baseboard_fab2(sch_1):page247_i120:p16"
				( attribute "PN" "19"
					( Origin gPackager )
				)
				( objectStatus "U6W1.19" )
			)
			( pin "@baseboard_fab2_lib.baseboard_fab2(sch_1):page247_i120:p17"
				( attribute "PN" "20"
					( Origin gPackager )
				)
				( objectStatus "U6W1.20" )
			)
			( pin "@baseboard_fab2_lib.baseboard_fab2(sch_1):page247_i120:scl"
				( attribute "PN" "22"
					( Origin gPackager )
				)
				( objectStatus "U6W1.22" )
			)
			( pin "@baseboard_fab2_lib.baseboard_fab2(sch_1):page247_i120:sda"
				( attribute "PN" "23"
					( Origin gPackager )
				)
				( objectStatus "U6W1.23" )
			)
			( pin "@baseboard_fab2_lib.baseboard_fab2(sch_1):page247_i120:vcc"
				( attribute "PN" "24"
					( Origin gPackager )
				)
				( objectStatus "U6W1.24" )
			)
			( pin "@baseboard_fab2_lib.baseboard_fab2(sch_1):page176_i139:a"
				( attribute "PN" "1"
					( Origin gPackager )
				)
				( objectStatus "C6W10.1" )
			)
			( pin "@baseboard_fab2_lib.baseboard_fab2(sch_1):page176_i139:b"
				( attribute "PN" "2"
					( Origin gPackager )
				)
				( objectStatus "C6W10.2" )
			)
			( pin "@baseboard_fab2_lib.baseboard_fab2(sch_1):page90_i100:a"
				( attribute "PN" "1"
					( Origin gPackager )
				)
				( objectStatus "R7P14.1" )
			)
			( pin "@baseboard_fab2_lib.baseboard_fab2(sch_1):page90_i100:b"
				( attribute "PN" "2"
					( Origin gPackager )
				)
				( objectStatus "R7P14.2" )
			)
			( pin "@baseboard_fab2_lib.baseboard_fab2(sch_1):page90_i96:a"
				( attribute "PN" "1"
					( Origin gPackager )
				)
				( objectStatus "R5D4.1" )
			)
			( pin "@baseboard_fab2_lib.baseboard_fab2(sch_1):page90_i96:b"
				( attribute "PN" "2"
					( Origin gPackager )
				)
				( objectStatus "R5D4.2" )
			)
			( pin "@baseboard_fab2_lib.baseboard_fab2(sch_1):page200_i246:a"
				( attribute "PN" "1"
					( Origin gPackager )
				)
				( objectStatus "R1D14.1" )
			)
			( pin "@baseboard_fab2_lib.baseboard_fab2(sch_1):page200_i246:b"
				( attribute "PN" "2"
					( Origin gPackager )
				)
				( objectStatus "R1D14.2" )
			)
			( pin "@baseboard_fab2_lib.baseboard_fab2(sch_1):page255_i95:drain(0)"
				( attribute "PN" "6"
					( Origin gPackager )
				)
				( objectStatus "Q25W4.6" )
			)
			( pin "@baseboard_fab2_lib.baseboard_fab2(sch_1):page255_i95:gate(0)"
				( attribute "PN" "2"
					( Origin gPackager )
				)
				( objectStatus "Q25W4.2" )
			)
			( pin "@baseboard_fab2_lib.baseboard_fab2(sch_1):page255_i95:source(0)"
				( attribute "PN" "1"
					( Origin gPackager )
				)
				( objectStatus "Q25W4.1" )
			)
			( pin "@baseboard_fab2_lib.baseboard_fab2(sch_1):page255_i96:drain(0)"
				( attribute "PN" "3"
					( Origin gPackager )
				)
				( objectStatus "Q25W4.3" )
			)
			( pin "@baseboard_fab2_lib.baseboard_fab2(sch_1):page255_i96:gate(0)"
				( attribute "PN" "5"
					( Origin gPackager )
				)
				( objectStatus "Q25W4.5" )
			)
			( pin "@baseboard_fab2_lib.baseboard_fab2(sch_1):page255_i96:source(0)"
				( attribute "PN" "4"
					( Origin gPackager )
				)
				( objectStatus "Q25W4.4" )
			)
			( pin "@baseboard_fab2_lib.baseboard_fab2(sch_1):page113_i273:a"
				( attribute "PN" "1"
					( Origin gPackager )
				)
				( objectStatus "R5W2.1" )
			)
			( pin "@baseboard_fab2_lib.baseboard_fab2(sch_1):page113_i273:b"
				( attribute "PN" "2"
					( Origin gPackager )
				)
				( objectStatus "R5W2.2" )
			)
			( pin "@baseboard_fab2_lib.baseboard_fab2(sch_1):page113_i272:a"
				( attribute "PN" "1"
					( Origin gPackager )
				)
				( objectStatus "R5W1.1" )
			)
			( pin "@baseboard_fab2_lib.baseboard_fab2(sch_1):page113_i272:b"
				( attribute "PN" "2"
					( Origin gPackager )
				)
				( objectStatus "R5W1.2" )
			)
			( pin "@baseboard_fab2_lib.baseboard_fab2(sch_1):page113_i271:a"
				( attribute "PN" "1"
					( Origin gPackager )
				)
				( objectStatus "R6M8.1" )
			)
			( pin "@baseboard_fab2_lib.baseboard_fab2(sch_1):page113_i271:b"
				( attribute "PN" "2"
					( Origin gPackager )
				)
				( objectStatus "R6M8.2" )
			)
			( pin "@baseboard_fab2_lib.baseboard_fab2(sch_1):page113_i270:a"
				( attribute "PN" "1"
					( Origin gPackager )
				)
				( objectStatus "R4R6.1" )
			)
			( pin "@baseboard_fab2_lib.baseboard_fab2(sch_1):page113_i270:b"
				( attribute "PN" "2"
					( Origin gPackager )
				)
				( objectStatus "R4R6.2" )
			)
			( pin "@baseboard_fab2_lib.baseboard_fab2(sch_1):page118_i167:a"
				( attribute "PN" "1"
					( Origin gPackager )
				)
				( objectStatus "R7W1.1" )
			)
			( pin "@baseboard_fab2_lib.baseboard_fab2(sch_1):page118_i167:b"
				( attribute "PN" "2"
					( Origin gPackager )
				)
				( objectStatus "R7W1.2" )
			)
			( pin "@baseboard_fab2_lib.baseboard_fab2(sch_1):page199_i131:\1\"
				( attribute "PN" "1"
					( Origin gPackager )
				)
				( objectStatus "J1B4.1" )
			)
			( pin "@baseboard_fab2_lib.baseboard_fab2(sch_1):page199_i131:\2\"
				( attribute "PN" "2"
					( Origin gPackager )
				)
				( objectStatus "J1B4.2" )
			)
			( pin "@baseboard_fab2_lib.baseboard_fab2(sch_1):page199_i131:\3\"
				( attribute "PN" "3"
					( Origin gPackager )
				)
				( objectStatus "J1B4.3" )
			)
			( pin "@baseboard_fab2_lib.baseboard_fab2(sch_1):page253_i5:ac0"
				( attribute "PN" "1"
					( Origin gPackager )
				)
				( objectStatus "CR30W1.1" )
			)
			( pin "@baseboard_fab2_lib.baseboard_fab2(sch_1):page253_i5:ac1"
				( attribute "PN" "2"
					( Origin gPackager )
				)
				( objectStatus "CR30W1.2" )
			)
			( pin "@baseboard_fab2_lib.baseboard_fab2(sch_1):page253_i5:ac2"
				( attribute "PN" "4"
					( Origin gPackager )
				)
				( objectStatus "CR30W1.4" )
			)
			( pin "@baseboard_fab2_lib.baseboard_fab2(sch_1):page253_i5:ac3"
				( attribute "PN" "5"
					( Origin gPackager )
				)
				( objectStatus "CR30W1.5" )
			)
			( pin "@baseboard_fab2_lib.baseboard_fab2(sch_1):page253_i5:gnd(0)"
				( attribute "PN" "3"
					( Origin gPackager )
				)
				( objectStatus "CR30W1.3" )
			)
			( pin "@baseboard_fab2_lib.baseboard_fab2(sch_1):page253_i5:out0"
				( attribute "PN" "9"
					( Origin gPackager )
				)
				( objectStatus "CR30W1.9" )
			)
			( pin "@baseboard_fab2_lib.baseboard_fab2(sch_1):page253_i5:out1"
				( attribute "PN" "8"
					( Origin gPackager )
				)
				( objectStatus "CR30W1.8" )
			)
			( pin "@baseboard_fab2_lib.baseboard_fab2(sch_1):page253_i5:out2"
				( attribute "PN" "7"
					( Origin gPackager )
				)
				( objectStatus "CR30W1.7" )
			)
			( pin "@baseboard_fab2_lib.baseboard_fab2(sch_1):page253_i5:out3"
				( attribute "PN" "6"
					( Origin gPackager )
				)
				( objectStatus "CR30W1.6" )
			)
			( pin "@baseboard_fab2_lib.baseboard_fab2(sch_1):page253_i11:\1\"
				( attribute "PN" "1"
					( Origin gPackager )
				)
				( objectStatus "L30W2.1" )
			)
			( pin "@baseboard_fab2_lib.baseboard_fab2(sch_1):page253_i11:\2\"
				( attribute "PN" "2"
					( Origin gPackager )
				)
				( objectStatus "L30W2.2" )
			)
			( pin "@baseboard_fab2_lib.baseboard_fab2(sch_1):page253_i11:\3\"
				( attribute "PN" "3"
					( Origin gPackager )
				)
				( objectStatus "L30W2.3" )
			)
			( pin "@baseboard_fab2_lib.baseboard_fab2(sch_1):page253_i11:\4\"
				( attribute "PN" "4"
					( Origin gPackager )
				)
				( objectStatus "L30W2.4" )
			)
			( pin "@baseboard_fab2_lib.baseboard_fab2(sch_1):page253_i12:a"
				( attribute "PN" "1"
					( Origin gPackager )
				)
				( objectStatus "R30W2.1" )
			)
			( pin "@baseboard_fab2_lib.baseboard_fab2(sch_1):page253_i12:b"
				( attribute "PN" "2"
					( Origin gPackager )
				)
				( objectStatus "R30W2.2" )
			)
			( pin "@baseboard_fab2_lib.baseboard_fab2(sch_1):page253_i13:a"
				( attribute "PN" "1"
					( Origin gPackager )
				)
				( objectStatus "R30W1.1" )
			)
			( pin "@baseboard_fab2_lib.baseboard_fab2(sch_1):page253_i13:b"
				( attribute "PN" "2"
					( Origin gPackager )
				)
				( objectStatus "R30W1.2" )
			)
			( pin "@baseboard_fab2_lib.baseboard_fab2(sch_1):page253_i14:a"
				( attribute "PN" "1"
					( Origin gPackager )
				)
				( objectStatus "R30W4.1" )
			)
			( pin "@baseboard_fab2_lib.baseboard_fab2(sch_1):page253_i14:b"
				( attribute "PN" "2"
					( Origin gPackager )
				)
				( objectStatus "R30W4.2" )
			)
			( pin "@baseboard_fab2_lib.baseboard_fab2(sch_1):page253_i15:a"
				( attribute "PN" "1"
					( Origin gPackager )
				)
				( objectStatus "R30W3.1" )
			)
			( pin "@baseboard_fab2_lib.baseboard_fab2(sch_1):page253_i15:b"
				( attribute "PN" "2"
					( Origin gPackager )
				)
				( objectStatus "R30W3.2" )
			)
			( pin "@baseboard_fab2_lib.baseboard_fab2(sch_1):page253_i16:\1\"
				( attribute "PN" "1"
					( Origin gPackager )
				)
				( objectStatus "L30W1.1" )
			)
			( pin "@baseboard_fab2_lib.baseboard_fab2(sch_1):page253_i16:\2\"
				( attribute "PN" "2"
					( Origin gPackager )
				)
				( objectStatus "L30W1.2" )
			)
			( pin "@baseboard_fab2_lib.baseboard_fab2(sch_1):page253_i16:\3\"
				( attribute "PN" "3"
					( Origin gPackager )
				)
				( objectStatus "L30W1.3" )
			)
			( pin "@baseboard_fab2_lib.baseboard_fab2(sch_1):page253_i16:\4\"
				( attribute "PN" "4"
					( Origin gPackager )
				)
				( objectStatus "L30W1.4" )
			)
			( pin "@baseboard_fab2_lib.baseboard_fab2(sch_1):page253_i19:a"
				( attribute "PN" "1"
					( Origin gPackager )
				)
				( objectStatus "C30W2.1" )
			)
			( pin "@baseboard_fab2_lib.baseboard_fab2(sch_1):page253_i19:b"
				( attribute "PN" "2"
					( Origin gPackager )
				)
				( objectStatus "C30W2.2" )
			)
			( pin "@baseboard_fab2_lib.baseboard_fab2(sch_1):page253_i20:a"
				( attribute "PN" "1"
					( Origin gPackager )
				)
				( objectStatus "C30W1.1" )
			)
			( pin "@baseboard_fab2_lib.baseboard_fab2(sch_1):page253_i20:b"
				( attribute "PN" "2"
					( Origin gPackager )
				)
				( objectStatus "C30W1.2" )
			)
			( pin "@baseboard_fab2_lib.baseboard_fab2(sch_1):page255_i111:a"
				( attribute "PN" "2"
					( Origin gPackager )
				)
				( objectStatus "U25W7.2" )
			)
			( pin "@baseboard_fab2_lib.baseboard_fab2(sch_1):page255_i111:gnd"
				( attribute "PN" "3"
					( Origin gPackager )
				)
				( objectStatus "U25W7.3" )
			)
			( pin "@baseboard_fab2_lib.baseboard_fab2(sch_1):page255_i111:\oe#\"
				( attribute "PN" "1"
					( Origin gPackager )
				)
				( objectStatus "U25W7.1" )
			)
			( pin "@baseboard_fab2_lib.baseboard_fab2(sch_1):page255_i111:vcc"
				( attribute "PN" "5"
					( Origin gPackager )
				)
				( objectStatus "U25W7.5" )
			)
			( pin "@baseboard_fab2_lib.baseboard_fab2(sch_1):page255_i111:y"
				( attribute "PN" "4"
					( Origin gPackager )
				)
				( objectStatus "U25W7.4" )
			)
			( pin "@baseboard_fab2_lib.baseboard_fab2(sch_1):page255_i112:a"
				( attribute "PN" "2"
					( Origin gPackager )
				)
				( objectStatus "U25W8.2" )
			)
			( pin "@baseboard_fab2_lib.baseboard_fab2(sch_1):page255_i112:gnd"
				( attribute "PN" "3"
					( Origin gPackager )
				)
				( objectStatus "U25W8.3" )
			)
			( pin "@baseboard_fab2_lib.baseboard_fab2(sch_1):page255_i112:\oe#\"
				( attribute "PN" "1"
					( Origin gPackager )
				)
				( objectStatus "U25W8.1" )
			)
			( pin "@baseboard_fab2_lib.baseboard_fab2(sch_1):page255_i112:vcc"
				( attribute "PN" "5"
					( Origin gPackager )
				)
				( objectStatus "U25W8.5" )
			)
			( pin "@baseboard_fab2_lib.baseboard_fab2(sch_1):page255_i112:y"
				( attribute "PN" "4"
					( Origin gPackager )
				)
				( objectStatus "U25W8.4" )
			)
			( pin "@baseboard_fab2_lib.baseboard_fab2(sch_1):page255_i118:a"
				( attribute "PN" "1"
					( Origin gPackager )
				)
				( objectStatus "C25W90.1" )
			)
			( pin "@baseboard_fab2_lib.baseboard_fab2(sch_1):page255_i118:b"
				( attribute "PN" "2"
					( Origin gPackager )
				)
				( objectStatus "C25W90.2" )
			)
			( pin "@baseboard_fab2_lib.baseboard_fab2(sch_1):page255_i128:anode"
				( attribute "PN" "A"
					( Origin gPackager )
				)
				( objectStatus "D25W8.A" )
			)
			( pin "@baseboard_fab2_lib.baseboard_fab2(sch_1):page255_i128:cathode"
				( attribute "PN" "K"
					( Origin gPackager )
				)
				( objectStatus "D25W8.K" )
			)
			( pin "@baseboard_fab2_lib.baseboard_fab2(sch_1):page255_i129:ac0"
				( attribute "PN" "1"
					( Origin gPackager )
				)
				( objectStatus "CR25W1.1" )
			)
			( pin "@baseboard_fab2_lib.baseboard_fab2(sch_1):page255_i129:ac1"
				( attribute "PN" "2"
					( Origin gPackager )
				)
				( objectStatus "CR25W1.2" )
			)
			( pin "@baseboard_fab2_lib.baseboard_fab2(sch_1):page255_i129:ac2"
				( attribute "PN" "4"
					( Origin gPackager )
				)
				( objectStatus "CR25W1.4" )
			)
			( pin "@baseboard_fab2_lib.baseboard_fab2(sch_1):page255_i129:ac3"
				( attribute "PN" "5"
					( Origin gPackager )
				)
				( objectStatus "CR25W1.5" )
			)
			( pin "@baseboard_fab2_lib.baseboard_fab2(sch_1):page255_i129:gnd(0)"
				( attribute "PN" "3"
					( Origin gPackager )
				)
				( objectStatus "CR25W1.3" )
			)
			( pin "@baseboard_fab2_lib.baseboard_fab2(sch_1):page255_i129:out0"
				( attribute "PN" "9"
					( Origin gPackager )
				)
				( objectStatus "CR25W1.9" )
			)
			( pin "@baseboard_fab2_lib.baseboard_fab2(sch_1):page255_i129:out1"
				( attribute "PN" "8"
					( Origin gPackager )
				)
				( objectStatus "CR25W1.8" )
			)
			( pin "@baseboard_fab2_lib.baseboard_fab2(sch_1):page255_i129:out2"
				( attribute "PN" "7"
					( Origin gPackager )
				)
				( objectStatus "CR25W1.7" )
			)
			( pin "@baseboard_fab2_lib.baseboard_fab2(sch_1):page255_i129:out3"
				( attribute "PN" "6"
					( Origin gPackager )
				)
				( objectStatus "CR25W1.6" )
			)
			( pin "@baseboard_fab2_lib.baseboard_fab2(sch_1):page255_i131:ac0"
				( attribute "PN" "1"
					( Origin gPackager )
				)
				( objectStatus "CR25W2.1" )
			)
			( pin "@baseboard_fab2_lib.baseboard_fab2(sch_1):page255_i131:ac1"
				( attribute "PN" "2"
					( Origin gPackager )
				)
				( objectStatus "CR25W2.2" )
			)
			( pin "@baseboard_fab2_lib.baseboard_fab2(sch_1):page255_i131:ac2"
				( attribute "PN" "4"
					( Origin gPackager )
				)
				( objectStatus "CR25W2.4" )
			)
			( pin "@baseboard_fab2_lib.baseboard_fab2(sch_1):page255_i131:ac3"
				( attribute "PN" "5"
					( Origin gPackager )
				)
				( objectStatus "CR25W2.5" )
			)
			( pin "@baseboard_fab2_lib.baseboard_fab2(sch_1):page255_i131:gnd(0)"
				( attribute "PN" "3"
					( Origin gPackager )
				)
				( objectStatus "CR25W2.3" )
			)
			( pin "@baseboard_fab2_lib.baseboard_fab2(sch_1):page255_i131:out0"
				( attribute "PN" "9"
					( Origin gPackager )
				)
				( objectStatus "CR25W2.9" )
			)
			( pin "@baseboard_fab2_lib.baseboard_fab2(sch_1):page255_i131:out1"
				( attribute "PN" "8"
					( Origin gPackager )
				)
				( objectStatus "CR25W2.8" )
			)
			( pin "@baseboard_fab2_lib.baseboard_fab2(sch_1):page255_i131:out2"
				( attribute "PN" "7"
					( Origin gPackager )
				)
				( objectStatus "CR25W2.7" )
			)
			( pin "@baseboard_fab2_lib.baseboard_fab2(sch_1):page255_i131:out3"
				( attribute "PN" "6"
					( Origin gPackager )
				)
				( objectStatus "CR25W2.6" )
			)
			( pin "@baseboard_fab2_lib.baseboard_fab2(sch_1):page255_i134:a"
				( attribute "PN" "1"
					( Origin gPackager )
				)
				( objectStatus "C25P80.1" )
			)
			( pin "@baseboard_fab2_lib.baseboard_fab2(sch_1):page255_i134:b"
				( attribute "PN" "2"
					( Origin gPackager )
				)
				( objectStatus "C25P80.2" )
			)
			( pin "@baseboard_fab2_lib.baseboard_fab2(sch_1):page199_i132:a"
				( attribute "PN" "1"
					( Origin gPackager )
				)
				( objectStatus "C1W16.1" )
			)
			( pin "@baseboard_fab2_lib.baseboard_fab2(sch_1):page199_i132:b"
				( attribute "PN" "2"
					( Origin gPackager )
				)
				( objectStatus "C1W16.2" )
			)
			( pin "@baseboard_fab2_lib.baseboard_fab2(sch_1):page199_i134:a"
				( attribute "PN" "1"
					( Origin gPackager )
				)
				( objectStatus "R1W20.1" )
			)
			( pin "@baseboard_fab2_lib.baseboard_fab2(sch_1):page199_i134:b"
				( attribute "PN" "2"
					( Origin gPackager )
				)
				( objectStatus "R1W20.2" )
			)
			( pin "@baseboard_fab2_lib.baseboard_fab2(sch_1):page199_i135:a"
				( attribute "PN" "1"
					( Origin gPackager )
				)
				( objectStatus "R1W21.1" )
			)
			( pin "@baseboard_fab2_lib.baseboard_fab2(sch_1):page199_i135:b"
				( attribute "PN" "2"
					( Origin gPackager )
				)
				( objectStatus "R1W21.2" )
			)
			( pin "@baseboard_fab2_lib.baseboard_fab2(sch_1):page183_i3:a"
				( attribute "PN" "1"
					( Origin gPackager )
				)
				( objectStatus "R9F55.1" )
			)
			( pin "@baseboard_fab2_lib.baseboard_fab2(sch_1):page183_i3:b"
				( attribute "PN" "2"
					( Origin gPackager )
				)
				( objectStatus "R9F55.2" )
			)
			( pin "@baseboard_fab2_lib.baseboard_fab2(sch_1):page145_i163:a"
				( attribute "PN" "1"
					( Origin gPackager )
				)
				( objectStatus "R25W121.1" )
			)
			( pin "@baseboard_fab2_lib.baseboard_fab2(sch_1):page145_i163:b"
				( attribute "PN" "2"
					( Origin gPackager )
				)
				( objectStatus "R25W121.2" )
			)
			( pin "@baseboard_fab2_lib.baseboard_fab2(sch_1):page145_i164:a"
				( attribute "PN" "1"
					( Origin gPackager )
				)
				( objectStatus "R25W122.1" )
			)
			( pin "@baseboard_fab2_lib.baseboard_fab2(sch_1):page145_i164:b"
				( attribute "PN" "2"
					( Origin gPackager )
				)
				( objectStatus "R25W122.2" )
			)
			( pin "@baseboard_fab2_lib.baseboard_fab2(sch_1):page172_i67:h1"
				( attribute "PN" "H1"
					( Origin gPackager )
				)
				( objectStatus "J2W1.H1" )
			)
			( pin "@baseboard_fab2_lib.baseboard_fab2(sch_1):page172_i67:h2"
				( attribute "PN" "H2"
					( Origin gPackager )
				)
				( objectStatus "J2W1.H2" )
			)
			( pin "@baseboard_fab2_lib.baseboard_fab2(sch_1):page172_i67:np1"
				( attribute "PN" "NP1"
					( Origin gPackager )
				)
				( objectStatus "J2W1.NP1" )
			)
			( pin "@baseboard_fab2_lib.baseboard_fab2(sch_1):page172_i67:np2"
				( attribute "PN" "NP2"
					( Origin gPackager )
				)
				( objectStatus "J2W1.NP2" )
			)
			( pin "@baseboard_fab2_lib.baseboard_fab2(sch_1):page172_i67:p1"
				( attribute "PN" "P1"
					( Origin gPackager )
				)
				( objectStatus "J2W1.P1" )
			)
			( pin "@baseboard_fab2_lib.baseboard_fab2(sch_1):page172_i67:p2"
				( attribute "PN" "P2"
					( Origin gPackager )
				)
				( objectStatus "J2W1.P2" )
			)
			( pin "@baseboard_fab2_lib.baseboard_fab2(sch_1):page172_i67:p3"
				( attribute "PN" "P3"
					( Origin gPackager )
				)
				( objectStatus "J2W1.P3" )
			)
			( pin "@baseboard_fab2_lib.baseboard_fab2(sch_1):page172_i67:p4"
				( attribute "PN" "P4"
					( Origin gPackager )
				)
				( objectStatus "J2W1.P4" )
			)
			( pin "@baseboard_fab2_lib.baseboard_fab2(sch_1):page172_i67:p5"
				( attribute "PN" "P5"
					( Origin gPackager )
				)
				( objectStatus "J2W1.P5" )
			)
			( pin "@baseboard_fab2_lib.baseboard_fab2(sch_1):page172_i67:p6"
				( attribute "PN" "P6"
					( Origin gPackager )
				)
				( objectStatus "J2W1.P6" )
			)
			( pin "@baseboard_fab2_lib.baseboard_fab2(sch_1):page172_i67:s1"
				( attribute "PN" "S1"
					( Origin gPackager )
				)
				( objectStatus "J2W1.S1" )
			)
			( pin "@baseboard_fab2_lib.baseboard_fab2(sch_1):page172_i67:s2"
				( attribute "PN" "S2"
					( Origin gPackager )
				)
				( objectStatus "J2W1.S2" )
			)
			( pin "@baseboard_fab2_lib.baseboard_fab2(sch_1):page172_i67:s3"
				( attribute "PN" "S3"
					( Origin gPackager )
				)
				( objectStatus "J2W1.S3" )
			)
			( pin "@baseboard_fab2_lib.baseboard_fab2(sch_1):page172_i67:s4"
				( attribute "PN" "S4"
					( Origin gPackager )
				)
				( objectStatus "J2W1.S4" )
			)
			( pin "@baseboard_fab2_lib.baseboard_fab2(sch_1):page172_i67:s5"
				( attribute "PN" "S5"
					( Origin gPackager )
				)
				( objectStatus "J2W1.S5" )
			)
			( pin "@baseboard_fab2_lib.baseboard_fab2(sch_1):page172_i67:s6"
				( attribute "PN" "S6"
					( Origin gPackager )
				)
				( objectStatus "J2W1.S6" )
			)
			( pin "@baseboard_fab2_lib.baseboard_fab2(sch_1):page172_i67:s7"
				( attribute "PN" "S7"
					( Origin gPackager )
				)
				( objectStatus "J2W1.S7" )
			)
			( pin "@baseboard_fab2_lib.baseboard_fab2(sch_1):page172_i68:h1"
				( attribute "PN" "H1"
					( Origin gPackager )
				)
				( objectStatus "J2W2.H1" )
			)
			( pin "@baseboard_fab2_lib.baseboard_fab2(sch_1):page172_i68:h2"
				( attribute "PN" "H2"
					( Origin gPackager )
				)
				( objectStatus "J2W2.H2" )
			)
			( pin "@baseboard_fab2_lib.baseboard_fab2(sch_1):page172_i68:np1"
				( attribute "PN" "NP1"
					( Origin gPackager )
				)
				( objectStatus "J2W2.NP1" )
			)
			( pin "@baseboard_fab2_lib.baseboard_fab2(sch_1):page172_i68:np2"
				( attribute "PN" "NP2"
					( Origin gPackager )
				)
				( objectStatus "J2W2.NP2" )
			)
			( pin "@baseboard_fab2_lib.baseboard_fab2(sch_1):page172_i68:p1"
				( attribute "PN" "P1"
					( Origin gPackager )
				)
				( objectStatus "J2W2.P1" )
			)
			( pin "@baseboard_fab2_lib.baseboard_fab2(sch_1):page172_i68:p2"
				( attribute "PN" "P2"
					( Origin gPackager )
				)
				( objectStatus "J2W2.P2" )
			)
			( pin "@baseboard_fab2_lib.baseboard_fab2(sch_1):page172_i68:p3"
				( attribute "PN" "P3"
					( Origin gPackager )
				)
				( objectStatus "J2W2.P3" )
			)
			( pin "@baseboard_fab2_lib.baseboard_fab2(sch_1):page172_i68:p4"
				( attribute "PN" "P4"
					( Origin gPackager )
				)
				( objectStatus "J2W2.P4" )
			)
			( pin "@baseboard_fab2_lib.baseboard_fab2(sch_1):page172_i68:p5"
				( attribute "PN" "P5"
					( Origin gPackager )
				)
				( objectStatus "J2W2.P5" )
			)
			( pin "@baseboard_fab2_lib.baseboard_fab2(sch_1):page172_i68:p6"
				( attribute "PN" "P6"
					( Origin gPackager )
				)
				( objectStatus "J2W2.P6" )
			)
			( pin "@baseboard_fab2_lib.baseboard_fab2(sch_1):page172_i68:s1"
				( attribute "PN" "S1"
					( Origin gPackager )
				)
				( objectStatus "J2W2.S1" )
			)
			( pin "@baseboard_fab2_lib.baseboard_fab2(sch_1):page172_i68:s2"
				( attribute "PN" "S2"
					( Origin gPackager )
				)
				( objectStatus "J2W2.S2" )
			)
			( pin "@baseboard_fab2_lib.baseboard_fab2(sch_1):page172_i68:s3"
				( attribute "PN" "S3"
					( Origin gPackager )
				)
				( objectStatus "J2W2.S3" )
			)
			( pin "@baseboard_fab2_lib.baseboard_fab2(sch_1):page172_i68:s4"
				( attribute "PN" "S4"
					( Origin gPackager )
				)
				( objectStatus "J2W2.S4" )
			)
			( pin "@baseboard_fab2_lib.baseboard_fab2(sch_1):page172_i68:s5"
				( attribute "PN" "S5"
					( Origin gPackager )
				)
				( objectStatus "J2W2.S5" )
			)
			( pin "@baseboard_fab2_lib.baseboard_fab2(sch_1):page172_i68:s6"
				( attribute "PN" "S6"
					( Origin gPackager )
				)
				( objectStatus "J2W2.S6" )
			)
			( pin "@baseboard_fab2_lib.baseboard_fab2(sch_1):page172_i68:s7"
				( attribute "PN" "S7"
					( Origin gPackager )
				)
				( objectStatus "J2W2.S7" )
			)
			( pin "@baseboard_fab2_lib.baseboard_fab2(sch_1):page141_i134:a"
				( attribute "PN" "1"
					( Origin gPackager )
				)
				( objectStatus "R9G2.1" )
			)
			( pin "@baseboard_fab2_lib.baseboard_fab2(sch_1):page141_i134:b"
				( attribute "PN" "2"
					( Origin gPackager )
				)
				( objectStatus "R9G2.2" )
			)
			( pin "@baseboard_fab2_lib.baseboard_fab2(sch_1):page141_i135:a"
				( attribute "PN" "1"
					( Origin gPackager )
				)
				( objectStatus "R9G3.1" )
			)
			( pin "@baseboard_fab2_lib.baseboard_fab2(sch_1):page141_i135:b"
				( attribute "PN" "2"
					( Origin gPackager )
				)
				( objectStatus "R9G3.2" )
			)
			( pin "@baseboard_fab2_lib.baseboard_fab2(sch_1):page141_i138:a"
				( attribute "PN" "1"
					( Origin gPackager )
				)
				( objectStatus "C9G3.1" )
			)
			( pin "@baseboard_fab2_lib.baseboard_fab2(sch_1):page141_i138:b"
				( attribute "PN" "2"
					( Origin gPackager )
				)
				( objectStatus "C9G3.2" )
			)
			( pin "@baseboard_fab2_lib.baseboard_fab2(sch_1):page141_i140:a"
				( attribute "PN" "1"
					( Origin gPackager )
				)
				( objectStatus "C9G1.1" )
			)
			( pin "@baseboard_fab2_lib.baseboard_fab2(sch_1):page141_i140:b"
				( attribute "PN" "2"
					( Origin gPackager )
				)
				( objectStatus "C9G1.2" )
			)
			( pin "@baseboard_fab2_lib.baseboard_fab2(sch_1):page141_i152:a"
				( attribute "PN" "1"
					( Origin gPackager )
				)
				( objectStatus "C9G2.1" )
			)
			( pin "@baseboard_fab2_lib.baseboard_fab2(sch_1):page141_i152:b"
				( attribute "PN" "2"
					( Origin gPackager )
				)
				( objectStatus "C9G2.2" )
			)
			( pin "@baseboard_fab2_lib.baseboard_fab2(sch_1):page141_i156:a"
				( attribute "PN" "1"
					( Origin gPackager )
				)
				( objectStatus "R9G4.1" )
			)
			( pin "@baseboard_fab2_lib.baseboard_fab2(sch_1):page141_i156:b"
				( attribute "PN" "2"
					( Origin gPackager )
				)
				( objectStatus "R9G4.2" )
			)
			( pin "@baseboard_fab2_lib.baseboard_fab2(sch_1):page141_i157:a"
				( attribute "PN" "1"
					( Origin gPackager )
				)
				( objectStatus "R9G1.1" )
			)
			( pin "@baseboard_fab2_lib.baseboard_fab2(sch_1):page141_i157:b"
				( attribute "PN" "2"
					( Origin gPackager )
				)
				( objectStatus "R9G1.2" )
			)
			( pin "@baseboard_fab2_lib.baseboard_fab2(sch_1):page141_i159:a"
				( attribute "PN" "1"
					( Origin gPackager )
				)
				( objectStatus "C9F22.1" )
			)
			( pin "@baseboard_fab2_lib.baseboard_fab2(sch_1):page141_i159:b"
				( attribute "PN" "2"
					( Origin gPackager )
				)
				( objectStatus "C9F22.2" )
			)
			( pin "@baseboard_fab2_lib.baseboard_fab2(sch_1):page202_i109:f"
				( attribute "PN" "2"
					( Origin gPackager )
				)
				( objectStatus "L4E1.2" )
			)
			( pin "@baseboard_fab2_lib.baseboard_fab2(sch_1):page202_i109:s"
				( attribute "PN" "1"
					( Origin gPackager )
				)
				( objectStatus "L4E1.1" )
			)
			( pin "@baseboard_fab2_lib.baseboard_fab2(sch_1):page203_i131:f"
				( attribute "PN" "2"
					( Origin gPackager )
				)
				( objectStatus "L4D1.2" )
			)
			( pin "@baseboard_fab2_lib.baseboard_fab2(sch_1):page203_i131:s"
				( attribute "PN" "1"
					( Origin gPackager )
				)
				( objectStatus "L4D1.1" )
			)
			( pin "@baseboard_fab2_lib.baseboard_fab2(sch_1):page208_i116:f"
				( attribute "PN" "2"
					( Origin gPackager )
				)
				( objectStatus "L1D2.2" )
			)
			( pin "@baseboard_fab2_lib.baseboard_fab2(sch_1):page208_i116:s"
				( attribute "PN" "1"
					( Origin gPackager )
				)
				( objectStatus "L1D2.1" )
			)
			( pin "@baseboard_fab2_lib.baseboard_fab2(sch_1):page208_i117:f"
				( attribute "PN" "2"
					( Origin gPackager )
				)
				( objectStatus "L1D1.2" )
			)
			( pin "@baseboard_fab2_lib.baseboard_fab2(sch_1):page208_i117:s"
				( attribute "PN" "1"
					( Origin gPackager )
				)
				( objectStatus "L1D1.1" )
			)
			( pin "@baseboard_fab2_lib.baseboard_fab2(sch_1):page230_i36:a"
				( attribute "PN" "1"
					( Origin gPackager )
				)
				( objectStatus "C4A14.1" )
			)
			( pin "@baseboard_fab2_lib.baseboard_fab2(sch_1):page230_i36:b"
				( attribute "PN" "2"
					( Origin gPackager )
				)
				( objectStatus "C4A14.2" )
			)
			( pin "@baseboard_fab2_lib.baseboard_fab2(sch_1):page230_i35:a"
				( attribute "PN" "1"
					( Origin gPackager )
				)
				( objectStatus "C6L5.1" )
			)
			( pin "@baseboard_fab2_lib.baseboard_fab2(sch_1):page230_i35:b"
				( attribute "PN" "2"
					( Origin gPackager )
				)
				( objectStatus "C6L5.2" )
			)
			( pin "@baseboard_fab2_lib.baseboard_fab2(sch_1):page230_i32:a"
				( attribute "PN" "1"
					( Origin gPackager )
				)
				( objectStatus "R4A4.1" )
			)
			( pin "@baseboard_fab2_lib.baseboard_fab2(sch_1):page230_i32:b"
				( attribute "PN" "2"
					( Origin gPackager )
				)
				( objectStatus "R4A4.2" )
			)
			( pin "@baseboard_fab2_lib.baseboard_fab2(sch_1):page230_i24:a"
				( attribute "PN" "1"
					( Origin gPackager )
				)
				( objectStatus "C8M12.1" )
			)
			( pin "@baseboard_fab2_lib.baseboard_fab2(sch_1):page230_i24:b"
				( attribute "PN" "2"
					( Origin gPackager )
				)
				( objectStatus "C8M12.2" )
			)
			( pin "@baseboard_fab2_lib.baseboard_fab2(sch_1):page230_i23:a"
				( attribute "PN" "1"
					( Origin gPackager )
				)
				( objectStatus "C4A3.1" )
			)
			( pin "@baseboard_fab2_lib.baseboard_fab2(sch_1):page230_i23:b"
				( attribute "PN" "2"
					( Origin gPackager )
				)
				( objectStatus "C4A3.2" )
			)
			( pin "@baseboard_fab2_lib.baseboard_fab2(sch_1):page255_i136:\1\"
				( attribute "PN" "1"
					( Origin gPackager )
				)
				( objectStatus "J25W1.1" )
			)
			( pin "@baseboard_fab2_lib.baseboard_fab2(sch_1):page255_i136:\2\"
				( attribute "PN" "2"
					( Origin gPackager )
				)
				( objectStatus "J25W1.2" )
			)
			( pin "@baseboard_fab2_lib.baseboard_fab2(sch_1):page255_i136:\3\"
				( attribute "PN" "3"
					( Origin gPackager )
				)
				( objectStatus "J25W1.3" )
			)
			( pin "@baseboard_fab2_lib.baseboard_fab2(sch_1):page255_i136:\4\"
				( attribute "PN" "4"
					( Origin gPackager )
				)
				( objectStatus "J25W1.4" )
			)
			( pin "@baseboard_fab2_lib.baseboard_fab2(sch_1):page255_i136:\5\"
				( attribute "PN" "5"
					( Origin gPackager )
				)
				( objectStatus "J25W1.5" )
			)
			( pin "@baseboard_fab2_lib.baseboard_fab2(sch_1):page255_i136:\6\"
				( attribute "PN" "6"
					( Origin gPackager )
				)
				( objectStatus "J25W1.6" )
			)
			( pin "@baseboard_fab2_lib.baseboard_fab2(sch_1):page255_i136:\7\"
				( attribute "PN" "7"
					( Origin gPackager )
				)
				( objectStatus "J25W1.7" )
			)
			( pin "@baseboard_fab2_lib.baseboard_fab2(sch_1):page255_i136:\8\"
				( attribute "PN" "8"
					( Origin gPackager )
				)
				( objectStatus "J25W1.8" )
			)
			( pin "@baseboard_fab2_lib.baseboard_fab2(sch_1):page255_i136:\9\"
				( attribute "PN" "9"
					( Origin gPackager )
				)
				( objectStatus "J25W1.9" )
			)
			( pin "@baseboard_fab2_lib.baseboard_fab2(sch_1):page255_i136:\10\"
				( attribute "PN" "10"
					( Origin gPackager )
				)
				( objectStatus "J25W1.10" )
			)
			( pin "@baseboard_fab2_lib.baseboard_fab2(sch_1):page255_i136:\11\"
				( attribute "PN" "11"
					( Origin gPackager )
				)
				( objectStatus "J25W1.11" )
			)
			( pin "@baseboard_fab2_lib.baseboard_fab2(sch_1):page255_i136:\12\"
				( attribute "PN" "12"
					( Origin gPackager )
				)
				( objectStatus "J25W1.12" )
			)
			( pin "@baseboard_fab2_lib.baseboard_fab2(sch_1):page255_i136:\13\"
				( attribute "PN" "13"
					( Origin gPackager )
				)
				( objectStatus "J25W1.13" )
			)
			( pin "@baseboard_fab2_lib.baseboard_fab2(sch_1):page255_i136:pth1"
				( attribute "PN" "PTH1"
					( Origin gPackager )
				)
				( objectStatus "J25W1.PTH1" )
			)
			( pin "@baseboard_fab2_lib.baseboard_fab2(sch_1):page255_i136:pth2"
				( attribute "PN" "PTH2"
					( Origin gPackager )
				)
				( objectStatus "J25W1.PTH2" )
			)
			( pin "@baseboard_fab2_lib.baseboard_fab2(sch_1):page172_i71:\1\"
				( attribute "PN" "1"
					( Origin gPackager )
				)
				( objectStatus "F8B1.1" )
			)
			( pin "@baseboard_fab2_lib.baseboard_fab2(sch_1):page172_i71:\2\"
				( attribute "PN" "2"
					( Origin gPackager )
				)
				( objectStatus "F8B1.2" )
			)
			( pin "@baseboard_fab2_lib.baseboard_fab2(sch_1):page240_i189:\1\"
				( attribute "PN" "1"
					( Origin gPackager )
				)
				( objectStatus "C8F14.1" )
			)
			( pin "@baseboard_fab2_lib.baseboard_fab2(sch_1):page240_i189:\2\"
				( attribute "PN" "2"
					( Origin gPackager )
				)
				( objectStatus "C8F14.2" )
			)
			( pin "@baseboard_fab2_lib.baseboard_fab2(sch_1):page147_i159:a"
				( attribute "PN" "1"
					( Origin gPackager )
				)
				( objectStatus "R25W143.1" )
			)
			( pin "@baseboard_fab2_lib.baseboard_fab2(sch_1):page147_i159:b"
				( attribute "PN" "2"
					( Origin gPackager )
				)
				( objectStatus "R25W143.2" )
			)
			( pin "@baseboard_fab2_lib.baseboard_fab2(sch_1):page240_i188:\1\"
				( attribute "PN" "1"
					( Origin gPackager )
				)
				( objectStatus "L8F1.1" )
			)
			( pin "@baseboard_fab2_lib.baseboard_fab2(sch_1):page240_i188:\2\"
				( attribute "PN" "2"
					( Origin gPackager )
				)
				( objectStatus "L8F1.2" )
			)
			( pin "@baseboard_fab2_lib.baseboard_fab2(sch_1):page240_i190:\1\"
				( attribute "PN" "1"
					( Origin gPackager )
				)
				( objectStatus "C8F8.1" )
			)
			( pin "@baseboard_fab2_lib.baseboard_fab2(sch_1):page240_i190:\2\"
				( attribute "PN" "2"
					( Origin gPackager )
				)
				( objectStatus "C8F8.2" )
			)
			( pin "@baseboard_fab2_lib.baseboard_fab2(sch_1):page185_i143:\1\"
				( attribute "PN" "1"
					( Origin gPackager )
				)
				( objectStatus "J8F1.1" )
			)
			( pin "@baseboard_fab2_lib.baseboard_fab2(sch_1):page185_i143:\2\"
				( attribute "PN" "2"
					( Origin gPackager )
				)
				( objectStatus "J8F1.2" )
			)
			( pin "@baseboard_fab2_lib.baseboard_fab2(sch_1):page185_i143:\3\"
				( attribute "PN" "3"
					( Origin gPackager )
				)
				( objectStatus "J8F1.3" )
			)
			( pin "@baseboard_fab2_lib.baseboard_fab2(sch_1):page185_i143:\4\"
				( attribute "PN" "4"
					( Origin gPackager )
				)
				( objectStatus "J8F1.4" )
			)
			( pin "@baseboard_fab2_lib.baseboard_fab2(sch_1):page185_i143:\5\"
				( attribute "PN" "5"
					( Origin gPackager )
				)
				( objectStatus "J8F1.5" )
			)
			( pin "@baseboard_fab2_lib.baseboard_fab2(sch_1):page185_i143:\6\"
				( attribute "PN" "6"
					( Origin gPackager )
				)
				( objectStatus "J8F1.6" )
			)
			( pin "@baseboard_fab2_lib.baseboard_fab2(sch_1):page185_i143:\7\"
				( attribute "PN" "7"
					( Origin gPackager )
				)
				( objectStatus "J8F1.7" )
			)
			( pin "@baseboard_fab2_lib.baseboard_fab2(sch_1):page185_i143:\8\"
				( attribute "PN" "8"
					( Origin gPackager )
				)
				( objectStatus "J8F1.8" )
			)
			( pin "@baseboard_fab2_lib.baseboard_fab2(sch_1):page185_i143:\9\"
				( attribute "PN" "9"
					( Origin gPackager )
				)
				( objectStatus "J8F1.9" )
			)
			( pin "@baseboard_fab2_lib.baseboard_fab2(sch_1):page185_i143:\10\"
				( attribute "PN" "10"
					( Origin gPackager )
				)
				( objectStatus "J8F1.10" )
			)
			( pin "@baseboard_fab2_lib.baseboard_fab2(sch_1):page185_i143:\11\"
				( attribute "PN" "11"
					( Origin gPackager )
				)
				( objectStatus "J8F1.11" )
			)
			( pin "@baseboard_fab2_lib.baseboard_fab2(sch_1):page185_i143:\12\"
				( attribute "PN" "12"
					( Origin gPackager )
				)
				( objectStatus "J8F1.12" )
			)
			( pin "@baseboard_fab2_lib.baseboard_fab2(sch_1):page185_i143:\13\"
				( attribute "PN" "13"
					( Origin gPackager )
				)
				( objectStatus "J8F1.13" )
			)
			( pin "@baseboard_fab2_lib.baseboard_fab2(sch_1):page185_i143:\14\"
				( attribute "PN" "14"
					( Origin gPackager )
				)
				( objectStatus "J8F1.14" )
			)
			( pin "@baseboard_fab2_lib.baseboard_fab2(sch_1):page185_i143:\15\"
				( attribute "PN" "15"
					( Origin gPackager )
				)
				( objectStatus "J8F1.15" )
			)
			( pin "@baseboard_fab2_lib.baseboard_fab2(sch_1):page185_i143:\16\"
				( attribute "PN" "16"
					( Origin gPackager )
				)
				( objectStatus "J8F1.16" )
			)
			( pin "@baseboard_fab2_lib.baseboard_fab2(sch_1):page185_i143:\17\"
				( attribute "PN" "17"
					( Origin gPackager )
				)
				( objectStatus "J8F1.17" )
			)
			( pin "@baseboard_fab2_lib.baseboard_fab2(sch_1):page185_i143:\18\"
				( attribute "PN" "18"
					( Origin gPackager )
				)
				( objectStatus "J8F1.18" )
			)
			( pin "@baseboard_fab2_lib.baseboard_fab2(sch_1):page185_i143:\19\"
				( attribute "PN" "19"
					( Origin gPackager )
				)
				( objectStatus "J8F1.19" )
			)
			( pin "@baseboard_fab2_lib.baseboard_fab2(sch_1):page185_i143:\20\"
				( attribute "PN" "20"
					( Origin gPackager )
				)
				( objectStatus "J8F1.20" )
			)
			( pin "@baseboard_fab2_lib.baseboard_fab2(sch_1):page185_i143:\21\"
				( attribute "PN" "21"
					( Origin gPackager )
				)
				( objectStatus "J8F1.21" )
			)
			( pin "@baseboard_fab2_lib.baseboard_fab2(sch_1):page185_i143:\22\"
				( attribute "PN" "22"
					( Origin gPackager )
				)
				( objectStatus "J8F1.22" )
			)
			( pin "@baseboard_fab2_lib.baseboard_fab2(sch_1):page185_i143:\23\"
				( attribute "PN" "23"
					( Origin gPackager )
				)
				( objectStatus "J8F1.23" )
			)
			( pin "@baseboard_fab2_lib.baseboard_fab2(sch_1):page185_i143:\24\"
				( attribute "PN" "24"
					( Origin gPackager )
				)
				( objectStatus "J8F1.24" )
			)
			( pin "@baseboard_fab2_lib.baseboard_fab2(sch_1):page185_i143:\25\"
				( attribute "PN" "25"
					( Origin gPackager )
				)
				( objectStatus "J8F1.25" )
			)
			( pin "@baseboard_fab2_lib.baseboard_fab2(sch_1):page185_i143:\26\"
				( attribute "PN" "26"
					( Origin gPackager )
				)
				( objectStatus "J8F1.26" )
			)
			( pin "@baseboard_fab2_lib.baseboard_fab2(sch_1):page185_i143:\27\"
				( attribute "PN" "27"
					( Origin gPackager )
				)
				( objectStatus "J8F1.27" )
			)
			( pin "@baseboard_fab2_lib.baseboard_fab2(sch_1):page185_i143:\28\"
				( attribute "PN" "28"
					( Origin gPackager )
				)
				( objectStatus "J8F1.28" )
			)
			( pin "@baseboard_fab2_lib.baseboard_fab2(sch_1):page185_i143:\29\"
				( attribute "PN" "29"
					( Origin gPackager )
				)
				( objectStatus "J8F1.29" )
			)
			( pin "@baseboard_fab2_lib.baseboard_fab2(sch_1):page185_i143:\30\"
				( attribute "PN" "30"
					( Origin gPackager )
				)
				( objectStatus "J8F1.30" )
			)
			( pin "@baseboard_fab2_lib.baseboard_fab2(sch_1):page185_i143:\31\"
				( attribute "PN" "31"
					( Origin gPackager )
				)
				( objectStatus "J8F1.31" )
			)
			( pin "@baseboard_fab2_lib.baseboard_fab2(sch_1):page185_i143:\32\"
				( attribute "PN" "32"
					( Origin gPackager )
				)
				( objectStatus "J8F1.32" )
			)
			( pin "@baseboard_fab2_lib.baseboard_fab2(sch_1):page185_i143:\33\"
				( attribute "PN" "33"
					( Origin gPackager )
				)
				( objectStatus "J8F1.33" )
			)
			( pin "@baseboard_fab2_lib.baseboard_fab2(sch_1):page185_i143:\34\"
				( attribute "PN" "34"
					( Origin gPackager )
				)
				( objectStatus "J8F1.34" )
			)
			( pin "@baseboard_fab2_lib.baseboard_fab2(sch_1):page185_i143:\35\"
				( attribute "PN" "35"
					( Origin gPackager )
				)
				( objectStatus "J8F1.35" )
			)
			( pin "@baseboard_fab2_lib.baseboard_fab2(sch_1):page185_i143:\36\"
				( attribute "PN" "36"
					( Origin gPackager )
				)
				( objectStatus "J8F1.36" )
			)
			( pin "@baseboard_fab2_lib.baseboard_fab2(sch_1):page185_i143:\37\"
				( attribute "PN" "37"
					( Origin gPackager )
				)
				( objectStatus "J8F1.37" )
			)
			( pin "@baseboard_fab2_lib.baseboard_fab2(sch_1):page185_i143:\38\"
				( attribute "PN" "38"
					( Origin gPackager )
				)
				( objectStatus "J8F1.38" )
			)
			( pin "@baseboard_fab2_lib.baseboard_fab2(sch_1):page185_i143:\39\"
				( attribute "PN" "39"
					( Origin gPackager )
				)
				( objectStatus "J8F1.39" )
			)
			( pin "@baseboard_fab2_lib.baseboard_fab2(sch_1):page185_i143:\40\"
				( attribute "PN" "40"
					( Origin gPackager )
				)
				( objectStatus "J8F1.40" )
			)
			( pin "@baseboard_fab2_lib.baseboard_fab2(sch_1):page185_i143:\41\"
				( attribute "PN" "41"
					( Origin gPackager )
				)
				( objectStatus "J8F1.41" )
			)
			( pin "@baseboard_fab2_lib.baseboard_fab2(sch_1):page185_i143:\42\"
				( attribute "PN" "42"
					( Origin gPackager )
				)
				( objectStatus "J8F1.42" )
			)
			( pin "@baseboard_fab2_lib.baseboard_fab2(sch_1):page185_i143:\43\"
				( attribute "PN" "43"
					( Origin gPackager )
				)
				( objectStatus "J8F1.43" )
			)
			( pin "@baseboard_fab2_lib.baseboard_fab2(sch_1):page185_i143:\44\"
				( attribute "PN" "44"
					( Origin gPackager )
				)
				( objectStatus "J8F1.44" )
			)
			( pin "@baseboard_fab2_lib.baseboard_fab2(sch_1):page185_i143:\45\"
				( attribute "PN" "45"
					( Origin gPackager )
				)
				( objectStatus "J8F1.45" )
			)
			( pin "@baseboard_fab2_lib.baseboard_fab2(sch_1):page185_i143:\46\"
				( attribute "PN" "46"
					( Origin gPackager )
				)
				( objectStatus "J8F1.46" )
			)
			( pin "@baseboard_fab2_lib.baseboard_fab2(sch_1):page185_i143:\47\"
				( attribute "PN" "47"
					( Origin gPackager )
				)
				( objectStatus "J8F1.47" )
			)
			( pin "@baseboard_fab2_lib.baseboard_fab2(sch_1):page185_i143:\48\"
				( attribute "PN" "48"
					( Origin gPackager )
				)
				( objectStatus "J8F1.48" )
			)
			( pin "@baseboard_fab2_lib.baseboard_fab2(sch_1):page185_i143:\49\"
				( attribute "PN" "49"
					( Origin gPackager )
				)
				( objectStatus "J8F1.49" )
			)
			( pin "@baseboard_fab2_lib.baseboard_fab2(sch_1):page185_i143:\50\"
				( attribute "PN" "50"
					( Origin gPackager )
				)
				( objectStatus "J8F1.50" )
			)
			( pin "@baseboard_fab2_lib.baseboard_fab2(sch_1):page185_i143:\51\"
				( attribute "PN" "51"
					( Origin gPackager )
				)
				( objectStatus "J8F1.51" )
			)
			( pin "@baseboard_fab2_lib.baseboard_fab2(sch_1):page185_i143:\52\"
				( attribute "PN" "52"
					( Origin gPackager )
				)
				( objectStatus "J8F1.52" )
			)
			( pin "@baseboard_fab2_lib.baseboard_fab2(sch_1):page185_i143:\53\"
				( attribute "PN" "53"
					( Origin gPackager )
				)
				( objectStatus "J8F1.53" )
			)
			( pin "@baseboard_fab2_lib.baseboard_fab2(sch_1):page185_i143:\54\"
				( attribute "PN" "54"
					( Origin gPackager )
				)
				( objectStatus "J8F1.54" )
			)
			( pin "@baseboard_fab2_lib.baseboard_fab2(sch_1):page185_i143:\55\"
				( attribute "PN" "55"
					( Origin gPackager )
				)
				( objectStatus "J8F1.55" )
			)
			( pin "@baseboard_fab2_lib.baseboard_fab2(sch_1):page185_i143:\56\"
				( attribute "PN" "56"
					( Origin gPackager )
				)
				( objectStatus "J8F1.56" )
			)
			( pin "@baseboard_fab2_lib.baseboard_fab2(sch_1):page185_i143:\57\"
				( attribute "PN" "57"
					( Origin gPackager )
				)
				( objectStatus "J8F1.57" )
			)
			( pin "@baseboard_fab2_lib.baseboard_fab2(sch_1):page185_i143:\58\"
				( attribute "PN" "58"
					( Origin gPackager )
				)
				( objectStatus "J8F1.58" )
			)
			( pin "@baseboard_fab2_lib.baseboard_fab2(sch_1):page185_i143:\67\"
				( attribute "PN" "67"
					( Origin gPackager )
				)
				( objectStatus "J8F1.67" )
			)
			( pin "@baseboard_fab2_lib.baseboard_fab2(sch_1):page185_i143:\68\"
				( attribute "PN" "68"
					( Origin gPackager )
				)
				( objectStatus "J8F1.68" )
			)
			( pin "@baseboard_fab2_lib.baseboard_fab2(sch_1):page185_i143:\69\"
				( attribute "PN" "69"
					( Origin gPackager )
				)
				( objectStatus "J8F1.69" )
			)
			( pin "@baseboard_fab2_lib.baseboard_fab2(sch_1):page185_i143:\70\"
				( attribute "PN" "70"
					( Origin gPackager )
				)
				( objectStatus "J8F1.70" )
			)
			( pin "@baseboard_fab2_lib.baseboard_fab2(sch_1):page185_i143:\71\"
				( attribute "PN" "71"
					( Origin gPackager )
				)
				( objectStatus "J8F1.71" )
			)
			( pin "@baseboard_fab2_lib.baseboard_fab2(sch_1):page185_i143:\72\"
				( attribute "PN" "72"
					( Origin gPackager )
				)
				( objectStatus "J8F1.72" )
			)
			( pin "@baseboard_fab2_lib.baseboard_fab2(sch_1):page185_i143:\73\"
				( attribute "PN" "73"
					( Origin gPackager )
				)
				( objectStatus "J8F1.73" )
			)
			( pin "@baseboard_fab2_lib.baseboard_fab2(sch_1):page185_i143:\74\"
				( attribute "PN" "74"
					( Origin gPackager )
				)
				( objectStatus "J8F1.74" )
			)
			( pin "@baseboard_fab2_lib.baseboard_fab2(sch_1):page185_i143:\75\"
				( attribute "PN" "75"
					( Origin gPackager )
				)
				( objectStatus "J8F1.75" )
			)
			( pin "@baseboard_fab2_lib.baseboard_fab2(sch_1):page185_i143:\76\"
				( attribute "PN" "76"
					( Origin gPackager )
				)
				( objectStatus "J8F1.76" )
			)
			( pin "@baseboard_fab2_lib.baseboard_fab2(sch_1):page185_i143:\77\"
				( attribute "PN" "77"
					( Origin gPackager )
				)
				( objectStatus "J8F1.77" )
			)
			( pin "@baseboard_fab2_lib.baseboard_fab2(sch_1):page185_i143:np1"
				( attribute "PN" "NP1"
					( Origin gPackager )
				)
				( objectStatus "J8F1.NP1" )
			)
			( pin "@baseboard_fab2_lib.baseboard_fab2(sch_1):page185_i143:np2"
				( attribute "PN" "NP2"
					( Origin gPackager )
				)
				( objectStatus "J8F1.NP2" )
			)
			( pin "@baseboard_fab2_lib.baseboard_fab2(sch_1):page185_i167:a"
				( attribute "PN" "1"
					( Origin gPackager )
				)
				( objectStatus "C2T11.1" )
			)
			( pin "@baseboard_fab2_lib.baseboard_fab2(sch_1):page185_i167:b"
				( attribute "PN" "2"
					( Origin gPackager )
				)
				( objectStatus "C2T11.2" )
			)
			( pin "@baseboard_fab2_lib.baseboard_fab2(sch_1):page185_i168:a"
				( attribute "PN" "1"
					( Origin gPackager )
				)
				( objectStatus "C2T10.1" )
			)
			( pin "@baseboard_fab2_lib.baseboard_fab2(sch_1):page185_i168:b"
				( attribute "PN" "2"
					( Origin gPackager )
				)
				( objectStatus "C2T10.2" )
			)
			( pin "@baseboard_fab2_lib.baseboard_fab2(sch_1):page101_i134:a"
				( attribute "PN" "1"
					( Origin gPackager )
				)
				( objectStatus "R1W22.1" )
			)
			( pin "@baseboard_fab2_lib.baseboard_fab2(sch_1):page101_i134:b"
				( attribute "PN" "2"
					( Origin gPackager )
				)
				( objectStatus "R1W22.2" )
			)
			( pin "@baseboard_fab2_lib.baseboard_fab2(sch_1):page101_i135:a"
				( attribute "PN" "1"
					( Origin gPackager )
				)
				( objectStatus "R1W23.1" )
			)
			( pin "@baseboard_fab2_lib.baseboard_fab2(sch_1):page101_i135:b"
				( attribute "PN" "2"
					( Origin gPackager )
				)
				( objectStatus "R1W23.2" )
			)
			( pin "@baseboard_fab2_lib.baseboard_fab2(sch_1):page101_i138:a"
				( attribute "PN" "1"
					( Origin gPackager )
				)
				( objectStatus "R1W24.1" )
			)
			( pin "@baseboard_fab2_lib.baseboard_fab2(sch_1):page101_i138:b"
				( attribute "PN" "2"
					( Origin gPackager )
				)
				( objectStatus "R1W24.2" )
			)
			( pin "@baseboard_fab2_lib.baseboard_fab2(sch_1):page101_i139:a"
				( attribute "PN" "1"
					( Origin gPackager )
				)
				( objectStatus "C1W17.1" )
			)
			( pin "@baseboard_fab2_lib.baseboard_fab2(sch_1):page101_i139:b"
				( attribute "PN" "2"
					( Origin gPackager )
				)
				( objectStatus "C1W17.2" )
			)
			( pin "@baseboard_fab2_lib.baseboard_fab2(sch_1):page101_i140:a"
				( attribute "PN" "1"
					( Origin gPackager )
				)
				( objectStatus "R1W25.1" )
			)
			( pin "@baseboard_fab2_lib.baseboard_fab2(sch_1):page101_i140:b"
				( attribute "PN" "2"
					( Origin gPackager )
				)
				( objectStatus "R1W25.2" )
			)
			( pin "@baseboard_fab2_lib.baseboard_fab2(sch_1):page251_i26:a"
				( attribute "PN" "2"
					( Origin gPackager )
				)
				( objectStatus "CR10W3.2" )
			)
			( pin "@baseboard_fab2_lib.baseboard_fab2(sch_1):page251_i26:c"
				( attribute "PN" "1"
					( Origin gPackager )
				)
				( objectStatus "CR10W3.1" )
			)
			( pin "@baseboard_fab2_lib.baseboard_fab2(sch_1):page101_i142:a"
				( attribute "PN" "1"
					( Origin gPackager )
				)
				( objectStatus "R8F27.1" )
			)
			( pin "@baseboard_fab2_lib.baseboard_fab2(sch_1):page101_i142:b"
				( attribute "PN" "2"
					( Origin gPackager )
				)
				( objectStatus "R8F27.2" )
			)
			( pin "@baseboard_fab2_lib.baseboard_fab2(sch_1):page101_i144:a"
				( attribute "PN" "1"
					( Origin gPackager )
				)
				( objectStatus "R8G25.1" )
			)
			( pin "@baseboard_fab2_lib.baseboard_fab2(sch_1):page101_i144:b"
				( attribute "PN" "2"
					( Origin gPackager )
				)
				( objectStatus "R8G25.2" )
			)
			( pin "@baseboard_fab2_lib.baseboard_fab2(sch_1):page101_i145:a"
				( attribute "PN" "1"
					( Origin gPackager )
				)
				( objectStatus "R8G1.1" )
			)
			( pin "@baseboard_fab2_lib.baseboard_fab2(sch_1):page101_i145:b"
				( attribute "PN" "2"
					( Origin gPackager )
				)
				( objectStatus "R8G1.2" )
			)
			( pin "@baseboard_fab2_lib.baseboard_fab2(sch_1):page150_i216:a"
				( attribute "PN" "1"
					( Origin gPackager )
				)
				( objectStatus "R25W148.1" )
			)
			( pin "@baseboard_fab2_lib.baseboard_fab2(sch_1):page150_i216:b"
				( attribute "PN" "2"
					( Origin gPackager )
				)
				( objectStatus "R25W148.2" )
			)
			( pin "@baseboard_fab2_lib.baseboard_fab2(sch_1):page190_i349:a"
				( attribute "PN" "1"
					( Origin gPackager )
				)
				( objectStatus "R1W26.1" )
			)
			( pin "@baseboard_fab2_lib.baseboard_fab2(sch_1):page190_i349:b"
				( attribute "PN" "2"
					( Origin gPackager )
				)
				( objectStatus "R1W26.2" )
			)
			( pin "@baseboard_fab2_lib.baseboard_fab2(sch_1):page201_i187:a"
				( attribute "PN" "1"
					( Origin gPackager )
				)
				( objectStatus "R4E4.1" )
			)
			( pin "@baseboard_fab2_lib.baseboard_fab2(sch_1):page201_i187:b"
				( attribute "PN" "2"
					( Origin gPackager )
				)
				( objectStatus "R4E4.2" )
			)
			( pin "@baseboard_fab2_lib.baseboard_fab2(sch_1):page235_i247:a"
				( attribute "PN" "1"
					( Origin gPackager )
				)
				( objectStatus "R8W2.1" )
			)
			( pin "@baseboard_fab2_lib.baseboard_fab2(sch_1):page235_i247:b"
				( attribute "PN" "2"
					( Origin gPackager )
				)
				( objectStatus "R8W2.2" )
			)
			( pin "@baseboard_fab2_lib.baseboard_fab2(sch_1):page235_i248:a"
				( attribute "PN" "1"
					( Origin gPackager )
				)
				( objectStatus "R8W3.1" )
			)
			( pin "@baseboard_fab2_lib.baseboard_fab2(sch_1):page235_i248:b"
				( attribute "PN" "2"
					( Origin gPackager )
				)
				( objectStatus "R8W3.2" )
			)
			( pin "@baseboard_fab2_lib.baseboard_fab2(sch_1):page231_i229:a"
				( attribute "PN" "1"
					( Origin gPackager )
				)
				( objectStatus "R7F8.1" )
			)
			( pin "@baseboard_fab2_lib.baseboard_fab2(sch_1):page231_i229:b"
				( attribute "PN" "2"
					( Origin gPackager )
				)
				( objectStatus "R7F8.2" )
			)
			( pin "@baseboard_fab2_lib.baseboard_fab2(sch_1):page190_i351:a"
				( attribute "PN" "1"
					( Origin gPackager )
				)
				( objectStatus "R1W27.1" )
			)
			( pin "@baseboard_fab2_lib.baseboard_fab2(sch_1):page190_i351:b"
				( attribute "PN" "2"
					( Origin gPackager )
				)
				( objectStatus "R1W27.2" )
			)
			( pin "@baseboard_fab2_lib.baseboard_fab2(sch_1):page145_i173:a"
				( attribute "PN" "1"
					( Origin gPackager )
				)
				( objectStatus "R25W144.1" )
			)
			( pin "@baseboard_fab2_lib.baseboard_fab2(sch_1):page145_i173:b"
				( attribute "PN" "2"
					( Origin gPackager )
				)
				( objectStatus "R25W144.2" )
			)
			( pin "@baseboard_fab2_lib.baseboard_fab2(sch_1):page191_i197:a"
				( attribute "PN" "1"
					( Origin gPackager )
				)
				( objectStatus "R1W28.1" )
			)
			( pin "@baseboard_fab2_lib.baseboard_fab2(sch_1):page191_i197:b"
				( attribute "PN" "2"
					( Origin gPackager )
				)
				( objectStatus "R1W28.2" )
			)
			( pin "@baseboard_fab2_lib.baseboard_fab2(sch_1):page145_i175:a"
				( attribute "PN" "1"
					( Origin gPackager )
				)
				( objectStatus "R25W145.1" )
			)
			( pin "@baseboard_fab2_lib.baseboard_fab2(sch_1):page145_i175:b"
				( attribute "PN" "2"
					( Origin gPackager )
				)
				( objectStatus "R25W145.2" )
			)
			( pin "@baseboard_fab2_lib.baseboard_fab2(sch_1):page191_i198:a"
				( attribute "PN" "1"
					( Origin gPackager )
				)
				( objectStatus "R1W29.1" )
			)
			( pin "@baseboard_fab2_lib.baseboard_fab2(sch_1):page191_i198:b"
				( attribute "PN" "2"
					( Origin gPackager )
				)
				( objectStatus "R1W29.2" )
			)
			( pin "@baseboard_fab2_lib.baseboard_fab2(sch_1):page118_i168:a"
				( attribute "PN" "1"
					( Origin gPackager )
				)
				( objectStatus "R1W30.1" )
			)
			( pin "@baseboard_fab2_lib.baseboard_fab2(sch_1):page118_i168:b"
				( attribute "PN" "2"
					( Origin gPackager )
				)
				( objectStatus "R1W30.2" )
			)
			( pin "@baseboard_fab2_lib.baseboard_fab2(sch_1):page150_i196:a"
				( attribute "PN" "1"
					( Origin gPackager )
				)
				( objectStatus "R25W105.1" )
			)
			( pin "@baseboard_fab2_lib.baseboard_fab2(sch_1):page150_i196:b"
				( attribute "PN" "2"
					( Origin gPackager )
				)
				( objectStatus "R25W105.2" )
			)
			( pin "@baseboard_fab2_lib.baseboard_fab2(sch_1):page162_i35:a"
				( attribute "PN" "1"
					( Origin gPackager )
				)
				( objectStatus "R8F13.1" )
			)
			( pin "@baseboard_fab2_lib.baseboard_fab2(sch_1):page162_i35:b"
				( attribute "PN" "2"
					( Origin gPackager )
				)
				( objectStatus "R8F13.2" )
			)
			( pin "@baseboard_fab2_lib.baseboard_fab2(sch_1):page150_i199:a"
				( attribute "PN" "1"
					( Origin gPackager )
				)
				( objectStatus "R25W146.1" )
			)
			( pin "@baseboard_fab2_lib.baseboard_fab2(sch_1):page150_i199:b"
				( attribute "PN" "2"
					( Origin gPackager )
				)
				( objectStatus "R25W146.2" )
			)
			( pin "@baseboard_fab2_lib.baseboard_fab2(sch_1):page150_i209:a"
				( attribute "PN" "1"
					( Origin gPackager )
				)
				( objectStatus "R25W98.1" )
			)
			( pin "@baseboard_fab2_lib.baseboard_fab2(sch_1):page150_i209:b"
				( attribute "PN" "2"
					( Origin gPackager )
				)
				( objectStatus "R25W98.2" )
			)
			( pin "@baseboard_fab2_lib.baseboard_fab2(sch_1):page150_i210:a"
				( attribute "PN" "1"
					( Origin gPackager )
				)
				( objectStatus "R25W99.1" )
			)
			( pin "@baseboard_fab2_lib.baseboard_fab2(sch_1):page150_i210:b"
				( attribute "PN" "2"
					( Origin gPackager )
				)
				( objectStatus "R25W99.2" )
			)
			( pin "@baseboard_fab2_lib.baseboard_fab2(sch_1):page150_i211:a"
				( attribute "PN" "1"
					( Origin gPackager )
				)
				( objectStatus "R25W100.1" )
			)
			( pin "@baseboard_fab2_lib.baseboard_fab2(sch_1):page150_i211:b"
				( attribute "PN" "2"
					( Origin gPackager )
				)
				( objectStatus "R25W100.2" )
			)
			( pin "@baseboard_fab2_lib.baseboard_fab2(sch_1):page144_i148:a"
				( attribute "PN" "1"
					( Origin gPackager )
				)
				( objectStatus "R25W140.1" )
			)
			( pin "@baseboard_fab2_lib.baseboard_fab2(sch_1):page144_i148:b"
				( attribute "PN" "2"
					( Origin gPackager )
				)
				( objectStatus "R25W140.2" )
			)
			( pin "@baseboard_fab2_lib.baseboard_fab2(sch_1):page150_i214:a"
				( attribute "PN" "1"
					( Origin gPackager )
				)
				( objectStatus "R25W103.1" )
			)
			( pin "@baseboard_fab2_lib.baseboard_fab2(sch_1):page150_i214:b"
				( attribute "PN" "2"
					( Origin gPackager )
				)
				( objectStatus "R25W103.2" )
			)
			( pin "@baseboard_fab2_lib.baseboard_fab2(sch_1):page150_i215:a"
				( attribute "PN" "1"
					( Origin gPackager )
				)
				( objectStatus "R25W104.1" )
			)
			( pin "@baseboard_fab2_lib.baseboard_fab2(sch_1):page150_i215:b"
				( attribute "PN" "2"
					( Origin gPackager )
				)
				( objectStatus "R25W104.2" )
			)
			( pin "@baseboard_fab2_lib.baseboard_fab2(sch_1):page150_i218:a"
				( attribute "PN" "1"
					( Origin gPackager )
				)
				( objectStatus "R25W114.1" )
			)
			( pin "@baseboard_fab2_lib.baseboard_fab2(sch_1):page150_i218:b"
				( attribute "PN" "2"
					( Origin gPackager )
				)
				( objectStatus "R25W114.2" )
			)
			( pin "@baseboard_fab2_lib.baseboard_fab2(sch_1):page150_i219:a"
				( attribute "PN" "1"
					( Origin gPackager )
				)
				( objectStatus "R25W149.1" )
			)
			( pin "@baseboard_fab2_lib.baseboard_fab2(sch_1):page150_i219:b"
				( attribute "PN" "2"
					( Origin gPackager )
				)
				( objectStatus "R25W149.2" )
			)
			( pin "@baseboard_fab2_lib.baseboard_fab2(sch_1):page199_i138:a"
				( attribute "PN" "1"
					( Origin gPackager )
				)
				( objectStatus "R9P28.1" )
			)
			( pin "@baseboard_fab2_lib.baseboard_fab2(sch_1):page199_i138:b"
				( attribute "PN" "2"
					( Origin gPackager )
				)
				( objectStatus "R9P28.2" )
			)
			( pin "@baseboard_fab2_lib.baseboard_fab2(sch_1):page150_i229:a"
				( attribute "PN" "1"
					( Origin gPackager )
				)
				( objectStatus "R25W150.1" )
			)
			( pin "@baseboard_fab2_lib.baseboard_fab2(sch_1):page150_i229:b"
				( attribute "PN" "2"
					( Origin gPackager )
				)
				( objectStatus "R25W150.2" )
			)
			( pin "@baseboard_fab2_lib.baseboard_fab2(sch_1):page150_i233:a"
				( attribute "PN" "1"
					( Origin gPackager )
				)
				( objectStatus "R25W110.1" )
			)
			( pin "@baseboard_fab2_lib.baseboard_fab2(sch_1):page150_i233:b"
				( attribute "PN" "2"
					( Origin gPackager )
				)
				( objectStatus "R25W110.2" )
			)
			( pin "@baseboard_fab2_lib.baseboard_fab2(sch_1):page150_i234:a"
				( attribute "PN" "1"
					( Origin gPackager )
				)
				( objectStatus "R25W152.1" )
			)
			( pin "@baseboard_fab2_lib.baseboard_fab2(sch_1):page150_i234:b"
				( attribute "PN" "2"
					( Origin gPackager )
				)
				( objectStatus "R25W152.2" )
			)
			( pin "@baseboard_fab2_lib.baseboard_fab2(sch_1):page150_i236:a"
				( attribute "PN" "1"
					( Origin gPackager )
				)
				( objectStatus "R25W109.1" )
			)
			( pin "@baseboard_fab2_lib.baseboard_fab2(sch_1):page150_i236:b"
				( attribute "PN" "2"
					( Origin gPackager )
				)
				( objectStatus "R25W109.2" )
			)
			( pin "@baseboard_fab2_lib.baseboard_fab2(sch_1):page151_i210:a"
				( attribute "PN" "1"
					( Origin gPackager )
				)
				( objectStatus "R25W119.1" )
			)
			( pin "@baseboard_fab2_lib.baseboard_fab2(sch_1):page151_i210:b"
				( attribute "PN" "2"
					( Origin gPackager )
				)
				( objectStatus "R25W119.2" )
			)
			( pin "@baseboard_fab2_lib.baseboard_fab2(sch_1):page157_i394:a"
				( attribute "PN" "2"
					( Origin gPackager )
				)
				( objectStatus "U25W9.2" )
			)
			( pin "@baseboard_fab2_lib.baseboard_fab2(sch_1):page157_i394:y"
				( attribute "PN" "4"
					( Origin gPackager )
				)
				( objectStatus "U25W9.4" )
			)
			( pin "@baseboard_fab2_lib.baseboard_fab2(sch_1):page157_i396:a"
				( attribute "PN" "1"
					( Origin gPackager )
				)
				( objectStatus "R25W153.1" )
			)
			( pin "@baseboard_fab2_lib.baseboard_fab2(sch_1):page157_i396:b"
				( attribute "PN" "2"
					( Origin gPackager )
				)
				( objectStatus "R25W153.2" )
			)
			( pin "@baseboard_fab2_lib.baseboard_fab2(sch_1):page138_i186:a"
				( attribute "PN" "1"
					( Origin gPackager )
				)
				( objectStatus "R8B24.1" )
			)
			( pin "@baseboard_fab2_lib.baseboard_fab2(sch_1):page138_i186:b"
				( attribute "PN" "2"
					( Origin gPackager )
				)
				( objectStatus "R8B24.2" )
			)
			( pin "@baseboard_fab2_lib.baseboard_fab2(sch_1):page138_i187:a"
				( attribute "PN" "1"
					( Origin gPackager )
				)
				( objectStatus "R8B26.1" )
			)
			( pin "@baseboard_fab2_lib.baseboard_fab2(sch_1):page138_i187:b"
				( attribute "PN" "2"
					( Origin gPackager )
				)
				( objectStatus "R8B26.2" )
			)
			( pin "@baseboard_fab2_lib.baseboard_fab2(sch_1):page195_i114:\1_1\"
				( attribute "PN" "1_1"
					( Origin gPackager )
				)
				( objectStatus "J1E1.1_1" )
			)
			( pin "@baseboard_fab2_lib.baseboard_fab2(sch_1):page195_i114:\1_2\"
				( attribute "PN" "1_2"
					( Origin gPackager )
				)
				( objectStatus "J1E1.1_2" )
			)
			( pin "@baseboard_fab2_lib.baseboard_fab2(sch_1):page195_i114:\1_3\"
				( attribute "PN" "1_3"
					( Origin gPackager )
				)
				( objectStatus "J1E1.1_3" )
			)
			( pin "@baseboard_fab2_lib.baseboard_fab2(sch_1):page195_i114:\2_1\"
				( attribute "PN" "2_1"
					( Origin gPackager )
				)
				( objectStatus "J1E1.2_1" )
			)
			( pin "@baseboard_fab2_lib.baseboard_fab2(sch_1):page195_i114:\2_2\"
				( attribute "PN" "2_2"
					( Origin gPackager )
				)
				( objectStatus "J1E1.2_2" )
			)
			( pin "@baseboard_fab2_lib.baseboard_fab2(sch_1):page195_i114:\2_3\"
				( attribute "PN" "2_3"
					( Origin gPackager )
				)
				( objectStatus "J1E1.2_3" )
			)
			( pin "@baseboard_fab2_lib.baseboard_fab2(sch_1):page195_i114:\3_1\"
				( attribute "PN" "3_1"
					( Origin gPackager )
				)
				( objectStatus "J1E1.3_1" )
			)
			( pin "@baseboard_fab2_lib.baseboard_fab2(sch_1):page195_i114:\3_2\"
				( attribute "PN" "3_2"
					( Origin gPackager )
				)
				( objectStatus "J1E1.3_2" )
			)
			( pin "@baseboard_fab2_lib.baseboard_fab2(sch_1):page195_i114:\3_3\"
				( attribute "PN" "3_3"
					( Origin gPackager )
				)
				( objectStatus "J1E1.3_3" )
			)
			( pin "@baseboard_fab2_lib.baseboard_fab2(sch_1):page195_i114:\4_1\"
				( attribute "PN" "4_1"
					( Origin gPackager )
				)
				( objectStatus "J1E1.4_1" )
			)
			( pin "@baseboard_fab2_lib.baseboard_fab2(sch_1):page195_i114:\4_2\"
				( attribute "PN" "4_2"
					( Origin gPackager )
				)
				( objectStatus "J1E1.4_2" )
			)
			( pin "@baseboard_fab2_lib.baseboard_fab2(sch_1):page195_i114:\4_3\"
				( attribute "PN" "4_3"
					( Origin gPackager )
				)
				( objectStatus "J1E1.4_3" )
			)
			( pin "@baseboard_fab2_lib.baseboard_fab2(sch_1):page195_i114:np1"
				( attribute "PN" "NP1"
					( Origin gPackager )
				)
				( objectStatus "J1E1.NP1" )
			)
			( pin "@baseboard_fab2_lib.baseboard_fab2(sch_1):page195_i115:\1_1\"
				( attribute "PN" "1_1"
					( Origin gPackager )
				)
				( objectStatus "J1D1.1_1" )
			)
			( pin "@baseboard_fab2_lib.baseboard_fab2(sch_1):page195_i115:\1_2\"
				( attribute "PN" "1_2"
					( Origin gPackager )
				)
				( objectStatus "J1D1.1_2" )
			)
			( pin "@baseboard_fab2_lib.baseboard_fab2(sch_1):page195_i115:\1_3\"
				( attribute "PN" "1_3"
					( Origin gPackager )
				)
				( objectStatus "J1D1.1_3" )
			)
			( pin "@baseboard_fab2_lib.baseboard_fab2(sch_1):page195_i115:\2_1\"
				( attribute "PN" "2_1"
					( Origin gPackager )
				)
				( objectStatus "J1D1.2_1" )
			)
			( pin "@baseboard_fab2_lib.baseboard_fab2(sch_1):page195_i115:\2_2\"
				( attribute "PN" "2_2"
					( Origin gPackager )
				)
				( objectStatus "J1D1.2_2" )
			)
			( pin "@baseboard_fab2_lib.baseboard_fab2(sch_1):page195_i115:\2_3\"
				( attribute "PN" "2_3"
					( Origin gPackager )
				)
				( objectStatus "J1D1.2_3" )
			)
			( pin "@baseboard_fab2_lib.baseboard_fab2(sch_1):page195_i115:\3_1\"
				( attribute "PN" "3_1"
					( Origin gPackager )
				)
				( objectStatus "J1D1.3_1" )
			)
			( pin "@baseboard_fab2_lib.baseboard_fab2(sch_1):page195_i115:\3_2\"
				( attribute "PN" "3_2"
					( Origin gPackager )
				)
				( objectStatus "J1D1.3_2" )
			)
			( pin "@baseboard_fab2_lib.baseboard_fab2(sch_1):page195_i115:\3_3\"
				( attribute "PN" "3_3"
					( Origin gPackager )
				)
				( objectStatus "J1D1.3_3" )
			)
			( pin "@baseboard_fab2_lib.baseboard_fab2(sch_1):page195_i115:\4_1\"
				( attribute "PN" "4_1"
					( Origin gPackager )
				)
				( objectStatus "J1D1.4_1" )
			)
			( pin "@baseboard_fab2_lib.baseboard_fab2(sch_1):page195_i115:\4_2\"
				( attribute "PN" "4_2"
					( Origin gPackager )
				)
				( objectStatus "J1D1.4_2" )
			)
			( pin "@baseboard_fab2_lib.baseboard_fab2(sch_1):page195_i115:\4_3\"
				( attribute "PN" "4_3"
					( Origin gPackager )
				)
				( objectStatus "J1D1.4_3" )
			)
			( pin "@baseboard_fab2_lib.baseboard_fab2(sch_1):page195_i115:np1"
				( attribute "PN" "NP1"
					( Origin gPackager )
				)
				( objectStatus "J1D1.NP1" )
			)
			( pin "@baseboard_fab2_lib.baseboard_fab2(sch_1):page253_i26:cc1"
				( attribute "PN" "A5"
					( Origin gPackager )
				)
				( objectStatus "J30W1.A5" )
			)
			( pin "@baseboard_fab2_lib.baseboard_fab2(sch_1):page253_i26:cc2"
				( attribute "PN" "B5"
					( Origin gPackager )
				)
				( objectStatus "J30W1.B5" )
			)
			( pin "@baseboard_fab2_lib.baseboard_fab2(sch_1):page253_i26:dn1"
				( attribute "PN" "A7"
					( Origin gPackager )
				)
				( objectStatus "J30W1.A7" )
			)
			( pin "@baseboard_fab2_lib.baseboard_fab2(sch_1):page253_i26:dn2"
				( attribute "PN" "B7"
					( Origin gPackager )
				)
				( objectStatus "J30W1.B7" )
			)
			( pin "@baseboard_fab2_lib.baseboard_fab2(sch_1):page253_i26:dp1"
				( attribute "PN" "A6"
					( Origin gPackager )
				)
				( objectStatus "J30W1.A6" )
			)
			( pin "@baseboard_fab2_lib.baseboard_fab2(sch_1):page253_i26:dp2"
				( attribute "PN" "B6"
					( Origin gPackager )
				)
				( objectStatus "J30W1.B6" )
			)
			( pin "@baseboard_fab2_lib.baseboard_fab2(sch_1):page253_i26:gnd(0)"
				( attribute "PN" "A1"
					( Origin gPackager )
				)
				( objectStatus "J30W1.A1" )
			)
			( pin "@baseboard_fab2_lib.baseboard_fab2(sch_1):page253_i26:gnd(1)"
				( attribute "PN" "A12"
					( Origin gPackager )
				)
				( objectStatus "J30W1.A12" )
			)
			( pin "@baseboard_fab2_lib.baseboard_fab2(sch_1):page253_i26:gnd(2)"
				( attribute "PN" "B1"
					( Origin gPackager )
				)
				( objectStatus "J30W1.B1" )
			)
			( pin "@baseboard_fab2_lib.baseboard_fab2(sch_1):page253_i26:gnd(3)"
				( attribute "PN" "B12"
					( Origin gPackager )
				)
				( objectStatus "J30W1.B12" )
			)
			( pin "@baseboard_fab2_lib.baseboard_fab2(sch_1):page253_i26:np1"
				( attribute "PN" "NP1"
					( Origin gPackager )
				)
				( objectStatus "J30W1.NP1" )
			)
			( pin "@baseboard_fab2_lib.baseboard_fab2(sch_1):page253_i26:np2"
				( attribute "PN" "NP2"
					( Origin gPackager )
				)
				( objectStatus "J30W1.NP2" )
			)
			( pin "@baseboard_fab2_lib.baseboard_fab2(sch_1):page253_i26:pth1"
				( attribute "PN" "PTH1"
					( Origin gPackager )
				)
				( objectStatus "J30W1.PTH1" )
			)
			( pin "@baseboard_fab2_lib.baseboard_fab2(sch_1):page253_i26:pth2"
				( attribute "PN" "PTH2"
					( Origin gPackager )
				)
				( objectStatus "J30W1.PTH2" )
			)
			( pin "@baseboard_fab2_lib.baseboard_fab2(sch_1):page253_i26:pth3"
				( attribute "PN" "PTH3"
					( Origin gPackager )
				)
				( objectStatus "J30W1.PTH3" )
			)
			( pin "@baseboard_fab2_lib.baseboard_fab2(sch_1):page253_i26:pth4"
				( attribute "PN" "PTH4"
					( Origin gPackager )
				)
				( objectStatus "J30W1.PTH4" )
			)
			( pin "@baseboard_fab2_lib.baseboard_fab2(sch_1):page253_i26:pth5"
				( attribute "PN" "PTH5"
					( Origin gPackager )
				)
				( objectStatus "J30W1.PTH5" )
			)
			( pin "@baseboard_fab2_lib.baseboard_fab2(sch_1):page253_i26:pth6"
				( attribute "PN" "PTH6"
					( Origin gPackager )
				)
				( objectStatus "J30W1.PTH6" )
			)
			( pin "@baseboard_fab2_lib.baseboard_fab2(sch_1):page253_i26:pth7"
				( attribute "PN" "PTH7"
					( Origin gPackager )
				)
				( objectStatus "J30W1.PTH7" )
			)
			( pin "@baseboard_fab2_lib.baseboard_fab2(sch_1):page253_i26:pth8"
				( attribute "PN" "PTH8"
					( Origin gPackager )
				)
				( objectStatus "J30W1.PTH8" )
			)
			( pin "@baseboard_fab2_lib.baseboard_fab2(sch_1):page253_i26:sbu1"
				( attribute "PN" "A8"
					( Origin gPackager )
				)
				( objectStatus "J30W1.A8" )
			)
			( pin "@baseboard_fab2_lib.baseboard_fab2(sch_1):page253_i26:sbu2"
				( attribute "PN" "B8"
					( Origin gPackager )
				)
				( objectStatus "J30W1.B8" )
			)
			( pin "@baseboard_fab2_lib.baseboard_fab2(sch_1):page253_i26:ssrxn1"
				( attribute "PN" "B10"
					( Origin gPackager )
				)
				( objectStatus "J30W1.B10" )
			)
			( pin "@baseboard_fab2_lib.baseboard_fab2(sch_1):page253_i26:ssrxn2"
				( attribute "PN" "A10"
					( Origin gPackager )
				)
				( objectStatus "J30W1.A10" )
			)
			( pin "@baseboard_fab2_lib.baseboard_fab2(sch_1):page253_i26:ssrxp1"
				( attribute "PN" "B11"
					( Origin gPackager )
				)
				( objectStatus "J30W1.B11" )
			)
			( pin "@baseboard_fab2_lib.baseboard_fab2(sch_1):page253_i26:ssrxp2"
				( attribute "PN" "A11"
					( Origin gPackager )
				)
				( objectStatus "J30W1.A11" )
			)
			( pin "@baseboard_fab2_lib.baseboard_fab2(sch_1):page253_i26:sstxn1"
				( attribute "PN" "A3"
					( Origin gPackager )
				)
				( objectStatus "J30W1.A3" )
			)
			( pin "@baseboard_fab2_lib.baseboard_fab2(sch_1):page253_i26:sstxn2"
				( attribute "PN" "B3"
					( Origin gPackager )
				)
				( objectStatus "J30W1.B3" )
			)
			( pin "@baseboard_fab2_lib.baseboard_fab2(sch_1):page253_i26:sstxp1"
				( attribute "PN" "A2"
					( Origin gPackager )
				)
				( objectStatus "J30W1.A2" )
			)
			( pin "@baseboard_fab2_lib.baseboard_fab2(sch_1):page253_i26:sstxp2"
				( attribute "PN" "B2"
					( Origin gPackager )
				)
				( objectStatus "J30W1.B2" )
			)
			( pin "@baseboard_fab2_lib.baseboard_fab2(sch_1):page253_i26:vbus(0)"
				( attribute "PN" "A4"
					( Origin gPackager )
				)
				( objectStatus "J30W1.A4" )
			)
			( pin "@baseboard_fab2_lib.baseboard_fab2(sch_1):page253_i26:vbus(1)"
				( attribute "PN" "A9"
					( Origin gPackager )
				)
				( objectStatus "J30W1.A9" )
			)
			( pin "@baseboard_fab2_lib.baseboard_fab2(sch_1):page253_i26:vbus(2)"
				( attribute "PN" "B4"
					( Origin gPackager )
				)
				( objectStatus "J30W1.B4" )
			)
			( pin "@baseboard_fab2_lib.baseboard_fab2(sch_1):page253_i26:vbus(3)"
				( attribute "PN" "B9"
					( Origin gPackager )
				)
				( objectStatus "J30W1.B9" )
			)
			( pin "@baseboard_fab2_lib.baseboard_fab2(sch_1):page230_i20:a"
				( attribute "PN" "1"
					( Origin gPackager )
				)
				( objectStatus "C4A13.1" )
			)
			( pin "@baseboard_fab2_lib.baseboard_fab2(sch_1):page230_i20:b"
				( attribute "PN" "2"
					( Origin gPackager )
				)
				( objectStatus "C4A13.2" )
			)
			( pin "@baseboard_fab2_lib.baseboard_fab2(sch_1):page230_i13:a"
				( attribute "PN" "1"
					( Origin gPackager )
				)
				( objectStatus "R6L8.1" )
			)
			( pin "@baseboard_fab2_lib.baseboard_fab2(sch_1):page230_i13:b"
				( attribute "PN" "2"
					( Origin gPackager )
				)
				( objectStatus "R6L8.2" )
			)
			( pin "@baseboard_fab2_lib.baseboard_fab2(sch_1):page230_i12:a"
				( attribute "PN" "1"
					( Origin gPackager )
				)
				( objectStatus "C4A8.1" )
			)
			( pin "@baseboard_fab2_lib.baseboard_fab2(sch_1):page230_i12:b"
				( attribute "PN" "2"
					( Origin gPackager )
				)
				( objectStatus "C4A8.2" )
			)
			( pin "@baseboard_fab2_lib.baseboard_fab2(sch_1):page230_i10:a"
				( attribute "PN" "1"
					( Origin gPackager )
				)
				( objectStatus "C4A7.1" )
			)
			( pin "@baseboard_fab2_lib.baseboard_fab2(sch_1):page230_i10:b"
				( attribute "PN" "2"
					( Origin gPackager )
				)
				( objectStatus "C4A7.2" )
			)
			( pin "@baseboard_fab2_lib.baseboard_fab2(sch_1):page230_i6:a"
				( attribute "PN" "1"
					( Origin gPackager )
				)
				( objectStatus "R6L6.1" )
			)
			( pin "@baseboard_fab2_lib.baseboard_fab2(sch_1):page230_i6:b"
				( attribute "PN" "2"
					( Origin gPackager )
				)
				( objectStatus "R6L6.2" )
			)
			( pin "@baseboard_fab2_lib.baseboard_fab2(sch_1):page230_i5:a"
				( attribute "PN" "1"
					( Origin gPackager )
				)
				( objectStatus "R6L5.1" )
			)
			( pin "@baseboard_fab2_lib.baseboard_fab2(sch_1):page230_i5:b"
				( attribute "PN" "2"
					( Origin gPackager )
				)
				( objectStatus "R6L5.2" )
			)
			( pin "@baseboard_fab2_lib.baseboard_fab2(sch_1):page230_i4:a"
				( attribute "PN" "1"
					( Origin gPackager )
				)
				( objectStatus "R4A3.1" )
			)
			( pin "@baseboard_fab2_lib.baseboard_fab2(sch_1):page230_i4:b"
				( attribute "PN" "2"
					( Origin gPackager )
				)
				( objectStatus "R4A3.2" )
			)
			( pin "@baseboard_fab2_lib.baseboard_fab2(sch_1):page230_i2:a"
				( attribute "PN" "1"
					( Origin gPackager )
				)
				( objectStatus "C4A6.1" )
			)
			( pin "@baseboard_fab2_lib.baseboard_fab2(sch_1):page230_i2:b"
				( attribute "PN" "2"
					( Origin gPackager )
				)
				( objectStatus "C4A6.2" )
			)
			( pin "@baseboard_fab2_lib.baseboard_fab2(sch_1):page201_i189:a"
				( attribute "PN" "1"
					( Origin gPackager )
				)
				( objectStatus "R4E9.1" )
			)
			( pin "@baseboard_fab2_lib.baseboard_fab2(sch_1):page201_i189:b"
				( attribute "PN" "2"
					( Origin gPackager )
				)
				( objectStatus "R4E9.2" )
			)
			( pin "@baseboard_fab2_lib.baseboard_fab2(sch_1):page133_i368:a"
				( attribute "PN" "1"
					( Origin gPackager )
				)
				( objectStatus "R3N15.1" )
			)
			( pin "@baseboard_fab2_lib.baseboard_fab2(sch_1):page133_i368:b"
				( attribute "PN" "2"
					( Origin gPackager )
				)
				( objectStatus "R3N15.2" )
			)
			( pin "@baseboard_fab2_lib.baseboard_fab2(sch_1):page133_i369:a"
				( attribute "PN" "1"
					( Origin gPackager )
				)
				( objectStatus "R3N16.1" )
			)
			( pin "@baseboard_fab2_lib.baseboard_fab2(sch_1):page133_i369:b"
				( attribute "PN" "2"
					( Origin gPackager )
				)
				( objectStatus "R3N16.2" )
			)
			( pin "@baseboard_fab2_lib.baseboard_fab2(sch_1):page133_i366:a"
				( attribute "PN" "1"
					( Origin gPackager )
				)
				( objectStatus "R3P5.1" )
			)
			( pin "@baseboard_fab2_lib.baseboard_fab2(sch_1):page133_i366:b"
				( attribute "PN" "2"
					( Origin gPackager )
				)
				( objectStatus "R3P5.2" )
			)
			( pin "@baseboard_fab2_lib.baseboard_fab2(sch_1):page133_i367:a"
				( attribute "PN" "1"
					( Origin gPackager )
				)
				( objectStatus "R3P6.1" )
			)
			( pin "@baseboard_fab2_lib.baseboard_fab2(sch_1):page133_i367:b"
				( attribute "PN" "2"
					( Origin gPackager )
				)
				( objectStatus "R3P6.2" )
			)
			( pin "@baseboard_fab2_lib.baseboard_fab2(sch_1):page182_i37:a"
				( attribute "PN" "1"
					( Origin gPackager )
				)
				( objectStatus "C9N12.1" )
			)
			( pin "@baseboard_fab2_lib.baseboard_fab2(sch_1):page182_i37:b"
				( attribute "PN" "2"
					( Origin gPackager )
				)
				( objectStatus "C9N12.2" )
			)
			( pin "@baseboard_fab2_lib.baseboard_fab2(sch_1):page182_i36:a"
				( attribute "PN" "1"
					( Origin gPackager )
				)
				( objectStatus "C9N2.1" )
			)
			( pin "@baseboard_fab2_lib.baseboard_fab2(sch_1):page182_i36:b"
				( attribute "PN" "2"
					( Origin gPackager )
				)
				( objectStatus "C9N2.2" )
			)
			( pin "@baseboard_fab2_lib.baseboard_fab2(sch_1):page182_i10:a"
				( attribute "PN" "1"
					( Origin gPackager )
				)
				( objectStatus "R1C11.1" )
			)
			( pin "@baseboard_fab2_lib.baseboard_fab2(sch_1):page182_i10:b"
				( attribute "PN" "2"
					( Origin gPackager )
				)
				( objectStatus "R1C11.2" )
			)
			( pin "@baseboard_fab2_lib.baseboard_fab2(sch_1):page182_i9:a"
				( attribute "PN" "1"
					( Origin gPackager )
				)
				( objectStatus "R1C10.1" )
			)
			( pin "@baseboard_fab2_lib.baseboard_fab2(sch_1):page182_i9:b"
				( attribute "PN" "2"
					( Origin gPackager )
				)
				( objectStatus "R1C10.2" )
			)
			( pin "@baseboard_fab2_lib.baseboard_fab2(sch_1):page182_i8:a"
				( attribute "PN" "1"
					( Origin gPackager )
				)
				( objectStatus "R1C9.1" )
			)
			( pin "@baseboard_fab2_lib.baseboard_fab2(sch_1):page182_i8:b"
				( attribute "PN" "2"
					( Origin gPackager )
				)
				( objectStatus "R1C9.2" )
			)
			( pin "@baseboard_fab2_lib.baseboard_fab2(sch_1):page182_i7:a"
				( attribute "PN" "1"
					( Origin gPackager )
				)
				( objectStatus "R1F9.1" )
			)
			( pin "@baseboard_fab2_lib.baseboard_fab2(sch_1):page182_i7:b"
				( attribute "PN" "2"
					( Origin gPackager )
				)
				( objectStatus "R1F9.2" )
			)
			( pin "@baseboard_fab2_lib.baseboard_fab2(sch_1):page182_i6:a"
				( attribute "PN" "1"
					( Origin gPackager )
				)
				( objectStatus "R1C31.1" )
			)
			( pin "@baseboard_fab2_lib.baseboard_fab2(sch_1):page182_i6:b"
				( attribute "PN" "2"
					( Origin gPackager )
				)
				( objectStatus "R1C31.2" )
			)
			( pin "@baseboard_fab2_lib.baseboard_fab2(sch_1):page137_i142:a"
				( attribute "PN" "1"
					( Origin gPackager )
				)
				( objectStatus "RN8F1.1" )
			)
			( pin "@baseboard_fab2_lib.baseboard_fab2(sch_1):page137_i142:b"
				( attribute "PN" "2"
					( Origin gPackager )
				)
				( objectStatus "RN8F1.2" )
			)
			( pin "@baseboard_fab2_lib.baseboard_fab2(sch_1):page137_i144:a"
				( attribute "PN" "1"
					( Origin gPackager )
				)
				( objectStatus "R6W2.1" )
			)
			( pin "@baseboard_fab2_lib.baseboard_fab2(sch_1):page137_i144:b"
				( attribute "PN" "2"
					( Origin gPackager )
				)
				( objectStatus "R6W2.2" )
			)
			( pin "@baseboard_fab2_lib.baseboard_fab2(sch_1):page215_i14:a"
				( attribute "PN" "1"
					( Origin gPackager )
				)
				( objectStatus "C7G4.1" )
			)
			( pin "@baseboard_fab2_lib.baseboard_fab2(sch_1):page215_i14:b"
				( attribute "PN" "2"
					( Origin gPackager )
				)
				( objectStatus "C7G4.2" )
			)
			( pin "@baseboard_fab2_lib.baseboard_fab2(sch_1):page215_i15:a"
				( attribute "PN" "1"
					( Origin gPackager )
				)
				( objectStatus "RF15.1" )
			)
			( pin "@baseboard_fab2_lib.baseboard_fab2(sch_1):page215_i15:b"
				( attribute "PN" "2"
					( Origin gPackager )
				)
				( objectStatus "RF15.2" )
			)
			( pin "@baseboard_fab2_lib.baseboard_fab2(sch_1):page215_i16:\1\"
				( attribute "PN" "1"
					( Origin gPackager )
				)
				( objectStatus "CF15.1" )
			)
			( pin "@baseboard_fab2_lib.baseboard_fab2(sch_1):page215_i16:\2\"
				( attribute "PN" "2"
					( Origin gPackager )
				)
				( objectStatus "CF15.2" )
			)
			( pin "@baseboard_fab2_lib.baseboard_fab2(sch_1):page226_i70:a"
				( attribute "PN" "1"
					( Origin gPackager )
				)
				( objectStatus "R9M6.1" )
			)
			( pin "@baseboard_fab2_lib.baseboard_fab2(sch_1):page226_i70:b"
				( attribute "PN" "2"
					( Origin gPackager )
				)
				( objectStatus "R9M6.2" )
			)
			( pin "@baseboard_fab2_lib.baseboard_fab2(sch_1):page235_i252:a"
				( attribute "PN" "1"
					( Origin gPackager )
				)
				( objectStatus "R2L25.1" )
			)
			( pin "@baseboard_fab2_lib.baseboard_fab2(sch_1):page235_i252:b"
				( attribute "PN" "2"
					( Origin gPackager )
				)
				( objectStatus "R2L25.2" )
			)
			( pin "@baseboard_fab2_lib.baseboard_fab2(sch_1):page215_i22:a"
				( attribute "PN" "1"
					( Origin gPackager )
				)
				( objectStatus "C7G3.1" )
			)
			( pin "@baseboard_fab2_lib.baseboard_fab2(sch_1):page215_i22:b"
				( attribute "PN" "2"
					( Origin gPackager )
				)
				( objectStatus "C7G3.2" )
			)
			( pin "@baseboard_fab2_lib.baseboard_fab2(sch_1):page218_i73:a"
				( attribute "PN" "1"
					( Origin gPackager )
				)
				( objectStatus "R7A10.1" )
			)
			( pin "@baseboard_fab2_lib.baseboard_fab2(sch_1):page218_i73:b"
				( attribute "PN" "2"
					( Origin gPackager )
				)
				( objectStatus "R7A10.2" )
			)
			( pin "@baseboard_fab2_lib.baseboard_fab2(sch_1):page215_i26:\1\"
				( attribute "PN" "1"
					( Origin gPackager )
				)
				( objectStatus "CF16.1" )
			)
			( pin "@baseboard_fab2_lib.baseboard_fab2(sch_1):page215_i26:\2\"
				( attribute "PN" "2"
					( Origin gPackager )
				)
				( objectStatus "CF16.2" )
			)
			( pin "@baseboard_fab2_lib.baseboard_fab2(sch_1):page215_i27:a"
				( attribute "PN" "1"
					( Origin gPackager )
				)
				( objectStatus "RF16.1" )
			)
			( pin "@baseboard_fab2_lib.baseboard_fab2(sch_1):page215_i27:b"
				( attribute "PN" "2"
					( Origin gPackager )
				)
				( objectStatus "RF16.2" )
			)
			( pin "@baseboard_fab2_lib.baseboard_fab2(sch_1):page215_i28:a"
				( attribute "PN" "1"
					( Origin gPackager )
				)
				( objectStatus "R7G24.1" )
			)
			( pin "@baseboard_fab2_lib.baseboard_fab2(sch_1):page215_i28:b"
				( attribute "PN" "2"
					( Origin gPackager )
				)
				( objectStatus "R7G24.2" )
			)
			( pin "@baseboard_fab2_lib.baseboard_fab2(sch_1):page215_i29:a"
				( attribute "PN" "1"
					( Origin gPackager )
				)
				( objectStatus "R7F20.1" )
			)
			( pin "@baseboard_fab2_lib.baseboard_fab2(sch_1):page215_i29:b"
				( attribute "PN" "2"
					( Origin gPackager )
				)
				( objectStatus "R7F20.2" )
			)
			( pin "@baseboard_fab2_lib.baseboard_fab2(sch_1):page215_i33:a"
				( attribute "PN" "1"
					( Origin gPackager )
				)
				( objectStatus "R3T13.1" )
			)
			( pin "@baseboard_fab2_lib.baseboard_fab2(sch_1):page215_i33:b"
				( attribute "PN" "2"
					( Origin gPackager )
				)
				( objectStatus "R3T13.2" )
			)
			( pin "@baseboard_fab2_lib.baseboard_fab2(sch_1):page215_i34:a"
				( attribute "PN" "1"
					( Origin gPackager )
				)
				( objectStatus "C7F17.1" )
			)
			( pin "@baseboard_fab2_lib.baseboard_fab2(sch_1):page215_i34:b"
				( attribute "PN" "2"
					( Origin gPackager )
				)
				( objectStatus "C7F17.2" )
			)
			( pin "@baseboard_fab2_lib.baseboard_fab2(sch_1):page215_i35:a"
				( attribute "PN" "1"
					( Origin gPackager )
				)
				( objectStatus "C7F18.1" )
			)
			( pin "@baseboard_fab2_lib.baseboard_fab2(sch_1):page215_i35:b"
				( attribute "PN" "2"
					( Origin gPackager )
				)
				( objectStatus "C7F18.2" )
			)
			( pin "@baseboard_fab2_lib.baseboard_fab2(sch_1):page215_i38:a"
				( attribute "PN" "1"
					( Origin gPackager )
				)
				( objectStatus "C7F15.1" )
			)
			( pin "@baseboard_fab2_lib.baseboard_fab2(sch_1):page215_i38:b"
				( attribute "PN" "2"
					( Origin gPackager )
				)
				( objectStatus "C7F15.2" )
			)
			( pin "@baseboard_fab2_lib.baseboard_fab2(sch_1):page215_i40:a"
				( attribute "PN" "1"
					( Origin gPackager )
				)
				( objectStatus "C7F16.1" )
			)
			( pin "@baseboard_fab2_lib.baseboard_fab2(sch_1):page215_i40:b"
				( attribute "PN" "2"
					( Origin gPackager )
				)
				( objectStatus "C7F16.2" )
			)
			( pin "@baseboard_fab2_lib.baseboard_fab2(sch_1):page215_i41:a"
				( attribute "PN" "1"
					( Origin gPackager )
				)
				( objectStatus "R7G2.1" )
			)
			( pin "@baseboard_fab2_lib.baseboard_fab2(sch_1):page215_i41:b"
				( attribute "PN" "2"
					( Origin gPackager )
				)
				( objectStatus "R7G2.2" )
			)
			( pin "@baseboard_fab2_lib.baseboard_fab2(sch_1):page215_i44:a"
				( attribute "PN" "1"
					( Origin gPackager )
				)
				( objectStatus "C7F14.1" )
			)
			( pin "@baseboard_fab2_lib.baseboard_fab2(sch_1):page215_i44:b"
				( attribute "PN" "2"
					( Origin gPackager )
				)
				( objectStatus "C7F14.2" )
			)
			( pin "@baseboard_fab2_lib.baseboard_fab2(sch_1):page215_i45:a"
				( attribute "PN" "1"
					( Origin gPackager )
				)
				( objectStatus "R12W26.1" )
			)
			( pin "@baseboard_fab2_lib.baseboard_fab2(sch_1):page215_i45:b"
				( attribute "PN" "2"
					( Origin gPackager )
				)
				( objectStatus "R12W26.2" )
			)
			( pin "@baseboard_fab2_lib.baseboard_fab2(sch_1):page218_i75:a"
				( attribute "PN" "1"
					( Origin gPackager )
				)
				( objectStatus "R12W28.1" )
			)
			( pin "@baseboard_fab2_lib.baseboard_fab2(sch_1):page218_i75:b"
				( attribute "PN" "2"
					( Origin gPackager )
				)
				( objectStatus "R12W28.2" )
			)
			( pin "@baseboard_fab2_lib.baseboard_fab2(sch_1):page215_i49:a"
				( attribute "PN" "1"
					( Origin gPackager )
				)
				( objectStatus "R7G4.1" )
			)
			( pin "@baseboard_fab2_lib.baseboard_fab2(sch_1):page215_i49:b"
				( attribute "PN" "2"
					( Origin gPackager )
				)
				( objectStatus "R7G4.2" )
			)
			( pin "@baseboard_fab2_lib.baseboard_fab2(sch_1):page215_i50:a"
				( attribute "PN" "1"
					( Origin gPackager )
				)
				( objectStatus "R7F27.1" )
			)
			( pin "@baseboard_fab2_lib.baseboard_fab2(sch_1):page215_i50:b"
				( attribute "PN" "2"
					( Origin gPackager )
				)
				( objectStatus "R7F27.2" )
			)
			( pin "@baseboard_fab2_lib.baseboard_fab2(sch_1):page215_i51:a"
				( attribute "PN" "1"
					( Origin gPackager )
				)
				( objectStatus "R7F22.1" )
			)
			( pin "@baseboard_fab2_lib.baseboard_fab2(sch_1):page215_i51:b"
				( attribute "PN" "2"
					( Origin gPackager )
				)
				( objectStatus "R7F22.2" )
			)
			( pin "@baseboard_fab2_lib.baseboard_fab2(sch_1):page215_i53:a"
				( attribute "PN" "1"
					( Origin gPackager )
				)
				( objectStatus "R7F23.1" )
			)
			( pin "@baseboard_fab2_lib.baseboard_fab2(sch_1):page215_i53:b"
				( attribute "PN" "2"
					( Origin gPackager )
				)
				( objectStatus "R7F23.2" )
			)
			( pin "@baseboard_fab2_lib.baseboard_fab2(sch_1):page215_i54:a"
				( attribute "PN" "1"
					( Origin gPackager )
				)
				( objectStatus "R12W27.1" )
			)
			( pin "@baseboard_fab2_lib.baseboard_fab2(sch_1):page215_i54:b"
				( attribute "PN" "2"
					( Origin gPackager )
				)
				( objectStatus "R12W27.2" )
			)
			( pin "@baseboard_fab2_lib.baseboard_fab2(sch_1):page215_i56:a"
				( attribute "PN" "1"
					( Origin gPackager )
				)
				( objectStatus "R7F24.1" )
			)
			( pin "@baseboard_fab2_lib.baseboard_fab2(sch_1):page215_i56:b"
				( attribute "PN" "2"
					( Origin gPackager )
				)
				( objectStatus "R7F24.2" )
			)
			( pin "@baseboard_fab2_lib.baseboard_fab2(sch_1):page218_i76:a"
				( attribute "PN" "1"
					( Origin gPackager )
				)
				( objectStatus "R7A9.1" )
			)
			( pin "@baseboard_fab2_lib.baseboard_fab2(sch_1):page218_i76:b"
				( attribute "PN" "2"
					( Origin gPackager )
				)
				( objectStatus "R7A9.2" )
			)
			( pin "@baseboard_fab2_lib.baseboard_fab2(sch_1):page215_i58:a"
				( attribute "PN" "1"
					( Origin gPackager )
				)
				( objectStatus "R3U2.1" )
			)
			( pin "@baseboard_fab2_lib.baseboard_fab2(sch_1):page215_i58:b"
				( attribute "PN" "2"
					( Origin gPackager )
				)
				( objectStatus "R3U2.2" )
			)
			( pin "@baseboard_fab2_lib.baseboard_fab2(sch_1):page215_i69:airef1"
				( attribute "PN" "21"
					( Origin gPackager )
				)
				( objectStatus "EU7G1.21" )
			)
			( pin "@baseboard_fab2_lib.baseboard_fab2(sch_1):page215_i69:airef2"
				( attribute "PN" "23"
					( Origin gPackager )
				)
				( objectStatus "EU7G1.23" )
			)
			( pin "@baseboard_fab2_lib.baseboard_fab2(sch_1):page215_i69:airef3"
				( attribute "PN" "25"
					( Origin gPackager )
				)
				( objectStatus "EU7G1.25" )
			)
			( pin "@baseboard_fab2_lib.baseboard_fab2(sch_1):page215_i69:aisen1"
				( attribute "PN" "22"
					( Origin gPackager )
				)
				( objectStatus "EU7G1.22" )
			)
			( pin "@baseboard_fab2_lib.baseboard_fab2(sch_1):page215_i69:aisen2"
				( attribute "PN" "24"
					( Origin gPackager )
				)
				( objectStatus "EU7G1.24" )
			)
			( pin "@baseboard_fab2_lib.baseboard_fab2(sch_1):page215_i69:aisen3"
				( attribute "PN" "26"
					( Origin gPackager )
				)
				( objectStatus "EU7G1.26" )
			)
			( pin "@baseboard_fab2_lib.baseboard_fab2(sch_1):page215_i69:apwm1"
				( attribute "PN" "5"
					( Origin gPackager )
				)
				( objectStatus "EU7G1.5" )
			)
			( pin "@baseboard_fab2_lib.baseboard_fab2(sch_1):page215_i69:apwm2"
				( attribute "PN" "4"
					( Origin gPackager )
				)
				( objectStatus "EU7G1.4" )
			)
			( pin "@baseboard_fab2_lib.baseboard_fab2(sch_1):page215_i69:apwm3"
				( attribute "PN" "3"
					( Origin gPackager )
				)
				( objectStatus "EU7G1.3" )
			)
			( pin "@baseboard_fab2_lib.baseboard_fab2(sch_1):page215_i69:atsen"
				( attribute "PN" "35"
					( Origin gPackager )
				)
				( objectStatus "EU7G1.35" )
			)
			( pin "@baseboard_fab2_lib.baseboard_fab2(sch_1):page215_i69:avref"
				( attribute "PN" "20"
					( Origin gPackager )
				)
				( objectStatus "EU7G1.20" )
			)
			( pin "@baseboard_fab2_lib.baseboard_fab2(sch_1):page215_i69:avren"
				( attribute "PN" "10"
					( Origin gPackager )
				)
				( objectStatus "EU7G1.10" )
			)
			( pin "@baseboard_fab2_lib.baseboard_fab2(sch_1):page215_i69:avrrdy"
				( attribute "PN" "9"
					( Origin gPackager )
				)
				( objectStatus "EU7G1.9" )
			)
			( pin "@baseboard_fab2_lib.baseboard_fab2(sch_1):page215_i69:avsen"
				( attribute "PN" "19"
					( Origin gPackager )
				)
				( objectStatus "EU7G1.19" )
			)
			( pin "@baseboard_fab2_lib.baseboard_fab2(sch_1):page215_i69:biref1"
				( attribute "PN" "31"
					( Origin gPackager )
				)
				( objectStatus "EU7G1.31" )
			)
			( pin "@baseboard_fab2_lib.baseboard_fab2(sch_1):page215_i69:bisen1"
				( attribute "PN" "32"
					( Origin gPackager )
				)
				( objectStatus "EU7G1.32" )
			)
			( pin "@baseboard_fab2_lib.baseboard_fab2(sch_1):page215_i69:bpwm1"
				( attribute "PN" "1"
					( Origin gPackager )
				)
				( objectStatus "EU7G1.1" )
			)
			( pin "@baseboard_fab2_lib.baseboard_fab2(sch_1):page215_i69:btsen"
				( attribute "PN" "34"
					( Origin gPackager )
				)
				( objectStatus "EU7G1.34" )
			)
			( pin "@baseboard_fab2_lib.baseboard_fab2(sch_1):page215_i69:bvref"
				( attribute "PN" "30"
					( Origin gPackager )
				)
				( objectStatus "EU7G1.30" )
			)
			( pin "@baseboard_fab2_lib.baseboard_fab2(sch_1):page215_i69:bvsen"
				( attribute "PN" "29"
					( Origin gPackager )
				)
				( objectStatus "EU7G1.29" )
			)
			( pin "@baseboard_fab2_lib.baseboard_fab2(sch_1):page215_i69:dnc(0)"
				( attribute "PN" "2"
					( Origin gPackager )
				)
				( objectStatus "EU7G1.2" )
			)
			( pin "@baseboard_fab2_lib.baseboard_fab2(sch_1):page215_i69:dnc(1)"
				( attribute "PN" "28"
					( Origin gPackager )
				)
				( objectStatus "EU7G1.28" )
			)
			( pin "@baseboard_fab2_lib.baseboard_fab2(sch_1):page215_i69:gnd"
				( attribute "PN" "27"
					( Origin gPackager )
				)
				( objectStatus "EU7G1.27" )
			)
			( pin "@baseboard_fab2_lib.baseboard_fab2(sch_1):page215_i69:iinsen"
				( attribute "PN" "38"
					( Origin gPackager )
				)
				( objectStatus "EU7G1.38" )
			)
			( pin "@baseboard_fab2_lib.baseboard_fab2(sch_1):page215_i69:mp0"
				( attribute "PN" "13"
					( Origin gPackager )
				)
				( objectStatus "EU7G1.13" )
			)
			( pin "@baseboard_fab2_lib.baseboard_fab2(sch_1):page215_i69:mp1"
				( attribute "PN" "14"
					( Origin gPackager )
				)
				( objectStatus "EU7G1.14" )
			)
			( pin "@baseboard_fab2_lib.baseboard_fab2(sch_1):page215_i69:mp2"
				( attribute "PN" "18"
					( Origin gPackager )
				)
				( objectStatus "EU7G1.18" )
			)
			( pin "@baseboard_fab2_lib.baseboard_fab2(sch_1):page215_i69:pinalrt_n"
				( attribute "PN" "12"
					( Origin gPackager )
				)
				( objectStatus "EU7G1.12" )
			)
			( pin "@baseboard_fab2_lib.baseboard_fab2(sch_1):page215_i69:reset_n"
				( attribute "PN" "8"
					( Origin gPackager )
				)
				( objectStatus "EU7G1.8" )
			)
			( pin "@baseboard_fab2_lib.baseboard_fab2(sch_1):page215_i69:scl"
				( attribute "PN" "7"
					( Origin gPackager )
				)
				( objectStatus "EU7G1.7" )
			)
			( pin "@baseboard_fab2_lib.baseboard_fab2(sch_1):page215_i69:sda"
				( attribute "PN" "6"
					( Origin gPackager )
				)
				( objectStatus "EU7G1.6" )
			)
			( pin "@baseboard_fab2_lib.baseboard_fab2(sch_1):page215_i69:thpad"
				( attribute "PN" "41"
					( Origin gPackager )
				)
				( objectStatus "EU7G1.41" )
			)
			( pin "@baseboard_fab2_lib.baseboard_fab2(sch_1):page215_i69:valrt_n"
				( attribute "PN" "17"
					( Origin gPackager )
				)
				( objectStatus "EU7G1.17" )
			)
			( pin "@baseboard_fab2_lib.baseboard_fab2(sch_1):page215_i69:vclk"
				( attribute "PN" "15"
					( Origin gPackager )
				)
				( objectStatus "EU7G1.15" )
			)
			( pin "@baseboard_fab2_lib.baseboard_fab2(sch_1):page215_i69:vd12"
				( attribute "PN" "40"
					( Origin gPackager )
				)
				( objectStatus "EU7G1.40" )
			)
			( pin "@baseboard_fab2_lib.baseboard_fab2(sch_1):page215_i69:vdd"
				( attribute "PN" "39"
					( Origin gPackager )
				)
				( objectStatus "EU7G1.39" )
			)
			( pin "@baseboard_fab2_lib.baseboard_fab2(sch_1):page215_i69:vdio"
				( attribute "PN" "16"
					( Origin gPackager )
				)
				( objectStatus "EU7G1.16" )
			)
			( pin "@baseboard_fab2_lib.baseboard_fab2(sch_1):page215_i69:vinsen"
				( attribute "PN" "37"
					( Origin gPackager )
				)
				( objectStatus "EU7G1.37" )
			)
			( pin "@baseboard_fab2_lib.baseboard_fab2(sch_1):page215_i69:vrhot_n"
				( attribute "PN" "11"
					( Origin gPackager )
				)
				( objectStatus "EU7G1.11" )
			)
			( pin "@baseboard_fab2_lib.baseboard_fab2(sch_1):page215_i69:xaddr1"
				( attribute "PN" "36"
					( Origin gPackager )
				)
				( objectStatus "EU7G1.36" )
			)
			( pin "@baseboard_fab2_lib.baseboard_fab2(sch_1):page215_i69:xaddr2"
				( attribute "PN" "33"
					( Origin gPackager )
				)
				( objectStatus "EU7G1.33" )
			)
			( pin "@baseboard_fab2_lib.baseboard_fab2(sch_1):page197_i37:a"
				( attribute "PN" "1"
					( Origin gPackager )
				)
				( objectStatus "R12W19.1" )
			)
			( pin "@baseboard_fab2_lib.baseboard_fab2(sch_1):page197_i37:b"
				( attribute "PN" "2"
					( Origin gPackager )
				)
				( objectStatus "R12W19.2" )
			)
			( pin "@baseboard_fab2_lib.baseboard_fab2(sch_1):page197_i42:a"
				( attribute "PN" "1"
					( Origin gPackager )
				)
				( objectStatus "C12W3.1" )
			)
			( pin "@baseboard_fab2_lib.baseboard_fab2(sch_1):page197_i42:b"
				( attribute "PN" "2"
					( Origin gPackager )
				)
				( objectStatus "C12W3.2" )
			)
			( pin "@baseboard_fab2_lib.baseboard_fab2(sch_1):page197_i43:\drain#4\"
				( attribute "PN" "4"
					( Origin gPackager )
				)
				( objectStatus "Q12W1.4" )
			)
			( pin "@baseboard_fab2_lib.baseboard_fab2(sch_1):page197_i43:\drain#6\"
				( attribute "PN" "6"
					( Origin gPackager )
				)
				( objectStatus "Q12W1.6" )
			)
			( pin "@baseboard_fab2_lib.baseboard_fab2(sch_1):page197_i43:\gate#1\"
				( attribute "PN" "1"
					( Origin gPackager )
				)
				( objectStatus "Q12W1.1" )
			)
			( pin "@baseboard_fab2_lib.baseboard_fab2(sch_1):page197_i43:\gate#3\"
				( attribute "PN" "3"
					( Origin gPackager )
				)
				( objectStatus "Q12W1.3" )
			)
			( pin "@baseboard_fab2_lib.baseboard_fab2(sch_1):page197_i43:\source#2\"
				( attribute "PN" "2"
					( Origin gPackager )
				)
				( objectStatus "Q12W1.2" )
			)
			( pin "@baseboard_fab2_lib.baseboard_fab2(sch_1):page197_i43:\source#5\"
				( attribute "PN" "5"
					( Origin gPackager )
				)
				( objectStatus "Q12W1.5" )
			)
			( pin "@baseboard_fab2_lib.baseboard_fab2(sch_1):page197_i45:a"
				( attribute "PN" "1"
					( Origin gPackager )
				)
				( objectStatus "R12W4.1" )
			)
			( pin "@baseboard_fab2_lib.baseboard_fab2(sch_1):page197_i45:b"
				( attribute "PN" "2"
					( Origin gPackager )
				)
				( objectStatus "R12W4.2" )
			)
			( pin "@baseboard_fab2_lib.baseboard_fab2(sch_1):page197_i113:\1\"
				( attribute "PN" "1"
					( Origin gPackager )
				)
				( objectStatus "R12W8.1" )
			)
			( pin "@baseboard_fab2_lib.baseboard_fab2(sch_1):page197_i113:\2\"
				( attribute "PN" "2"
					( Origin gPackager )
				)
				( objectStatus "R12W8.2" )
			)
			( pin "@baseboard_fab2_lib.baseboard_fab2(sch_1):page101_i147:a"
				( attribute "PN" "1"
					( Origin gPackager )
				)
				( objectStatus "C8F18.1" )
			)
			( pin "@baseboard_fab2_lib.baseboard_fab2(sch_1):page101_i147:b"
				( attribute "PN" "2"
					( Origin gPackager )
				)
				( objectStatus "C8F18.2" )
			)
			( pin "@baseboard_fab2_lib.baseboard_fab2(sch_1):page197_i50:a"
				( attribute "PN" "1"
					( Origin gPackager )
				)
				( objectStatus "R1F3.1" )
			)
			( pin "@baseboard_fab2_lib.baseboard_fab2(sch_1):page197_i50:b"
				( attribute "PN" "2"
					( Origin gPackager )
				)
				( objectStatus "R1F3.2" )
			)
			( pin "@baseboard_fab2_lib.baseboard_fab2(sch_1):page197_i53:a"
				( attribute "PN" "1"
					( Origin gPackager )
				)
				( objectStatus "R12W14.1" )
			)
			( pin "@baseboard_fab2_lib.baseboard_fab2(sch_1):page197_i53:b"
				( attribute "PN" "2"
					( Origin gPackager )
				)
				( objectStatus "R12W14.2" )
			)
			( pin "@baseboard_fab2_lib.baseboard_fab2(sch_1):page197_i56:a"
				( attribute "PN" "1"
					( Origin gPackager )
				)
				( objectStatus "C9T8.1" )
			)
			( pin "@baseboard_fab2_lib.baseboard_fab2(sch_1):page197_i56:b"
				( attribute "PN" "2"
					( Origin gPackager )
				)
				( objectStatus "C9T8.2" )
			)
			( pin "@baseboard_fab2_lib.baseboard_fab2(sch_1):page197_i60:a"
				( attribute "PN" "1"
					( Origin gPackager )
				)
				( objectStatus "C1A4.1" )
			)
			( pin "@baseboard_fab2_lib.baseboard_fab2(sch_1):page197_i60:b"
				( attribute "PN" "2"
					( Origin gPackager )
				)
				( objectStatus "C1A4.2" )
			)
			( pin "@baseboard_fab2_lib.baseboard_fab2(sch_1):page197_i63:a"
				( attribute "PN" "1"
					( Origin gPackager )
				)
				( objectStatus "C9U11.1" )
			)
			( pin "@baseboard_fab2_lib.baseboard_fab2(sch_1):page197_i63:b"
				( attribute "PN" "2"
					( Origin gPackager )
				)
				( objectStatus "C9U11.2" )
			)
			( pin "@baseboard_fab2_lib.baseboard_fab2(sch_1):page197_i66:a"
				( attribute "PN" "1"
					( Origin gPackager )
				)
				( objectStatus "C9U8.1" )
			)
			( pin "@baseboard_fab2_lib.baseboard_fab2(sch_1):page197_i66:b"
				( attribute "PN" "2"
					( Origin gPackager )
				)
				( objectStatus "C9U8.2" )
			)
			( pin "@baseboard_fab2_lib.baseboard_fab2(sch_1):page197_i69:a"
				( attribute "PN" "1"
					( Origin gPackager )
				)
				( objectStatus "C6U18.1" )
			)
			( pin "@baseboard_fab2_lib.baseboard_fab2(sch_1):page197_i69:b"
				( attribute "PN" "2"
					( Origin gPackager )
				)
				( objectStatus "C6U18.2" )
			)
			( pin "@baseboard_fab2_lib.baseboard_fab2(sch_1):page197_i71:a"
				( attribute "PN" "1"
					( Origin gPackager )
				)
				( objectStatus "C6T2.1" )
			)
			( pin "@baseboard_fab2_lib.baseboard_fab2(sch_1):page197_i71:b"
				( attribute "PN" "2"
					( Origin gPackager )
				)
				( objectStatus "C6T2.2" )
			)
			( pin "@baseboard_fab2_lib.baseboard_fab2(sch_1):page197_i72:a"
				( attribute "PN" "1"
					( Origin gPackager )
				)
				( objectStatus "C1B7.1" )
			)
			( pin "@baseboard_fab2_lib.baseboard_fab2(sch_1):page197_i72:b"
				( attribute "PN" "2"
					( Origin gPackager )
				)
				( objectStatus "C1B7.2" )
			)
			( pin "@baseboard_fab2_lib.baseboard_fab2(sch_1):page197_i75:a"
				( attribute "PN" "1"
					( Origin gPackager )
				)
				( objectStatus "C1A16.1" )
			)
			( pin "@baseboard_fab2_lib.baseboard_fab2(sch_1):page197_i75:b"
				( attribute "PN" "2"
					( Origin gPackager )
				)
				( objectStatus "C1A16.2" )
			)
			( pin "@baseboard_fab2_lib.baseboard_fab2(sch_1):page197_i78:a"
				( attribute "PN" "1"
					( Origin gPackager )
				)
				( objectStatus "C4B11.1" )
			)
			( pin "@baseboard_fab2_lib.baseboard_fab2(sch_1):page197_i78:b"
				( attribute "PN" "2"
					( Origin gPackager )
				)
				( objectStatus "C4B11.2" )
			)
			( pin "@baseboard_fab2_lib.baseboard_fab2(sch_1):page197_i81:a"
				( attribute "PN" "1"
					( Origin gPackager )
				)
				( objectStatus "C4A4.1" )
			)
			( pin "@baseboard_fab2_lib.baseboard_fab2(sch_1):page197_i81:b"
				( attribute "PN" "2"
					( Origin gPackager )
				)
				( objectStatus "C4A4.2" )
			)
			( pin "@baseboard_fab2_lib.baseboard_fab2(sch_1):page197_i84:a"
				( attribute "PN" "1"
					( Origin gPackager )
				)
				( objectStatus "C6U10.1" )
			)
			( pin "@baseboard_fab2_lib.baseboard_fab2(sch_1):page197_i84:b"
				( attribute "PN" "2"
					( Origin gPackager )
				)
				( objectStatus "C6U10.2" )
			)
			( pin "@baseboard_fab2_lib.baseboard_fab2(sch_1):page197_i88:a"
				( attribute "PN" "1"
					( Origin gPackager )
				)
				( objectStatus "C4A17.1" )
			)
			( pin "@baseboard_fab2_lib.baseboard_fab2(sch_1):page197_i88:b"
				( attribute "PN" "2"
					( Origin gPackager )
				)
				( objectStatus "C4A17.2" )
			)
			( pin "@baseboard_fab2_lib.baseboard_fab2(sch_1):page197_i91:\drain#4\"
				( attribute "PN" "4"
					( Origin gPackager )
				)
				( objectStatus "Q12W3.4" )
			)
			( pin "@baseboard_fab2_lib.baseboard_fab2(sch_1):page197_i91:\drain#6\"
				( attribute "PN" "6"
					( Origin gPackager )
				)
				( objectStatus "Q12W3.6" )
			)
			( pin "@baseboard_fab2_lib.baseboard_fab2(sch_1):page197_i91:\gate#1\"
				( attribute "PN" "1"
					( Origin gPackager )
				)
				( objectStatus "Q12W3.1" )
			)
			( pin "@baseboard_fab2_lib.baseboard_fab2(sch_1):page197_i91:\gate#3\"
				( attribute "PN" "3"
					( Origin gPackager )
				)
				( objectStatus "Q12W3.3" )
			)
			( pin "@baseboard_fab2_lib.baseboard_fab2(sch_1):page197_i91:\source#2\"
				( attribute "PN" "2"
					( Origin gPackager )
				)
				( objectStatus "Q12W3.2" )
			)
			( pin "@baseboard_fab2_lib.baseboard_fab2(sch_1):page197_i91:\source#5\"
				( attribute "PN" "5"
					( Origin gPackager )
				)
				( objectStatus "Q12W3.5" )
			)
			( pin "@baseboard_fab2_lib.baseboard_fab2(sch_1):page181_i4:a"
				( attribute "PN" "1"
					( Origin gPackager )
				)
				( objectStatus "R9T9.1" )
			)
			( pin "@baseboard_fab2_lib.baseboard_fab2(sch_1):page181_i4:b"
				( attribute "PN" "2"
					( Origin gPackager )
				)
				( objectStatus "R9T9.2" )
			)
			( pin "@baseboard_fab2_lib.baseboard_fab2(sch_1):page181_i5:a"
				( attribute "PN" "2"
					( Origin gPackager )
				)
				( objectStatus "CR1F4.2" )
			)
			( pin "@baseboard_fab2_lib.baseboard_fab2(sch_1):page181_i5:c"
				( attribute "PN" "1"
					( Origin gPackager )
				)
				( objectStatus "CR1F4.1" )
			)
			( pin "@baseboard_fab2_lib.baseboard_fab2(sch_1):page181_i22:a"
				( attribute "PN" "1"
					( Origin gPackager )
				)
				( objectStatus "R1F8.1" )
			)
			( pin "@baseboard_fab2_lib.baseboard_fab2(sch_1):page181_i22:b"
				( attribute "PN" "2"
					( Origin gPackager )
				)
				( objectStatus "R1F8.2" )
			)
			( pin "@baseboard_fab2_lib.baseboard_fab2(sch_1):page181_i26:a"
				( attribute "PN" "1"
					( Origin gPackager )
				)
				( objectStatus "R9T1.1" )
			)
			( pin "@baseboard_fab2_lib.baseboard_fab2(sch_1):page181_i26:b"
				( attribute "PN" "2"
					( Origin gPackager )
				)
				( objectStatus "R9T1.2" )
			)
			( pin "@baseboard_fab2_lib.baseboard_fab2(sch_1):page181_i27:a"
				( attribute "PN" "1"
					( Origin gPackager )
				)
				( objectStatus "R9R12.1" )
			)
			( pin "@baseboard_fab2_lib.baseboard_fab2(sch_1):page181_i27:b"
				( attribute "PN" "2"
					( Origin gPackager )
				)
				( objectStatus "R9R12.2" )
			)
			( pin "@baseboard_fab2_lib.baseboard_fab2(sch_1):page181_i28:a"
				( attribute "PN" "1"
					( Origin gPackager )
				)
				( objectStatus "R9F63.1" )
			)
			( pin "@baseboard_fab2_lib.baseboard_fab2(sch_1):page181_i28:b"
				( attribute "PN" "2"
					( Origin gPackager )
				)
				( objectStatus "R9F63.2" )
			)
			( pin "@baseboard_fab2_lib.baseboard_fab2(sch_1):page181_i29:a"
				( attribute "PN" "1"
					( Origin gPackager )
				)
				( objectStatus "R9F64.1" )
			)
			( pin "@baseboard_fab2_lib.baseboard_fab2(sch_1):page181_i29:b"
				( attribute "PN" "2"
					( Origin gPackager )
				)
				( objectStatus "R9F64.2" )
			)
			( pin "@baseboard_fab2_lib.baseboard_fab2(sch_1):page181_i30:a"
				( attribute "PN" "1"
					( Origin gPackager )
				)
				( objectStatus "R9F70.1" )
			)
			( pin "@baseboard_fab2_lib.baseboard_fab2(sch_1):page181_i30:b"
				( attribute "PN" "2"
					( Origin gPackager )
				)
				( objectStatus "R9F70.2" )
			)
			( pin "@baseboard_fab2_lib.baseboard_fab2(sch_1):page181_i31:a"
				( attribute "PN" "1"
					( Origin gPackager )
				)
				( objectStatus "R9R10.1" )
			)
			( pin "@baseboard_fab2_lib.baseboard_fab2(sch_1):page181_i31:b"
				( attribute "PN" "2"
					( Origin gPackager )
				)
				( objectStatus "R9R10.2" )
			)
			( pin "@baseboard_fab2_lib.baseboard_fab2(sch_1):page181_i32:a"
				( attribute "PN" "1"
					( Origin gPackager )
				)
				( objectStatus "R9R9.1" )
			)
			( pin "@baseboard_fab2_lib.baseboard_fab2(sch_1):page181_i32:b"
				( attribute "PN" "2"
					( Origin gPackager )
				)
				( objectStatus "R9R9.2" )
			)
			( pin "@baseboard_fab2_lib.baseboard_fab2(sch_1):page181_i33:a"
				( attribute "PN" "1"
					( Origin gPackager )
				)
				( objectStatus "R9F67.1" )
			)
			( pin "@baseboard_fab2_lib.baseboard_fab2(sch_1):page181_i33:b"
				( attribute "PN" "2"
					( Origin gPackager )
				)
				( objectStatus "R9F67.2" )
			)
			( pin "@baseboard_fab2_lib.baseboard_fab2(sch_1):page181_i34:a"
				( attribute "PN" "1"
					( Origin gPackager )
				)
				( objectStatus "C8E1.1" )
			)
			( pin "@baseboard_fab2_lib.baseboard_fab2(sch_1):page181_i34:b"
				( attribute "PN" "2"
					( Origin gPackager )
				)
				( objectStatus "C8E1.2" )
			)
			( pin "@baseboard_fab2_lib.baseboard_fab2(sch_1):page181_i37:a"
				( attribute "PN" "2"
					( Origin gPackager )
				)
				( objectStatus "CR1F3.2" )
			)
			( pin "@baseboard_fab2_lib.baseboard_fab2(sch_1):page181_i37:c"
				( attribute "PN" "1"
					( Origin gPackager )
				)
				( objectStatus "CR1F3.1" )
			)
			( pin "@baseboard_fab2_lib.baseboard_fab2(sch_1):page181_i40:a"
				( attribute "PN" "1"
					( Origin gPackager )
				)
				( objectStatus "C2R6.1" )
			)
			( pin "@baseboard_fab2_lib.baseboard_fab2(sch_1):page181_i40:b"
				( attribute "PN" "2"
					( Origin gPackager )
				)
				( objectStatus "C2R6.2" )
			)
			( pin "@baseboard_fab2_lib.baseboard_fab2(sch_1):page181_i42:b"
				( attribute "PN" "1"
					( Origin gPackager )
				)
				( objectStatus "Q9T1.1" )
			)
			( pin "@baseboard_fab2_lib.baseboard_fab2(sch_1):page181_i42:c"
				( attribute "PN" "3"
					( Origin gPackager )
				)
				( objectStatus "Q9T1.3" )
			)
			( pin "@baseboard_fab2_lib.baseboard_fab2(sch_1):page181_i42:e"
				( attribute "PN" "2"
					( Origin gPackager )
				)
				( objectStatus "Q9T1.2" )
			)
			( pin "@baseboard_fab2_lib.baseboard_fab2(sch_1):page181_i60:a(0)"
				( attribute "PN" "9"
					( Origin gPackager )
				)
				( objectStatus "U8E1.9" )
			)
			( pin "@baseboard_fab2_lib.baseboard_fab2(sch_1):page181_i60:b(0)"
				( attribute "PN" "10"
					( Origin gPackager )
				)
				( objectStatus "U8E1.10" )
			)
			( pin "@baseboard_fab2_lib.baseboard_fab2(sch_1):page181_i60:y(0)"
				( attribute "PN" "8"
					( Origin gPackager )
				)
				( objectStatus "U8E1.8" )
			)
			( pin "@baseboard_fab2_lib.baseboard_fab2(sch_1):page181_i63:a"
				( attribute "PN" "1"
					( Origin gPackager )
				)
				( objectStatus "R8E5.1" )
			)
			( pin "@baseboard_fab2_lib.baseboard_fab2(sch_1):page181_i63:b"
				( attribute "PN" "2"
					( Origin gPackager )
				)
				( objectStatus "R8E5.2" )
			)
			( pin "@baseboard_fab2_lib.baseboard_fab2(sch_1):page181_i64:a"
				( attribute "PN" "1"
					( Origin gPackager )
				)
				( objectStatus "R9T3.1" )
			)
			( pin "@baseboard_fab2_lib.baseboard_fab2(sch_1):page181_i64:b"
				( attribute "PN" "2"
					( Origin gPackager )
				)
				( objectStatus "R9T3.2" )
			)
			( pin "@baseboard_fab2_lib.baseboard_fab2(sch_1):page181_i68:a"
				( attribute "PN" "1"
					( Origin gPackager )
				)
				( objectStatus "R9T6.1" )
			)
			( pin "@baseboard_fab2_lib.baseboard_fab2(sch_1):page181_i68:b"
				( attribute "PN" "2"
					( Origin gPackager )
				)
				( objectStatus "R9T6.2" )
			)
			( pin "@baseboard_fab2_lib.baseboard_fab2(sch_1):page181_i70:a"
				( attribute "PN" "1"
					( Origin gPackager )
				)
				( objectStatus "C1F14.1" )
			)
			( pin "@baseboard_fab2_lib.baseboard_fab2(sch_1):page181_i70:b"
				( attribute "PN" "2"
					( Origin gPackager )
				)
				( objectStatus "C1F14.2" )
			)
			( pin "@baseboard_fab2_lib.baseboard_fab2(sch_1):page181_i71:a"
				( attribute "PN" "1"
					( Origin gPackager )
				)
				( objectStatus "C1F17.1" )
			)
			( pin "@baseboard_fab2_lib.baseboard_fab2(sch_1):page181_i71:b"
				( attribute "PN" "2"
					( Origin gPackager )
				)
				( objectStatus "C1F17.2" )
			)
			( pin "@baseboard_fab2_lib.baseboard_fab2(sch_1):page181_i72:a"
				( attribute "PN" "1"
					( Origin gPackager )
				)
				( objectStatus "C1F18.1" )
			)
			( pin "@baseboard_fab2_lib.baseboard_fab2(sch_1):page181_i72:b"
				( attribute "PN" "2"
					( Origin gPackager )
				)
				( objectStatus "C1F18.2" )
			)
			( pin "@baseboard_fab2_lib.baseboard_fab2(sch_1):page181_i73:a"
				( attribute "PN" "1"
					( Origin gPackager )
				)
				( objectStatus "C1F8.1" )
			)
			( pin "@baseboard_fab2_lib.baseboard_fab2(sch_1):page181_i73:b"
				( attribute "PN" "2"
					( Origin gPackager )
				)
				( objectStatus "C1F8.2" )
			)
			( pin "@baseboard_fab2_lib.baseboard_fab2(sch_1):page181_i74:a"
				( attribute "PN" "1"
					( Origin gPackager )
				)
				( objectStatus "C1F11.1" )
			)
			( pin "@baseboard_fab2_lib.baseboard_fab2(sch_1):page181_i74:b"
				( attribute "PN" "2"
					( Origin gPackager )
				)
				( objectStatus "C1F11.2" )
			)
			( pin "@baseboard_fab2_lib.baseboard_fab2(sch_1):page181_i75:a"
				( attribute "PN" "1"
					( Origin gPackager )
				)
				( objectStatus "C1F12.1" )
			)
			( pin "@baseboard_fab2_lib.baseboard_fab2(sch_1):page181_i75:b"
				( attribute "PN" "2"
					( Origin gPackager )
				)
				( objectStatus "C1F12.2" )
			)
			( pin "@baseboard_fab2_lib.baseboard_fab2(sch_1):page181_i76:a"
				( attribute "PN" "1"
					( Origin gPackager )
				)
				( objectStatus "C1F3.1" )
			)
			( pin "@baseboard_fab2_lib.baseboard_fab2(sch_1):page181_i76:b"
				( attribute "PN" "2"
					( Origin gPackager )
				)
				( objectStatus "C1F3.2" )
			)
			( pin "@baseboard_fab2_lib.baseboard_fab2(sch_1):page181_i77:a"
				( attribute "PN" "1"
					( Origin gPackager )
				)
				( objectStatus "C1F5.1" )
			)
			( pin "@baseboard_fab2_lib.baseboard_fab2(sch_1):page181_i77:b"
				( attribute "PN" "2"
					( Origin gPackager )
				)
				( objectStatus "C1F5.2" )
			)
			( pin "@baseboard_fab2_lib.baseboard_fab2(sch_1):page181_i78:a"
				( attribute "PN" "1"
					( Origin gPackager )
				)
				( objectStatus "C1F15.1" )
			)
			( pin "@baseboard_fab2_lib.baseboard_fab2(sch_1):page181_i78:b"
				( attribute "PN" "2"
					( Origin gPackager )
				)
				( objectStatus "C1F15.2" )
			)
			( pin "@baseboard_fab2_lib.baseboard_fab2(sch_1):page181_i79:a"
				( attribute "PN" "1"
					( Origin gPackager )
				)
				( objectStatus "C1F16.1" )
			)
			( pin "@baseboard_fab2_lib.baseboard_fab2(sch_1):page181_i79:b"
				( attribute "PN" "2"
					( Origin gPackager )
				)
				( objectStatus "C1F16.2" )
			)
			( pin "@baseboard_fab2_lib.baseboard_fab2(sch_1):page181_i80:a"
				( attribute "PN" "1"
					( Origin gPackager )
				)
				( objectStatus "R7D9.1" )
			)
			( pin "@baseboard_fab2_lib.baseboard_fab2(sch_1):page181_i80:b"
				( attribute "PN" "2"
					( Origin gPackager )
				)
				( objectStatus "R7D9.2" )
			)
			( pin "@baseboard_fab2_lib.baseboard_fab2(sch_1):page181_i81:a"
				( attribute "PN" "1"
					( Origin gPackager )
				)
				( objectStatus "R3P61.1" )
			)
			( pin "@baseboard_fab2_lib.baseboard_fab2(sch_1):page181_i81:b"
				( attribute "PN" "2"
					( Origin gPackager )
				)
				( objectStatus "R3P61.2" )
			)
			( pin "@baseboard_fab2_lib.baseboard_fab2(sch_1):page181_i82:a"
				( attribute "PN" "1"
					( Origin gPackager )
				)
				( objectStatus "R7D5.1" )
			)
			( pin "@baseboard_fab2_lib.baseboard_fab2(sch_1):page181_i82:b"
				( attribute "PN" "2"
					( Origin gPackager )
				)
				( objectStatus "R7D5.2" )
			)
			( pin "@baseboard_fab2_lib.baseboard_fab2(sch_1):page181_i86:a"
				( attribute "PN" "1"
					( Origin gPackager )
				)
				( objectStatus "C1F20.1" )
			)
			( pin "@baseboard_fab2_lib.baseboard_fab2(sch_1):page181_i86:b"
				( attribute "PN" "2"
					( Origin gPackager )
				)
				( objectStatus "C1F20.2" )
			)
			( pin "@baseboard_fab2_lib.baseboard_fab2(sch_1):page181_i87:a"
				( attribute "PN" "1"
					( Origin gPackager )
				)
				( objectStatus "C1F10.1" )
			)
			( pin "@baseboard_fab2_lib.baseboard_fab2(sch_1):page181_i87:b"
				( attribute "PN" "2"
					( Origin gPackager )
				)
				( objectStatus "C1F10.2" )
			)
			( pin "@baseboard_fab2_lib.baseboard_fab2(sch_1):page181_i88:a"
				( attribute "PN" "1"
					( Origin gPackager )
				)
				( objectStatus "C1F6.1" )
			)
			( pin "@baseboard_fab2_lib.baseboard_fab2(sch_1):page181_i88:b"
				( attribute "PN" "2"
					( Origin gPackager )
				)
				( objectStatus "C1F6.2" )
			)
			( pin "@baseboard_fab2_lib.baseboard_fab2(sch_1):page181_i89:a"
				( attribute "PN" "1"
					( Origin gPackager )
				)
				( objectStatus "C1F13.1" )
			)
			( pin "@baseboard_fab2_lib.baseboard_fab2(sch_1):page181_i89:b"
				( attribute "PN" "2"
					( Origin gPackager )
				)
				( objectStatus "C1F13.2" )
			)
			( pin "@baseboard_fab2_lib.baseboard_fab2(sch_1):page181_i90:a"
				( attribute "PN" "1"
					( Origin gPackager )
				)
				( objectStatus "C1F2.1" )
			)
			( pin "@baseboard_fab2_lib.baseboard_fab2(sch_1):page181_i90:b"
				( attribute "PN" "2"
					( Origin gPackager )
				)
				( objectStatus "C1F2.2" )
			)
			( pin "@baseboard_fab2_lib.baseboard_fab2(sch_1):page181_i91:a"
				( attribute "PN" "1"
					( Origin gPackager )
				)
				( objectStatus "C1F4.1" )
			)
			( pin "@baseboard_fab2_lib.baseboard_fab2(sch_1):page181_i91:b"
				( attribute "PN" "2"
					( Origin gPackager )
				)
				( objectStatus "C1F4.2" )
			)
			( pin "@baseboard_fab2_lib.baseboard_fab2(sch_1):page181_i106:io1"
				( attribute "PN" "1"
					( Origin gPackager )
				)
				( objectStatus "J1F3.1" )
			)
			( pin "@baseboard_fab2_lib.baseboard_fab2(sch_1):page181_i106:io2"
				( attribute "PN" "2"
					( Origin gPackager )
				)
				( objectStatus "J1F3.2" )
			)
			( pin "@baseboard_fab2_lib.baseboard_fab2(sch_1):page181_i106:io3"
				( attribute "PN" "3"
					( Origin gPackager )
				)
				( objectStatus "J1F3.3" )
			)
			( pin "@baseboard_fab2_lib.baseboard_fab2(sch_1):page181_i106:io4"
				( attribute "PN" "4"
					( Origin gPackager )
				)
				( objectStatus "J1F3.4" )
			)
			( pin "@baseboard_fab2_lib.baseboard_fab2(sch_1):page181_i106:io5"
				( attribute "PN" "5"
					( Origin gPackager )
				)
				( objectStatus "J1F3.5" )
			)
			( pin "@baseboard_fab2_lib.baseboard_fab2(sch_1):page181_i106:io6"
				( attribute "PN" "6"
					( Origin gPackager )
				)
				( objectStatus "J1F3.6" )
			)
			( pin "@baseboard_fab2_lib.baseboard_fab2(sch_1):page181_i106:io7"
				( attribute "PN" "7"
					( Origin gPackager )
				)
				( objectStatus "J1F3.7" )
			)
			( pin "@baseboard_fab2_lib.baseboard_fab2(sch_1):page181_i106:io8"
				( attribute "PN" "8"
					( Origin gPackager )
				)
				( objectStatus "J1F3.8" )
			)
			( pin "@baseboard_fab2_lib.baseboard_fab2(sch_1):page182_i79:com_rx"
				( attribute "PN" "H3"
					( Origin gPackager )
				)
				( objectStatus "J1C1.H3" )
			)
			( pin "@baseboard_fab2_lib.baseboard_fab2(sch_1):page182_i79:com_tx"
				( attribute "PN" "G3"
					( Origin gPackager )
				)
				( objectStatus "J1C1.G3" )
			)
			( pin "@baseboard_fab2_lib.baseboard_fab2(sch_1):page182_i79:fan_pwm0"
				( attribute "PN" "F4"
					( Origin gPackager )
				)
				( objectStatus "J1C1.F4" )
			)
			( pin "@baseboard_fab2_lib.baseboard_fab2(sch_1):page182_i79:fan_tach0"
				( attribute "PN" "D4"
					( Origin gPackager )
				)
				( objectStatus "J1C1.D4" )
			)
			( pin "@baseboard_fab2_lib.baseboard_fab2(sch_1):page182_i79:fan_tach1"
				( attribute "PN" "C4"
					( Origin gPackager )
				)
				( objectStatus "J1C1.C4" )
			)
			( pin "@baseboard_fab2_lib.baseboard_fab2(sch_1):page182_i79:fan_tach2"
				( attribute "PN" "B4"
					( Origin gPackager )
				)
				( objectStatus "J1C1.B4" )
			)
			( pin "@baseboard_fab2_lib.baseboard_fab2(sch_1):page182_i79:fan_tach3"
				( attribute "PN" "A4"
					( Origin gPackager )
				)
				( objectStatus "J1C1.A4" )
			)
			( pin "@baseboard_fab2_lib.baseboard_fab2(sch_1):page182_i79:gnd1"
				( attribute "PN" "A2"
					( Origin gPackager )
				)
				( objectStatus "J1C1.A2" )
			)
			( pin "@baseboard_fab2_lib.baseboard_fab2(sch_1):page182_i79:gnd2"
				( attribute "PN" "A8"
					( Origin gPackager )
				)
				( objectStatus "J1C1.A8" )
			)
			( pin "@baseboard_fab2_lib.baseboard_fab2(sch_1):page182_i79:gnd3"
				( attribute "PN" "C1"
					( Origin gPackager )
				)
				( objectStatus "J1C1.C1" )
			)
			( pin "@baseboard_fab2_lib.baseboard_fab2(sch_1):page182_i79:gnd4"
				( attribute "PN" "C3"
					( Origin gPackager )
				)
				( objectStatus "J1C1.C3" )
			)
			( pin "@baseboard_fab2_lib.baseboard_fab2(sch_1):page182_i79:gnd5"
				( attribute "PN" "C5"
					( Origin gPackager )
				)
				( objectStatus "J1C1.C5" )
			)
			( pin "@baseboard_fab2_lib.baseboard_fab2(sch_1):page182_i79:gnd6"
				( attribute "PN" "C7"
					( Origin gPackager )
				)
				( objectStatus "J1C1.C7" )
			)
			( pin "@baseboard_fab2_lib.baseboard_fab2(sch_1):page182_i79:gnd7"
				( attribute "PN" "D2"
					( Origin gPackager )
				)
				( objectStatus "J1C1.D2" )
			)
			( pin "@baseboard_fab2_lib.baseboard_fab2(sch_1):page182_i79:gnd8"
				( attribute "PN" "D6"
					( Origin gPackager )
				)
				( objectStatus "J1C1.D6" )
			)
			( pin "@baseboard_fab2_lib.baseboard_fab2(sch_1):page182_i79:gnd9"
				( attribute "PN" "D8"
					( Origin gPackager )
				)
				( objectStatus "J1C1.D8" )
			)
			( pin "@baseboard_fab2_lib.baseboard_fab2(sch_1):page182_i79:gnd10"
				( attribute "PN" "F1"
					( Origin gPackager )
				)
				( objectStatus "J1C1.F1" )
			)
			( pin "@baseboard_fab2_lib.baseboard_fab2(sch_1):page182_i79:gnd11"
				( attribute "PN" "F3"
					( Origin gPackager )
				)
				( objectStatus "J1C1.F3" )
			)
			( pin "@baseboard_fab2_lib.baseboard_fab2(sch_1):page182_i79:gnd12"
				( attribute "PN" "F7"
					( Origin gPackager )
				)
				( objectStatus "J1C1.F7" )
			)
			( pin "@baseboard_fab2_lib.baseboard_fab2(sch_1):page182_i79:gnd13"
				( attribute "PN" "G2"
					( Origin gPackager )
				)
				( objectStatus "J1C1.G2" )
			)
			( pin "@baseboard_fab2_lib.baseboard_fab2(sch_1):page182_i79:gnd14"
				( attribute "PN" "G4"
					( Origin gPackager )
				)
				( objectStatus "J1C1.G4" )
			)
			( pin "@baseboard_fab2_lib.baseboard_fab2(sch_1):page182_i79:gnd15"
				( attribute "PN" "G6"
					( Origin gPackager )
				)
				( objectStatus "J1C1.G6" )
			)
			( pin "@baseboard_fab2_lib.baseboard_fab2(sch_1):page182_i79:gnd16"
				( attribute "PN" "G8"
					( Origin gPackager )
				)
				( objectStatus "J1C1.G8" )
			)
			( pin "@baseboard_fab2_lib.baseboard_fab2(sch_1):page182_i79:gnd17"
				( attribute "PN" "I1"
					( Origin gPackager )
				)
				( objectStatus "J1C1.I1" )
			)
			( pin "@baseboard_fab2_lib.baseboard_fab2(sch_1):page182_i79:gnd18"
				( attribute "PN" "I7"
					( Origin gPackager )
				)
				( objectStatus "J1C1.I7" )
			)
			( pin "@baseboard_fab2_lib.baseboard_fab2(sch_1):page182_i79:j2"
				( attribute "PN" "J2"
					( Origin gPackager )
				)
				( objectStatus "J1C1.J2" )
			)
			( pin "@baseboard_fab2_lib.baseboard_fab2(sch_1):page182_i79:j4"
				( attribute "PN" "J4"
					( Origin gPackager )
				)
				( objectStatus "J1C1.J4" )
			)
			( pin "@baseboard_fab2_lib.baseboard_fab2(sch_1):page182_i79:j6"
				( attribute "PN" "J6"
					( Origin gPackager )
				)
				( objectStatus "J1C1.J6" )
			)
			( pin "@baseboard_fab2_lib.baseboard_fab2(sch_1):page182_i79:j8"
				( attribute "PN" "J8"
					( Origin gPackager )
				)
				( objectStatus "J1C1.J8" )
			)
			( pin "@baseboard_fab2_lib.baseboard_fab2(sch_1):page182_i79:\mated_in#\"
				( attribute "PN" "E4"
					( Origin gPackager )
				)
				( objectStatus "J1C1.E4" )
			)
			( pin "@baseboard_fab2_lib.baseboard_fab2(sch_1):page182_i79:\mb_on#\"
				( attribute "PN" "I3"
					( Origin gPackager )
				)
				( objectStatus "J1C1.I3" )
			)
			( pin "@baseboard_fab2_lib.baseboard_fab2(sch_1):page182_i79:mb_slot_id0"
				( attribute "PN" "F5"
					( Origin gPackager )
				)
				( objectStatus "J1C1.F5" )
			)
			( pin "@baseboard_fab2_lib.baseboard_fab2(sch_1):page182_i79:mb_slot_id1"
				( attribute "PN" "G5"
					( Origin gPackager )
				)
				( objectStatus "J1C1.G5" )
			)
			( pin "@baseboard_fab2_lib.baseboard_fab2(sch_1):page182_i79:mb_slot_id2"
				( attribute "PN" "H5"
					( Origin gPackager )
				)
				( objectStatus "J1C1.H5" )
			)
			( pin "@baseboard_fab2_lib.baseboard_fab2(sch_1):page182_i79:mng_rx_dn"
				( attribute "PN" "E5"
					( Origin gPackager )
				)
				( objectStatus "J1C1.E5" )
			)
			( pin "@baseboard_fab2_lib.baseboard_fab2(sch_1):page182_i79:mng_rx_dp"
				( attribute "PN" "D5"
					( Origin gPackager )
				)
				( objectStatus "J1C1.D5" )
			)
			( pin "@baseboard_fab2_lib.baseboard_fab2(sch_1):page182_i79:mng_tx_dn"
				( attribute "PN" "B5"
					( Origin gPackager )
				)
				( objectStatus "J1C1.B5" )
			)
			( pin "@baseboard_fab2_lib.baseboard_fab2(sch_1):page182_i79:mng_tx_dp"
				( attribute "PN" "A5"
					( Origin gPackager )
				)
				( objectStatus "J1C1.A5" )
			)
			( pin "@baseboard_fab2_lib.baseboard_fab2(sch_1):page182_i79:pcie_clk_100m_dn"
				( attribute "PN" "I4"
					( Origin gPackager )
				)
				( objectStatus "J1C1.I4" )
			)
			( pin "@baseboard_fab2_lib.baseboard_fab2(sch_1):page182_i79:pcie_clk_100m_dp"
				( attribute "PN" "H4"
					( Origin gPackager )
				)
				( objectStatus "J1C1.H4" )
			)
			( pin "@baseboard_fab2_lib.baseboard_fab2(sch_1):page182_i79:\pcie_perst#\"
				( attribute "PN" "I5"
					( Origin gPackager )
				)
				( objectStatus "J1C1.I5" )
			)
			( pin "@baseboard_fab2_lib.baseboard_fab2(sch_1):page182_i79:pcie_rx_dn0"
				( attribute "PN" "B1"
					( Origin gPackager )
				)
				( objectStatus "J1C1.B1" )
			)
			( pin "@baseboard_fab2_lib.baseboard_fab2(sch_1):page182_i79:pcie_rx_dn1"
				( attribute "PN" "E1"
					( Origin gPackager )
				)
				( objectStatus "J1C1.E1" )
			)
			( pin "@baseboard_fab2_lib.baseboard_fab2(sch_1):page182_i79:pcie_rx_dn2"
				( attribute "PN" "H1"
					( Origin gPackager )
				)
				( objectStatus "J1C1.H1" )
			)
			( pin "@baseboard_fab2_lib.baseboard_fab2(sch_1):page182_i79:pcie_rx_dn3"
				( attribute "PN" "C2"
					( Origin gPackager )
				)
				( objectStatus "J1C1.C2" )
			)
			( pin "@baseboard_fab2_lib.baseboard_fab2(sch_1):page182_i79:pcie_rx_dn4"
				( attribute "PN" "F2"
					( Origin gPackager )
				)
				( objectStatus "J1C1.F2" )
			)
			( pin "@baseboard_fab2_lib.baseboard_fab2(sch_1):page182_i79:pcie_rx_dn5"
				( attribute "PN" "I2"
					( Origin gPackager )
				)
				( objectStatus "J1C1.I2" )
			)
			( pin "@baseboard_fab2_lib.baseboard_fab2(sch_1):page182_i79:pcie_rx_dn6"
				( attribute "PN" "B3"
					( Origin gPackager )
				)
				( objectStatus "J1C1.B3" )
			)
			( pin "@baseboard_fab2_lib.baseboard_fab2(sch_1):page182_i79:pcie_rx_dn7"
				( attribute "PN" "E3"
					( Origin gPackager )
				)
				( objectStatus "J1C1.E3" )
			)
			( pin "@baseboard_fab2_lib.baseboard_fab2(sch_1):page182_i79:pcie_rx_dp0"
				( attribute "PN" "A1"
					( Origin gPackager )
				)
				( objectStatus "J1C1.A1" )
			)
			( pin "@baseboard_fab2_lib.baseboard_fab2(sch_1):page182_i79:pcie_rx_dp1"
				( attribute "PN" "D1"
					( Origin gPackager )
				)
				( objectStatus "J1C1.D1" )
			)
			( pin "@baseboard_fab2_lib.baseboard_fab2(sch_1):page182_i79:pcie_rx_dp2"
				( attribute "PN" "G1"
					( Origin gPackager )
				)
				( objectStatus "J1C1.G1" )
			)
			( pin "@baseboard_fab2_lib.baseboard_fab2(sch_1):page182_i79:pcie_rx_dp3"
				( attribute "PN" "B2"
					( Origin gPackager )
				)
				( objectStatus "J1C1.B2" )
			)
			( pin "@baseboard_fab2_lib.baseboard_fab2(sch_1):page182_i79:pcie_rx_dp4"
				( attribute "PN" "E2"
					( Origin gPackager )
				)
				( objectStatus "J1C1.E2" )
			)
			( pin "@baseboard_fab2_lib.baseboard_fab2(sch_1):page182_i79:pcie_rx_dp5"
				( attribute "PN" "H2"
					( Origin gPackager )
				)
				( objectStatus "J1C1.H2" )
			)
			( pin "@baseboard_fab2_lib.baseboard_fab2(sch_1):page182_i79:pcie_rx_dp6"
				( attribute "PN" "A3"
					( Origin gPackager )
				)
				( objectStatus "J1C1.A3" )
			)
			( pin "@baseboard_fab2_lib.baseboard_fab2(sch_1):page182_i79:pcie_rx_dp7"
				( attribute "PN" "D3"
					( Origin gPackager )
				)
				( objectStatus "J1C1.D3" )
			)
			( pin "@baseboard_fab2_lib.baseboard_fab2(sch_1):page182_i79:pcie_tx_dn0"
				( attribute "PN" "C8"
					( Origin gPackager )
				)
				( objectStatus "J1C1.C8" )
			)
			( pin "@baseboard_fab2_lib.baseboard_fab2(sch_1):page182_i79:pcie_tx_dn1"
				( attribute "PN" "F8"
					( Origin gPackager )
				)
				( objectStatus "J1C1.F8" )
			)
			( pin "@baseboard_fab2_lib.baseboard_fab2(sch_1):page182_i79:pcie_tx_dn2"
				( attribute "PN" "I8"
					( Origin gPackager )
				)
				( objectStatus "J1C1.I8" )
			)
			( pin "@baseboard_fab2_lib.baseboard_fab2(sch_1):page182_i79:pcie_tx_dn3"
				( attribute "PN" "B7"
					( Origin gPackager )
				)
				( objectStatus "J1C1.B7" )
			)
			( pin "@baseboard_fab2_lib.baseboard_fab2(sch_1):page182_i79:pcie_tx_dn4"
				( attribute "PN" "E7"
					( Origin gPackager )
				)
				( objectStatus "J1C1.E7" )
			)
			( pin "@baseboard_fab2_lib.baseboard_fab2(sch_1):page182_i79:pcie_tx_dn5"
				( attribute "PN" "H7"
					( Origin gPackager )
				)
				( objectStatus "J1C1.H7" )
			)
			( pin "@baseboard_fab2_lib.baseboard_fab2(sch_1):page182_i79:pcie_tx_dn6"
				( attribute "PN" "F6"
					( Origin gPackager )
				)
				( objectStatus "J1C1.F6" )
			)
			( pin "@baseboard_fab2_lib.baseboard_fab2(sch_1):page182_i79:pcie_tx_dn7"
				( attribute "PN" "I6"
					( Origin gPackager )
				)
				( objectStatus "J1C1.I6" )
			)
			( pin "@baseboard_fab2_lib.baseboard_fab2(sch_1):page182_i79:pcie_tx_dp0"
				( attribute "PN" "B8"
					( Origin gPackager )
				)
				( objectStatus "J1C1.B8" )
			)
			( pin "@baseboard_fab2_lib.baseboard_fab2(sch_1):page182_i79:pcie_tx_dp1"
				( attribute "PN" "E8"
					( Origin gPackager )
				)
				( objectStatus "J1C1.E8" )
			)
			( pin "@baseboard_fab2_lib.baseboard_fab2(sch_1):page182_i79:pcie_tx_dp2"
				( attribute "PN" "H8"
					( Origin gPackager )
				)
				( objectStatus "J1C1.H8" )
			)
			( pin "@baseboard_fab2_lib.baseboard_fab2(sch_1):page182_i79:pcie_tx_dp3"
				( attribute "PN" "A7"
					( Origin gPackager )
				)
				( objectStatus "J1C1.A7" )
			)
			( pin "@baseboard_fab2_lib.baseboard_fab2(sch_1):page182_i79:pcie_tx_dp4"
				( attribute "PN" "D7"
					( Origin gPackager )
				)
				( objectStatus "J1C1.D7" )
			)
			( pin "@baseboard_fab2_lib.baseboard_fab2(sch_1):page182_i79:pcie_tx_dp5"
				( attribute "PN" "G7"
					( Origin gPackager )
				)
				( objectStatus "J1C1.G7" )
			)
			( pin "@baseboard_fab2_lib.baseboard_fab2(sch_1):page182_i79:pcie_tx_dp6"
				( attribute "PN" "E6"
					( Origin gPackager )
				)
				( objectStatus "J1C1.E6" )
			)
			( pin "@baseboard_fab2_lib.baseboard_fab2(sch_1):page182_i79:pcie_tx_dp7"
				( attribute "PN" "H6"
					( Origin gPackager )
				)
				( objectStatus "J1C1.H6" )
			)
			( pin "@baseboard_fab2_lib.baseboard_fab2(sch_1):page182_i79:\pmbus_alert#\"
				( attribute "PN" "A6"
					( Origin gPackager )
				)
				( objectStatus "J1C1.A6" )
			)
			( pin "@baseboard_fab2_lib.baseboard_fab2(sch_1):page182_i79:pmbus_clk"
				( attribute "PN" "C6"
					( Origin gPackager )
				)
				( objectStatus "J1C1.C6" )
			)
			( pin "@baseboard_fab2_lib.baseboard_fab2(sch_1):page182_i79:pmbus_data"
				( attribute "PN" "B6"
					( Origin gPackager )
				)
				( objectStatus "J1C1.B6" )
			)
			( pin "@baseboard_fab2_lib.baseboard_fab2(sch_1):page241_i100:\1\"
				( attribute "PN" "1"
					( Origin gPackager )
				)
				( objectStatus "C8E4.1" )
			)
			( pin "@baseboard_fab2_lib.baseboard_fab2(sch_1):page241_i100:\2\"
				( attribute "PN" "2"
					( Origin gPackager )
				)
				( objectStatus "C8E4.2" )
			)
			( pin "@baseboard_fab2_lib.baseboard_fab2(sch_1):page181_i134:com_rx"
				( attribute "PN" "H3"
					( Origin gPackager )
				)
				( objectStatus "J1F1.H3" )
			)
			( pin "@baseboard_fab2_lib.baseboard_fab2(sch_1):page181_i134:com_tx"
				( attribute "PN" "G3"
					( Origin gPackager )
				)
				( objectStatus "J1F1.G3" )
			)
			( pin "@baseboard_fab2_lib.baseboard_fab2(sch_1):page181_i134:fan_pwm0"
				( attribute "PN" "F4"
					( Origin gPackager )
				)
				( objectStatus "J1F1.F4" )
			)
			( pin "@baseboard_fab2_lib.baseboard_fab2(sch_1):page181_i134:fan_tach0"
				( attribute "PN" "D4"
					( Origin gPackager )
				)
				( objectStatus "J1F1.D4" )
			)
			( pin "@baseboard_fab2_lib.baseboard_fab2(sch_1):page181_i134:fan_tach1"
				( attribute "PN" "C4"
					( Origin gPackager )
				)
				( objectStatus "J1F1.C4" )
			)
			( pin "@baseboard_fab2_lib.baseboard_fab2(sch_1):page181_i134:fan_tach2"
				( attribute "PN" "B4"
					( Origin gPackager )
				)
				( objectStatus "J1F1.B4" )
			)
			( pin "@baseboard_fab2_lib.baseboard_fab2(sch_1):page181_i134:fan_tach3"
				( attribute "PN" "A4"
					( Origin gPackager )
				)
				( objectStatus "J1F1.A4" )
			)
			( pin "@baseboard_fab2_lib.baseboard_fab2(sch_1):page181_i134:gnd1"
				( attribute "PN" "A2"
					( Origin gPackager )
				)
				( objectStatus "J1F1.A2" )
			)
			( pin "@baseboard_fab2_lib.baseboard_fab2(sch_1):page181_i134:gnd2"
				( attribute "PN" "A8"
					( Origin gPackager )
				)
				( objectStatus "J1F1.A8" )
			)
			( pin "@baseboard_fab2_lib.baseboard_fab2(sch_1):page181_i134:gnd3"
				( attribute "PN" "C1"
					( Origin gPackager )
				)
				( objectStatus "J1F1.C1" )
			)
			( pin "@baseboard_fab2_lib.baseboard_fab2(sch_1):page181_i134:gnd4"
				( attribute "PN" "C3"
					( Origin gPackager )
				)
				( objectStatus "J1F1.C3" )
			)
			( pin "@baseboard_fab2_lib.baseboard_fab2(sch_1):page181_i134:gnd5"
				( attribute "PN" "C5"
					( Origin gPackager )
				)
				( objectStatus "J1F1.C5" )
			)
			( pin "@baseboard_fab2_lib.baseboard_fab2(sch_1):page181_i134:gnd6"
				( attribute "PN" "C7"
					( Origin gPackager )
				)
				( objectStatus "J1F1.C7" )
			)
			( pin "@baseboard_fab2_lib.baseboard_fab2(sch_1):page181_i134:gnd7"
				( attribute "PN" "D2"
					( Origin gPackager )
				)
				( objectStatus "J1F1.D2" )
			)
			( pin "@baseboard_fab2_lib.baseboard_fab2(sch_1):page181_i134:gnd8"
				( attribute "PN" "D6"
					( Origin gPackager )
				)
				( objectStatus "J1F1.D6" )
			)
			( pin "@baseboard_fab2_lib.baseboard_fab2(sch_1):page181_i134:gnd9"
				( attribute "PN" "D8"
					( Origin gPackager )
				)
				( objectStatus "J1F1.D8" )
			)
			( pin "@baseboard_fab2_lib.baseboard_fab2(sch_1):page181_i134:gnd10"
				( attribute "PN" "F1"
					( Origin gPackager )
				)
				( objectStatus "J1F1.F1" )
			)
			( pin "@baseboard_fab2_lib.baseboard_fab2(sch_1):page181_i134:gnd11"
				( attribute "PN" "F3"
					( Origin gPackager )
				)
				( objectStatus "J1F1.F3" )
			)
			( pin "@baseboard_fab2_lib.baseboard_fab2(sch_1):page181_i134:gnd12"
				( attribute "PN" "F7"
					( Origin gPackager )
				)
				( objectStatus "J1F1.F7" )
			)
			( pin "@baseboard_fab2_lib.baseboard_fab2(sch_1):page181_i134:gnd13"
				( attribute "PN" "G2"
					( Origin gPackager )
				)
				( objectStatus "J1F1.G2" )
			)
			( pin "@baseboard_fab2_lib.baseboard_fab2(sch_1):page181_i134:gnd14"
				( attribute "PN" "G4"
					( Origin gPackager )
				)
				( objectStatus "J1F1.G4" )
			)
			( pin "@baseboard_fab2_lib.baseboard_fab2(sch_1):page181_i134:gnd15"
				( attribute "PN" "G6"
					( Origin gPackager )
				)
				( objectStatus "J1F1.G6" )
			)
			( pin "@baseboard_fab2_lib.baseboard_fab2(sch_1):page181_i134:gnd16"
				( attribute "PN" "G8"
					( Origin gPackager )
				)
				( objectStatus "J1F1.G8" )
			)
			( pin "@baseboard_fab2_lib.baseboard_fab2(sch_1):page181_i134:gnd17"
				( attribute "PN" "I1"
					( Origin gPackager )
				)
				( objectStatus "J1F1.I1" )
			)
			( pin "@baseboard_fab2_lib.baseboard_fab2(sch_1):page181_i134:gnd18"
				( attribute "PN" "I7"
					( Origin gPackager )
				)
				( objectStatus "J1F1.I7" )
			)
			( pin "@baseboard_fab2_lib.baseboard_fab2(sch_1):page181_i134:j2"
				( attribute "PN" "J2"
					( Origin gPackager )
				)
				( objectStatus "J1F1.J2" )
			)
			( pin "@baseboard_fab2_lib.baseboard_fab2(sch_1):page181_i134:j4"
				( attribute "PN" "J4"
					( Origin gPackager )
				)
				( objectStatus "J1F1.J4" )
			)
			( pin "@baseboard_fab2_lib.baseboard_fab2(sch_1):page181_i134:j6"
				( attribute "PN" "J6"
					( Origin gPackager )
				)
				( objectStatus "J1F1.J6" )
			)
			( pin "@baseboard_fab2_lib.baseboard_fab2(sch_1):page181_i134:j8"
				( attribute "PN" "J8"
					( Origin gPackager )
				)
				( objectStatus "J1F1.J8" )
			)
			( pin "@baseboard_fab2_lib.baseboard_fab2(sch_1):page181_i134:\mated_in#\"
				( attribute "PN" "E4"
					( Origin gPackager )
				)
				( objectStatus "J1F1.E4" )
			)
			( pin "@baseboard_fab2_lib.baseboard_fab2(sch_1):page181_i134:\mb_on#\"
				( attribute "PN" "I3"
					( Origin gPackager )
				)
				( objectStatus "J1F1.I3" )
			)
			( pin "@baseboard_fab2_lib.baseboard_fab2(sch_1):page181_i134:mb_slot_id0"
				( attribute "PN" "F5"
					( Origin gPackager )
				)
				( objectStatus "J1F1.F5" )
			)
			( pin "@baseboard_fab2_lib.baseboard_fab2(sch_1):page181_i134:mb_slot_id1"
				( attribute "PN" "G5"
					( Origin gPackager )
				)
				( objectStatus "J1F1.G5" )
			)
			( pin "@baseboard_fab2_lib.baseboard_fab2(sch_1):page181_i134:mb_slot_id2"
				( attribute "PN" "H5"
					( Origin gPackager )
				)
				( objectStatus "J1F1.H5" )
			)
			( pin "@baseboard_fab2_lib.baseboard_fab2(sch_1):page181_i134:mng_rx_dn"
				( attribute "PN" "E5"
					( Origin gPackager )
				)
				( objectStatus "J1F1.E5" )
			)
			( pin "@baseboard_fab2_lib.baseboard_fab2(sch_1):page181_i134:mng_rx_dp"
				( attribute "PN" "D5"
					( Origin gPackager )
				)
				( objectStatus "J1F1.D5" )
			)
			( pin "@baseboard_fab2_lib.baseboard_fab2(sch_1):page181_i134:mng_tx_dn"
				( attribute "PN" "B5"
					( Origin gPackager )
				)
				( objectStatus "J1F1.B5" )
			)
			( pin "@baseboard_fab2_lib.baseboard_fab2(sch_1):page181_i134:mng_tx_dp"
				( attribute "PN" "A5"
					( Origin gPackager )
				)
				( objectStatus "J1F1.A5" )
			)
			( pin "@baseboard_fab2_lib.baseboard_fab2(sch_1):page181_i134:pcie_clk_100m_dn"
				( attribute "PN" "I4"
					( Origin gPackager )
				)
				( objectStatus "J1F1.I4" )
			)
			( pin "@baseboard_fab2_lib.baseboard_fab2(sch_1):page181_i134:pcie_clk_100m_dp"
				( attribute "PN" "H4"
					( Origin gPackager )
				)
				( objectStatus "J1F1.H4" )
			)
			( pin "@baseboard_fab2_lib.baseboard_fab2(sch_1):page181_i134:\pcie_perst#\"
				( attribute "PN" "I5"
					( Origin gPackager )
				)
				( objectStatus "J1F1.I5" )
			)
			( pin "@baseboard_fab2_lib.baseboard_fab2(sch_1):page181_i134:pcie_rx_dn0"
				( attribute "PN" "B1"
					( Origin gPackager )
				)
				( objectStatus "J1F1.B1" )
			)
			( pin "@baseboard_fab2_lib.baseboard_fab2(sch_1):page181_i134:pcie_rx_dn1"
				( attribute "PN" "E1"
					( Origin gPackager )
				)
				( objectStatus "J1F1.E1" )
			)
			( pin "@baseboard_fab2_lib.baseboard_fab2(sch_1):page181_i134:pcie_rx_dn2"
				( attribute "PN" "H1"
					( Origin gPackager )
				)
				( objectStatus "J1F1.H1" )
			)
			( pin "@baseboard_fab2_lib.baseboard_fab2(sch_1):page181_i134:pcie_rx_dn3"
				( attribute "PN" "C2"
					( Origin gPackager )
				)
				( objectStatus "J1F1.C2" )
			)
			( pin "@baseboard_fab2_lib.baseboard_fab2(sch_1):page181_i134:pcie_rx_dn4"
				( attribute "PN" "F2"
					( Origin gPackager )
				)
				( objectStatus "J1F1.F2" )
			)
			( pin "@baseboard_fab2_lib.baseboard_fab2(sch_1):page181_i134:pcie_rx_dn5"
				( attribute "PN" "I2"
					( Origin gPackager )
				)
				( objectStatus "J1F1.I2" )
			)
			( pin "@baseboard_fab2_lib.baseboard_fab2(sch_1):page181_i134:pcie_rx_dn6"
				( attribute "PN" "B3"
					( Origin gPackager )
				)
				( objectStatus "J1F1.B3" )
			)
			( pin "@baseboard_fab2_lib.baseboard_fab2(sch_1):page181_i134:pcie_rx_dn7"
				( attribute "PN" "E3"
					( Origin gPackager )
				)
				( objectStatus "J1F1.E3" )
			)
			( pin "@baseboard_fab2_lib.baseboard_fab2(sch_1):page181_i134:pcie_rx_dp0"
				( attribute "PN" "A1"
					( Origin gPackager )
				)
				( objectStatus "J1F1.A1" )
			)
			( pin "@baseboard_fab2_lib.baseboard_fab2(sch_1):page181_i134:pcie_rx_dp1"
				( attribute "PN" "D1"
					( Origin gPackager )
				)
				( objectStatus "J1F1.D1" )
			)
			( pin "@baseboard_fab2_lib.baseboard_fab2(sch_1):page181_i134:pcie_rx_dp2"
				( attribute "PN" "G1"
					( Origin gPackager )
				)
				( objectStatus "J1F1.G1" )
			)
			( pin "@baseboard_fab2_lib.baseboard_fab2(sch_1):page181_i134:pcie_rx_dp3"
				( attribute "PN" "B2"
					( Origin gPackager )
				)
				( objectStatus "J1F1.B2" )
			)
			( pin "@baseboard_fab2_lib.baseboard_fab2(sch_1):page181_i134:pcie_rx_dp4"
				( attribute "PN" "E2"
					( Origin gPackager )
				)
				( objectStatus "J1F1.E2" )
			)
			( pin "@baseboard_fab2_lib.baseboard_fab2(sch_1):page181_i134:pcie_rx_dp5"
				( attribute "PN" "H2"
					( Origin gPackager )
				)
				( objectStatus "J1F1.H2" )
			)
			( pin "@baseboard_fab2_lib.baseboard_fab2(sch_1):page181_i134:pcie_rx_dp6"
				( attribute "PN" "A3"
					( Origin gPackager )
				)
				( objectStatus "J1F1.A3" )
			)
			( pin "@baseboard_fab2_lib.baseboard_fab2(sch_1):page181_i134:pcie_rx_dp7"
				( attribute "PN" "D3"
					( Origin gPackager )
				)
				( objectStatus "J1F1.D3" )
			)
			( pin "@baseboard_fab2_lib.baseboard_fab2(sch_1):page181_i134:pcie_tx_dn0"
				( attribute "PN" "C8"
					( Origin gPackager )
				)
				( objectStatus "J1F1.C8" )
			)
			( pin "@baseboard_fab2_lib.baseboard_fab2(sch_1):page181_i134:pcie_tx_dn1"
				( attribute "PN" "F8"
					( Origin gPackager )
				)
				( objectStatus "J1F1.F8" )
			)
			( pin "@baseboard_fab2_lib.baseboard_fab2(sch_1):page181_i134:pcie_tx_dn2"
				( attribute "PN" "I8"
					( Origin gPackager )
				)
				( objectStatus "J1F1.I8" )
			)
			( pin "@baseboard_fab2_lib.baseboard_fab2(sch_1):page181_i134:pcie_tx_dn3"
				( attribute "PN" "B7"
					( Origin gPackager )
				)
				( objectStatus "J1F1.B7" )
			)
			( pin "@baseboard_fab2_lib.baseboard_fab2(sch_1):page181_i134:pcie_tx_dn4"
				( attribute "PN" "E7"
					( Origin gPackager )
				)
				( objectStatus "J1F1.E7" )
			)
			( pin "@baseboard_fab2_lib.baseboard_fab2(sch_1):page181_i134:pcie_tx_dn5"
				( attribute "PN" "H7"
					( Origin gPackager )
				)
				( objectStatus "J1F1.H7" )
			)
			( pin "@baseboard_fab2_lib.baseboard_fab2(sch_1):page181_i134:pcie_tx_dn6"
				( attribute "PN" "F6"
					( Origin gPackager )
				)
				( objectStatus "J1F1.F6" )
			)
			( pin "@baseboard_fab2_lib.baseboard_fab2(sch_1):page181_i134:pcie_tx_dn7"
				( attribute "PN" "I6"
					( Origin gPackager )
				)
				( objectStatus "J1F1.I6" )
			)
			( pin "@baseboard_fab2_lib.baseboard_fab2(sch_1):page181_i134:pcie_tx_dp0"
				( attribute "PN" "B8"
					( Origin gPackager )
				)
				( objectStatus "J1F1.B8" )
			)
			( pin "@baseboard_fab2_lib.baseboard_fab2(sch_1):page181_i134:pcie_tx_dp1"
				( attribute "PN" "E8"
					( Origin gPackager )
				)
				( objectStatus "J1F1.E8" )
			)
			( pin "@baseboard_fab2_lib.baseboard_fab2(sch_1):page181_i134:pcie_tx_dp2"
				( attribute "PN" "H8"
					( Origin gPackager )
				)
				( objectStatus "J1F1.H8" )
			)
			( pin "@baseboard_fab2_lib.baseboard_fab2(sch_1):page181_i134:pcie_tx_dp3"
				( attribute "PN" "A7"
					( Origin gPackager )
				)
				( objectStatus "J1F1.A7" )
			)
			( pin "@baseboard_fab2_lib.baseboard_fab2(sch_1):page181_i134:pcie_tx_dp4"
				( attribute "PN" "D7"
					( Origin gPackager )
				)
				( objectStatus "J1F1.D7" )
			)
			( pin "@baseboard_fab2_lib.baseboard_fab2(sch_1):page181_i134:pcie_tx_dp5"
				( attribute "PN" "G7"
					( Origin gPackager )
				)
				( objectStatus "J1F1.G7" )
			)
			( pin "@baseboard_fab2_lib.baseboard_fab2(sch_1):page181_i134:pcie_tx_dp6"
				( attribute "PN" "E6"
					( Origin gPackager )
				)
				( objectStatus "J1F1.E6" )
			)
			( pin "@baseboard_fab2_lib.baseboard_fab2(sch_1):page181_i134:pcie_tx_dp7"
				( attribute "PN" "H6"
					( Origin gPackager )
				)
				( objectStatus "J1F1.H6" )
			)
			( pin "@baseboard_fab2_lib.baseboard_fab2(sch_1):page181_i134:\pmbus_alert#\"
				( attribute "PN" "A6"
					( Origin gPackager )
				)
				( objectStatus "J1F1.A6" )
			)
			( pin "@baseboard_fab2_lib.baseboard_fab2(sch_1):page181_i134:pmbus_clk"
				( attribute "PN" "C6"
					( Origin gPackager )
				)
				( objectStatus "J1F1.C6" )
			)
			( pin "@baseboard_fab2_lib.baseboard_fab2(sch_1):page181_i134:pmbus_data"
				( attribute "PN" "B6"
					( Origin gPackager )
				)
				( objectStatus "J1F1.B6" )
			)
			( pin "@baseboard_fab2_lib.baseboard_fab2(sch_1):page108_i350:a"
				( attribute "PN" "1"
					( Origin gPackager )
				)
				( objectStatus "R2U35.1" )
			)
			( pin "@baseboard_fab2_lib.baseboard_fab2(sch_1):page108_i350:b"
				( attribute "PN" "2"
					( Origin gPackager )
				)
				( objectStatus "R2U35.2" )
			)
			( pin "@baseboard_fab2_lib.baseboard_fab2(sch_1):page108_i351:a"
				( attribute "PN" "1"
					( Origin gPackager )
				)
				( objectStatus "R2U36.1" )
			)
			( pin "@baseboard_fab2_lib.baseboard_fab2(sch_1):page108_i351:b"
				( attribute "PN" "2"
					( Origin gPackager )
				)
				( objectStatus "R2U36.2" )
			)
			( pin "@baseboard_fab2_lib.baseboard_fab2(sch_1):page138_i198:a"
				( attribute "PN" "1"
					( Origin gPackager )
				)
				( objectStatus "R24W1.1" )
			)
			( pin "@baseboard_fab2_lib.baseboard_fab2(sch_1):page138_i198:b"
				( attribute "PN" "2"
					( Origin gPackager )
				)
				( objectStatus "R24W1.2" )
			)
			( pin "@baseboard_fab2_lib.baseboard_fab2(sch_1):page138_i199:a"
				( attribute "PN" "1"
					( Origin gPackager )
				)
				( objectStatus "R24W2.1" )
			)
			( pin "@baseboard_fab2_lib.baseboard_fab2(sch_1):page138_i199:b"
				( attribute "PN" "2"
					( Origin gPackager )
				)
				( objectStatus "R24W2.2" )
			)
			( pin "@baseboard_fab2_lib.baseboard_fab2(sch_1):page164_i41:a"
				( attribute "PN" "1"
					( Origin gPackager )
				)
				( objectStatus "R1U21.1" )
			)
			( pin "@baseboard_fab2_lib.baseboard_fab2(sch_1):page164_i41:b"
				( attribute "PN" "2"
					( Origin gPackager )
				)
				( objectStatus "R1U21.2" )
			)
			( pin "@baseboard_fab2_lib.baseboard_fab2(sch_1):page164_i43:a"
				( attribute "PN" "1"
					( Origin gPackager )
				)
				( objectStatus "R1U22.1" )
			)
			( pin "@baseboard_fab2_lib.baseboard_fab2(sch_1):page164_i43:b"
				( attribute "PN" "2"
					( Origin gPackager )
				)
				( objectStatus "R1U22.2" )
			)
			( pin "@baseboard_fab2_lib.baseboard_fab2(sch_1):page246_i21:a"
				( attribute "PN" "1"
					( Origin gPackager )
				)
				( objectStatus "CN8F1.1" )
			)
			( pin "@baseboard_fab2_lib.baseboard_fab2(sch_1):page246_i21:b"
				( attribute "PN" "2"
					( Origin gPackager )
				)
				( objectStatus "CN8F1.2" )
			)
			( pin "@baseboard_fab2_lib.baseboard_fab2(sch_1):page151_i214:a"
				( attribute "PN" "1"
					( Origin gPackager )
				)
				( objectStatus "C25W11.1" )
			)
			( pin "@baseboard_fab2_lib.baseboard_fab2(sch_1):page151_i214:b"
				( attribute "PN" "2"
					( Origin gPackager )
				)
				( objectStatus "C25W11.2" )
			)
			( pin "@baseboard_fab2_lib.baseboard_fab2(sch_1):page149_i121:a"
				( attribute "PN" "1"
					( Origin gPackager )
				)
				( objectStatus "C25W38.1" )
			)
			( pin "@baseboard_fab2_lib.baseboard_fab2(sch_1):page149_i121:b"
				( attribute "PN" "2"
					( Origin gPackager )
				)
				( objectStatus "C25W38.2" )
			)
			( pin "@baseboard_fab2_lib.baseboard_fab2(sch_1):page149_i122:a"
				( attribute "PN" "1"
					( Origin gPackager )
				)
				( objectStatus "C25W45.1" )
			)
			( pin "@baseboard_fab2_lib.baseboard_fab2(sch_1):page149_i122:b"
				( attribute "PN" "2"
					( Origin gPackager )
				)
				( objectStatus "C25W45.2" )
			)
			( pin "@baseboard_fab2_lib.baseboard_fab2(sch_1):page220_i310:a"
				( attribute "PN" "1"
					( Origin gPackager )
				)
				( objectStatus "C5L3.1" )
			)
			( pin "@baseboard_fab2_lib.baseboard_fab2(sch_1):page220_i310:b"
				( attribute "PN" "2"
					( Origin gPackager )
				)
				( objectStatus "C5L3.2" )
			)
			( pin "@baseboard_fab2_lib.baseboard_fab2(sch_1):page220_i309:a"
				( attribute "PN" "1"
					( Origin gPackager )
				)
				( objectStatus "C5L1.1" )
			)
			( pin "@baseboard_fab2_lib.baseboard_fab2(sch_1):page220_i309:b"
				( attribute "PN" "2"
					( Origin gPackager )
				)
				( objectStatus "C5L1.2" )
			)
			( pin "@baseboard_fab2_lib.baseboard_fab2(sch_1):page217_i329:a"
				( attribute "PN" "1"
					( Origin gPackager )
				)
				( objectStatus "C5G20.1" )
			)
			( pin "@baseboard_fab2_lib.baseboard_fab2(sch_1):page217_i329:b"
				( attribute "PN" "2"
					( Origin gPackager )
				)
				( objectStatus "C5G20.2" )
			)
			( pin "@baseboard_fab2_lib.baseboard_fab2(sch_1):page228_i303:a"
				( attribute "PN" "1"
					( Origin gPackager )
				)
				( objectStatus "C8P2.1" )
			)
			( pin "@baseboard_fab2_lib.baseboard_fab2(sch_1):page228_i303:b"
				( attribute "PN" "2"
					( Origin gPackager )
				)
				( objectStatus "C8P2.2" )
			)
			( pin "@baseboard_fab2_lib.baseboard_fab2(sch_1):page220_i320:a"
				( attribute "PN" "1"
					( Origin gPackager )
				)
				( objectStatus "C5P1.1" )
			)
			( pin "@baseboard_fab2_lib.baseboard_fab2(sch_1):page220_i320:b"
				( attribute "PN" "2"
					( Origin gPackager )
				)
				( objectStatus "C5P1.2" )
			)
			( pin "@baseboard_fab2_lib.baseboard_fab2(sch_1):page220_i319:a"
				( attribute "PN" "1"
					( Origin gPackager )
				)
				( objectStatus "C5P2.1" )
			)
			( pin "@baseboard_fab2_lib.baseboard_fab2(sch_1):page220_i319:b"
				( attribute "PN" "2"
					( Origin gPackager )
				)
				( objectStatus "C5P2.2" )
			)
			( pin "@baseboard_fab2_lib.baseboard_fab2(sch_1):page148_i29:a"
				( attribute "PN" "1"
					( Origin gPackager )
				)
				( objectStatus "R25W155.1" )
			)
			( pin "@baseboard_fab2_lib.baseboard_fab2(sch_1):page148_i29:b"
				( attribute "PN" "2"
					( Origin gPackager )
				)
				( objectStatus "R25W155.2" )
			)
			( pin "@baseboard_fab2_lib.baseboard_fab2(sch_1):page138_i202:a"
				( attribute "PN" "1"
					( Origin gPackager )
				)
				( objectStatus "R8W7.1" )
			)
			( pin "@baseboard_fab2_lib.baseboard_fab2(sch_1):page138_i202:b"
				( attribute "PN" "2"
					( Origin gPackager )
				)
				( objectStatus "R8W7.2" )
			)
			( pin "@baseboard_fab2_lib.baseboard_fab2(sch_1):page138_i205:a"
				( attribute "PN" "1"
					( Origin gPackager )
				)
				( objectStatus "R8W6.1" )
			)
			( pin "@baseboard_fab2_lib.baseboard_fab2(sch_1):page138_i205:b"
				( attribute "PN" "2"
					( Origin gPackager )
				)
				( objectStatus "R8W6.2" )
			)
			( pin "@baseboard_fab2_lib.baseboard_fab2(sch_1):page159_i235:a"
				( attribute "PN" "1"
					( Origin gPackager )
				)
				( objectStatus "R8C15.1" )
			)
			( pin "@baseboard_fab2_lib.baseboard_fab2(sch_1):page159_i235:b"
				( attribute "PN" "2"
					( Origin gPackager )
				)
				( objectStatus "R8C15.2" )
			)
			( pin "@baseboard_fab2_lib.baseboard_fab2(sch_1):page159_i237:a"
				( attribute "PN" "1"
					( Origin gPackager )
				)
				( objectStatus "R8C16.1" )
			)
			( pin "@baseboard_fab2_lib.baseboard_fab2(sch_1):page159_i237:b"
				( attribute "PN" "2"
					( Origin gPackager )
				)
				( objectStatus "R8C16.2" )
			)
			( pin "@baseboard_fab2_lib.baseboard_fab2(sch_1):page225_i261:a"
				( attribute "PN" "1"
					( Origin gPackager )
				)
				( objectStatus "C2D45.1" )
			)
			( pin "@baseboard_fab2_lib.baseboard_fab2(sch_1):page225_i261:b"
				( attribute "PN" "2"
					( Origin gPackager )
				)
				( objectStatus "C2D45.2" )
			)
			( pin "@baseboard_fab2_lib.baseboard_fab2(sch_1):page228_i256:a"
				( attribute "PN" "1"
					( Origin gPackager )
				)
				( objectStatus "C2D3.1" )
			)
			( pin "@baseboard_fab2_lib.baseboard_fab2(sch_1):page228_i256:b"
				( attribute "PN" "2"
					( Origin gPackager )
				)
				( objectStatus "C2D3.2" )
			)
			( pin "@baseboard_fab2_lib.baseboard_fab2(sch_1):page228_i255:a"
				( attribute "PN" "1"
					( Origin gPackager )
				)
				( objectStatus "C3D1.1" )
			)
			( pin "@baseboard_fab2_lib.baseboard_fab2(sch_1):page228_i255:b"
				( attribute "PN" "2"
					( Origin gPackager )
				)
				( objectStatus "C3D1.2" )
			)
			( pin "@baseboard_fab2_lib.baseboard_fab2(sch_1):page195_i117:\1\"
				( attribute "PN" "1"
					( Origin gPackager )
				)
				( objectStatus "RM1G1.1" )
			)
			( pin "@baseboard_fab2_lib.baseboard_fab2(sch_1):page201_i190:a"
				( attribute "PN" "1"
					( Origin gPackager )
				)
				( objectStatus "R4E10.1" )
			)
			( pin "@baseboard_fab2_lib.baseboard_fab2(sch_1):page201_i190:b"
				( attribute "PN" "2"
					( Origin gPackager )
				)
				( objectStatus "R4E10.2" )
			)
			( pin "@baseboard_fab2_lib.baseboard_fab2(sch_1):page235_i249:a"
				( attribute "PN" "1"
					( Origin gPackager )
				)
				( objectStatus "R8W8.1" )
			)
			( pin "@baseboard_fab2_lib.baseboard_fab2(sch_1):page235_i249:b"
				( attribute "PN" "2"
					( Origin gPackager )
				)
				( objectStatus "R8W8.2" )
			)
			( pin "@baseboard_fab2_lib.baseboard_fab2(sch_1):page102_i103:a"
				( attribute "PN" "1"
					( Origin gPackager )
				)
				( objectStatus "R4W2.1" )
			)
			( pin "@baseboard_fab2_lib.baseboard_fab2(sch_1):page102_i103:b"
				( attribute "PN" "2"
					( Origin gPackager )
				)
				( objectStatus "R4W2.2" )
			)
			( pin "@baseboard_fab2_lib.baseboard_fab2(sch_1):page102_i101:drain(0)"
				( attribute "PN" "3"
					( Origin gPackager )
				)
				( objectStatus "Q4W1.3" )
			)
			( pin "@baseboard_fab2_lib.baseboard_fab2(sch_1):page102_i101:gate(0)"
				( attribute "PN" "5"
					( Origin gPackager )
				)
				( objectStatus "Q4W1.5" )
			)
			( pin "@baseboard_fab2_lib.baseboard_fab2(sch_1):page102_i101:source(0)"
				( attribute "PN" "4"
					( Origin gPackager )
				)
				( objectStatus "Q4W1.4" )
			)
			( pin "@baseboard_fab2_lib.baseboard_fab2(sch_1):page102_i106:a"
				( attribute "PN" "1"
					( Origin gPackager )
				)
				( objectStatus "R4W4.1" )
			)
			( pin "@baseboard_fab2_lib.baseboard_fab2(sch_1):page102_i106:b"
				( attribute "PN" "2"
					( Origin gPackager )
				)
				( objectStatus "R4W4.2" )
			)
			( pin "@baseboard_fab2_lib.baseboard_fab2(sch_1):page102_i112:drn"
				( attribute "PN" "3"
					( Origin gPackager )
				)
				( objectStatus "Q4W2.3" )
			)
			( pin "@baseboard_fab2_lib.baseboard_fab2(sch_1):page102_i112:gate"
				( attribute "PN" "1"
					( Origin gPackager )
				)
				( objectStatus "Q4W2.1" )
			)
			( pin "@baseboard_fab2_lib.baseboard_fab2(sch_1):page102_i112:src"
				( attribute "PN" "2"
					( Origin gPackager )
				)
				( objectStatus "Q4W2.2" )
			)
			( pin "@baseboard_fab2_lib.baseboard_fab2(sch_1):page102_i109:a"
				( attribute "PN" "1"
					( Origin gPackager )
				)
				( objectStatus "R4W6.1" )
			)
			( pin "@baseboard_fab2_lib.baseboard_fab2(sch_1):page102_i109:b"
				( attribute "PN" "2"
					( Origin gPackager )
				)
				( objectStatus "R4W6.2" )
			)
			( pin "@baseboard_fab2_lib.baseboard_fab2(sch_1):page102_i114:a"
				( attribute "PN" "1"
					( Origin gPackager )
				)
				( objectStatus "R4W5.1" )
			)
			( pin "@baseboard_fab2_lib.baseboard_fab2(sch_1):page102_i114:b"
				( attribute "PN" "2"
					( Origin gPackager )
				)
				( objectStatus "R4W5.2" )
			)
			( pin "@baseboard_fab2_lib.baseboard_fab2(sch_1):page197_i101:\1\"
				( attribute "PN" "1"
					( Origin gPackager )
				)
				( objectStatus "R12W1.1" )
			)
			( pin "@baseboard_fab2_lib.baseboard_fab2(sch_1):page197_i101:\2\"
				( attribute "PN" "2"
					( Origin gPackager )
				)
				( objectStatus "R12W1.2" )
			)
			( pin "@baseboard_fab2_lib.baseboard_fab2(sch_1):page197_i118:\1\"
				( attribute "PN" "1"
					( Origin gPackager )
				)
				( objectStatus "R12W11.1" )
			)
			( pin "@baseboard_fab2_lib.baseboard_fab2(sch_1):page197_i118:\2\"
				( attribute "PN" "2"
					( Origin gPackager )
				)
				( objectStatus "R12W11.2" )
			)
			( pin "@baseboard_fab2_lib.baseboard_fab2(sch_1):page225_i319:a"
				( attribute "PN" "1"
					( Origin gPackager )
				)
				( objectStatus "C8U1.1" )
			)
			( pin "@baseboard_fab2_lib.baseboard_fab2(sch_1):page225_i319:b"
				( attribute "PN" "2"
					( Origin gPackager )
				)
				( objectStatus "C8U1.2" )
			)
			( pin "@baseboard_fab2_lib.baseboard_fab2(sch_1):page228_i309:a"
				( attribute "PN" "1"
					( Origin gPackager )
				)
				( objectStatus "C2A8.1" )
			)
			( pin "@baseboard_fab2_lib.baseboard_fab2(sch_1):page228_i309:b"
				( attribute "PN" "2"
					( Origin gPackager )
				)
				( objectStatus "C2A8.2" )
			)
			( pin "@baseboard_fab2_lib.baseboard_fab2(sch_1):page217_i324:a"
				( attribute "PN" "1"
					( Origin gPackager )
				)
				( objectStatus "C5P44.1" )
			)
			( pin "@baseboard_fab2_lib.baseboard_fab2(sch_1):page217_i324:b"
				( attribute "PN" "2"
					( Origin gPackager )
				)
				( objectStatus "C5P44.2" )
			)
			( pin "@baseboard_fab2_lib.baseboard_fab2(sch_1):page217_i279:a"
				( attribute "PN" "1"
					( Origin gPackager )
				)
				( objectStatus "C5D54.1" )
			)
			( pin "@baseboard_fab2_lib.baseboard_fab2(sch_1):page217_i279:b"
				( attribute "PN" "2"
					( Origin gPackager )
				)
				( objectStatus "C5D54.2" )
			)
			( pin "@baseboard_fab2_lib.baseboard_fab2(sch_1):page217_i280:a"
				( attribute "PN" "1"
					( Origin gPackager )
				)
				( objectStatus "C5D55.1" )
			)
			( pin "@baseboard_fab2_lib.baseboard_fab2(sch_1):page217_i280:b"
				( attribute "PN" "2"
					( Origin gPackager )
				)
				( objectStatus "C5D55.2" )
			)
			( pin "@baseboard_fab2_lib.baseboard_fab2(sch_1):page217_i281:a"
				( attribute "PN" "1"
					( Origin gPackager )
				)
				( objectStatus "C5D56.1" )
			)
			( pin "@baseboard_fab2_lib.baseboard_fab2(sch_1):page217_i281:b"
				( attribute "PN" "2"
					( Origin gPackager )
				)
				( objectStatus "C5D56.2" )
			)
			( pin "@baseboard_fab2_lib.baseboard_fab2(sch_1):page217_i282:a"
				( attribute "PN" "1"
					( Origin gPackager )
				)
				( objectStatus "C5D57.1" )
			)
			( pin "@baseboard_fab2_lib.baseboard_fab2(sch_1):page217_i282:b"
				( attribute "PN" "2"
					( Origin gPackager )
				)
				( objectStatus "C5D57.2" )
			)
			( pin "@baseboard_fab2_lib.baseboard_fab2(sch_1):page217_i287:a"
				( attribute "PN" "1"
					( Origin gPackager )
				)
				( objectStatus "C5U6.1" )
			)
			( pin "@baseboard_fab2_lib.baseboard_fab2(sch_1):page217_i287:b"
				( attribute "PN" "2"
					( Origin gPackager )
				)
				( objectStatus "C5U6.2" )
			)
			( pin "@baseboard_fab2_lib.baseboard_fab2(sch_1):page217_i288:a"
				( attribute "PN" "1"
					( Origin gPackager )
				)
				( objectStatus "C5U7.1" )
			)
			( pin "@baseboard_fab2_lib.baseboard_fab2(sch_1):page217_i288:b"
				( attribute "PN" "2"
					( Origin gPackager )
				)
				( objectStatus "C5U7.2" )
			)
			( pin "@baseboard_fab2_lib.baseboard_fab2(sch_1):page217_i289:a"
				( attribute "PN" "1"
					( Origin gPackager )
				)
				( objectStatus "C5U8.1" )
			)
			( pin "@baseboard_fab2_lib.baseboard_fab2(sch_1):page217_i289:b"
				( attribute "PN" "2"
					( Origin gPackager )
				)
				( objectStatus "C5U8.2" )
			)
			( pin "@baseboard_fab2_lib.baseboard_fab2(sch_1):page217_i290:a"
				( attribute "PN" "1"
					( Origin gPackager )
				)
				( objectStatus "C5U9.1" )
			)
			( pin "@baseboard_fab2_lib.baseboard_fab2(sch_1):page217_i290:b"
				( attribute "PN" "2"
					( Origin gPackager )
				)
				( objectStatus "C5U9.2" )
			)
			( pin "@baseboard_fab2_lib.baseboard_fab2(sch_1):page217_i291:a"
				( attribute "PN" "1"
					( Origin gPackager )
				)
				( objectStatus "C5T12.1" )
			)
			( pin "@baseboard_fab2_lib.baseboard_fab2(sch_1):page217_i291:b"
				( attribute "PN" "2"
					( Origin gPackager )
				)
				( objectStatus "C5T12.2" )
			)
			( pin "@baseboard_fab2_lib.baseboard_fab2(sch_1):page217_i292:a"
				( attribute "PN" "1"
					( Origin gPackager )
				)
				( objectStatus "C5T11.1" )
			)
			( pin "@baseboard_fab2_lib.baseboard_fab2(sch_1):page217_i292:b"
				( attribute "PN" "2"
					( Origin gPackager )
				)
				( objectStatus "C5T11.2" )
			)
			( pin "@baseboard_fab2_lib.baseboard_fab2(sch_1):page217_i293:a"
				( attribute "PN" "1"
					( Origin gPackager )
				)
				( objectStatus "C5T10.1" )
			)
			( pin "@baseboard_fab2_lib.baseboard_fab2(sch_1):page217_i293:b"
				( attribute "PN" "2"
					( Origin gPackager )
				)
				( objectStatus "C5T10.2" )
			)
			( pin "@baseboard_fab2_lib.baseboard_fab2(sch_1):page217_i294:a"
				( attribute "PN" "1"
					( Origin gPackager )
				)
				( objectStatus "C5T9.1" )
			)
			( pin "@baseboard_fab2_lib.baseboard_fab2(sch_1):page217_i294:b"
				( attribute "PN" "2"
					( Origin gPackager )
				)
				( objectStatus "C5T9.2" )
			)
			( pin "@baseboard_fab2_lib.baseboard_fab2(sch_1):page217_i295:a"
				( attribute "PN" "1"
					( Origin gPackager )
				)
				( objectStatus "C5T8.1" )
			)
			( pin "@baseboard_fab2_lib.baseboard_fab2(sch_1):page217_i295:b"
				( attribute "PN" "2"
					( Origin gPackager )
				)
				( objectStatus "C5T8.2" )
			)
			( pin "@baseboard_fab2_lib.baseboard_fab2(sch_1):page217_i296:a"
				( attribute "PN" "1"
					( Origin gPackager )
				)
				( objectStatus "C5T7.1" )
			)
			( pin "@baseboard_fab2_lib.baseboard_fab2(sch_1):page217_i296:b"
				( attribute "PN" "2"
					( Origin gPackager )
				)
				( objectStatus "C5T7.2" )
			)
			( pin "@baseboard_fab2_lib.baseboard_fab2(sch_1):page217_i297:a"
				( attribute "PN" "1"
					( Origin gPackager )
				)
				( objectStatus "C5T6.1" )
			)
			( pin "@baseboard_fab2_lib.baseboard_fab2(sch_1):page217_i297:b"
				( attribute "PN" "2"
					( Origin gPackager )
				)
				( objectStatus "C5T6.2" )
			)
			( pin "@baseboard_fab2_lib.baseboard_fab2(sch_1):page217_i298:a"
				( attribute "PN" "1"
					( Origin gPackager )
				)
				( objectStatus "C5T5.1" )
			)
			( pin "@baseboard_fab2_lib.baseboard_fab2(sch_1):page217_i298:b"
				( attribute "PN" "2"
					( Origin gPackager )
				)
				( objectStatus "C5T5.2" )
			)
			( pin "@baseboard_fab2_lib.baseboard_fab2(sch_1):page225_i288:a"
				( attribute "PN" "1"
					( Origin gPackager )
				)
				( objectStatus "C3G5.1" )
			)
			( pin "@baseboard_fab2_lib.baseboard_fab2(sch_1):page225_i288:b"
				( attribute "PN" "2"
					( Origin gPackager )
				)
				( objectStatus "C3G5.2" )
			)
			( pin "@baseboard_fab2_lib.baseboard_fab2(sch_1):page225_i289:a"
				( attribute "PN" "1"
					( Origin gPackager )
				)
				( objectStatus "C3G6.1" )
			)
			( pin "@baseboard_fab2_lib.baseboard_fab2(sch_1):page225_i289:b"
				( attribute "PN" "2"
					( Origin gPackager )
				)
				( objectStatus "C3G6.2" )
			)
			( pin "@baseboard_fab2_lib.baseboard_fab2(sch_1):page225_i290:a"
				( attribute "PN" "1"
					( Origin gPackager )
				)
				( objectStatus "C8U7.1" )
			)
			( pin "@baseboard_fab2_lib.baseboard_fab2(sch_1):page225_i290:b"
				( attribute "PN" "2"
					( Origin gPackager )
				)
				( objectStatus "C8U7.2" )
			)
			( pin "@baseboard_fab2_lib.baseboard_fab2(sch_1):page225_i291:a"
				( attribute "PN" "1"
					( Origin gPackager )
				)
				( objectStatus "C8U2.1" )
			)
			( pin "@baseboard_fab2_lib.baseboard_fab2(sch_1):page225_i291:b"
				( attribute "PN" "2"
					( Origin gPackager )
				)
				( objectStatus "C8U2.2" )
			)
			( pin "@baseboard_fab2_lib.baseboard_fab2(sch_1):page225_i292:a"
				( attribute "PN" "1"
					( Origin gPackager )
				)
				( objectStatus "C7U2.1" )
			)
			( pin "@baseboard_fab2_lib.baseboard_fab2(sch_1):page225_i292:b"
				( attribute "PN" "2"
					( Origin gPackager )
				)
				( objectStatus "C7U2.2" )
			)
			( pin "@baseboard_fab2_lib.baseboard_fab2(sch_1):page225_i293:a"
				( attribute "PN" "1"
					( Origin gPackager )
				)
				( objectStatus "C7U1.1" )
			)
			( pin "@baseboard_fab2_lib.baseboard_fab2(sch_1):page225_i293:b"
				( attribute "PN" "2"
					( Origin gPackager )
				)
				( objectStatus "C7U1.2" )
			)
			( pin "@baseboard_fab2_lib.baseboard_fab2(sch_1):page225_i294:a"
				( attribute "PN" "1"
					( Origin gPackager )
				)
				( objectStatus "C8U3.1" )
			)
			( pin "@baseboard_fab2_lib.baseboard_fab2(sch_1):page225_i294:b"
				( attribute "PN" "2"
					( Origin gPackager )
				)
				( objectStatus "C8U3.2" )
			)
			( pin "@baseboard_fab2_lib.baseboard_fab2(sch_1):page225_i295:a"
				( attribute "PN" "1"
					( Origin gPackager )
				)
				( objectStatus "C7T4.1" )
			)
			( pin "@baseboard_fab2_lib.baseboard_fab2(sch_1):page225_i295:b"
				( attribute "PN" "2"
					( Origin gPackager )
				)
				( objectStatus "C7T4.2" )
			)
			( pin "@baseboard_fab2_lib.baseboard_fab2(sch_1):page225_i296:a"
				( attribute "PN" "1"
					( Origin gPackager )
				)
				( objectStatus "C7T5.1" )
			)
			( pin "@baseboard_fab2_lib.baseboard_fab2(sch_1):page225_i296:b"
				( attribute "PN" "2"
					( Origin gPackager )
				)
				( objectStatus "C7T5.2" )
			)
			( pin "@baseboard_fab2_lib.baseboard_fab2(sch_1):page225_i297:a"
				( attribute "PN" "1"
					( Origin gPackager )
				)
				( objectStatus "C8T5.1" )
			)
			( pin "@baseboard_fab2_lib.baseboard_fab2(sch_1):page225_i297:b"
				( attribute "PN" "2"
					( Origin gPackager )
				)
				( objectStatus "C8T5.2" )
			)
			( pin "@baseboard_fab2_lib.baseboard_fab2(sch_1):page225_i298:a"
				( attribute "PN" "1"
					( Origin gPackager )
				)
				( objectStatus "C8U6.1" )
			)
			( pin "@baseboard_fab2_lib.baseboard_fab2(sch_1):page225_i298:b"
				( attribute "PN" "2"
					( Origin gPackager )
				)
				( objectStatus "C8U6.2" )
			)
			( pin "@baseboard_fab2_lib.baseboard_fab2(sch_1):page225_i299:a"
				( attribute "PN" "1"
					( Origin gPackager )
				)
				( objectStatus "C8T6.1" )
			)
			( pin "@baseboard_fab2_lib.baseboard_fab2(sch_1):page225_i299:b"
				( attribute "PN" "2"
					( Origin gPackager )
				)
				( objectStatus "C8T6.2" )
			)
			( pin "@baseboard_fab2_lib.baseboard_fab2(sch_1):page225_i300:a"
				( attribute "PN" "1"
					( Origin gPackager )
				)
				( objectStatus "C8T7.1" )
			)
			( pin "@baseboard_fab2_lib.baseboard_fab2(sch_1):page225_i300:b"
				( attribute "PN" "2"
					( Origin gPackager )
				)
				( objectStatus "C8T7.2" )
			)
			( pin "@baseboard_fab2_lib.baseboard_fab2(sch_1):page225_i301:a"
				( attribute "PN" "1"
					( Origin gPackager )
				)
				( objectStatus "C8T8.1" )
			)
			( pin "@baseboard_fab2_lib.baseboard_fab2(sch_1):page225_i301:b"
				( attribute "PN" "2"
					( Origin gPackager )
				)
				( objectStatus "C8T8.2" )
			)
			( pin "@baseboard_fab2_lib.baseboard_fab2(sch_1):page225_i302:a"
				( attribute "PN" "1"
					( Origin gPackager )
				)
				( objectStatus "C8U5.1" )
			)
			( pin "@baseboard_fab2_lib.baseboard_fab2(sch_1):page225_i302:b"
				( attribute "PN" "2"
					( Origin gPackager )
				)
				( objectStatus "C8U5.2" )
			)
			( pin "@baseboard_fab2_lib.baseboard_fab2(sch_1):page225_i303:a"
				( attribute "PN" "1"
					( Origin gPackager )
				)
				( objectStatus "C8T9.1" )
			)
			( pin "@baseboard_fab2_lib.baseboard_fab2(sch_1):page225_i303:b"
				( attribute "PN" "2"
					( Origin gPackager )
				)
				( objectStatus "C8T9.2" )
			)
			( pin "@baseboard_fab2_lib.baseboard_fab2(sch_1):page225_i304:a"
				( attribute "PN" "1"
					( Origin gPackager )
				)
				( objectStatus "C8T10.1" )
			)
			( pin "@baseboard_fab2_lib.baseboard_fab2(sch_1):page225_i304:b"
				( attribute "PN" "2"
					( Origin gPackager )
				)
				( objectStatus "C8T10.2" )
			)
			( pin "@baseboard_fab2_lib.baseboard_fab2(sch_1):page225_i305:a"
				( attribute "PN" "1"
					( Origin gPackager )
				)
				( objectStatus "C8U4.1" )
			)
			( pin "@baseboard_fab2_lib.baseboard_fab2(sch_1):page225_i305:b"
				( attribute "PN" "2"
					( Origin gPackager )
				)
				( objectStatus "C8U4.2" )
			)
			( pin "@baseboard_fab2_lib.baseboard_fab2(sch_1):page220_i316:a"
				( attribute "PN" "1"
					( Origin gPackager )
				)
				( objectStatus "C5P6.1" )
			)
			( pin "@baseboard_fab2_lib.baseboard_fab2(sch_1):page220_i316:b"
				( attribute "PN" "2"
					( Origin gPackager )
				)
				( objectStatus "C5P6.2" )
			)
			( pin "@baseboard_fab2_lib.baseboard_fab2(sch_1):page220_i298:\1\"
				( attribute "PN" "1"
					( Origin gPackager )
				)
				( objectStatus "C7W5.1" )
			)
			( pin "@baseboard_fab2_lib.baseboard_fab2(sch_1):page220_i298:\2\"
				( attribute "PN" "2"
					( Origin gPackager )
				)
				( objectStatus "C7W5.2" )
			)
			( pin "@baseboard_fab2_lib.baseboard_fab2(sch_1):page220_i299:\1\"
				( attribute "PN" "1"
					( Origin gPackager )
				)
				( objectStatus "C7W9.1" )
			)
			( pin "@baseboard_fab2_lib.baseboard_fab2(sch_1):page220_i299:\2\"
				( attribute "PN" "2"
					( Origin gPackager )
				)
				( objectStatus "C7W9.2" )
			)
			( pin "@baseboard_fab2_lib.baseboard_fab2(sch_1):page220_i300:\1\"
				( attribute "PN" "1"
					( Origin gPackager )
				)
				( objectStatus "C7W8.1" )
			)
			( pin "@baseboard_fab2_lib.baseboard_fab2(sch_1):page220_i300:\2\"
				( attribute "PN" "2"
					( Origin gPackager )
				)
				( objectStatus "C7W8.2" )
			)
			( pin "@baseboard_fab2_lib.baseboard_fab2(sch_1):page220_i301:\1\"
				( attribute "PN" "1"
					( Origin gPackager )
				)
				( objectStatus "C7W7.1" )
			)
			( pin "@baseboard_fab2_lib.baseboard_fab2(sch_1):page220_i301:\2\"
				( attribute "PN" "2"
					( Origin gPackager )
				)
				( objectStatus "C7W7.2" )
			)
			( pin "@baseboard_fab2_lib.baseboard_fab2(sch_1):page220_i302:\1\"
				( attribute "PN" "1"
					( Origin gPackager )
				)
				( objectStatus "C7W6.1" )
			)
			( pin "@baseboard_fab2_lib.baseboard_fab2(sch_1):page220_i302:\2\"
				( attribute "PN" "2"
					( Origin gPackager )
				)
				( objectStatus "C7W6.2" )
			)
			( pin "@baseboard_fab2_lib.baseboard_fab2(sch_1):page220_i303:\1\"
				( attribute "PN" "1"
					( Origin gPackager )
				)
				( objectStatus "C7W13.1" )
			)
			( pin "@baseboard_fab2_lib.baseboard_fab2(sch_1):page220_i303:\2\"
				( attribute "PN" "2"
					( Origin gPackager )
				)
				( objectStatus "C7W13.2" )
			)
			( pin "@baseboard_fab2_lib.baseboard_fab2(sch_1):page220_i304:\1\"
				( attribute "PN" "1"
					( Origin gPackager )
				)
				( objectStatus "C7W12.1" )
			)
			( pin "@baseboard_fab2_lib.baseboard_fab2(sch_1):page220_i304:\2\"
				( attribute "PN" "2"
					( Origin gPackager )
				)
				( objectStatus "C7W12.2" )
			)
			( pin "@baseboard_fab2_lib.baseboard_fab2(sch_1):page220_i305:\1\"
				( attribute "PN" "1"
					( Origin gPackager )
				)
				( objectStatus "C7W11.1" )
			)
			( pin "@baseboard_fab2_lib.baseboard_fab2(sch_1):page220_i305:\2\"
				( attribute "PN" "2"
					( Origin gPackager )
				)
				( objectStatus "C7W11.2" )
			)
			( pin "@baseboard_fab2_lib.baseboard_fab2(sch_1):page220_i306:\1\"
				( attribute "PN" "1"
					( Origin gPackager )
				)
				( objectStatus "C7W10.1" )
			)
			( pin "@baseboard_fab2_lib.baseboard_fab2(sch_1):page220_i306:\2\"
				( attribute "PN" "2"
					( Origin gPackager )
				)
				( objectStatus "C7W10.2" )
			)
			( pin "@baseboard_fab2_lib.baseboard_fab2(sch_1):page201_i191:\1\"
				( attribute "PN" "1"
					( Origin gPackager )
				)
				( objectStatus "J8D4.1" )
			)
			( pin "@baseboard_fab2_lib.baseboard_fab2(sch_1):page201_i191:\2\"
				( attribute "PN" "2"
					( Origin gPackager )
				)
				( objectStatus "J8D4.2" )
			)
			( pin "@baseboard_fab2_lib.baseboard_fab2(sch_1):page201_i191:\3\"
				( attribute "PN" "3"
					( Origin gPackager )
				)
				( objectStatus "J8D4.3" )
			)
			( pin "@baseboard_fab2_lib.baseboard_fab2(sch_1):page147_i160:a"
				( attribute "PN" "1"
					( Origin gPackager )
				)
				( objectStatus "C25W9.1" )
			)
			( pin "@baseboard_fab2_lib.baseboard_fab2(sch_1):page147_i160:b"
				( attribute "PN" "2"
					( Origin gPackager )
				)
				( objectStatus "C25W9.2" )
			)
			( pin "@baseboard_fab2_lib.baseboard_fab2(sch_1):page241_i103:\1\"
				( attribute "PN" "1"
					( Origin gPackager )
				)
				( objectStatus "C8E7.1" )
			)
			( pin "@baseboard_fab2_lib.baseboard_fab2(sch_1):page241_i103:\2\"
				( attribute "PN" "2"
					( Origin gPackager )
				)
				( objectStatus "C8E7.2" )
			)
			( pin "@baseboard_fab2_lib.baseboard_fab2(sch_1):page241_i104:\1\"
				( attribute "PN" "1"
					( Origin gPackager )
				)
				( objectStatus "C8E9.1" )
			)
			( pin "@baseboard_fab2_lib.baseboard_fab2(sch_1):page241_i104:\2\"
				( attribute "PN" "2"
					( Origin gPackager )
				)
				( objectStatus "C8E9.2" )
			)
			( pin "@baseboard_fab2_lib.baseboard_fab2(sch_1):page89_i40:a"
				( attribute "PN" "1"
					( Origin gPackager )
				)
				( objectStatus "R6W29.1" )
			)
			( pin "@baseboard_fab2_lib.baseboard_fab2(sch_1):page89_i40:b"
				( attribute "PN" "2"
					( Origin gPackager )
				)
				( objectStatus "R6W29.2" )
			)
			( pin "@baseboard_fab2_lib.baseboard_fab2(sch_1):page89_i45:a"
				( attribute "PN" "1"
					( Origin gPackager )
				)
				( objectStatus "WR8D30.1" )
			)
			( pin "@baseboard_fab2_lib.baseboard_fab2(sch_1):page89_i45:b"
				( attribute "PN" "2"
					( Origin gPackager )
				)
				( objectStatus "WR8D30.2" )
			)
			( pin "@baseboard_fab2_lib.baseboard_fab2(sch_1):page89_i46:b(0)"
				( attribute "PN" "2"
					( Origin gPackager )
				)
				( objectStatus "Q8D1.2" )
			)
			( pin "@baseboard_fab2_lib.baseboard_fab2(sch_1):page89_i46:c(0)"
				( attribute "PN" "6"
					( Origin gPackager )
				)
				( objectStatus "Q8D1.6" )
			)
			( pin "@baseboard_fab2_lib.baseboard_fab2(sch_1):page89_i46:e(0)"
				( attribute "PN" "1"
					( Origin gPackager )
				)
				( objectStatus "Q8D1.1" )
			)
			( pin "@baseboard_fab2_lib.baseboard_fab2(sch_1):page89_i49:a"
				( attribute "PN" "1"
					( Origin gPackager )
				)
				( objectStatus "R8W9.1" )
			)
			( pin "@baseboard_fab2_lib.baseboard_fab2(sch_1):page89_i49:b"
				( attribute "PN" "2"
					( Origin gPackager )
				)
				( objectStatus "R8W9.2" )
			)
			( pin "@baseboard_fab2_lib.baseboard_fab2(sch_1):page89_i51:b(0)"
				( attribute "PN" "2"
					( Origin gPackager )
				)
				( objectStatus "Q8W1.2" )
			)
			( pin "@baseboard_fab2_lib.baseboard_fab2(sch_1):page89_i51:c(0)"
				( attribute "PN" "6"
					( Origin gPackager )
				)
				( objectStatus "Q8W1.6" )
			)
			( pin "@baseboard_fab2_lib.baseboard_fab2(sch_1):page89_i51:e(0)"
				( attribute "PN" "1"
					( Origin gPackager )
				)
				( objectStatus "Q8W1.1" )
			)
			( pin "@baseboard_fab2_lib.baseboard_fab2(sch_1):page89_i52:b(0)"
				( attribute "PN" "5"
					( Origin gPackager )
				)
				( objectStatus "Q8W1.5" )
			)
			( pin "@baseboard_fab2_lib.baseboard_fab2(sch_1):page89_i52:c(0)"
				( attribute "PN" "3"
					( Origin gPackager )
				)
				( objectStatus "Q8W1.3" )
			)
			( pin "@baseboard_fab2_lib.baseboard_fab2(sch_1):page89_i52:e(0)"
				( attribute "PN" "4"
					( Origin gPackager )
				)
				( objectStatus "Q8W1.4" )
			)
			( pin "@baseboard_fab2_lib.baseboard_fab2(sch_1):page89_i53:b"
				( attribute "PN" "1"
					( Origin gPackager )
				)
				( objectStatus "Q1F1.1" )
			)
			( pin "@baseboard_fab2_lib.baseboard_fab2(sch_1):page89_i53:c"
				( attribute "PN" "3"
					( Origin gPackager )
				)
				( objectStatus "Q1F1.3" )
			)
			( pin "@baseboard_fab2_lib.baseboard_fab2(sch_1):page89_i53:e"
				( attribute "PN" "2"
					( Origin gPackager )
				)
				( objectStatus "Q1F1.2" )
			)
			( pin "@baseboard_fab2_lib.baseboard_fab2(sch_1):page89_i54:a"
				( attribute "PN" "1"
					( Origin gPackager )
				)
				( objectStatus "R1W32.1" )
			)
			( pin "@baseboard_fab2_lib.baseboard_fab2(sch_1):page89_i54:b"
				( attribute "PN" "2"
					( Origin gPackager )
				)
				( objectStatus "R1W32.2" )
			)
			( pin "@baseboard_fab2_lib.baseboard_fab2(sch_1):page89_i55:b"
				( attribute "PN" "1"
					( Origin gPackager )
				)
				( objectStatus "Q1W6.1" )
			)
			( pin "@baseboard_fab2_lib.baseboard_fab2(sch_1):page89_i55:c"
				( attribute "PN" "3"
					( Origin gPackager )
				)
				( objectStatus "Q1W6.3" )
			)
			( pin "@baseboard_fab2_lib.baseboard_fab2(sch_1):page89_i55:e"
				( attribute "PN" "2"
					( Origin gPackager )
				)
				( objectStatus "Q1W6.2" )
			)
			( pin "@baseboard_fab2_lib.baseboard_fab2(sch_1):page89_i56:a"
				( attribute "PN" "1"
					( Origin gPackager )
				)
				( objectStatus "R1W31.1" )
			)
			( pin "@baseboard_fab2_lib.baseboard_fab2(sch_1):page89_i56:b"
				( attribute "PN" "2"
					( Origin gPackager )
				)
				( objectStatus "R1W31.2" )
			)
			( pin "@baseboard_fab2_lib.baseboard_fab2(sch_1):page253_i35:\1\"
				( attribute "PN" "1"
					( Origin gPackager )
				)
				( objectStatus "C30W3.1" )
			)
			( pin "@baseboard_fab2_lib.baseboard_fab2(sch_1):page253_i35:\2\"
				( attribute "PN" "2"
					( Origin gPackager )
				)
				( objectStatus "C30W3.2" )
			)
			( pin "@baseboard_fab2_lib.baseboard_fab2(sch_1):page253_i36:\1\"
				( attribute "PN" "1"
					( Origin gPackager )
				)
				( objectStatus "C30W4.1" )
			)
			( pin "@baseboard_fab2_lib.baseboard_fab2(sch_1):page253_i36:\2\"
				( attribute "PN" "2"
					( Origin gPackager )
				)
				( objectStatus "C30W4.2" )
			)
			( pin "@baseboard_fab2_lib.baseboard_fab2(sch_1):page253_i37:\1\"
				( attribute "PN" "1"
					( Origin gPackager )
				)
				( objectStatus "C30W6.1" )
			)
			( pin "@baseboard_fab2_lib.baseboard_fab2(sch_1):page253_i37:\2\"
				( attribute "PN" "2"
					( Origin gPackager )
				)
				( objectStatus "C30W6.2" )
			)
			( pin "@baseboard_fab2_lib.baseboard_fab2(sch_1):page253_i38:\1\"
				( attribute "PN" "1"
					( Origin gPackager )
				)
				( objectStatus "C30W5.1" )
			)
			( pin "@baseboard_fab2_lib.baseboard_fab2(sch_1):page253_i38:\2\"
				( attribute "PN" "2"
					( Origin gPackager )
				)
				( objectStatus "C30W5.2" )
			)
			( pin "@baseboard_fab2_lib.baseboard_fab2(sch_1):page253_i40:\1\"
				( attribute "PN" "1"
					( Origin gPackager )
				)
				( objectStatus "C30W9.1" )
			)
			( pin "@baseboard_fab2_lib.baseboard_fab2(sch_1):page253_i40:\2\"
				( attribute "PN" "2"
					( Origin gPackager )
				)
				( objectStatus "C30W9.2" )
			)
			( pin "@baseboard_fab2_lib.baseboard_fab2(sch_1):page253_i41:\1\"
				( attribute "PN" "1"
					( Origin gPackager )
				)
				( objectStatus "C30W8.1" )
			)
			( pin "@baseboard_fab2_lib.baseboard_fab2(sch_1):page253_i41:\2\"
				( attribute "PN" "2"
					( Origin gPackager )
				)
				( objectStatus "C30W8.2" )
			)
			( pin "@baseboard_fab2_lib.baseboard_fab2(sch_1):page253_i42:\1\"
				( attribute "PN" "1"
					( Origin gPackager )
				)
				( objectStatus "C30W7.1" )
			)
			( pin "@baseboard_fab2_lib.baseboard_fab2(sch_1):page253_i42:\2\"
				( attribute "PN" "2"
					( Origin gPackager )
				)
				( objectStatus "C30W7.2" )
			)
			( pin "@baseboard_fab2_lib.baseboard_fab2(sch_1):page213_i103:a"
				( attribute "PN" "1"
					( Origin gPackager )
				)
				( objectStatus "R4E2.1" )
			)
			( pin "@baseboard_fab2_lib.baseboard_fab2(sch_1):page213_i103:b"
				( attribute "PN" "2"
					( Origin gPackager )
				)
				( objectStatus "R4E2.2" )
			)
			( pin "@baseboard_fab2_lib.baseboard_fab2(sch_1):page90_i98:a"
				( attribute "PN" "1"
					( Origin gPackager )
				)
				( objectStatus "R4P1.1" )
			)
			( pin "@baseboard_fab2_lib.baseboard_fab2(sch_1):page90_i98:b"
				( attribute "PN" "2"
					( Origin gPackager )
				)
				( objectStatus "R4P1.2" )
			)
			( pin "@baseboard_fab2_lib.baseboard_fab2(sch_1):page90_i99:a"
				( attribute "PN" "1"
					( Origin gPackager )
				)
				( objectStatus "R3D13.1" )
			)
			( pin "@baseboard_fab2_lib.baseboard_fab2(sch_1):page90_i99:b"
				( attribute "PN" "2"
					( Origin gPackager )
				)
				( objectStatus "R3D13.2" )
			)
			( pin "@baseboard_fab2_lib.baseboard_fab2(sch_1):page164_i48:a"
				( attribute "PN" "1"
					( Origin gPackager )
				)
				( objectStatus "R1U15.1" )
			)
			( pin "@baseboard_fab2_lib.baseboard_fab2(sch_1):page164_i48:b"
				( attribute "PN" "2"
					( Origin gPackager )
				)
				( objectStatus "R1U15.2" )
			)
			( pin "@baseboard_fab2_lib.baseboard_fab2(sch_1):page90_i101:a"
				( attribute "PN" "1"
					( Origin gPackager )
				)
				( objectStatus "R6D6.1" )
			)
			( pin "@baseboard_fab2_lib.baseboard_fab2(sch_1):page90_i101:b"
				( attribute "PN" "2"
					( Origin gPackager )
				)
				( objectStatus "R6D6.2" )
			)
			( pin "@baseboard_fab2_lib.baseboard_fab2(sch_1):page90_i102:a"
				( attribute "PN" "1"
					( Origin gPackager )
				)
				( objectStatus "R3D12.1" )
			)
			( pin "@baseboard_fab2_lib.baseboard_fab2(sch_1):page90_i102:b"
				( attribute "PN" "2"
					( Origin gPackager )
				)
				( objectStatus "R3D12.2" )
			)
			( pin "@baseboard_fab2_lib.baseboard_fab2(sch_1):page125_i89:a"
				( attribute "PN" "1"
					( Origin gPackager )
				)
				( objectStatus "R2T1.1" )
			)
			( pin "@baseboard_fab2_lib.baseboard_fab2(sch_1):page125_i89:b"
				( attribute "PN" "2"
					( Origin gPackager )
				)
				( objectStatus "R2T1.2" )
			)
			( pin "@baseboard_fab2_lib.baseboard_fab2(sch_1):page239_i100:a"
				( attribute "PN" "1"
					( Origin gPackager )
				)
				( objectStatus "R9F32.1" )
			)
			( pin "@baseboard_fab2_lib.baseboard_fab2(sch_1):page239_i100:b"
				( attribute "PN" "2"
					( Origin gPackager )
				)
				( objectStatus "R9F32.2" )
			)
			( pin "@baseboard_fab2_lib.baseboard_fab2(sch_1):page239_i101:a"
				( attribute "PN" "1"
					( Origin gPackager )
				)
				( objectStatus "R9W32.1" )
			)
			( pin "@baseboard_fab2_lib.baseboard_fab2(sch_1):page239_i101:b"
				( attribute "PN" "2"
					( Origin gPackager )
				)
				( objectStatus "R9W32.2" )
			)
			( pin "@baseboard_fab2_lib.baseboard_fab2(sch_1):page215_i72:a"
				( attribute "PN" "1"
					( Origin gPackager )
				)
				( objectStatus "R7G8.1" )
			)
			( pin "@baseboard_fab2_lib.baseboard_fab2(sch_1):page215_i72:b"
				( attribute "PN" "2"
					( Origin gPackager )
				)
				( objectStatus "R7G8.2" )
			)
			( pin "@baseboard_fab2_lib.baseboard_fab2(sch_1):page235_i253:a"
				( attribute "PN" "1"
					( Origin gPackager )
				)
				( objectStatus "R2L26.1" )
			)
			( pin "@baseboard_fab2_lib.baseboard_fab2(sch_1):page235_i253:b"
				( attribute "PN" "2"
					( Origin gPackager )
				)
				( objectStatus "R2L26.2" )
			)
			( pin "@baseboard_fab2_lib.baseboard_fab2(sch_1):page231_i230:a"
				( attribute "PN" "1"
					( Origin gPackager )
				)
				( objectStatus "R7F11.1" )
			)
			( pin "@baseboard_fab2_lib.baseboard_fab2(sch_1):page231_i230:b"
				( attribute "PN" "2"
					( Origin gPackager )
				)
				( objectStatus "R7F11.2" )
			)
			( pin "@baseboard_fab2_lib.baseboard_fab2(sch_1):page176_i148:a"
				( attribute "PN" "2"
					( Origin gPackager )
				)
				( objectStatus "U6W5.2" )
			)
			( pin "@baseboard_fab2_lib.baseboard_fab2(sch_1):page176_i148:oe"
				( attribute "PN" "1"
					( Origin gPackager )
				)
				( objectStatus "U6W5.1" )
			)
			( pin "@baseboard_fab2_lib.baseboard_fab2(sch_1):page176_i148:y"
				( attribute "PN" "4"
					( Origin gPackager )
				)
				( objectStatus "U6W5.4" )
			)
			( pin "@baseboard_fab2_lib.baseboard_fab2(sch_1):page150_i240:a"
				( attribute "PN" "1"
					( Origin gPackager )
				)
				( objectStatus "R25W156.1" )
			)
			( pin "@baseboard_fab2_lib.baseboard_fab2(sch_1):page150_i240:b"
				( attribute "PN" "2"
					( Origin gPackager )
				)
				( objectStatus "R25W156.2" )
			)
			( pin "@baseboard_fab2_lib.baseboard_fab2(sch_1):page137_i149:a"
				( attribute "PN" "1"
					( Origin gPackager )
				)
				( objectStatus "R6W1.1" )
			)
			( pin "@baseboard_fab2_lib.baseboard_fab2(sch_1):page137_i149:b"
				( attribute "PN" "2"
					( Origin gPackager )
				)
				( objectStatus "R6W1.2" )
			)
			( pin "@baseboard_fab2_lib.baseboard_fab2(sch_1):page176_i142:a"
				( attribute "PN" "1"
					( Origin gPackager )
				)
				( objectStatus "R1W33.1" )
			)
			( pin "@baseboard_fab2_lib.baseboard_fab2(sch_1):page176_i142:b"
				( attribute "PN" "2"
					( Origin gPackager )
				)
				( objectStatus "R1W33.2" )
			)
			( pin "@baseboard_fab2_lib.baseboard_fab2(sch_1):page176_i143:a"
				( attribute "PN" "1"
					( Origin gPackager )
				)
				( objectStatus "R1W34.1" )
			)
			( pin "@baseboard_fab2_lib.baseboard_fab2(sch_1):page176_i143:b"
				( attribute "PN" "2"
					( Origin gPackager )
				)
				( objectStatus "R1W34.2" )
			)
			( pin "@baseboard_fab2_lib.baseboard_fab2(sch_1):page176_i146:a"
				( attribute "PN" "2"
					( Origin gPackager )
				)
				( objectStatus "U6W4.2" )
			)
			( pin "@baseboard_fab2_lib.baseboard_fab2(sch_1):page176_i146:oe"
				( attribute "PN" "1"
					( Origin gPackager )
				)
				( objectStatus "U6W4.1" )
			)
			( pin "@baseboard_fab2_lib.baseboard_fab2(sch_1):page176_i146:y"
				( attribute "PN" "4"
					( Origin gPackager )
				)
				( objectStatus "U6W4.4" )
			)
			( pin "@baseboard_fab2_lib.baseboard_fab2(sch_1):page176_i147:a"
				( attribute "PN" "1"
					( Origin gPackager )
				)
				( objectStatus "R6W30.1" )
			)
			( pin "@baseboard_fab2_lib.baseboard_fab2(sch_1):page176_i147:b"
				( attribute "PN" "2"
					( Origin gPackager )
				)
				( objectStatus "R6W30.2" )
			)
			( pin "@baseboard_fab2_lib.baseboard_fab2(sch_1):page176_i157:a"
				( attribute "PN" "2"
					( Origin gPackager )
				)
				( objectStatus "U6W6.2" )
			)
			( pin "@baseboard_fab2_lib.baseboard_fab2(sch_1):page176_i157:oe"
				( attribute "PN" "1"
					( Origin gPackager )
				)
				( objectStatus "U6W6.1" )
			)
			( pin "@baseboard_fab2_lib.baseboard_fab2(sch_1):page176_i157:y"
				( attribute "PN" "4"
					( Origin gPackager )
				)
				( objectStatus "U6W6.4" )
			)
			( pin "@baseboard_fab2_lib.baseboard_fab2(sch_1):page222_i41:a"
				( attribute "PN" "1"
					( Origin gPackager )
				)
				( objectStatus "C5M13.1" )
			)
			( pin "@baseboard_fab2_lib.baseboard_fab2(sch_1):page222_i41:b"
				( attribute "PN" "2"
					( Origin gPackager )
				)
				( objectStatus "C5M13.2" )
			)
			( pin "@baseboard_fab2_lib.baseboard_fab2(sch_1):page230_i42:a"
				( attribute "PN" "1"
					( Origin gPackager )
				)
				( objectStatus "C8L4.1" )
			)
			( pin "@baseboard_fab2_lib.baseboard_fab2(sch_1):page230_i42:b"
				( attribute "PN" "2"
					( Origin gPackager )
				)
				( objectStatus "C8L4.2" )
			)
			( pin "@baseboard_fab2_lib.baseboard_fab2(sch_1):page155_i198:a"
				( attribute "PN" "1"
					( Origin gPackager )
				)
				( objectStatus "R9A5.1" )
			)
			( pin "@baseboard_fab2_lib.baseboard_fab2(sch_1):page155_i198:b"
				( attribute "PN" "2"
					( Origin gPackager )
				)
				( objectStatus "R9A5.2" )
			)
			( pin "@baseboard_fab2_lib.baseboard_fab2(sch_1):page247_i157:a"
				( attribute "PN" "2"
					( Origin gPackager )
				)
				( objectStatus "CR6W1.2" )
			)
			( pin "@baseboard_fab2_lib.baseboard_fab2(sch_1):page247_i157:c"
				( attribute "PN" "1"
					( Origin gPackager )
				)
				( objectStatus "CR6W1.1" )
			)
			( pin "@baseboard_fab2_lib.baseboard_fab2(sch_1):page247_i158:a"
				( attribute "PN" "2"
					( Origin gPackager )
				)
				( objectStatus "CR6W2.2" )
			)
			( pin "@baseboard_fab2_lib.baseboard_fab2(sch_1):page247_i158:c"
				( attribute "PN" "1"
					( Origin gPackager )
				)
				( objectStatus "CR6W2.1" )
			)
			( pin "@baseboard_fab2_lib.baseboard_fab2(sch_1):page176_i156:a"
				( attribute "PN" "1"
					( Origin gPackager )
				)
				( objectStatus "R6W38.1" )
			)
			( pin "@baseboard_fab2_lib.baseboard_fab2(sch_1):page176_i156:b"
				( attribute "PN" "2"
					( Origin gPackager )
				)
				( objectStatus "R6W38.2" )
			)
			( pin "@baseboard_fab2_lib.baseboard_fab2(sch_1):page176_i158:a"
				( attribute "PN" "1"
					( Origin gPackager )
				)
				( objectStatus "R6W39.1" )
			)
			( pin "@baseboard_fab2_lib.baseboard_fab2(sch_1):page176_i158:b"
				( attribute "PN" "2"
					( Origin gPackager )
				)
				( objectStatus "R6W39.2" )
			)
			( pin "@baseboard_fab2_lib.baseboard_fab2(sch_1):page92_i106:a"
				( attribute "PN" "1"
					( Origin gPackager )
				)
				( objectStatus "R7W4.1" )
			)
			( pin "@baseboard_fab2_lib.baseboard_fab2(sch_1):page92_i106:b"
				( attribute "PN" "2"
					( Origin gPackager )
				)
				( objectStatus "R7W4.2" )
			)
			( pin "@baseboard_fab2_lib.baseboard_fab2(sch_1):page92_i108:a"
				( attribute "PN" "1"
					( Origin gPackager )
				)
				( objectStatus "R3W10.1" )
			)
			( pin "@baseboard_fab2_lib.baseboard_fab2(sch_1):page92_i108:b"
				( attribute "PN" "2"
					( Origin gPackager )
				)
				( objectStatus "R3W10.2" )
			)
			( pin "@baseboard_fab2_lib.baseboard_fab2(sch_1):page93_i147:a"
				( attribute "PN" "1"
					( Origin gPackager )
				)
				( objectStatus "R2W2.1" )
			)
			( pin "@baseboard_fab2_lib.baseboard_fab2(sch_1):page93_i147:b"
				( attribute "PN" "2"
					( Origin gPackager )
				)
				( objectStatus "R2W2.2" )
			)
			( pin "@baseboard_fab2_lib.baseboard_fab2(sch_1):page152_i105:a"
				( attribute "PN" "1"
					( Origin gPackager )
				)
				( objectStatus "R1W35.1" )
			)
			( pin "@baseboard_fab2_lib.baseboard_fab2(sch_1):page152_i105:b"
				( attribute "PN" "2"
					( Origin gPackager )
				)
				( objectStatus "R1W35.2" )
			)
			( pin "@baseboard_fab2_lib.baseboard_fab2(sch_1):page176_i160:a"
				( attribute "PN" "1"
					( Origin gPackager )
				)
				( objectStatus "R6W37.1" )
			)
			( pin "@baseboard_fab2_lib.baseboard_fab2(sch_1):page176_i160:b"
				( attribute "PN" "2"
					( Origin gPackager )
				)
				( objectStatus "R6W37.2" )
			)
			( pin "@baseboard_fab2_lib.baseboard_fab2(sch_1):page176_i161:a"
				( attribute "PN" "1"
					( Origin gPackager )
				)
				( objectStatus "R6W36.1" )
			)
			( pin "@baseboard_fab2_lib.baseboard_fab2(sch_1):page176_i161:b"
				( attribute "PN" "2"
					( Origin gPackager )
				)
				( objectStatus "R6W36.2" )
			)
			( pin "@baseboard_fab2_lib.baseboard_fab2(sch_1):page222_i44:a"
				( attribute "PN" "1"
					( Origin gPackager )
				)
				( objectStatus "C5L5.1" )
			)
			( pin "@baseboard_fab2_lib.baseboard_fab2(sch_1):page222_i44:b"
				( attribute "PN" "2"
					( Origin gPackager )
				)
				( objectStatus "C5L5.2" )
			)
			( pin "@baseboard_fab2_lib.baseboard_fab2(sch_1):page176_i163:a"
				( attribute "PN" "1"
					( Origin gPackager )
				)
				( objectStatus "C1W18.1" )
			)
			( pin "@baseboard_fab2_lib.baseboard_fab2(sch_1):page176_i163:b"
				( attribute "PN" "2"
					( Origin gPackager )
				)
				( objectStatus "C1W18.2" )
			)
			( pin "@baseboard_fab2_lib.baseboard_fab2(sch_1):page176_i166:a"
				( attribute "PN" "1"
					( Origin gPackager )
				)
				( objectStatus "C1W19.1" )
			)
			( pin "@baseboard_fab2_lib.baseboard_fab2(sch_1):page176_i166:b"
				( attribute "PN" "2"
					( Origin gPackager )
				)
				( objectStatus "C1W19.2" )
			)
			( pin "@baseboard_fab2_lib.baseboard_fab2(sch_1):page176_i172:a"
				( attribute "PN" "1"
					( Origin gPackager )
				)
				( objectStatus "R1W36.1" )
			)
			( pin "@baseboard_fab2_lib.baseboard_fab2(sch_1):page176_i172:b"
				( attribute "PN" "2"
					( Origin gPackager )
				)
				( objectStatus "R1W36.2" )
			)
			( pin "@baseboard_fab2_lib.baseboard_fab2(sch_1):page176_i173:a"
				( attribute "PN" "1"
					( Origin gPackager )
				)
				( objectStatus "R1W37.1" )
			)
			( pin "@baseboard_fab2_lib.baseboard_fab2(sch_1):page176_i173:b"
				( attribute "PN" "2"
					( Origin gPackager )
				)
				( objectStatus "R1W37.2" )
			)
			( pin "@baseboard_fab2_lib.baseboard_fab2(sch_1):page142_i34:\1\"
				( attribute "PN" "1"
					( Origin gPackager )
				)
				( objectStatus "R8E36.1" )
			)
			( pin "@baseboard_fab2_lib.baseboard_fab2(sch_1):page142_i34:\2\"
				( attribute "PN" "2"
					( Origin gPackager )
				)
				( objectStatus "R8E36.2" )
			)
			( pin "@baseboard_fab2_lib.baseboard_fab2(sch_1):page142_i35:\1\"
				( attribute "PN" "1"
					( Origin gPackager )
				)
				( objectStatus "R8E30.1" )
			)
			( pin "@baseboard_fab2_lib.baseboard_fab2(sch_1):page142_i35:\2\"
				( attribute "PN" "2"
					( Origin gPackager )
				)
				( objectStatus "R8E30.2" )
			)
			( pin "@baseboard_fab2_lib.baseboard_fab2(sch_1):page176_i176:a"
				( attribute "PN" "1"
					( Origin gPackager )
				)
				( objectStatus "R1W38.1" )
			)
			( pin "@baseboard_fab2_lib.baseboard_fab2(sch_1):page176_i176:b"
				( attribute "PN" "2"
					( Origin gPackager )
				)
				( objectStatus "R1W38.2" )
			)
			( pin "@baseboard_fab2_lib.baseboard_fab2(sch_1):page200_i250:\1\"
				( attribute "PN" "1"
					( Origin gPackager )
				)
				( objectStatus "R6W3.1" )
			)
			( pin "@baseboard_fab2_lib.baseboard_fab2(sch_1):page200_i250:\2\"
				( attribute "PN" "2"
					( Origin gPackager )
				)
				( objectStatus "R6W3.2" )
			)
			( pin "@baseboard_fab2_lib.baseboard_fab2(sch_1):page151_i220:a"
				( attribute "PN" "1"
					( Origin gPackager )
				)
				( objectStatus "C1W20.1" )
			)
			( pin "@baseboard_fab2_lib.baseboard_fab2(sch_1):page151_i220:b"
				( attribute "PN" "2"
					( Origin gPackager )
				)
				( objectStatus "C1W20.2" )
			)
			( pin "@baseboard_fab2_lib.baseboard_fab2(sch_1):page240_i193:\1\"
				( attribute "PN" "1"
					( Origin gPackager )
				)
				( objectStatus "FB9E1.1" )
			)
			( pin "@baseboard_fab2_lib.baseboard_fab2(sch_1):page240_i193:\2\"
				( attribute "PN" "2"
					( Origin gPackager )
				)
				( objectStatus "FB9E1.2" )
			)
			( pin "@baseboard_fab2_lib.baseboard_fab2(sch_1):page155_i201:a"
				( attribute "PN" "1"
					( Origin gPackager )
				)
				( objectStatus "R6W40.1" )
			)
			( pin "@baseboard_fab2_lib.baseboard_fab2(sch_1):page155_i201:b"
				( attribute "PN" "2"
					( Origin gPackager )
				)
				( objectStatus "R6W40.2" )
			)
			( pin "@baseboard_fab2_lib.baseboard_fab2(sch_1):page151_i222:a"
				( attribute "PN" "1"
					( Origin gPackager )
				)
				( objectStatus "R25W30.1" )
			)
			( pin "@baseboard_fab2_lib.baseboard_fab2(sch_1):page151_i222:b"
				( attribute "PN" "2"
					( Origin gPackager )
				)
				( objectStatus "R25W30.2" )
			)
			( pin "@baseboard_fab2_lib.baseboard_fab2(sch_1):page199_i137:a"
				( attribute "PN" "1"
					( Origin gPackager )
				)
				( objectStatus "R1D29.1" )
			)
			( pin "@baseboard_fab2_lib.baseboard_fab2(sch_1):page199_i137:b"
				( attribute "PN" "2"
					( Origin gPackager )
				)
				( objectStatus "R1D29.2" )
			)
			( pin "@baseboard_fab2_lib.baseboard_fab2(sch_1):page164_i101:a"
				( attribute "PN" "1"
					( Origin gPackager )
				)
				( objectStatus "R1T10.1" )
			)
			( pin "@baseboard_fab2_lib.baseboard_fab2(sch_1):page164_i101:b"
				( attribute "PN" "2"
					( Origin gPackager )
				)
				( objectStatus "R1T10.2" )
			)
			( pin "@baseboard_fab2_lib.baseboard_fab2(sch_1):page164_i51:a"
				( attribute "PN" "1"
					( Origin gPackager )
				)
				( objectStatus "R1T6.1" )
			)
			( pin "@baseboard_fab2_lib.baseboard_fab2(sch_1):page164_i51:b"
				( attribute "PN" "2"
					( Origin gPackager )
				)
				( objectStatus "R1T6.2" )
			)
			( pin "@baseboard_fab2_lib.baseboard_fab2(sch_1):page164_i53:a"
				( attribute "PN" "1"
					( Origin gPackager )
				)
				( objectStatus "R1T12.1" )
			)
			( pin "@baseboard_fab2_lib.baseboard_fab2(sch_1):page164_i53:b"
				( attribute "PN" "2"
					( Origin gPackager )
				)
				( objectStatus "R1T12.2" )
			)
			( pin "@baseboard_fab2_lib.baseboard_fab2(sch_1):page211_i102:a"
				( attribute "PN" "1"
					( Origin gPackager )
				)
				( objectStatus "R3N22.1" )
			)
			( pin "@baseboard_fab2_lib.baseboard_fab2(sch_1):page211_i102:b"
				( attribute "PN" "2"
					( Origin gPackager )
				)
				( objectStatus "R3N22.2" )
			)
			( pin "@baseboard_fab2_lib.baseboard_fab2(sch_1):page213_i104:a"
				( attribute "PN" "1"
					( Origin gPackager )
				)
				( objectStatus "R4D64.1" )
			)
			( pin "@baseboard_fab2_lib.baseboard_fab2(sch_1):page213_i104:b"
				( attribute "PN" "2"
					( Origin gPackager )
				)
				( objectStatus "R4D64.2" )
			)
			( pin "@baseboard_fab2_lib.baseboard_fab2(sch_1):page239_i102:\1\"
				( attribute "PN" "1"
					( Origin gPackager )
				)
				( objectStatus "R9W31.1" )
			)
			( pin "@baseboard_fab2_lib.baseboard_fab2(sch_1):page239_i102:\2\"
				( attribute "PN" "2"
					( Origin gPackager )
				)
				( objectStatus "R9W31.2" )
			)
			( pin "@baseboard_fab2_lib.baseboard_fab2(sch_1):page151_i224:\1\"
				( attribute "PN" "1"
					( Origin gPackager )
				)
				( objectStatus "R25W28.1" )
			)
			( pin "@baseboard_fab2_lib.baseboard_fab2(sch_1):page151_i224:\2\"
				( attribute "PN" "2"
					( Origin gPackager )
				)
				( objectStatus "R25W28.2" )
			)
			( pin "@baseboard_fab2_lib.baseboard_fab2(sch_1):page151_i225:\1\"
				( attribute "PN" "1"
					( Origin gPackager )
				)
				( objectStatus "R25W29.1" )
			)
			( pin "@baseboard_fab2_lib.baseboard_fab2(sch_1):page151_i225:\2\"
				( attribute "PN" "2"
					( Origin gPackager )
				)
				( objectStatus "R25W29.2" )
			)
			( pin "@baseboard_fab2_lib.baseboard_fab2(sch_1):page151_i229:\1\"
				( attribute "PN" "1"
					( Origin gPackager )
				)
				( objectStatus "R25W34.1" )
			)
			( pin "@baseboard_fab2_lib.baseboard_fab2(sch_1):page151_i229:\2\"
				( attribute "PN" "2"
					( Origin gPackager )
				)
				( objectStatus "R25W34.2" )
			)
			( pin "@baseboard_fab2_lib.baseboard_fab2(sch_1):page151_i230:\1\"
				( attribute "PN" "1"
					( Origin gPackager )
				)
				( objectStatus "R25W35.1" )
			)
			( pin "@baseboard_fab2_lib.baseboard_fab2(sch_1):page151_i230:\2\"
				( attribute "PN" "2"
					( Origin gPackager )
				)
				( objectStatus "R25W35.2" )
			)
			( pin "@baseboard_fab2_lib.baseboard_fab2(sch_1):page151_i231:\1\"
				( attribute "PN" "1"
					( Origin gPackager )
				)
				( objectStatus "R25W36.1" )
			)
			( pin "@baseboard_fab2_lib.baseboard_fab2(sch_1):page151_i231:\2\"
				( attribute "PN" "2"
					( Origin gPackager )
				)
				( objectStatus "R25W36.2" )
			)
			( pin "@baseboard_fab2_lib.baseboard_fab2(sch_1):page151_i232:\1\"
				( attribute "PN" "1"
					( Origin gPackager )
				)
				( objectStatus "R25W37.1" )
			)
			( pin "@baseboard_fab2_lib.baseboard_fab2(sch_1):page151_i232:\2\"
				( attribute "PN" "2"
					( Origin gPackager )
				)
				( objectStatus "R25W37.2" )
			)
			( pin "@baseboard_fab2_lib.baseboard_fab2(sch_1):page151_i233:\1\"
				( attribute "PN" "1"
					( Origin gPackager )
				)
				( objectStatus "R25W38.1" )
			)
			( pin "@baseboard_fab2_lib.baseboard_fab2(sch_1):page151_i233:\2\"
				( attribute "PN" "2"
					( Origin gPackager )
				)
				( objectStatus "R25W38.2" )
			)
			( pin "@baseboard_fab2_lib.baseboard_fab2(sch_1):page151_i234:\1\"
				( attribute "PN" "1"
					( Origin gPackager )
				)
				( objectStatus "R25W39.1" )
			)
			( pin "@baseboard_fab2_lib.baseboard_fab2(sch_1):page151_i234:\2\"
				( attribute "PN" "2"
					( Origin gPackager )
				)
				( objectStatus "R25W39.2" )
			)
			( pin "@baseboard_fab2_lib.baseboard_fab2(sch_1):page151_i235:\1\"
				( attribute "PN" "1"
					( Origin gPackager )
				)
				( objectStatus "R25W41.1" )
			)
			( pin "@baseboard_fab2_lib.baseboard_fab2(sch_1):page151_i235:\2\"
				( attribute "PN" "2"
					( Origin gPackager )
				)
				( objectStatus "R25W41.2" )
			)
			( pin "@baseboard_fab2_lib.baseboard_fab2(sch_1):page151_i236:\1\"
				( attribute "PN" "1"
					( Origin gPackager )
				)
				( objectStatus "R25W42.1" )
			)
			( pin "@baseboard_fab2_lib.baseboard_fab2(sch_1):page151_i236:\2\"
				( attribute "PN" "2"
					( Origin gPackager )
				)
				( objectStatus "R25W42.2" )
			)
			( pin "@baseboard_fab2_lib.baseboard_fab2(sch_1):page151_i237:\1\"
				( attribute "PN" "1"
					( Origin gPackager )
				)
				( objectStatus "R25W44.1" )
			)
			( pin "@baseboard_fab2_lib.baseboard_fab2(sch_1):page151_i237:\2\"
				( attribute "PN" "2"
					( Origin gPackager )
				)
				( objectStatus "R25W44.2" )
			)
			( pin "@baseboard_fab2_lib.baseboard_fab2(sch_1):page151_i238:\1\"
				( attribute "PN" "1"
					( Origin gPackager )
				)
				( objectStatus "R25W43.1" )
			)
			( pin "@baseboard_fab2_lib.baseboard_fab2(sch_1):page151_i238:\2\"
				( attribute "PN" "2"
					( Origin gPackager )
				)
				( objectStatus "R25W43.2" )
			)
			( pin "@baseboard_fab2_lib.baseboard_fab2(sch_1):page151_i239:\1\"
				( attribute "PN" "1"
					( Origin gPackager )
				)
				( objectStatus "R25W47.1" )
			)
			( pin "@baseboard_fab2_lib.baseboard_fab2(sch_1):page151_i239:\2\"
				( attribute "PN" "2"
					( Origin gPackager )
				)
				( objectStatus "R25W47.2" )
			)
			( pin "@baseboard_fab2_lib.baseboard_fab2(sch_1):page151_i240:\1\"
				( attribute "PN" "1"
					( Origin gPackager )
				)
				( objectStatus "R25W48.1" )
			)
			( pin "@baseboard_fab2_lib.baseboard_fab2(sch_1):page151_i240:\2\"
				( attribute "PN" "2"
					( Origin gPackager )
				)
				( objectStatus "R25W48.2" )
			)
			( pin "@baseboard_fab2_lib.baseboard_fab2(sch_1):page151_i241:\1\"
				( attribute "PN" "1"
					( Origin gPackager )
				)
				( objectStatus "R25W46.1" )
			)
			( pin "@baseboard_fab2_lib.baseboard_fab2(sch_1):page151_i241:\2\"
				( attribute "PN" "2"
					( Origin gPackager )
				)
				( objectStatus "R25W46.2" )
			)
			( pin "@baseboard_fab2_lib.baseboard_fab2(sch_1):page151_i242:\1\"
				( attribute "PN" "1"
					( Origin gPackager )
				)
				( objectStatus "R25W45.1" )
			)
			( pin "@baseboard_fab2_lib.baseboard_fab2(sch_1):page151_i242:\2\"
				( attribute "PN" "2"
					( Origin gPackager )
				)
				( objectStatus "R25W45.2" )
			)
			( pin "@baseboard_fab2_lib.baseboard_fab2(sch_1):page151_i243:\1\"
				( attribute "PN" "1"
					( Origin gPackager )
				)
				( objectStatus "R25W49.1" )
			)
			( pin "@baseboard_fab2_lib.baseboard_fab2(sch_1):page151_i243:\2\"
				( attribute "PN" "2"
					( Origin gPackager )
				)
				( objectStatus "R25W49.2" )
			)
			( pin "@baseboard_fab2_lib.baseboard_fab2(sch_1):page151_i244:\1\"
				( attribute "PN" "1"
					( Origin gPackager )
				)
				( objectStatus "R25W50.1" )
			)
			( pin "@baseboard_fab2_lib.baseboard_fab2(sch_1):page151_i244:\2\"
				( attribute "PN" "2"
					( Origin gPackager )
				)
				( objectStatus "R25W50.2" )
			)
			( pin "@baseboard_fab2_lib.baseboard_fab2(sch_1):page151_i245:\1\"
				( attribute "PN" "1"
					( Origin gPackager )
				)
				( objectStatus "R25W51.1" )
			)
			( pin "@baseboard_fab2_lib.baseboard_fab2(sch_1):page151_i245:\2\"
				( attribute "PN" "2"
					( Origin gPackager )
				)
				( objectStatus "R25W51.2" )
			)
			( pin "@baseboard_fab2_lib.baseboard_fab2(sch_1):page151_i246:\1\"
				( attribute "PN" "1"
					( Origin gPackager )
				)
				( objectStatus "R25W52.1" )
			)
			( pin "@baseboard_fab2_lib.baseboard_fab2(sch_1):page151_i246:\2\"
				( attribute "PN" "2"
					( Origin gPackager )
				)
				( objectStatus "R25W52.2" )
			)
			( pin "@baseboard_fab2_lib.baseboard_fab2(sch_1):page151_i247:\1\"
				( attribute "PN" "1"
					( Origin gPackager )
				)
				( objectStatus "R25W40.1" )
			)
			( pin "@baseboard_fab2_lib.baseboard_fab2(sch_1):page151_i247:\2\"
				( attribute "PN" "2"
					( Origin gPackager )
				)
				( objectStatus "R25W40.2" )
			)
			( pin "@baseboard_fab2_lib.baseboard_fab2(sch_1):page151_i270:\1\"
				( attribute "PN" "1"
					( Origin gPackager )
				)
				( objectStatus "R25W22.1" )
			)
			( pin "@baseboard_fab2_lib.baseboard_fab2(sch_1):page151_i270:\2\"
				( attribute "PN" "2"
					( Origin gPackager )
				)
				( objectStatus "R25W22.2" )
			)
			( pin "@baseboard_fab2_lib.baseboard_fab2(sch_1):page151_i271:\1\"
				( attribute "PN" "1"
					( Origin gPackager )
				)
				( objectStatus "R25W21.1" )
			)
			( pin "@baseboard_fab2_lib.baseboard_fab2(sch_1):page151_i271:\2\"
				( attribute "PN" "2"
					( Origin gPackager )
				)
				( objectStatus "R25W21.2" )
			)
			( pin "@baseboard_fab2_lib.baseboard_fab2(sch_1):page151_i274:\1\"
				( attribute "PN" "1"
					( Origin gPackager )
				)
				( objectStatus "R25W26.1" )
			)
			( pin "@baseboard_fab2_lib.baseboard_fab2(sch_1):page151_i274:\2\"
				( attribute "PN" "2"
					( Origin gPackager )
				)
				( objectStatus "R25W26.2" )
			)
			( pin "@baseboard_fab2_lib.baseboard_fab2(sch_1):page151_i275:\1\"
				( attribute "PN" "1"
					( Origin gPackager )
				)
				( objectStatus "R25W25.1" )
			)
			( pin "@baseboard_fab2_lib.baseboard_fab2(sch_1):page151_i275:\2\"
				( attribute "PN" "2"
					( Origin gPackager )
				)
				( objectStatus "R25W25.2" )
			)
			( pin "@baseboard_fab2_lib.baseboard_fab2(sch_1):page226_i73:a"
				( attribute "PN" "1"
					( Origin gPackager )
				)
				( objectStatus "R1B15.1" )
			)
			( pin "@baseboard_fab2_lib.baseboard_fab2(sch_1):page226_i73:b"
				( attribute "PN" "2"
					( Origin gPackager )
				)
				( objectStatus "R1B15.2" )
			)
			( pin "@baseboard_fab2_lib.baseboard_fab2(sch_1):page247_i159:a"
				( attribute "PN" "1"
					( Origin gPackager )
				)
				( objectStatus "R6W4.1" )
			)
			( pin "@baseboard_fab2_lib.baseboard_fab2(sch_1):page247_i159:b"
				( attribute "PN" "2"
					( Origin gPackager )
				)
				( objectStatus "R6W4.2" )
			)
			( pin "@baseboard_fab2_lib.baseboard_fab2(sch_1):page247_i160:a"
				( attribute "PN" "1"
					( Origin gPackager )
				)
				( objectStatus "R6W5.1" )
			)
			( pin "@baseboard_fab2_lib.baseboard_fab2(sch_1):page247_i160:b"
				( attribute "PN" "2"
					( Origin gPackager )
				)
				( objectStatus "R6W5.2" )
			)
			( pin "@baseboard_fab2_lib.baseboard_fab2(sch_1):page247_i161:a"
				( attribute "PN" "1"
					( Origin gPackager )
				)
				( objectStatus "R6W6.1" )
			)
			( pin "@baseboard_fab2_lib.baseboard_fab2(sch_1):page247_i161:b"
				( attribute "PN" "2"
					( Origin gPackager )
				)
				( objectStatus "R6W6.2" )
			)
			( pin "@baseboard_fab2_lib.baseboard_fab2(sch_1):page247_i162:a"
				( attribute "PN" "1"
					( Origin gPackager )
				)
				( objectStatus "R6W9.1" )
			)
			( pin "@baseboard_fab2_lib.baseboard_fab2(sch_1):page247_i162:b"
				( attribute "PN" "2"
					( Origin gPackager )
				)
				( objectStatus "R6W9.2" )
			)
			( pin "@baseboard_fab2_lib.baseboard_fab2(sch_1):page247_i163:a"
				( attribute "PN" "1"
					( Origin gPackager )
				)
				( objectStatus "R6W8.1" )
			)
			( pin "@baseboard_fab2_lib.baseboard_fab2(sch_1):page247_i163:b"
				( attribute "PN" "2"
					( Origin gPackager )
				)
				( objectStatus "R6W8.2" )
			)
			( pin "@baseboard_fab2_lib.baseboard_fab2(sch_1):page247_i164:a"
				( attribute "PN" "1"
					( Origin gPackager )
				)
				( objectStatus "R6W7.1" )
			)
			( pin "@baseboard_fab2_lib.baseboard_fab2(sch_1):page247_i164:b"
				( attribute "PN" "2"
					( Origin gPackager )
				)
				( objectStatus "R6W7.2" )
			)
			( pin "@baseboard_fab2_lib.baseboard_fab2(sch_1):page151_i278:a"
				( attribute "PN" "1"
					( Origin gPackager )
				)
				( objectStatus "R1T40.1" )
			)
			( pin "@baseboard_fab2_lib.baseboard_fab2(sch_1):page151_i278:b"
				( attribute "PN" "2"
					( Origin gPackager )
				)
				( objectStatus "R1T40.2" )
			)
			( pin "@baseboard_fab2_lib.baseboard_fab2(sch_1):page151_i279:a"
				( attribute "PN" "1"
					( Origin gPackager )
				)
				( objectStatus "R1T28.1" )
			)
			( pin "@baseboard_fab2_lib.baseboard_fab2(sch_1):page151_i279:b"
				( attribute "PN" "2"
					( Origin gPackager )
				)
				( objectStatus "R1T28.2" )
			)
			( pin "@baseboard_fab2_lib.baseboard_fab2(sch_1):page240_i195:a"
				( attribute "PN" "1"
					( Origin gPackager )
				)
				( objectStatus "R8F9.1" )
			)
			( pin "@baseboard_fab2_lib.baseboard_fab2(sch_1):page240_i195:b"
				( attribute "PN" "2"
					( Origin gPackager )
				)
				( objectStatus "R8F9.2" )
			)
			( pin "@baseboard_fab2_lib.baseboard_fab2(sch_1):page224_i160:f"
				( attribute "PN" "2"
					( Origin gPackager )
				)
				( objectStatus "L1G1.2" )
			)
			( pin "@baseboard_fab2_lib.baseboard_fab2(sch_1):page224_i160:s"
				( attribute "PN" "1"
					( Origin gPackager )
				)
				( objectStatus "L1G1.1" )
			)
			( pin "@baseboard_fab2_lib.baseboard_fab2(sch_1):page76_i245:a"
				( attribute "PN" "1"
					( Origin gPackager )
				)
				( objectStatus "C8W4.1" )
			)
			( pin "@baseboard_fab2_lib.baseboard_fab2(sch_1):page76_i245:b"
				( attribute "PN" "2"
					( Origin gPackager )
				)
				( objectStatus "C8W4.2" )
			)
			( pin "@baseboard_fab2_lib.baseboard_fab2(sch_1):page217_i317:a"
				( attribute "PN" "1"
					( Origin gPackager )
				)
				( objectStatus "C5U10.1" )
			)
			( pin "@baseboard_fab2_lib.baseboard_fab2(sch_1):page217_i317:b"
				( attribute "PN" "2"
					( Origin gPackager )
				)
				( objectStatus "C5U10.2" )
			)
			( pin "@baseboard_fab2_lib.baseboard_fab2(sch_1):page217_i320:a"
				( attribute "PN" "1"
					( Origin gPackager )
				)
				( objectStatus "C5U15.1" )
			)
			( pin "@baseboard_fab2_lib.baseboard_fab2(sch_1):page217_i320:b"
				( attribute "PN" "2"
					( Origin gPackager )
				)
				( objectStatus "C5U15.2" )
			)
			( pin "@baseboard_fab2_lib.baseboard_fab2(sch_1):page217_i327:a"
				( attribute "PN" "1"
					( Origin gPackager )
				)
				( objectStatus "C5P38.1" )
			)
			( pin "@baseboard_fab2_lib.baseboard_fab2(sch_1):page217_i327:b"
				( attribute "PN" "2"
					( Origin gPackager )
				)
				( objectStatus "C5P38.2" )
			)
			( pin "@baseboard_fab2_lib.baseboard_fab2(sch_1):page217_i328:a"
				( attribute "PN" "1"
					( Origin gPackager )
				)
				( objectStatus "C5P39.1" )
			)
			( pin "@baseboard_fab2_lib.baseboard_fab2(sch_1):page217_i328:b"
				( attribute "PN" "2"
					( Origin gPackager )
				)
				( objectStatus "C5P39.2" )
			)
			( pin "@baseboard_fab2_lib.baseboard_fab2(sch_1):page247_i165:a"
				( attribute "PN" "1"
					( Origin gPackager )
				)
				( objectStatus "R6W35.1" )
			)
			( pin "@baseboard_fab2_lib.baseboard_fab2(sch_1):page247_i165:b"
				( attribute "PN" "2"
					( Origin gPackager )
				)
				( objectStatus "R6W35.2" )
			)
			( pin "@baseboard_fab2_lib.baseboard_fab2(sch_1):page114_i195:a"
				( attribute "PN" "1"
					( Origin gPackager )
				)
				( objectStatus "C7C13.1" )
			)
			( pin "@baseboard_fab2_lib.baseboard_fab2(sch_1):page114_i195:b"
				( attribute "PN" "2"
					( Origin gPackager )
				)
				( objectStatus "C7C13.2" )
			)
			( pin "@baseboard_fab2_lib.baseboard_fab2(sch_1):page114_i196:a"
				( attribute "PN" "1"
					( Origin gPackager )
				)
				( objectStatus "C7C15.1" )
			)
			( pin "@baseboard_fab2_lib.baseboard_fab2(sch_1):page114_i196:b"
				( attribute "PN" "2"
					( Origin gPackager )
				)
				( objectStatus "C7C15.2" )
			)
			( pin "@baseboard_fab2_lib.baseboard_fab2(sch_1):page42_i214:a"
				( attribute "PN" "1"
					( Origin gPackager )
				)
				( objectStatus "C5P8.1" )
			)
			( pin "@baseboard_fab2_lib.baseboard_fab2(sch_1):page42_i214:b"
				( attribute "PN" "2"
					( Origin gPackager )
				)
				( objectStatus "C5P8.2" )
			)
			( pin "@baseboard_fab2_lib.baseboard_fab2(sch_1):page76_i247:a"
				( attribute "PN" "1"
					( Origin gPackager )
				)
				( objectStatus "C8P6.1" )
			)
			( pin "@baseboard_fab2_lib.baseboard_fab2(sch_1):page76_i247:b"
				( attribute "PN" "2"
					( Origin gPackager )
				)
				( objectStatus "C8P6.2" )
			)
			( pin "@baseboard_fab2_lib.baseboard_fab2(sch_1):page76_i248:a"
				( attribute "PN" "1"
					( Origin gPackager )
				)
				( objectStatus "C8P7.1" )
			)
			( pin "@baseboard_fab2_lib.baseboard_fab2(sch_1):page76_i248:b"
				( attribute "PN" "2"
					( Origin gPackager )
				)
				( objectStatus "C8P7.2" )
			)
			( pin "@baseboard_fab2_lib.baseboard_fab2(sch_1):page76_i252:a"
				( attribute "PN" "1"
					( Origin gPackager )
				)
				( objectStatus "C8P17.1" )
			)
			( pin "@baseboard_fab2_lib.baseboard_fab2(sch_1):page76_i252:b"
				( attribute "PN" "2"
					( Origin gPackager )
				)
				( objectStatus "C8P17.2" )
			)
			( pin "@baseboard_fab2_lib.baseboard_fab2(sch_1):page147_i164:a"
				( attribute "PN" "1"
					( Origin gPackager )
				)
				( objectStatus "R25W157.1" )
			)
			( pin "@baseboard_fab2_lib.baseboard_fab2(sch_1):page147_i164:b"
				( attribute "PN" "2"
					( Origin gPackager )
				)
				( objectStatus "R25W157.2" )
			)
			( pin "@baseboard_fab2_lib.baseboard_fab2(sch_1):page185_i183:a"
				( attribute "PN" "1"
					( Origin gPackager )
				)
				( objectStatus "R32W10.1" )
			)
			( pin "@baseboard_fab2_lib.baseboard_fab2(sch_1):page185_i183:b"
				( attribute "PN" "2"
					( Origin gPackager )
				)
				( objectStatus "R32W10.2" )
			)
			( pin "@baseboard_fab2_lib.baseboard_fab2(sch_1):page185_i184:a"
				( attribute "PN" "1"
					( Origin gPackager )
				)
				( objectStatus "R32W11.1" )
			)
			( pin "@baseboard_fab2_lib.baseboard_fab2(sch_1):page185_i184:b"
				( attribute "PN" "2"
					( Origin gPackager )
				)
				( objectStatus "R32W11.2" )
			)
			( pin "@baseboard_fab2_lib.baseboard_fab2(sch_1):page185_i187:a"
				( attribute "PN" "1"
					( Origin gPackager )
				)
				( objectStatus "R32W12.1" )
			)
			( pin "@baseboard_fab2_lib.baseboard_fab2(sch_1):page185_i187:b"
				( attribute "PN" "2"
					( Origin gPackager )
				)
				( objectStatus "R32W12.2" )
			)
			( pin "@baseboard_fab2_lib.baseboard_fab2(sch_1):page185_i188:a"
				( attribute "PN" "1"
					( Origin gPackager )
				)
				( objectStatus "C32W1.1" )
			)
			( pin "@baseboard_fab2_lib.baseboard_fab2(sch_1):page185_i188:b"
				( attribute "PN" "2"
					( Origin gPackager )
				)
				( objectStatus "C32W1.2" )
			)
			( pin "@baseboard_fab2_lib.baseboard_fab2(sch_1):page185_i190:a"
				( attribute "PN" "1"
					( Origin gPackager )
				)
				( objectStatus "C32W3.1" )
			)
			( pin "@baseboard_fab2_lib.baseboard_fab2(sch_1):page185_i190:b"
				( attribute "PN" "2"
					( Origin gPackager )
				)
				( objectStatus "C32W3.2" )
			)
			( pin "@baseboard_fab2_lib.baseboard_fab2(sch_1):page185_i191:en"
				( attribute "PN" "5"
					( Origin gPackager )
				)
				( objectStatus "U32W1.5" )
			)
			( pin "@baseboard_fab2_lib.baseboard_fab2(sch_1):page185_i191:gnd"
				( attribute "PN" "4"
					( Origin gPackager )
				)
				( objectStatus "U32W1.4" )
			)
			( pin "@baseboard_fab2_lib.baseboard_fab2(sch_1):page185_i191:scla"
				( attribute "PN" "2"
					( Origin gPackager )
				)
				( objectStatus "U32W1.2" )
			)
			( pin "@baseboard_fab2_lib.baseboard_fab2(sch_1):page185_i191:sclb"
				( attribute "PN" "7"
					( Origin gPackager )
				)
				( objectStatus "U32W1.7" )
			)
			( pin "@baseboard_fab2_lib.baseboard_fab2(sch_1):page185_i191:sdaa"
				( attribute "PN" "3"
					( Origin gPackager )
				)
				( objectStatus "U32W1.3" )
			)
			( pin "@baseboard_fab2_lib.baseboard_fab2(sch_1):page185_i191:sdab"
				( attribute "PN" "6"
					( Origin gPackager )
				)
				( objectStatus "U32W1.6" )
			)
			( pin "@baseboard_fab2_lib.baseboard_fab2(sch_1):page185_i191:vcca"
				( attribute "PN" "1"
					( Origin gPackager )
				)
				( objectStatus "U32W1.1" )
			)
			( pin "@baseboard_fab2_lib.baseboard_fab2(sch_1):page185_i191:vccb"
				( attribute "PN" "8"
					( Origin gPackager )
				)
				( objectStatus "U32W1.8" )
			)
			( pin "@baseboard_fab2_lib.baseboard_fab2(sch_1):page185_i193:a"
				( attribute "PN" "1"
					( Origin gPackager )
				)
				( objectStatus "C32W2.1" )
			)
			( pin "@baseboard_fab2_lib.baseboard_fab2(sch_1):page185_i193:b"
				( attribute "PN" "2"
					( Origin gPackager )
				)
				( objectStatus "C32W2.2" )
			)
			( pin "@baseboard_fab2_lib.baseboard_fab2(sch_1):page185_i196:a"
				( attribute "PN" "1"
					( Origin gPackager )
				)
				( objectStatus "C32W4.1" )
			)
			( pin "@baseboard_fab2_lib.baseboard_fab2(sch_1):page185_i196:b"
				( attribute "PN" "2"
					( Origin gPackager )
				)
				( objectStatus "C32W4.2" )
			)
			( pin "@baseboard_fab2_lib.baseboard_fab2(sch_1):page185_i200:a"
				( attribute "PN" "1"
					( Origin gPackager )
				)
				( objectStatus "R32W9.1" )
			)
			( pin "@baseboard_fab2_lib.baseboard_fab2(sch_1):page185_i200:b"
				( attribute "PN" "2"
					( Origin gPackager )
				)
				( objectStatus "R32W9.2" )
			)
			( pin "@baseboard_fab2_lib.baseboard_fab2(sch_1):page185_i204:en"
				( attribute "PN" "5"
					( Origin gPackager )
				)
				( objectStatus "U32W2.5" )
			)
			( pin "@baseboard_fab2_lib.baseboard_fab2(sch_1):page185_i204:gnd"
				( attribute "PN" "4"
					( Origin gPackager )
				)
				( objectStatus "U32W2.4" )
			)
			( pin "@baseboard_fab2_lib.baseboard_fab2(sch_1):page185_i204:scla"
				( attribute "PN" "2"
					( Origin gPackager )
				)
				( objectStatus "U32W2.2" )
			)
			( pin "@baseboard_fab2_lib.baseboard_fab2(sch_1):page185_i204:sclb"
				( attribute "PN" "7"
					( Origin gPackager )
				)
				( objectStatus "U32W2.7" )
			)
			( pin "@baseboard_fab2_lib.baseboard_fab2(sch_1):page185_i204:sdaa"
				( attribute "PN" "3"
					( Origin gPackager )
				)
				( objectStatus "U32W2.3" )
			)
			( pin "@baseboard_fab2_lib.baseboard_fab2(sch_1):page185_i204:sdab"
				( attribute "PN" "6"
					( Origin gPackager )
				)
				( objectStatus "U32W2.6" )
			)
			( pin "@baseboard_fab2_lib.baseboard_fab2(sch_1):page185_i204:vcca"
				( attribute "PN" "1"
					( Origin gPackager )
				)
				( objectStatus "U32W2.1" )
			)
			( pin "@baseboard_fab2_lib.baseboard_fab2(sch_1):page185_i204:vccb"
				( attribute "PN" "8"
					( Origin gPackager )
				)
				( objectStatus "U32W2.8" )
			)
			( pin "@baseboard_fab2_lib.baseboard_fab2(sch_1):page185_i206:a"
				( attribute "PN" "1"
					( Origin gPackager )
				)
				( objectStatus "R32W3.1" )
			)
			( pin "@baseboard_fab2_lib.baseboard_fab2(sch_1):page185_i206:b"
				( attribute "PN" "2"
					( Origin gPackager )
				)
				( objectStatus "R32W3.2" )
			)
			( pin "@baseboard_fab2_lib.baseboard_fab2(sch_1):page185_i207:a"
				( attribute "PN" "1"
					( Origin gPackager )
				)
				( objectStatus "R32W2.1" )
			)
			( pin "@baseboard_fab2_lib.baseboard_fab2(sch_1):page185_i207:b"
				( attribute "PN" "2"
					( Origin gPackager )
				)
				( objectStatus "R32W2.2" )
			)
			( pin "@baseboard_fab2_lib.baseboard_fab2(sch_1):page185_i208:a"
				( attribute "PN" "1"
					( Origin gPackager )
				)
				( objectStatus "R32W1.1" )
			)
			( pin "@baseboard_fab2_lib.baseboard_fab2(sch_1):page185_i208:b"
				( attribute "PN" "2"
					( Origin gPackager )
				)
				( objectStatus "R32W1.2" )
			)
			( pin "@baseboard_fab2_lib.baseboard_fab2(sch_1):page185_i211:a"
				( attribute "PN" "1"
					( Origin gPackager )
				)
				( objectStatus "R32W4.1" )
			)
			( pin "@baseboard_fab2_lib.baseboard_fab2(sch_1):page185_i211:b"
				( attribute "PN" "2"
					( Origin gPackager )
				)
				( objectStatus "R32W4.2" )
			)
			( pin "@baseboard_fab2_lib.baseboard_fab2(sch_1):page185_i213:anode"
				( attribute "PN" "3"
					( Origin gPackager )
				)
				( objectStatus "VR32W1.3" )
			)
			( pin "@baseboard_fab2_lib.baseboard_fab2(sch_1):page185_i213:cathode"
				( attribute "PN" "2"
					( Origin gPackager )
				)
				( objectStatus "VR32W1.2" )
			)
			( pin "@baseboard_fab2_lib.baseboard_fab2(sch_1):page185_i213:ref"
				( attribute "PN" "1"
					( Origin gPackager )
				)
				( objectStatus "VR32W1.1" )
			)
			( pin "@baseboard_fab2_lib.baseboard_fab2(sch_1):page185_i214:a"
				( attribute "PN" "1"
					( Origin gPackager )
				)
				( objectStatus "R32W6.1" )
			)
			( pin "@baseboard_fab2_lib.baseboard_fab2(sch_1):page185_i214:b"
				( attribute "PN" "2"
					( Origin gPackager )
				)
				( objectStatus "R32W6.2" )
			)
			( pin "@baseboard_fab2_lib.baseboard_fab2(sch_1):page185_i215:a"
				( attribute "PN" "1"
					( Origin gPackager )
				)
				( objectStatus "R32W7.1" )
			)
			( pin "@baseboard_fab2_lib.baseboard_fab2(sch_1):page185_i215:b"
				( attribute "PN" "2"
					( Origin gPackager )
				)
				( objectStatus "R32W7.2" )
			)
			( pin "@baseboard_fab2_lib.baseboard_fab2(sch_1):page185_i216:a"
				( attribute "PN" "1"
					( Origin gPackager )
				)
				( objectStatus "R32W5.1" )
			)
			( pin "@baseboard_fab2_lib.baseboard_fab2(sch_1):page185_i216:b"
				( attribute "PN" "2"
					( Origin gPackager )
				)
				( objectStatus "R32W5.2" )
			)
			( pin "@baseboard_fab2_lib.baseboard_fab2(sch_1):page249_i52:\1\"
				( attribute "PN" "1"
					( Origin gPackager )
				)
				( objectStatus "C8W1.1" )
			)
			( pin "@baseboard_fab2_lib.baseboard_fab2(sch_1):page249_i52:\2\"
				( attribute "PN" "2"
					( Origin gPackager )
				)
				( objectStatus "C8W1.2" )
			)
			( pin "@baseboard_fab2_lib.baseboard_fab2(sch_1):page197_i117:\1\"
				( attribute "PN" "1"
					( Origin gPackager )
				)
				( objectStatus "R12W2.1" )
			)
			( pin "@baseboard_fab2_lib.baseboard_fab2(sch_1):page197_i117:\2\"
				( attribute "PN" "2"
					( Origin gPackager )
				)
				( objectStatus "R12W2.2" )
			)
			( pin "@baseboard_fab2_lib.baseboard_fab2(sch_1):page197_i119:\1\"
				( attribute "PN" "1"
					( Origin gPackager )
				)
				( objectStatus "R12W12.1" )
			)
			( pin "@baseboard_fab2_lib.baseboard_fab2(sch_1):page197_i119:\2\"
				( attribute "PN" "2"
					( Origin gPackager )
				)
				( objectStatus "R12W12.2" )
			)
			( pin "@baseboard_fab2_lib.baseboard_fab2(sch_1):page197_i120:\1\"
				( attribute "PN" "1"
					( Origin gPackager )
				)
				( objectStatus "R12W6.1" )
			)
			( pin "@baseboard_fab2_lib.baseboard_fab2(sch_1):page197_i120:\2\"
				( attribute "PN" "2"
					( Origin gPackager )
				)
				( objectStatus "R12W6.2" )
			)
			( pin "@baseboard_fab2_lib.baseboard_fab2(sch_1):page197_i121:\1\"
				( attribute "PN" "1"
					( Origin gPackager )
				)
				( objectStatus "R12W7.1" )
			)
			( pin "@baseboard_fab2_lib.baseboard_fab2(sch_1):page197_i121:\2\"
				( attribute "PN" "2"
					( Origin gPackager )
				)
				( objectStatus "R12W7.2" )
			)
			( pin "@baseboard_fab2_lib.baseboard_fab2(sch_1):page197_i122:\1\"
				( attribute "PN" "1"
					( Origin gPackager )
				)
				( objectStatus "R12W16.1" )
			)
			( pin "@baseboard_fab2_lib.baseboard_fab2(sch_1):page197_i122:\2\"
				( attribute "PN" "2"
					( Origin gPackager )
				)
				( objectStatus "R12W16.2" )
			)
			( pin "@baseboard_fab2_lib.baseboard_fab2(sch_1):page197_i123:\1\"
				( attribute "PN" "1"
					( Origin gPackager )
				)
				( objectStatus "R12W17.1" )
			)
			( pin "@baseboard_fab2_lib.baseboard_fab2(sch_1):page197_i123:\2\"
				( attribute "PN" "2"
					( Origin gPackager )
				)
				( objectStatus "R12W17.2" )
			)
			( pin "@baseboard_fab2_lib.baseboard_fab2(sch_1):page249_i49:b"
				( attribute "PN" "1"
					( Origin gPackager )
				)
				( objectStatus "Q9W3.1" )
			)
			( pin "@baseboard_fab2_lib.baseboard_fab2(sch_1):page249_i49:c"
				( attribute "PN" "3"
					( Origin gPackager )
				)
				( objectStatus "Q9W3.3" )
			)
			( pin "@baseboard_fab2_lib.baseboard_fab2(sch_1):page249_i49:e"
				( attribute "PN" "2"
					( Origin gPackager )
				)
				( objectStatus "Q9W3.2" )
			)
			( pin "@baseboard_fab2_lib.baseboard_fab2(sch_1):page139_i250:a"
				( attribute "PN" "1"
					( Origin gPackager )
				)
				( objectStatus "C9E8.1" )
			)
			( pin "@baseboard_fab2_lib.baseboard_fab2(sch_1):page139_i250:b"
				( attribute "PN" "2"
					( Origin gPackager )
				)
				( objectStatus "C9E8.2" )
			)
			( pin "@baseboard_fab2_lib.baseboard_fab2(sch_1):page139_i252:a"
				( attribute "PN" "1"
					( Origin gPackager )
				)
				( objectStatus "R9W36.1" )
			)
			( pin "@baseboard_fab2_lib.baseboard_fab2(sch_1):page139_i252:b"
				( attribute "PN" "2"
					( Origin gPackager )
				)
				( objectStatus "R9W36.2" )
			)
			( pin "@baseboard_fab2_lib.baseboard_fab2(sch_1):page167_i93:b"
				( attribute "PN" "B"
					( Origin gPackager )
				)
				( objectStatus "Q9B1.B" )
			)
			( pin "@baseboard_fab2_lib.baseboard_fab2(sch_1):page167_i93:c"
				( attribute "PN" "C"
					( Origin gPackager )
				)
				( objectStatus "Q9B1.C" )
			)
			( pin "@baseboard_fab2_lib.baseboard_fab2(sch_1):page167_i93:e"
				( attribute "PN" "E"
					( Origin gPackager )
				)
				( objectStatus "Q9B1.E" )
			)
			( pin "@baseboard_fab2_lib.baseboard_fab2(sch_1):page167_i94:b"
				( attribute "PN" "B"
					( Origin gPackager )
				)
				( objectStatus "Q1E1.B" )
			)
			( pin "@baseboard_fab2_lib.baseboard_fab2(sch_1):page167_i94:c"
				( attribute "PN" "C"
					( Origin gPackager )
				)
				( objectStatus "Q1E1.C" )
			)
			( pin "@baseboard_fab2_lib.baseboard_fab2(sch_1):page167_i94:e"
				( attribute "PN" "E"
					( Origin gPackager )
				)
				( objectStatus "Q1E1.E" )
			)
			( pin "@baseboard_fab2_lib.baseboard_fab2(sch_1):page249_i56:a"
				( attribute "PN" "1"
					( Origin gPackager )
				)
				( objectStatus "R3W2.1" )
			)
			( pin "@baseboard_fab2_lib.baseboard_fab2(sch_1):page249_i56:b"
				( attribute "PN" "2"
					( Origin gPackager )
				)
				( objectStatus "R3W2.2" )
			)
			( pin "@baseboard_fab2_lib.baseboard_fab2(sch_1):page201_i192:a"
				( attribute "PN" "1"
					( Origin gPackager )
				)
				( objectStatus "C4D20.1" )
			)
			( pin "@baseboard_fab2_lib.baseboard_fab2(sch_1):page201_i192:b"
				( attribute "PN" "2"
					( Origin gPackager )
				)
				( objectStatus "C4D20.2" )
			)
			( pin "@baseboard_fab2_lib.baseboard_fab2(sch_1):page249_i55:a"
				( attribute "PN" "2"
					( Origin gPackager )
				)
				( objectStatus "CR3W1.2" )
			)
			( pin "@baseboard_fab2_lib.baseboard_fab2(sch_1):page249_i55:c"
				( attribute "PN" "1"
					( Origin gPackager )
				)
				( objectStatus "CR3W1.1" )
			)
			( pin "@baseboard_fab2_lib.baseboard_fab2(sch_1):page249_i58:a"
				( attribute "PN" "1"
					( Origin gPackager )
				)
				( objectStatus "R3W5.1" )
			)
			( pin "@baseboard_fab2_lib.baseboard_fab2(sch_1):page249_i58:b"
				( attribute "PN" "2"
					( Origin gPackager )
				)
				( objectStatus "R3W5.2" )
			)
			( pin "@baseboard_fab2_lib.baseboard_fab2(sch_1):page42_i217:a"
				( attribute "PN" "1"
					( Origin gPackager )
				)
				( objectStatus "C5W1.1" )
			)
			( pin "@baseboard_fab2_lib.baseboard_fab2(sch_1):page42_i217:b"
				( attribute "PN" "2"
					( Origin gPackager )
				)
				( objectStatus "C5W1.2" )
			)
			( pin "@baseboard_fab2_lib.baseboard_fab2(sch_1):page42_i218:a"
				( attribute "PN" "1"
					( Origin gPackager )
				)
				( objectStatus "C5W2.1" )
			)
			( pin "@baseboard_fab2_lib.baseboard_fab2(sch_1):page42_i218:b"
				( attribute "PN" "2"
					( Origin gPackager )
				)
				( objectStatus "C5W2.2" )
			)
			( pin "@baseboard_fab2_lib.baseboard_fab2(sch_1):page76_i254:a"
				( attribute "PN" "1"
					( Origin gPackager )
				)
				( objectStatus "C3W4.1" )
			)
			( pin "@baseboard_fab2_lib.baseboard_fab2(sch_1):page76_i254:b"
				( attribute "PN" "2"
					( Origin gPackager )
				)
				( objectStatus "C3W4.2" )
			)
			( pin "@baseboard_fab2_lib.baseboard_fab2(sch_1):page76_i256:a"
				( attribute "PN" "1"
					( Origin gPackager )
				)
				( objectStatus "C3W3.1" )
			)
			( pin "@baseboard_fab2_lib.baseboard_fab2(sch_1):page76_i256:b"
				( attribute "PN" "2"
					( Origin gPackager )
				)
				( objectStatus "C3W3.2" )
			)
			( pin "@baseboard_fab2_lib.baseboard_fab2(sch_1):page215_i74:a"
				( attribute "PN" "1"
					( Origin gPackager )
				)
				( objectStatus "R12W25.1" )
			)
			( pin "@baseboard_fab2_lib.baseboard_fab2(sch_1):page215_i74:b"
				( attribute "PN" "2"
					( Origin gPackager )
				)
				( objectStatus "R12W25.2" )
			)
			( pin "@baseboard_fab2_lib.baseboard_fab2(sch_1):page119_i223:a"
				( attribute "PN" "1"
					( Origin gPackager )
				)
				( objectStatus "R2W3.1" )
			)
			( pin "@baseboard_fab2_lib.baseboard_fab2(sch_1):page119_i223:b"
				( attribute "PN" "2"
					( Origin gPackager )
				)
				( objectStatus "R2W3.2" )
			)
			( pin "@baseboard_fab2_lib.baseboard_fab2(sch_1):page119_i224:a"
				( attribute "PN" "1"
					( Origin gPackager )
				)
				( objectStatus "R2W4.1" )
			)
			( pin "@baseboard_fab2_lib.baseboard_fab2(sch_1):page119_i224:b"
				( attribute "PN" "2"
					( Origin gPackager )
				)
				( objectStatus "R2W4.2" )
			)
			( pin "@baseboard_fab2_lib.baseboard_fab2(sch_1):page145_i176:a"
				( attribute "PN" "1"
					( Origin gPackager )
				)
				( objectStatus "R2W5.1" )
			)
			( pin "@baseboard_fab2_lib.baseboard_fab2(sch_1):page145_i176:b"
				( attribute "PN" "2"
					( Origin gPackager )
				)
				( objectStatus "R2W5.2" )
			)
			( pin "@baseboard_fab2_lib.baseboard_fab2(sch_1):page269_i76:a"
				( attribute "PN" "2"
					( Origin gPackager )
				)
				( objectStatus "U25W19.2" )
			)
			( pin "@baseboard_fab2_lib.baseboard_fab2(sch_1):page269_i76:oe"
				( attribute "PN" "1"
					( Origin gPackager )
				)
				( objectStatus "U25W19.1" )
			)
			( pin "@baseboard_fab2_lib.baseboard_fab2(sch_1):page269_i76:y"
				( attribute "PN" "4"
					( Origin gPackager )
				)
				( objectStatus "U25W19.4" )
			)
			( pin "@baseboard_fab2_lib.baseboard_fab2(sch_1):page269_i4:a"
				( attribute "PN" "1"
					( Origin gPackager )
				)
				( objectStatus "R25W174.1" )
			)
			( pin "@baseboard_fab2_lib.baseboard_fab2(sch_1):page269_i4:b"
				( attribute "PN" "2"
					( Origin gPackager )
				)
				( objectStatus "R25W174.2" )
			)
			( pin "@baseboard_fab2_lib.baseboard_fab2(sch_1):page168_i46:a"
				( attribute "PN" "1"
					( Origin gPackager )
				)
				( objectStatus "R6W16.1" )
			)
			( pin "@baseboard_fab2_lib.baseboard_fab2(sch_1):page168_i46:b"
				( attribute "PN" "2"
					( Origin gPackager )
				)
				( objectStatus "R6W16.2" )
			)
			( pin "@baseboard_fab2_lib.baseboard_fab2(sch_1):page269_i10:a"
				( attribute "PN" "1"
					( Origin gPackager )
				)
				( objectStatus "R25W167.1" )
			)
			( pin "@baseboard_fab2_lib.baseboard_fab2(sch_1):page269_i10:b"
				( attribute "PN" "2"
					( Origin gPackager )
				)
				( objectStatus "R25W167.2" )
			)
			( pin "@baseboard_fab2_lib.baseboard_fab2(sch_1):page269_i11:a"
				( attribute "PN" "1"
					( Origin gPackager )
				)
				( objectStatus "R25W168.1" )
			)
			( pin "@baseboard_fab2_lib.baseboard_fab2(sch_1):page269_i11:b"
				( attribute "PN" "2"
					( Origin gPackager )
				)
				( objectStatus "R25W168.2" )
			)
			( pin "@baseboard_fab2_lib.baseboard_fab2(sch_1):page269_i12:a"
				( attribute "PN" "1"
					( Origin gPackager )
				)
				( objectStatus "R25W169.1" )
			)
			( pin "@baseboard_fab2_lib.baseboard_fab2(sch_1):page269_i12:b"
				( attribute "PN" "2"
					( Origin gPackager )
				)
				( objectStatus "R25W169.2" )
			)
			( pin "@baseboard_fab2_lib.baseboard_fab2(sch_1):page269_i13:a"
				( attribute "PN" "1"
					( Origin gPackager )
				)
				( objectStatus "R25W170.1" )
			)
			( pin "@baseboard_fab2_lib.baseboard_fab2(sch_1):page269_i13:b"
				( attribute "PN" "2"
					( Origin gPackager )
				)
				( objectStatus "R25W170.2" )
			)
			( pin "@baseboard_fab2_lib.baseboard_fab2(sch_1):page269_i18:a"
				( attribute "PN" "1"
					( Origin gPackager )
				)
				( objectStatus "R25W177.1" )
			)
			( pin "@baseboard_fab2_lib.baseboard_fab2(sch_1):page269_i18:b"
				( attribute "PN" "2"
					( Origin gPackager )
				)
				( objectStatus "R25W177.2" )
			)
			( pin "@baseboard_fab2_lib.baseboard_fab2(sch_1):page269_i19:a"
				( attribute "PN" "1"
					( Origin gPackager )
				)
				( objectStatus "R25W178.1" )
			)
			( pin "@baseboard_fab2_lib.baseboard_fab2(sch_1):page269_i19:b"
				( attribute "PN" "2"
					( Origin gPackager )
				)
				( objectStatus "R25W178.2" )
			)
			( pin "@baseboard_fab2_lib.baseboard_fab2(sch_1):page269_i20:a"
				( attribute "PN" "1"
					( Origin gPackager )
				)
				( objectStatus "R25W160.1" )
			)
			( pin "@baseboard_fab2_lib.baseboard_fab2(sch_1):page269_i20:b"
				( attribute "PN" "2"
					( Origin gPackager )
				)
				( objectStatus "R25W160.2" )
			)
			( pin "@baseboard_fab2_lib.baseboard_fab2(sch_1):page269_i21:a"
				( attribute "PN" "1"
					( Origin gPackager )
				)
				( objectStatus "R25W161.1" )
			)
			( pin "@baseboard_fab2_lib.baseboard_fab2(sch_1):page269_i21:b"
				( attribute "PN" "2"
					( Origin gPackager )
				)
				( objectStatus "R25W161.2" )
			)
			( pin "@baseboard_fab2_lib.baseboard_fab2(sch_1):page269_i22:a"
				( attribute "PN" "1"
					( Origin gPackager )
				)
				( objectStatus "R25W158.1" )
			)
			( pin "@baseboard_fab2_lib.baseboard_fab2(sch_1):page269_i22:b"
				( attribute "PN" "2"
					( Origin gPackager )
				)
				( objectStatus "R25W158.2" )
			)
			( pin "@baseboard_fab2_lib.baseboard_fab2(sch_1):page269_i24:a"
				( attribute "PN" "1"
					( Origin gPackager )
				)
				( objectStatus "R25W159.1" )
			)
			( pin "@baseboard_fab2_lib.baseboard_fab2(sch_1):page269_i24:b"
				( attribute "PN" "2"
					( Origin gPackager )
				)
				( objectStatus "R25W159.2" )
			)
			( pin "@baseboard_fab2_lib.baseboard_fab2(sch_1):page269_i26:a"
				( attribute "PN" "1"
					( Origin gPackager )
				)
				( objectStatus "C25W91.1" )
			)
			( pin "@baseboard_fab2_lib.baseboard_fab2(sch_1):page269_i26:b"
				( attribute "PN" "2"
					( Origin gPackager )
				)
				( objectStatus "C25W91.2" )
			)
			( pin "@baseboard_fab2_lib.baseboard_fab2(sch_1):page269_i32:a"
				( attribute "PN" "1"
					( Origin gPackager )
				)
				( objectStatus "C25W94.1" )
			)
			( pin "@baseboard_fab2_lib.baseboard_fab2(sch_1):page269_i32:b"
				( attribute "PN" "2"
					( Origin gPackager )
				)
				( objectStatus "C25W94.2" )
			)
			( pin "@baseboard_fab2_lib.baseboard_fab2(sch_1):page269_i33:a(0)"
				( attribute "CDS_SEC" "4"
					( Origin gPackager )
				)
				( attribute "PN" "12"
					( Origin gPackager )
				)
				( attribute "SEC" "4"
					( Origin gPackager )
				)
				( objectStatus "U25W12.12" )
			)
			( pin "@baseboard_fab2_lib.baseboard_fab2(sch_1):page269_i33:a(1)"
				( attribute "CDS_SEC" "3"
					( Origin gPackager )
				)
				( attribute "PN" "9"
					( Origin gPackager )
				)
				( attribute "SEC" "3"
					( Origin gPackager )
				)
				( objectStatus "U25W12.9" )
			)
			( pin "@baseboard_fab2_lib.baseboard_fab2(sch_1):page269_i33:a(2)"
				( attribute "CDS_SEC" "2"
					( Origin gPackager )
				)
				( attribute "PN" "5"
					( Origin gPackager )
				)
				( attribute "SEC" "2"
					( Origin gPackager )
				)
				( objectStatus "U25W12.5" )
			)
			( pin "@baseboard_fab2_lib.baseboard_fab2(sch_1):page269_i33:a(3)"
				( attribute "CDS_SEC" "1"
					( Origin gPackager )
				)
				( attribute "PN" "2"
					( Origin gPackager )
				)
				( attribute "SEC" "1"
					( Origin gPackager )
				)
				( objectStatus "U25W12.2" )
			)
			( pin "@baseboard_fab2_lib.baseboard_fab2(sch_1):page269_i33:b(0)"
				( attribute "CDS_SEC" "4"
					( Origin gPackager )
				)
				( attribute "PN" "11"
					( Origin gPackager )
				)
				( attribute "SEC" "4"
					( Origin gPackager )
				)
				( objectStatus "U25W12.11" )
			)
			( pin "@baseboard_fab2_lib.baseboard_fab2(sch_1):page269_i33:b(1)"
				( attribute "CDS_SEC" "3"
					( Origin gPackager )
				)
				( attribute "PN" "8"
					( Origin gPackager )
				)
				( attribute "SEC" "3"
					( Origin gPackager )
				)
				( objectStatus "U25W12.8" )
			)
			( pin "@baseboard_fab2_lib.baseboard_fab2(sch_1):page269_i33:b(2)"
				( attribute "CDS_SEC" "2"
					( Origin gPackager )
				)
				( attribute "PN" "6"
					( Origin gPackager )
				)
				( attribute "SEC" "2"
					( Origin gPackager )
				)
				( objectStatus "U25W12.6" )
			)
			( pin "@baseboard_fab2_lib.baseboard_fab2(sch_1):page269_i33:b(3)"
				( attribute "CDS_SEC" "1"
					( Origin gPackager )
				)
				( attribute "PN" "3"
					( Origin gPackager )
				)
				( attribute "SEC" "1"
					( Origin gPackager )
				)
				( objectStatus "U25W12.3" )
			)
			( pin "@baseboard_fab2_lib.baseboard_fab2(sch_1):page269_i33:oe(0)"
				( attribute "CDS_SEC" "4"
					( Origin gPackager )
				)
				( attribute "PN" "13"
					( Origin gPackager )
				)
				( attribute "SEC" "4"
					( Origin gPackager )
				)
				( objectStatus "U25W12.13" )
			)
			( pin "@baseboard_fab2_lib.baseboard_fab2(sch_1):page269_i33:oe(1)"
				( attribute "CDS_SEC" "3"
					( Origin gPackager )
				)
				( attribute "PN" "10"
					( Origin gPackager )
				)
				( attribute "SEC" "3"
					( Origin gPackager )
				)
				( objectStatus "U25W12.10" )
			)
			( pin "@baseboard_fab2_lib.baseboard_fab2(sch_1):page269_i33:oe(2)"
				( attribute "CDS_SEC" "2"
					( Origin gPackager )
				)
				( attribute "PN" "4"
					( Origin gPackager )
				)
				( attribute "SEC" "2"
					( Origin gPackager )
				)
				( objectStatus "U25W12.4" )
			)
			( pin "@baseboard_fab2_lib.baseboard_fab2(sch_1):page269_i33:oe(3)"
				( attribute "CDS_SEC" "1"
					( Origin gPackager )
				)
				( attribute "PN" "1"
					( Origin gPackager )
				)
				( attribute "SEC" "1"
					( Origin gPackager )
				)
				( objectStatus "U25W12.1" )
			)
			( pin "@baseboard_fab2_lib.baseboard_fab2(sch_1):page269_i49:a0"
				( attribute "PN" "13"
					( Origin gPackager )
				)
				( objectStatus "U25W10.13" )
			)
			( pin "@baseboard_fab2_lib.baseboard_fab2(sch_1):page269_i49:a1"
				( attribute "PN" "12"
					( Origin gPackager )
				)
				( objectStatus "U25W10.12" )
			)
			( pin "@baseboard_fab2_lib.baseboard_fab2(sch_1):page269_i49:a2"
				( attribute "PN" "10"
					( Origin gPackager )
				)
				( objectStatus "U25W10.10" )
			)
			( pin "@baseboard_fab2_lib.baseboard_fab2(sch_1):page269_i49:a3"
				( attribute "PN" "9"
					( Origin gPackager )
				)
				( objectStatus "U25W10.9" )
			)
			( pin "@baseboard_fab2_lib.baseboard_fab2(sch_1):page269_i49:b0"
				( attribute "PN" "2"
					( Origin gPackager )
				)
				( objectStatus "U25W10.2" )
			)
			( pin "@baseboard_fab2_lib.baseboard_fab2(sch_1):page269_i49:b1"
				( attribute "PN" "3"
					( Origin gPackager )
				)
				( objectStatus "U25W10.3" )
			)
			( pin "@baseboard_fab2_lib.baseboard_fab2(sch_1):page269_i49:b2"
				( attribute "PN" "5"
					( Origin gPackager )
				)
				( objectStatus "U25W10.5" )
			)
			( pin "@baseboard_fab2_lib.baseboard_fab2(sch_1):page269_i49:b3"
				( attribute "PN" "6"
					( Origin gPackager )
				)
				( objectStatus "U25W10.6" )
			)
			( pin "@baseboard_fab2_lib.baseboard_fab2(sch_1):page269_i49:dir"
				( attribute "PN" "1"
					( Origin gPackager )
				)
				( objectStatus "U25W10.1" )
			)
			( pin "@baseboard_fab2_lib.baseboard_fab2(sch_1):page269_i49:gnd(0)"
				( attribute "PN" "7"
					( Origin gPackager )
				)
				( objectStatus "U25W10.7" )
			)
			( pin "@baseboard_fab2_lib.baseboard_fab2(sch_1):page269_i49:gnd(1)"
				( attribute "PN" "8"
					( Origin gPackager )
				)
				( objectStatus "U25W10.8" )
			)
			( pin "@baseboard_fab2_lib.baseboard_fab2(sch_1):page269_i49:gnd(2)"
				( attribute "PN" "11"
					( Origin gPackager )
				)
				( objectStatus "U25W10.11" )
			)
			( pin "@baseboard_fab2_lib.baseboard_fab2(sch_1):page269_i49:vcc"
				( attribute "PN" "14"
					( Origin gPackager )
				)
				( objectStatus "U25W10.14" )
			)
			( pin "@baseboard_fab2_lib.baseboard_fab2(sch_1):page269_i49:vref"
				( attribute "PN" "4"
					( Origin gPackager )
				)
				( objectStatus "U25W10.4" )
			)
			( pin "@baseboard_fab2_lib.baseboard_fab2(sch_1):page268_i2:a"
				( attribute "PN" "1"
					( Origin gPackager )
				)
				( objectStatus "R25W180.1" )
			)
			( pin "@baseboard_fab2_lib.baseboard_fab2(sch_1):page268_i2:b"
				( attribute "PN" "2"
					( Origin gPackager )
				)
				( objectStatus "R25W180.2" )
			)
			( pin "@baseboard_fab2_lib.baseboard_fab2(sch_1):page268_i4:a"
				( attribute "PN" "1"
					( Origin gPackager )
				)
				( objectStatus "C25W97.1" )
			)
			( pin "@baseboard_fab2_lib.baseboard_fab2(sch_1):page268_i4:b"
				( attribute "PN" "2"
					( Origin gPackager )
				)
				( objectStatus "C25W97.2" )
			)
			( pin "@baseboard_fab2_lib.baseboard_fab2(sch_1):page268_i7:a"
				( attribute "PN" "1"
					( Origin gPackager )
				)
				( objectStatus "R25W179.1" )
			)
			( pin "@baseboard_fab2_lib.baseboard_fab2(sch_1):page268_i7:b"
				( attribute "PN" "2"
					( Origin gPackager )
				)
				( objectStatus "R25W179.2" )
			)
			( pin "@baseboard_fab2_lib.baseboard_fab2(sch_1):page268_i9:a"
				( attribute "PN" "1"
					( Origin gPackager )
				)
				( objectStatus "C25W96.1" )
			)
			( pin "@baseboard_fab2_lib.baseboard_fab2(sch_1):page268_i9:b"
				( attribute "PN" "2"
					( Origin gPackager )
				)
				( objectStatus "C25W96.2" )
			)
			( pin "@baseboard_fab2_lib.baseboard_fab2(sch_1):page268_i12:a"
				( attribute "PN" "2"
					( Origin gPackager )
				)
				( objectStatus "U25W15.2" )
			)
			( pin "@baseboard_fab2_lib.baseboard_fab2(sch_1):page268_i12:y"
				( attribute "PN" "4"
					( Origin gPackager )
				)
				( objectStatus "U25W15.4" )
			)
			( pin "@baseboard_fab2_lib.baseboard_fab2(sch_1):page268_i13:a"
				( attribute "PN" "2"
					( Origin gPackager )
				)
				( objectStatus "U25W14.2" )
			)
			( pin "@baseboard_fab2_lib.baseboard_fab2(sch_1):page268_i13:y"
				( attribute "PN" "4"
					( Origin gPackager )
				)
				( objectStatus "U25W14.4" )
			)
			( pin "@baseboard_fab2_lib.baseboard_fab2(sch_1):page268_i14:a"
				( attribute "PN" "1"
					( Origin gPackager )
				)
				( objectStatus "R25W176.1" )
			)
			( pin "@baseboard_fab2_lib.baseboard_fab2(sch_1):page268_i14:b"
				( attribute "PN" "2"
					( Origin gPackager )
				)
				( objectStatus "R25W176.2" )
			)
			( pin "@baseboard_fab2_lib.baseboard_fab2(sch_1):page268_i17:a"
				( attribute "PN" "1"
					( Origin gPackager )
				)
				( objectStatus "R25W175.1" )
			)
			( pin "@baseboard_fab2_lib.baseboard_fab2(sch_1):page268_i17:b"
				( attribute "PN" "2"
					( Origin gPackager )
				)
				( objectStatus "R25W175.2" )
			)
			( pin "@baseboard_fab2_lib.baseboard_fab2(sch_1):page268_i23:a"
				( attribute "PN" "1"
					( Origin gPackager )
				)
				( objectStatus "C25W92.1" )
			)
			( pin "@baseboard_fab2_lib.baseboard_fab2(sch_1):page268_i23:b"
				( attribute "PN" "2"
					( Origin gPackager )
				)
				( objectStatus "C25W92.2" )
			)
			( pin "@baseboard_fab2_lib.baseboard_fab2(sch_1):page268_i26:a"
				( attribute "PN" "1"
					( Origin gPackager )
				)
				( objectStatus "R25W166.1" )
			)
			( pin "@baseboard_fab2_lib.baseboard_fab2(sch_1):page268_i26:b"
				( attribute "PN" "2"
					( Origin gPackager )
				)
				( objectStatus "R25W166.2" )
			)
			( pin "@baseboard_fab2_lib.baseboard_fab2(sch_1):page268_i27:a"
				( attribute "PN" "1"
					( Origin gPackager )
				)
				( objectStatus "C25W93.1" )
			)
			( pin "@baseboard_fab2_lib.baseboard_fab2(sch_1):page268_i27:b"
				( attribute "PN" "2"
					( Origin gPackager )
				)
				( objectStatus "C25W93.2" )
			)
			( pin "@baseboard_fab2_lib.baseboard_fab2(sch_1):page268_i28:a"
				( attribute "PN" "1"
					( Origin gPackager )
				)
				( objectStatus "R25W165.1" )
			)
			( pin "@baseboard_fab2_lib.baseboard_fab2(sch_1):page268_i28:b"
				( attribute "PN" "2"
					( Origin gPackager )
				)
				( objectStatus "R25W165.2" )
			)
			( pin "@baseboard_fab2_lib.baseboard_fab2(sch_1):page268_i29:a"
				( attribute "PN" "1"
					( Origin gPackager )
				)
				( objectStatus "R25W164.1" )
			)
			( pin "@baseboard_fab2_lib.baseboard_fab2(sch_1):page268_i29:b"
				( attribute "PN" "2"
					( Origin gPackager )
				)
				( objectStatus "R25W164.2" )
			)
			( pin "@baseboard_fab2_lib.baseboard_fab2(sch_1):page268_i33:a0"
				( attribute "PN" "13"
					( Origin gPackager )
				)
				( objectStatus "U25W11.13" )
			)
			( pin "@baseboard_fab2_lib.baseboard_fab2(sch_1):page268_i33:a1"
				( attribute "PN" "12"
					( Origin gPackager )
				)
				( objectStatus "U25W11.12" )
			)
			( pin "@baseboard_fab2_lib.baseboard_fab2(sch_1):page268_i33:a2"
				( attribute "PN" "10"
					( Origin gPackager )
				)
				( objectStatus "U25W11.10" )
			)
			( pin "@baseboard_fab2_lib.baseboard_fab2(sch_1):page268_i33:a3"
				( attribute "PN" "9"
					( Origin gPackager )
				)
				( objectStatus "U25W11.9" )
			)
			( pin "@baseboard_fab2_lib.baseboard_fab2(sch_1):page268_i33:b0"
				( attribute "PN" "2"
					( Origin gPackager )
				)
				( objectStatus "U25W11.2" )
			)
			( pin "@baseboard_fab2_lib.baseboard_fab2(sch_1):page268_i33:b1"
				( attribute "PN" "3"
					( Origin gPackager )
				)
				( objectStatus "U25W11.3" )
			)
			( pin "@baseboard_fab2_lib.baseboard_fab2(sch_1):page268_i33:b2"
				( attribute "PN" "5"
					( Origin gPackager )
				)
				( objectStatus "U25W11.5" )
			)
			( pin "@baseboard_fab2_lib.baseboard_fab2(sch_1):page268_i33:b3"
				( attribute "PN" "6"
					( Origin gPackager )
				)
				( objectStatus "U25W11.6" )
			)
			( pin "@baseboard_fab2_lib.baseboard_fab2(sch_1):page268_i33:dir"
				( attribute "PN" "1"
					( Origin gPackager )
				)
				( objectStatus "U25W11.1" )
			)
			( pin "@baseboard_fab2_lib.baseboard_fab2(sch_1):page268_i33:gnd(0)"
				( attribute "PN" "7"
					( Origin gPackager )
				)
				( objectStatus "U25W11.7" )
			)
			( pin "@baseboard_fab2_lib.baseboard_fab2(sch_1):page268_i33:gnd(1)"
				( attribute "PN" "8"
					( Origin gPackager )
				)
				( objectStatus "U25W11.8" )
			)
			( pin "@baseboard_fab2_lib.baseboard_fab2(sch_1):page268_i33:gnd(2)"
				( attribute "PN" "11"
					( Origin gPackager )
				)
				( objectStatus "U25W11.11" )
			)
			( pin "@baseboard_fab2_lib.baseboard_fab2(sch_1):page268_i33:vcc"
				( attribute "PN" "14"
					( Origin gPackager )
				)
				( objectStatus "U25W11.14" )
			)
			( pin "@baseboard_fab2_lib.baseboard_fab2(sch_1):page268_i33:vref"
				( attribute "PN" "4"
					( Origin gPackager )
				)
				( objectStatus "U25W11.4" )
			)
			( pin "@baseboard_fab2_lib.baseboard_fab2(sch_1):page269_i53:com"
				( attribute "PN" "8"
					( Origin gPackager )
				)
				( objectStatus "U25W13.8" )
			)
			( pin "@baseboard_fab2_lib.baseboard_fab2(sch_1):page269_i53:\en#\"
				( attribute "PN" "7"
					( Origin gPackager )
				)
				( objectStatus "U25W13.7" )
			)
			( pin "@baseboard_fab2_lib.baseboard_fab2(sch_1):page269_i53:gnd"
				( attribute "PN" "5"
					( Origin gPackager )
				)
				( objectStatus "U25W13.5" )
			)
			( pin "@baseboard_fab2_lib.baseboard_fab2(sch_1):page269_i53:\in\"
				( attribute "PN" "3"
					( Origin gPackager )
				)
				( objectStatus "U25W13.3" )
			)
			( pin "@baseboard_fab2_lib.baseboard_fab2(sch_1):page269_i53:nc"
				( attribute "PN" "1"
					( Origin gPackager )
				)
				( objectStatus "U25W13.1" )
			)
			( pin "@baseboard_fab2_lib.baseboard_fab2(sch_1):page269_i53:no"
				( attribute "PN" "4"
					( Origin gPackager )
				)
				( objectStatus "U25W13.4" )
			)
			( pin "@baseboard_fab2_lib.baseboard_fab2(sch_1):page269_i53:\v+\"
				( attribute "PN" "2"
					( Origin gPackager )
				)
				( objectStatus "U25W13.2" )
			)
			( pin "@baseboard_fab2_lib.baseboard_fab2(sch_1):page269_i53:\v-\"
				( attribute "PN" "6"
					( Origin gPackager )
				)
				( objectStatus "U25W13.6" )
			)
			( pin "@baseboard_fab2_lib.baseboard_fab2(sch_1):page269_i56:a"
				( attribute "PN" "1"
					( Origin gPackager )
				)
				( objectStatus "C25W95.1" )
			)
			( pin "@baseboard_fab2_lib.baseboard_fab2(sch_1):page269_i56:b"
				( attribute "PN" "2"
					( Origin gPackager )
				)
				( objectStatus "C25W95.2" )
			)
			( pin "@baseboard_fab2_lib.baseboard_fab2(sch_1):page164_i93:a"
				( attribute "PN" "1"
					( Origin gPackager )
				)
				( objectStatus "R6W46.1" )
			)
			( pin "@baseboard_fab2_lib.baseboard_fab2(sch_1):page164_i93:b"
				( attribute "PN" "2"
					( Origin gPackager )
				)
				( objectStatus "R6W46.2" )
			)
			( pin "@baseboard_fab2_lib.baseboard_fab2(sch_1):page144_i151:a"
				( attribute "PN" "1"
					( Origin gPackager )
				)
				( objectStatus "R25W182.1" )
			)
			( pin "@baseboard_fab2_lib.baseboard_fab2(sch_1):page144_i151:b"
				( attribute "PN" "2"
					( Origin gPackager )
				)
				( objectStatus "R25W182.2" )
			)
			( pin "@baseboard_fab2_lib.baseboard_fab2(sch_1):page147_i173:a"
				( attribute "PN" "1"
					( Origin gPackager )
				)
				( objectStatus "R25W181.1" )
			)
			( pin "@baseboard_fab2_lib.baseboard_fab2(sch_1):page147_i173:b"
				( attribute "PN" "2"
					( Origin gPackager )
				)
				( objectStatus "R25W181.2" )
			)
			( pin "@baseboard_fab2_lib.baseboard_fab2(sch_1):page164_i94:a"
				( attribute "PN" "1"
					( Origin gPackager )
				)
				( objectStatus "R6W45.1" )
			)
			( pin "@baseboard_fab2_lib.baseboard_fab2(sch_1):page164_i94:b"
				( attribute "PN" "2"
					( Origin gPackager )
				)
				( objectStatus "R6W45.2" )
			)
			( pin "@baseboard_fab2_lib.baseboard_fab2(sch_1):page164_i95:a"
				( attribute "PN" "1"
					( Origin gPackager )
				)
				( objectStatus "R6W42.1" )
			)
			( pin "@baseboard_fab2_lib.baseboard_fab2(sch_1):page164_i95:b"
				( attribute "PN" "2"
					( Origin gPackager )
				)
				( objectStatus "R6W42.2" )
			)
			( pin "@baseboard_fab2_lib.baseboard_fab2(sch_1):page164_i96:a"
				( attribute "PN" "1"
					( Origin gPackager )
				)
				( objectStatus "R6W43.1" )
			)
			( pin "@baseboard_fab2_lib.baseboard_fab2(sch_1):page164_i96:b"
				( attribute "PN" "2"
					( Origin gPackager )
				)
				( objectStatus "R6W43.2" )
			)
			( pin "@baseboard_fab2_lib.baseboard_fab2(sch_1):page189_i67:a(0)"
				( attribute "PN" "12"
					( Origin gPackager )
				)
				( attribute "CDS_SEC" "4"
					( Origin gPackager )
				)
				( attribute "SEC" "4"
					( Origin gPackager )
				)
				( objectStatus "U1L10.12" )
			)
			( pin "@baseboard_fab2_lib.baseboard_fab2(sch_1):page189_i67:a(1)"
				( attribute "PN" "9"
					( Origin gPackager )
				)
				( attribute "CDS_SEC" "3"
					( Origin gPackager )
				)
				( attribute "SEC" "3"
					( Origin gPackager )
				)
				( objectStatus "U1L10.9" )
			)
			( pin "@baseboard_fab2_lib.baseboard_fab2(sch_1):page189_i67:a(2)"
				( attribute "PN" "5"
					( Origin gPackager )
				)
				( attribute "CDS_SEC" "2"
					( Origin gPackager )
				)
				( attribute "SEC" "2"
					( Origin gPackager )
				)
				( objectStatus "U1L10.5" )
			)
			( pin "@baseboard_fab2_lib.baseboard_fab2(sch_1):page189_i67:a(3)"
				( attribute "PN" "2"
					( Origin gPackager )
				)
				( attribute "CDS_SEC" "1"
					( Origin gPackager )
				)
				( attribute "SEC" "1"
					( Origin gPackager )
				)
				( objectStatus "U1L10.2" )
			)
			( pin "@baseboard_fab2_lib.baseboard_fab2(sch_1):page189_i67:b(0)"
				( attribute "PN" "11"
					( Origin gPackager )
				)
				( attribute "CDS_SEC" "4"
					( Origin gPackager )
				)
				( attribute "SEC" "4"
					( Origin gPackager )
				)
				( objectStatus "U1L10.11" )
			)
			( pin "@baseboard_fab2_lib.baseboard_fab2(sch_1):page189_i67:b(1)"
				( attribute "PN" "8"
					( Origin gPackager )
				)
				( attribute "CDS_SEC" "3"
					( Origin gPackager )
				)
				( attribute "SEC" "3"
					( Origin gPackager )
				)
				( objectStatus "U1L10.8" )
			)
			( pin "@baseboard_fab2_lib.baseboard_fab2(sch_1):page189_i67:b(2)"
				( attribute "PN" "6"
					( Origin gPackager )
				)
				( attribute "CDS_SEC" "2"
					( Origin gPackager )
				)
				( attribute "SEC" "2"
					( Origin gPackager )
				)
				( objectStatus "U1L10.6" )
			)
			( pin "@baseboard_fab2_lib.baseboard_fab2(sch_1):page189_i67:b(3)"
				( attribute "PN" "3"
					( Origin gPackager )
				)
				( attribute "CDS_SEC" "1"
					( Origin gPackager )
				)
				( attribute "SEC" "1"
					( Origin gPackager )
				)
				( objectStatus "U1L10.3" )
			)
			( pin "@baseboard_fab2_lib.baseboard_fab2(sch_1):page189_i67:oe(0)"
				( attribute "PN" "13"
					( Origin gPackager )
				)
				( attribute "CDS_SEC" "4"
					( Origin gPackager )
				)
				( attribute "SEC" "4"
					( Origin gPackager )
				)
				( objectStatus "U1L10.13" )
			)
			( pin "@baseboard_fab2_lib.baseboard_fab2(sch_1):page189_i67:oe(1)"
				( attribute "PN" "10"
					( Origin gPackager )
				)
				( attribute "CDS_SEC" "3"
					( Origin gPackager )
				)
				( attribute "SEC" "3"
					( Origin gPackager )
				)
				( objectStatus "U1L10.10" )
			)
			( pin "@baseboard_fab2_lib.baseboard_fab2(sch_1):page189_i67:oe(2)"
				( attribute "PN" "4"
					( Origin gPackager )
				)
				( attribute "CDS_SEC" "2"
					( Origin gPackager )
				)
				( attribute "SEC" "2"
					( Origin gPackager )
				)
				( objectStatus "U1L10.4" )
			)
			( pin "@baseboard_fab2_lib.baseboard_fab2(sch_1):page189_i67:oe(3)"
				( attribute "PN" "1"
					( Origin gPackager )
				)
				( attribute "CDS_SEC" "1"
					( Origin gPackager )
				)
				( attribute "SEC" "1"
					( Origin gPackager )
				)
				( objectStatus "U1L10.1" )
			)
			( pin "@baseboard_fab2_lib.baseboard_fab2(sch_1):page189_i69:a"
				( attribute "PN" "1"
					( Origin gPackager )
				)
				( objectStatus "C1L119.1" )
			)
			( pin "@baseboard_fab2_lib.baseboard_fab2(sch_1):page189_i69:b"
				( attribute "PN" "2"
					( Origin gPackager )
				)
				( objectStatus "C1L119.2" )
			)
			( pin "@baseboard_fab2_lib.baseboard_fab2(sch_1):page189_i76:a"
				( attribute "PN" "1"
					( Origin gPackager )
				)
				( objectStatus "R7G114.1" )
			)
			( pin "@baseboard_fab2_lib.baseboard_fab2(sch_1):page189_i76:b"
				( attribute "PN" "2"
					( Origin gPackager )
				)
				( objectStatus "R7G114.2" )
			)
			( pin "@baseboard_fab2_lib.baseboard_fab2(sch_1):page193_i175:a"
				( attribute "PN" "1"
					( Origin gPackager )
				)
				( objectStatus "C4E29.1" )
			)
			( pin "@baseboard_fab2_lib.baseboard_fab2(sch_1):page193_i175:b"
				( attribute "PN" "2"
					( Origin gPackager )
				)
				( objectStatus "C4E29.2" )
			)
			( pin "@baseboard_fab2_lib.baseboard_fab2(sch_1):page146_i166:a"
				( attribute "PN" "1"
					( Origin gPackager )
				)
				( objectStatus "R25W184.1" )
			)
			( pin "@baseboard_fab2_lib.baseboard_fab2(sch_1):page146_i166:b"
				( attribute "PN" "2"
					( Origin gPackager )
				)
				( objectStatus "R25W184.2" )
			)
			( pin "@baseboard_fab2_lib.baseboard_fab2(sch_1):page133_i371:a"
				( attribute "PN" "1"
					( Origin gPackager )
				)
				( objectStatus "R8E3.1" )
			)
			( pin "@baseboard_fab2_lib.baseboard_fab2(sch_1):page133_i371:b"
				( attribute "PN" "2"
					( Origin gPackager )
				)
				( objectStatus "R8E3.2" )
			)
			( pin "@baseboard_fab2_lib.baseboard_fab2(sch_1):page42_i221:a"
				( attribute "PN" "1"
					( Origin gPackager )
				)
				( objectStatus "C5P30.1" )
			)
			( pin "@baseboard_fab2_lib.baseboard_fab2(sch_1):page42_i221:b"
				( attribute "PN" "2"
					( Origin gPackager )
				)
				( objectStatus "C5P30.2" )
			)
			( pin "@baseboard_fab2_lib.baseboard_fab2(sch_1):page42_i222:a"
				( attribute "PN" "1"
					( Origin gPackager )
				)
				( objectStatus "C5P19.1" )
			)
			( pin "@baseboard_fab2_lib.baseboard_fab2(sch_1):page42_i222:b"
				( attribute "PN" "2"
					( Origin gPackager )
				)
				( objectStatus "C5P19.2" )
			)
			( pin "@baseboard_fab2_lib.baseboard_fab2(sch_1):page42_i223:a"
				( attribute "PN" "1"
					( Origin gPackager )
				)
				( objectStatus "C4P4.1" )
			)
			( pin "@baseboard_fab2_lib.baseboard_fab2(sch_1):page42_i223:b"
				( attribute "PN" "2"
					( Origin gPackager )
				)
				( objectStatus "C4P4.2" )
			)
			( pin "@baseboard_fab2_lib.baseboard_fab2(sch_1):page42_i224:a"
				( attribute "PN" "1"
					( Origin gPackager )
				)
				( objectStatus "C4P7.1" )
			)
			( pin "@baseboard_fab2_lib.baseboard_fab2(sch_1):page42_i224:b"
				( attribute "PN" "2"
					( Origin gPackager )
				)
				( objectStatus "C4P7.2" )
			)
			( pin "@baseboard_fab2_lib.baseboard_fab2(sch_1):page42_i225:a"
				( attribute "PN" "1"
					( Origin gPackager )
				)
				( objectStatus "C4P3.1" )
			)
			( pin "@baseboard_fab2_lib.baseboard_fab2(sch_1):page42_i225:b"
				( attribute "PN" "2"
					( Origin gPackager )
				)
				( objectStatus "C4P3.2" )
			)
			( pin "@baseboard_fab2_lib.baseboard_fab2(sch_1):page42_i226:a"
				( attribute "PN" "1"
					( Origin gPackager )
				)
				( objectStatus "C5P10.1" )
			)
			( pin "@baseboard_fab2_lib.baseboard_fab2(sch_1):page42_i226:b"
				( attribute "PN" "2"
					( Origin gPackager )
				)
				( objectStatus "C5P10.2" )
			)
			( pin "@baseboard_fab2_lib.baseboard_fab2(sch_1):page42_i227:a"
				( attribute "PN" "1"
					( Origin gPackager )
				)
				( objectStatus "C5P11.1" )
			)
			( pin "@baseboard_fab2_lib.baseboard_fab2(sch_1):page42_i227:b"
				( attribute "PN" "2"
					( Origin gPackager )
				)
				( objectStatus "C5P11.2" )
			)
			( pin "@baseboard_fab2_lib.baseboard_fab2(sch_1):page42_i228:a"
				( attribute "PN" "1"
					( Origin gPackager )
				)
				( objectStatus "C5P18.1" )
			)
			( pin "@baseboard_fab2_lib.baseboard_fab2(sch_1):page42_i228:b"
				( attribute "PN" "2"
					( Origin gPackager )
				)
				( objectStatus "C5P18.2" )
			)
			( pin "@baseboard_fab2_lib.baseboard_fab2(sch_1):page42_i229:a"
				( attribute "PN" "1"
					( Origin gPackager )
				)
				( objectStatus "C5P28.1" )
			)
			( pin "@baseboard_fab2_lib.baseboard_fab2(sch_1):page42_i229:b"
				( attribute "PN" "2"
					( Origin gPackager )
				)
				( objectStatus "C5P28.2" )
			)
			( pin "@baseboard_fab2_lib.baseboard_fab2(sch_1):page42_i230:a"
				( attribute "PN" "1"
					( Origin gPackager )
				)
				( objectStatus "C4P2.1" )
			)
			( pin "@baseboard_fab2_lib.baseboard_fab2(sch_1):page42_i230:b"
				( attribute "PN" "2"
					( Origin gPackager )
				)
				( objectStatus "C4P2.2" )
			)
			( pin "@baseboard_fab2_lib.baseboard_fab2(sch_1):page42_i231:a"
				( attribute "PN" "1"
					( Origin gPackager )
				)
				( objectStatus "C5P31.1" )
			)
			( pin "@baseboard_fab2_lib.baseboard_fab2(sch_1):page42_i231:b"
				( attribute "PN" "2"
					( Origin gPackager )
				)
				( objectStatus "C5P31.2" )
			)
			( pin "@baseboard_fab2_lib.baseboard_fab2(sch_1):page42_i232:a"
				( attribute "PN" "1"
					( Origin gPackager )
				)
				( objectStatus "C5P13.1" )
			)
			( pin "@baseboard_fab2_lib.baseboard_fab2(sch_1):page42_i232:b"
				( attribute "PN" "2"
					( Origin gPackager )
				)
				( objectStatus "C5P13.2" )
			)
			( pin "@baseboard_fab2_lib.baseboard_fab2(sch_1):page42_i233:a"
				( attribute "PN" "1"
					( Origin gPackager )
				)
				( objectStatus "C4P5.1" )
			)
			( pin "@baseboard_fab2_lib.baseboard_fab2(sch_1):page42_i233:b"
				( attribute "PN" "2"
					( Origin gPackager )
				)
				( objectStatus "C4P5.2" )
			)
			( pin "@baseboard_fab2_lib.baseboard_fab2(sch_1):page42_i234:a"
				( attribute "PN" "1"
					( Origin gPackager )
				)
				( objectStatus "C5P20.1" )
			)
			( pin "@baseboard_fab2_lib.baseboard_fab2(sch_1):page42_i234:b"
				( attribute "PN" "2"
					( Origin gPackager )
				)
				( objectStatus "C5P20.2" )
			)
			( pin "@baseboard_fab2_lib.baseboard_fab2(sch_1):page42_i235:a"
				( attribute "PN" "1"
					( Origin gPackager )
				)
				( objectStatus "C5P21.1" )
			)
			( pin "@baseboard_fab2_lib.baseboard_fab2(sch_1):page42_i235:b"
				( attribute "PN" "2"
					( Origin gPackager )
				)
				( objectStatus "C5P21.2" )
			)
			( pin "@baseboard_fab2_lib.baseboard_fab2(sch_1):page42_i236:a"
				( attribute "PN" "1"
					( Origin gPackager )
				)
				( objectStatus "C5P12.1" )
			)
			( pin "@baseboard_fab2_lib.baseboard_fab2(sch_1):page42_i236:b"
				( attribute "PN" "2"
					( Origin gPackager )
				)
				( objectStatus "C5P12.2" )
			)
			( pin "@baseboard_fab2_lib.baseboard_fab2(sch_1):page76_i258:a"
				( attribute "PN" "1"
					( Origin gPackager )
				)
				( objectStatus "C7P9.1" )
			)
			( pin "@baseboard_fab2_lib.baseboard_fab2(sch_1):page76_i258:b"
				( attribute "PN" "2"
					( Origin gPackager )
				)
				( objectStatus "C7P9.2" )
			)
			( pin "@baseboard_fab2_lib.baseboard_fab2(sch_1):page76_i259:a"
				( attribute "PN" "1"
					( Origin gPackager )
				)
				( objectStatus "C7P5.1" )
			)
			( pin "@baseboard_fab2_lib.baseboard_fab2(sch_1):page76_i259:b"
				( attribute "PN" "2"
					( Origin gPackager )
				)
				( objectStatus "C7P5.2" )
			)
			( pin "@baseboard_fab2_lib.baseboard_fab2(sch_1):page76_i266:a"
				( attribute "PN" "1"
					( Origin gPackager )
				)
				( objectStatus "C7P10.1" )
			)
			( pin "@baseboard_fab2_lib.baseboard_fab2(sch_1):page76_i266:b"
				( attribute "PN" "2"
					( Origin gPackager )
				)
				( objectStatus "C7P10.2" )
			)
			( pin "@baseboard_fab2_lib.baseboard_fab2(sch_1):page76_i267:a"
				( attribute "PN" "1"
					( Origin gPackager )
				)
				( objectStatus "C7P7.1" )
			)
			( pin "@baseboard_fab2_lib.baseboard_fab2(sch_1):page76_i267:b"
				( attribute "PN" "2"
					( Origin gPackager )
				)
				( objectStatus "C7P7.2" )
			)
			( pin "@baseboard_fab2_lib.baseboard_fab2(sch_1):page76_i272:a"
				( attribute "PN" "1"
					( Origin gPackager )
				)
				( objectStatus "C8P14.1" )
			)
			( pin "@baseboard_fab2_lib.baseboard_fab2(sch_1):page76_i272:b"
				( attribute "PN" "2"
					( Origin gPackager )
				)
				( objectStatus "C8P14.2" )
			)
			( pin "@baseboard_fab2_lib.baseboard_fab2(sch_1):page76_i273:a"
				( attribute "PN" "1"
					( Origin gPackager )
				)
				( objectStatus "C8P9.1" )
			)
			( pin "@baseboard_fab2_lib.baseboard_fab2(sch_1):page76_i273:b"
				( attribute "PN" "2"
					( Origin gPackager )
				)
				( objectStatus "C8P9.2" )
			)
			( pin "@baseboard_fab2_lib.baseboard_fab2(sch_1):page76_i274:a"
				( attribute "PN" "1"
					( Origin gPackager )
				)
				( objectStatus "C8P8.1" )
			)
			( pin "@baseboard_fab2_lib.baseboard_fab2(sch_1):page76_i274:b"
				( attribute "PN" "2"
					( Origin gPackager )
				)
				( objectStatus "C8P8.2" )
			)
			( pin "@baseboard_fab2_lib.baseboard_fab2(sch_1):page215_i75:a"
				( attribute "PN" "1"
					( Origin gPackager )
				)
				( objectStatus "R7F36.1" )
			)
			( pin "@baseboard_fab2_lib.baseboard_fab2(sch_1):page215_i75:b"
				( attribute "PN" "2"
					( Origin gPackager )
				)
				( objectStatus "R7F36.2" )
			)
			( pin "@baseboard_fab2_lib.baseboard_fab2(sch_1):page268_i40:a"
				( attribute "PN" "1"
					( Origin gPackager )
				)
				( objectStatus "C25W98.1" )
			)
			( pin "@baseboard_fab2_lib.baseboard_fab2(sch_1):page268_i40:b"
				( attribute "PN" "2"
					( Origin gPackager )
				)
				( objectStatus "C25W98.2" )
			)
			( pin "@baseboard_fab2_lib.baseboard_fab2(sch_1):page268_i51:drn"
				( attribute "PN" "3"
					( Origin gPackager )
				)
				( objectStatus "Q25W5.3" )
			)
			( pin "@baseboard_fab2_lib.baseboard_fab2(sch_1):page268_i51:gate"
				( attribute "PN" "1"
					( Origin gPackager )
				)
				( objectStatus "Q25W5.1" )
			)
			( pin "@baseboard_fab2_lib.baseboard_fab2(sch_1):page268_i51:src"
				( attribute "PN" "2"
					( Origin gPackager )
				)
				( objectStatus "Q25W5.2" )
			)
			( pin "@baseboard_fab2_lib.baseboard_fab2(sch_1):page268_i54:a"
				( attribute "PN" "1"
					( Origin gPackager )
				)
				( objectStatus "R25W185.1" )
			)
			( pin "@baseboard_fab2_lib.baseboard_fab2(sch_1):page268_i54:b"
				( attribute "PN" "2"
					( Origin gPackager )
				)
				( objectStatus "R25W185.2" )
			)
			( pin "@baseboard_fab2_lib.baseboard_fab2(sch_1):page189_i77:a"
				( attribute "PN" "1"
					( Origin gPackager )
				)
				( objectStatus "R25W186.1" )
			)
			( pin "@baseboard_fab2_lib.baseboard_fab2(sch_1):page189_i77:b"
				( attribute "PN" "2"
					( Origin gPackager )
				)
				( objectStatus "R25W186.2" )
			)
			( pin "@baseboard_fab2_lib.baseboard_fab2(sch_1):page153_i187:a"
				( attribute "PN" "1"
					( Origin gPackager )
				)
				( objectStatus "R7W5.1" )
			)
			( pin "@baseboard_fab2_lib.baseboard_fab2(sch_1):page153_i187:b"
				( attribute "PN" "2"
					( Origin gPackager )
				)
				( objectStatus "R7W5.2" )
			)
			( pin "@baseboard_fab2_lib.baseboard_fab2(sch_1):page207_i113:boost"
				( attribute "PN" "33"
					( Origin gPackager )
				)
				( objectStatus "EU1D4.33" )
			)
			( pin "@baseboard_fab2_lib.baseboard_fab2(sch_1):page207_i113:en"
				( attribute "PN" "35"
					( Origin gPackager )
				)
				( objectStatus "EU1D4.35" )
			)
			( pin "@baseboard_fab2_lib.baseboard_fab2(sch_1):page207_i113:gl(0)"
				( attribute "PN" "6"
					( Origin gPackager )
				)
				( objectStatus "EU1D4.6" )
			)
			( pin "@baseboard_fab2_lib.baseboard_fab2(sch_1):page207_i113:gl(1)"
				( attribute "PN" "41"
					( Origin gPackager )
				)
				( objectStatus "EU1D4.41" )
			)
			( pin "@baseboard_fab2_lib.baseboard_fab2(sch_1):page207_i113:iout"
				( attribute "PN" "38"
					( Origin gPackager )
				)
				( objectStatus "EU1D4.38" )
			)
			( pin "@baseboard_fab2_lib.baseboard_fab2(sch_1):page207_i113:lgnd"
				( attribute "PN" "2"
					( Origin gPackager )
				)
				( objectStatus "EU1D4.2" )
			)
			( pin "@baseboard_fab2_lib.baseboard_fab2(sch_1):page207_i113:nc"
				( attribute "PN" "31"
					( Origin gPackager )
				)
				( objectStatus "EU1D4.31" )
			)
			( pin "@baseboard_fab2_lib.baseboard_fab2(sch_1):page207_i113:ocset"
				( attribute "PN" "37"
					( Origin gPackager )
				)
				( objectStatus "EU1D4.37" )
			)
			( pin "@baseboard_fab2_lib.baseboard_fab2(sch_1):page207_i113:pgnd(0)"
				( attribute "PN" "5"
					( Origin gPackager )
				)
				( objectStatus "EU1D4.5" )
			)
			( pin "@baseboard_fab2_lib.baseboard_fab2(sch_1):page207_i113:pgnd(1)"
				( attribute "PN" "7"
					( Origin gPackager )
				)
				( objectStatus "EU1D4.7" )
			)
			( pin "@baseboard_fab2_lib.baseboard_fab2(sch_1):page207_i113:pgnd(2)"
				( attribute "PN" "40"
					( Origin gPackager )
				)
				( objectStatus "EU1D4.40" )
			)
			( pin "@baseboard_fab2_lib.baseboard_fab2(sch_1):page207_i113:phase"
				( attribute "PN" "32"
					( Origin gPackager )
				)
				( objectStatus "EU1D4.32" )
			)
			( pin "@baseboard_fab2_lib.baseboard_fab2(sch_1):page207_i113:pwm"
				( attribute "PN" "34"
					( Origin gPackager )
				)
				( objectStatus "EU1D4.34" )
			)
			( pin "@baseboard_fab2_lib.baseboard_fab2(sch_1):page207_i113:refin"
				( attribute "PN" "39"
					( Origin gPackager )
				)
				( objectStatus "EU1D4.39" )
			)
			( pin "@baseboard_fab2_lib.baseboard_fab2(sch_1):page207_i113:sw"
				( attribute "PN" "10"
					( Origin gPackager )
				)
				( objectStatus "EU1D4.10" )
			)
			( pin "@baseboard_fab2_lib.baseboard_fab2(sch_1):page207_i113:tout_flt"
				( attribute "PN" "36"
					( Origin gPackager )
				)
				( objectStatus "EU1D4.36" )
			)
			( pin "@baseboard_fab2_lib.baseboard_fab2(sch_1):page207_i113:vcc"
				( attribute "PN" "3"
					( Origin gPackager )
				)
				( objectStatus "EU1D4.3" )
			)
			( pin "@baseboard_fab2_lib.baseboard_fab2(sch_1):page207_i113:vdrv"
				( attribute "PN" "4"
					( Origin gPackager )
				)
				( objectStatus "EU1D4.4" )
			)
			( pin "@baseboard_fab2_lib.baseboard_fab2(sch_1):page207_i113:vin(0)"
				( attribute "PN" "25"
					( Origin gPackager )
				)
				( objectStatus "EU1D4.25" )
			)
			( pin "@baseboard_fab2_lib.baseboard_fab2(sch_1):page207_i113:vin(1)"
				( attribute "PN" "30"
					( Origin gPackager )
				)
				( objectStatus "EU1D4.30" )
			)
			( pin "@baseboard_fab2_lib.baseboard_fab2(sch_1):page207_i113:vos"
				( attribute "PN" "1"
					( Origin gPackager )
				)
				( objectStatus "EU1D4.1" )
			)
			( pin "@baseboard_fab2_lib.baseboard_fab2(sch_1):page269_i61:a(0)"
				( attribute "PN" "1"
					( Origin gPackager )
				)
				( objectStatus "U25W17.1" )
			)
			( pin "@baseboard_fab2_lib.baseboard_fab2(sch_1):page269_i61:b(0)"
				( attribute "PN" "2"
					( Origin gPackager )
				)
				( objectStatus "U25W17.2" )
			)
			( pin "@baseboard_fab2_lib.baseboard_fab2(sch_1):page269_i61:y(0)"
				( attribute "PN" "4"
					( Origin gPackager )
				)
				( objectStatus "U25W17.4" )
			)
			( pin "@baseboard_fab2_lib.baseboard_fab2(sch_1):page269_i62:a"
				( attribute "PN" "1"
					( Origin gPackager )
				)
				( objectStatus "C25W99.1" )
			)
			( pin "@baseboard_fab2_lib.baseboard_fab2(sch_1):page269_i62:b"
				( attribute "PN" "2"
					( Origin gPackager )
				)
				( objectStatus "C25W99.2" )
			)
			( pin "@baseboard_fab2_lib.baseboard_fab2(sch_1):page268_i57:a(0)"
				( attribute "PN" "1"
					( Origin gPackager )
				)
				( objectStatus "U25W18.1" )
			)
			( pin "@baseboard_fab2_lib.baseboard_fab2(sch_1):page268_i57:b(0)"
				( attribute "PN" "2"
					( Origin gPackager )
				)
				( objectStatus "U25W18.2" )
			)
			( pin "@baseboard_fab2_lib.baseboard_fab2(sch_1):page268_i57:y(0)"
				( attribute "PN" "4"
					( Origin gPackager )
				)
				( objectStatus "U25W18.4" )
			)
			( pin "@baseboard_fab2_lib.baseboard_fab2(sch_1):page268_i60:a"
				( attribute "PN" "1"
					( Origin gPackager )
				)
				( objectStatus "C25W100.1" )
			)
			( pin "@baseboard_fab2_lib.baseboard_fab2(sch_1):page268_i60:b"
				( attribute "PN" "2"
					( Origin gPackager )
				)
				( objectStatus "C25W100.2" )
			)
			( pin "@baseboard_fab2_lib.baseboard_fab2(sch_1):page158_i153:a"
				( attribute "PN" "1"
					( Origin gPackager )
				)
				( objectStatus "R9W33.1" )
			)
			( pin "@baseboard_fab2_lib.baseboard_fab2(sch_1):page158_i153:b"
				( attribute "PN" "2"
					( Origin gPackager )
				)
				( objectStatus "R9W33.2" )
			)
			( pin "@baseboard_fab2_lib.baseboard_fab2(sch_1):page158_i154:a"
				( attribute "PN" "1"
					( Origin gPackager )
				)
				( objectStatus "R9W34.1" )
			)
			( pin "@baseboard_fab2_lib.baseboard_fab2(sch_1):page158_i154:b"
				( attribute "PN" "2"
					( Origin gPackager )
				)
				( objectStatus "R9W34.2" )
			)
			( pin "@baseboard_fab2_lib.baseboard_fab2(sch_1):page158_i155:a"
				( attribute "PN" "1"
					( Origin gPackager )
				)
				( objectStatus "R9W35.1" )
			)
			( pin "@baseboard_fab2_lib.baseboard_fab2(sch_1):page158_i155:b"
				( attribute "PN" "2"
					( Origin gPackager )
				)
				( objectStatus "R9W35.2" )
			)
			( pin "@baseboard_fab2_lib.baseboard_fab2(sch_1):page155_i202:a"
				( attribute "PN" "2"
					( Origin gPackager )
				)
				( objectStatus "CR9W1.2" )
			)
			( pin "@baseboard_fab2_lib.baseboard_fab2(sch_1):page155_i202:c"
				( attribute "PN" "1"
					( Origin gPackager )
				)
				( objectStatus "CR9W1.1" )
			)
			( pin "@baseboard_fab2_lib.baseboard_fab2(sch_1):page238_i46:a"
				( attribute "PN" "1"
					( Origin gPackager )
				)
				( objectStatus "C9W14.1" )
			)
			( pin "@baseboard_fab2_lib.baseboard_fab2(sch_1):page238_i46:b"
				( attribute "PN" "2"
					( Origin gPackager )
				)
				( objectStatus "C9W14.2" )
			)
			( pin "@baseboard_fab2_lib.baseboard_fab2(sch_1):page239_i104:a"
				( attribute "PN" "1"
					( Origin gPackager )
				)
				( objectStatus "C9W17.1" )
			)
			( pin "@baseboard_fab2_lib.baseboard_fab2(sch_1):page239_i104:b"
				( attribute "PN" "2"
					( Origin gPackager )
				)
				( objectStatus "C9W17.2" )
			)
			( pin "@baseboard_fab2_lib.baseboard_fab2(sch_1):page238_i50:a"
				( attribute "PN" "1"
					( Origin gPackager )
				)
				( objectStatus "C9W16.1" )
			)
			( pin "@baseboard_fab2_lib.baseboard_fab2(sch_1):page238_i50:b"
				( attribute "PN" "2"
					( Origin gPackager )
				)
				( objectStatus "C9W16.2" )
			)
			( pin "@baseboard_fab2_lib.baseboard_fab2(sch_1):page239_i111:a"
				( attribute "PN" "1"
					( Origin gPackager )
				)
				( objectStatus "C9W19.1" )
			)
			( pin "@baseboard_fab2_lib.baseboard_fab2(sch_1):page239_i111:b"
				( attribute "PN" "2"
					( Origin gPackager )
				)
				( objectStatus "C9W19.2" )
			)
			( pin "@baseboard_fab2_lib.baseboard_fab2(sch_1):page104_i103:a"
				( attribute "PN" "1"
					( Origin gPackager )
				)
				( objectStatus "R7D39.1" )
			)
			( pin "@baseboard_fab2_lib.baseboard_fab2(sch_1):page104_i103:b"
				( attribute "PN" "2"
					( Origin gPackager )
				)
				( objectStatus "R7D39.2" )
			)
			( pin "@baseboard_fab2_lib.baseboard_fab2(sch_1):page104_i104:a"
				( attribute "PN" "1"
					( Origin gPackager )
				)
				( objectStatus "R7D37.1" )
			)
			( pin "@baseboard_fab2_lib.baseboard_fab2(sch_1):page104_i104:b"
				( attribute "PN" "2"
					( Origin gPackager )
				)
				( objectStatus "R7D37.2" )
			)
			( pin "@baseboard_fab2_lib.baseboard_fab2(sch_1):page268_i63:\1\"
				( attribute "PN" "1"
					( Origin gPackager )
				)
				( objectStatus "S9W1.1" )
			)
			( pin "@baseboard_fab2_lib.baseboard_fab2(sch_1):page268_i63:\2\"
				( attribute "PN" "2"
					( Origin gPackager )
				)
				( objectStatus "S9W1.2" )
			)
			( pin "@baseboard_fab2_lib.baseboard_fab2(sch_1):page268_i63:\3\"
				( attribute "PN" "3"
					( Origin gPackager )
				)
				( objectStatus "S9W1.3" )
			)
			( pin "@baseboard_fab2_lib.baseboard_fab2(sch_1):page268_i63:\4\"
				( attribute "PN" "4"
					( Origin gPackager )
				)
				( objectStatus "S9W1.4" )
			)
			( pin "@baseboard_fab2_lib.baseboard_fab2(sch_1):page268_i63:\5\"
				( attribute "PN" "5"
					( Origin gPackager )
				)
				( objectStatus "S9W1.5" )
			)
			( pin "@baseboard_fab2_lib.baseboard_fab2(sch_1):page268_i63:\6\"
				( attribute "PN" "6"
					( Origin gPackager )
				)
				( objectStatus "S9W1.6" )
			)
			( pin "@baseboard_fab2_lib.baseboard_fab2(sch_1):page268_i63:\7\"
				( attribute "PN" "7"
					( Origin gPackager )
				)
				( objectStatus "S9W1.7" )
			)
			( pin "@baseboard_fab2_lib.baseboard_fab2(sch_1):page268_i63:np1"
				( attribute "PN" "NP1"
					( Origin gPackager )
				)
				( objectStatus "S9W1.NP1" )
			)
			( pin "@baseboard_fab2_lib.baseboard_fab2(sch_1):page268_i63:np2"
				( attribute "PN" "NP2"
					( Origin gPackager )
				)
				( objectStatus "S9W1.NP2" )
			)
			( pin "@baseboard_fab2_lib.baseboard_fab2(sch_1):page269_i71:\1\"
				( attribute "PN" "1"
					( Origin gPackager )
				)
				( objectStatus "FB25W1.1" )
			)
			( pin "@baseboard_fab2_lib.baseboard_fab2(sch_1):page269_i71:\2\"
				( attribute "PN" "2"
					( Origin gPackager )
				)
				( objectStatus "FB25W1.2" )
			)
			( pin "@baseboard_fab2_lib.baseboard_fab2(sch_1):page269_i72:\1\"
				( attribute "PN" "1"
					( Origin gPackager )
				)
				( objectStatus "FB25W2.1" )
			)
			( pin "@baseboard_fab2_lib.baseboard_fab2(sch_1):page269_i72:\2\"
				( attribute "PN" "2"
					( Origin gPackager )
				)
				( objectStatus "FB25W2.2" )
			)
			( pin "@baseboard_fab2_lib.baseboard_fab2(sch_1):page269_i73:\1\"
				( attribute "PN" "1"
					( Origin gPackager )
				)
				( objectStatus "FB25W3.1" )
			)
			( pin "@baseboard_fab2_lib.baseboard_fab2(sch_1):page269_i73:\2\"
				( attribute "PN" "2"
					( Origin gPackager )
				)
				( objectStatus "FB25W3.2" )
			)
			( pin "@baseboard_fab2_lib.baseboard_fab2(sch_1):page269_i74:\1\"
				( attribute "PN" "1"
					( Origin gPackager )
				)
				( objectStatus "FB25W5.1" )
			)
			( pin "@baseboard_fab2_lib.baseboard_fab2(sch_1):page269_i74:\2\"
				( attribute "PN" "2"
					( Origin gPackager )
				)
				( objectStatus "FB25W5.2" )
			)
			( pin "@baseboard_fab2_lib.baseboard_fab2(sch_1):page269_i75:\1\"
				( attribute "PN" "1"
					( Origin gPackager )
				)
				( objectStatus "FB25W4.1" )
			)
			( pin "@baseboard_fab2_lib.baseboard_fab2(sch_1):page269_i75:\2\"
				( attribute "PN" "2"
					( Origin gPackager )
				)
				( objectStatus "FB25W4.2" )
			)
			( pin "@baseboard_fab2_lib.baseboard_fab2(sch_1):page225_i327:\1\"
				( attribute "PN" "1"
					( Origin gPackager )
				)
				( objectStatus "C1G15.1" )
			)
			( pin "@baseboard_fab2_lib.baseboard_fab2(sch_1):page225_i327:\2\"
				( attribute "PN" "2"
					( Origin gPackager )
				)
				( objectStatus "C1G15.2" )
			)
			( pin "@baseboard_fab2_lib.baseboard_fab2(sch_1):page225_i328:\1\"
				( attribute "PN" "1"
					( Origin gPackager )
				)
				( objectStatus "C1G12.1" )
			)
			( pin "@baseboard_fab2_lib.baseboard_fab2(sch_1):page225_i328:\2\"
				( attribute "PN" "2"
					( Origin gPackager )
				)
				( objectStatus "C1G12.2" )
			)
			( pin "@baseboard_fab2_lib.baseboard_fab2(sch_1):page225_i329:\1\"
				( attribute "PN" "1"
					( Origin gPackager )
				)
				( objectStatus "C1G7.1" )
			)
			( pin "@baseboard_fab2_lib.baseboard_fab2(sch_1):page225_i329:\2\"
				( attribute "PN" "2"
					( Origin gPackager )
				)
				( objectStatus "C1G7.2" )
			)
			( pin "@baseboard_fab2_lib.baseboard_fab2(sch_1):page220_i324:\1\"
				( attribute "PN" "1"
					( Origin gPackager )
				)
				( objectStatus "C7W2.1" )
			)
			( pin "@baseboard_fab2_lib.baseboard_fab2(sch_1):page220_i324:\2\"
				( attribute "PN" "2"
					( Origin gPackager )
				)
				( objectStatus "C7W2.2" )
			)
			( pin "@baseboard_fab2_lib.baseboard_fab2(sch_1):page271_i30:\1\"
				( attribute "PN" "1"
					( Origin gPackager )
				)
				( objectStatus "T1P14.1" )
			)
			( pin "@baseboard_fab2_lib.baseboard_fab2(sch_1):page271_i30:\2\"
				( attribute "PN" "2"
					( Origin gPackager )
				)
				( objectStatus "T1P14.2" )
			)
			( pin "@baseboard_fab2_lib.baseboard_fab2(sch_1):page271_i30:gnd1"
				( attribute "PN" "GND1"
					( Origin gPackager )
				)
				( objectStatus "T1P14.GND1" )
			)
			( pin "@baseboard_fab2_lib.baseboard_fab2(sch_1):page271_i30:gnd2"
				( attribute "PN" "GND2"
					( Origin gPackager )
				)
				( objectStatus "T1P14.GND2" )
			)
			( pin "@baseboard_fab2_lib.baseboard_fab2(sch_1):page271_i3:\1\"
				( attribute "PN" "1"
					( Origin gPackager )
				)
				( objectStatus "T1P1.1" )
			)
			( pin "@baseboard_fab2_lib.baseboard_fab2(sch_1):page271_i3:\2\"
				( attribute "PN" "2"
					( Origin gPackager )
				)
				( objectStatus "T1P1.2" )
			)
			( pin "@baseboard_fab2_lib.baseboard_fab2(sch_1):page271_i3:gnd1"
				( attribute "PN" "GND1"
					( Origin gPackager )
				)
				( objectStatus "T1P1.GND1" )
			)
			( pin "@baseboard_fab2_lib.baseboard_fab2(sch_1):page271_i3:gnd2"
				( attribute "PN" "GND2"
					( Origin gPackager )
				)
				( objectStatus "T1P1.GND2" )
			)
			( pin "@baseboard_fab2_lib.baseboard_fab2(sch_1):page270_i17:dn"
				( attribute "PN" "2"
					( Origin gPackager )
				)
				( objectStatus "T1D10.2" )
			)
			( pin "@baseboard_fab2_lib.baseboard_fab2(sch_1):page270_i17:dp"
				( attribute "PN" "1"
					( Origin gPackager )
				)
				( objectStatus "T1D10.1" )
			)
			( pin "@baseboard_fab2_lib.baseboard_fab2(sch_1):page270_i17:gnd(0)"
				( attribute "PN" "3"
					( Origin gPackager )
				)
				( objectStatus "T1D10.3" )
			)
			( pin "@baseboard_fab2_lib.baseboard_fab2(sch_1):page270_i17:gnd(1)"
				( attribute "PN" "4"
					( Origin gPackager )
				)
				( objectStatus "T1D10.4" )
			)
			( pin "@baseboard_fab2_lib.baseboard_fab2(sch_1):page270_i17:gnd(2)"
				( attribute "PN" "5"
					( Origin gPackager )
				)
				( objectStatus "T1D10.5" )
			)
			( pin "@baseboard_fab2_lib.baseboard_fab2(sch_1):page270_i17:gnd(3)"
				( attribute "PN" "6"
					( Origin gPackager )
				)
				( objectStatus "T1D10.6" )
			)
			( pin "@baseboard_fab2_lib.baseboard_fab2(sch_1):page270_i17:gnd(4)"
				( attribute "PN" "7"
					( Origin gPackager )
				)
				( objectStatus "T1D10.7" )
			)
			( pin "@baseboard_fab2_lib.baseboard_fab2(sch_1):page270_i17:gnd(5)"
				( attribute "PN" "8"
					( Origin gPackager )
				)
				( objectStatus "T1D10.8" )
			)
			( pin "@baseboard_fab2_lib.baseboard_fab2(sch_1):page270_i17:gnd(6)"
				( attribute "PN" "9"
					( Origin gPackager )
				)
				( objectStatus "T1D10.9" )
			)
			( pin "@baseboard_fab2_lib.baseboard_fab2(sch_1):page270_i17:gnd(7)"
				( attribute "PN" "10"
					( Origin gPackager )
				)
				( objectStatus "T1D10.10" )
			)
			( pin "@baseboard_fab2_lib.baseboard_fab2(sch_1):page270_i17:gnd(8)"
				( attribute "PN" "11"
					( Origin gPackager )
				)
				( objectStatus "T1D10.11" )
			)
			( pin "@baseboard_fab2_lib.baseboard_fab2(sch_1):page270_i17:gnd(9)"
				( attribute "PN" "12"
					( Origin gPackager )
				)
				( objectStatus "T1D10.12" )
			)
			( pin "@baseboard_fab2_lib.baseboard_fab2(sch_1):page270_i1:dn"
				( attribute "PN" "2"
					( Origin gPackager )
				)
				( objectStatus "T1D1.2" )
			)
			( pin "@baseboard_fab2_lib.baseboard_fab2(sch_1):page270_i1:dp"
				( attribute "PN" "1"
					( Origin gPackager )
				)
				( objectStatus "T1D1.1" )
			)
			( pin "@baseboard_fab2_lib.baseboard_fab2(sch_1):page270_i1:gnd(0)"
				( attribute "PN" "3"
					( Origin gPackager )
				)
				( objectStatus "T1D1.3" )
			)
			( pin "@baseboard_fab2_lib.baseboard_fab2(sch_1):page270_i1:gnd(1)"
				( attribute "PN" "4"
					( Origin gPackager )
				)
				( objectStatus "T1D1.4" )
			)
			( pin "@baseboard_fab2_lib.baseboard_fab2(sch_1):page270_i1:gnd(2)"
				( attribute "PN" "5"
					( Origin gPackager )
				)
				( objectStatus "T1D1.5" )
			)
			( pin "@baseboard_fab2_lib.baseboard_fab2(sch_1):page270_i1:gnd(3)"
				( attribute "PN" "6"
					( Origin gPackager )
				)
				( objectStatus "T1D1.6" )
			)
			( pin "@baseboard_fab2_lib.baseboard_fab2(sch_1):page270_i1:gnd(4)"
				( attribute "PN" "7"
					( Origin gPackager )
				)
				( objectStatus "T1D1.7" )
			)
			( pin "@baseboard_fab2_lib.baseboard_fab2(sch_1):page270_i1:gnd(5)"
				( attribute "PN" "8"
					( Origin gPackager )
				)
				( objectStatus "T1D1.8" )
			)
			( pin "@baseboard_fab2_lib.baseboard_fab2(sch_1):page270_i1:gnd(6)"
				( attribute "PN" "9"
					( Origin gPackager )
				)
				( objectStatus "T1D1.9" )
			)
			( pin "@baseboard_fab2_lib.baseboard_fab2(sch_1):page270_i1:gnd(7)"
				( attribute "PN" "10"
					( Origin gPackager )
				)
				( objectStatus "T1D1.10" )
			)
			( pin "@baseboard_fab2_lib.baseboard_fab2(sch_1):page270_i1:gnd(8)"
				( attribute "PN" "11"
					( Origin gPackager )
				)
				( objectStatus "T1D1.11" )
			)
			( pin "@baseboard_fab2_lib.baseboard_fab2(sch_1):page270_i1:gnd(9)"
				( attribute "PN" "12"
					( Origin gPackager )
				)
				( objectStatus "T1D1.12" )
			)
			( pin "@baseboard_fab2_lib.baseboard_fab2(sch_1):page270_i3:dn"
				( attribute "PN" "2"
					( Origin gPackager )
				)
				( objectStatus "T1D2.2" )
			)
			( pin "@baseboard_fab2_lib.baseboard_fab2(sch_1):page270_i3:dp"
				( attribute "PN" "1"
					( Origin gPackager )
				)
				( objectStatus "T1D2.1" )
			)
			( pin "@baseboard_fab2_lib.baseboard_fab2(sch_1):page270_i3:gnd(0)"
				( attribute "PN" "3"
					( Origin gPackager )
				)
				( objectStatus "T1D2.3" )
			)
			( pin "@baseboard_fab2_lib.baseboard_fab2(sch_1):page270_i3:gnd(1)"
				( attribute "PN" "4"
					( Origin gPackager )
				)
				( objectStatus "T1D2.4" )
			)
			( pin "@baseboard_fab2_lib.baseboard_fab2(sch_1):page270_i3:gnd(2)"
				( attribute "PN" "5"
					( Origin gPackager )
				)
				( objectStatus "T1D2.5" )
			)
			( pin "@baseboard_fab2_lib.baseboard_fab2(sch_1):page270_i3:gnd(3)"
				( attribute "PN" "6"
					( Origin gPackager )
				)
				( objectStatus "T1D2.6" )
			)
			( pin "@baseboard_fab2_lib.baseboard_fab2(sch_1):page270_i3:gnd(4)"
				( attribute "PN" "7"
					( Origin gPackager )
				)
				( objectStatus "T1D2.7" )
			)
			( pin "@baseboard_fab2_lib.baseboard_fab2(sch_1):page270_i3:gnd(5)"
				( attribute "PN" "8"
					( Origin gPackager )
				)
				( objectStatus "T1D2.8" )
			)
			( pin "@baseboard_fab2_lib.baseboard_fab2(sch_1):page270_i3:gnd(6)"
				( attribute "PN" "9"
					( Origin gPackager )
				)
				( objectStatus "T1D2.9" )
			)
			( pin "@baseboard_fab2_lib.baseboard_fab2(sch_1):page270_i3:gnd(7)"
				( attribute "PN" "10"
					( Origin gPackager )
				)
				( objectStatus "T1D2.10" )
			)
			( pin "@baseboard_fab2_lib.baseboard_fab2(sch_1):page270_i3:gnd(8)"
				( attribute "PN" "11"
					( Origin gPackager )
				)
				( objectStatus "T1D2.11" )
			)
			( pin "@baseboard_fab2_lib.baseboard_fab2(sch_1):page270_i3:gnd(9)"
				( attribute "PN" "12"
					( Origin gPackager )
				)
				( objectStatus "T1D2.12" )
			)
			( pin "@baseboard_fab2_lib.baseboard_fab2(sch_1):page270_i5:dn"
				( attribute "PN" "2"
					( Origin gPackager )
				)
				( objectStatus "T1D3.2" )
			)
			( pin "@baseboard_fab2_lib.baseboard_fab2(sch_1):page270_i5:dp"
				( attribute "PN" "1"
					( Origin gPackager )
				)
				( objectStatus "T1D3.1" )
			)
			( pin "@baseboard_fab2_lib.baseboard_fab2(sch_1):page270_i5:gnd(0)"
				( attribute "PN" "3"
					( Origin gPackager )
				)
				( objectStatus "T1D3.3" )
			)
			( pin "@baseboard_fab2_lib.baseboard_fab2(sch_1):page270_i5:gnd(1)"
				( attribute "PN" "4"
					( Origin gPackager )
				)
				( objectStatus "T1D3.4" )
			)
			( pin "@baseboard_fab2_lib.baseboard_fab2(sch_1):page270_i5:gnd(2)"
				( attribute "PN" "5"
					( Origin gPackager )
				)
				( objectStatus "T1D3.5" )
			)
			( pin "@baseboard_fab2_lib.baseboard_fab2(sch_1):page270_i5:gnd(3)"
				( attribute "PN" "6"
					( Origin gPackager )
				)
				( objectStatus "T1D3.6" )
			)
			( pin "@baseboard_fab2_lib.baseboard_fab2(sch_1):page270_i5:gnd(4)"
				( attribute "PN" "7"
					( Origin gPackager )
				)
				( objectStatus "T1D3.7" )
			)
			( pin "@baseboard_fab2_lib.baseboard_fab2(sch_1):page270_i5:gnd(5)"
				( attribute "PN" "8"
					( Origin gPackager )
				)
				( objectStatus "T1D3.8" )
			)
			( pin "@baseboard_fab2_lib.baseboard_fab2(sch_1):page270_i5:gnd(6)"
				( attribute "PN" "9"
					( Origin gPackager )
				)
				( objectStatus "T1D3.9" )
			)
			( pin "@baseboard_fab2_lib.baseboard_fab2(sch_1):page270_i5:gnd(7)"
				( attribute "PN" "10"
					( Origin gPackager )
				)
				( objectStatus "T1D3.10" )
			)
			( pin "@baseboard_fab2_lib.baseboard_fab2(sch_1):page270_i5:gnd(8)"
				( attribute "PN" "11"
					( Origin gPackager )
				)
				( objectStatus "T1D3.11" )
			)
			( pin "@baseboard_fab2_lib.baseboard_fab2(sch_1):page270_i5:gnd(9)"
				( attribute "PN" "12"
					( Origin gPackager )
				)
				( objectStatus "T1D3.12" )
			)
			( pin "@baseboard_fab2_lib.baseboard_fab2(sch_1):page270_i6:dn"
				( attribute "PN" "2"
					( Origin gPackager )
				)
				( objectStatus "T1D4.2" )
			)
			( pin "@baseboard_fab2_lib.baseboard_fab2(sch_1):page270_i6:dp"
				( attribute "PN" "1"
					( Origin gPackager )
				)
				( objectStatus "T1D4.1" )
			)
			( pin "@baseboard_fab2_lib.baseboard_fab2(sch_1):page270_i6:gnd(0)"
				( attribute "PN" "3"
					( Origin gPackager )
				)
				( objectStatus "T1D4.3" )
			)
			( pin "@baseboard_fab2_lib.baseboard_fab2(sch_1):page270_i6:gnd(1)"
				( attribute "PN" "4"
					( Origin gPackager )
				)
				( objectStatus "T1D4.4" )
			)
			( pin "@baseboard_fab2_lib.baseboard_fab2(sch_1):page270_i6:gnd(2)"
				( attribute "PN" "5"
					( Origin gPackager )
				)
				( objectStatus "T1D4.5" )
			)
			( pin "@baseboard_fab2_lib.baseboard_fab2(sch_1):page270_i6:gnd(3)"
				( attribute "PN" "6"
					( Origin gPackager )
				)
				( objectStatus "T1D4.6" )
			)
			( pin "@baseboard_fab2_lib.baseboard_fab2(sch_1):page270_i6:gnd(4)"
				( attribute "PN" "7"
					( Origin gPackager )
				)
				( objectStatus "T1D4.7" )
			)
			( pin "@baseboard_fab2_lib.baseboard_fab2(sch_1):page270_i6:gnd(5)"
				( attribute "PN" "8"
					( Origin gPackager )
				)
				( objectStatus "T1D4.8" )
			)
			( pin "@baseboard_fab2_lib.baseboard_fab2(sch_1):page270_i6:gnd(6)"
				( attribute "PN" "9"
					( Origin gPackager )
				)
				( objectStatus "T1D4.9" )
			)
			( pin "@baseboard_fab2_lib.baseboard_fab2(sch_1):page270_i6:gnd(7)"
				( attribute "PN" "10"
					( Origin gPackager )
				)
				( objectStatus "T1D4.10" )
			)
			( pin "@baseboard_fab2_lib.baseboard_fab2(sch_1):page270_i6:gnd(8)"
				( attribute "PN" "11"
					( Origin gPackager )
				)
				( objectStatus "T1D4.11" )
			)
			( pin "@baseboard_fab2_lib.baseboard_fab2(sch_1):page270_i6:gnd(9)"
				( attribute "PN" "12"
					( Origin gPackager )
				)
				( objectStatus "T1D4.12" )
			)
			( pin "@baseboard_fab2_lib.baseboard_fab2(sch_1):page270_i9:dn"
				( attribute "PN" "2"
					( Origin gPackager )
				)
				( objectStatus "T1D6.2" )
			)
			( pin "@baseboard_fab2_lib.baseboard_fab2(sch_1):page270_i9:dp"
				( attribute "PN" "1"
					( Origin gPackager )
				)
				( objectStatus "T1D6.1" )
			)
			( pin "@baseboard_fab2_lib.baseboard_fab2(sch_1):page270_i9:gnd(0)"
				( attribute "PN" "3"
					( Origin gPackager )
				)
				( objectStatus "T1D6.3" )
			)
			( pin "@baseboard_fab2_lib.baseboard_fab2(sch_1):page270_i9:gnd(1)"
				( attribute "PN" "4"
					( Origin gPackager )
				)
				( objectStatus "T1D6.4" )
			)
			( pin "@baseboard_fab2_lib.baseboard_fab2(sch_1):page270_i9:gnd(2)"
				( attribute "PN" "5"
					( Origin gPackager )
				)
				( objectStatus "T1D6.5" )
			)
			( pin "@baseboard_fab2_lib.baseboard_fab2(sch_1):page270_i9:gnd(3)"
				( attribute "PN" "6"
					( Origin gPackager )
				)
				( objectStatus "T1D6.6" )
			)
			( pin "@baseboard_fab2_lib.baseboard_fab2(sch_1):page270_i9:gnd(4)"
				( attribute "PN" "7"
					( Origin gPackager )
				)
				( objectStatus "T1D6.7" )
			)
			( pin "@baseboard_fab2_lib.baseboard_fab2(sch_1):page270_i9:gnd(5)"
				( attribute "PN" "8"
					( Origin gPackager )
				)
				( objectStatus "T1D6.8" )
			)
			( pin "@baseboard_fab2_lib.baseboard_fab2(sch_1):page270_i9:gnd(6)"
				( attribute "PN" "9"
					( Origin gPackager )
				)
				( objectStatus "T1D6.9" )
			)
			( pin "@baseboard_fab2_lib.baseboard_fab2(sch_1):page270_i9:gnd(7)"
				( attribute "PN" "10"
					( Origin gPackager )
				)
				( objectStatus "T1D6.10" )
			)
			( pin "@baseboard_fab2_lib.baseboard_fab2(sch_1):page270_i9:gnd(8)"
				( attribute "PN" "11"
					( Origin gPackager )
				)
				( objectStatus "T1D6.11" )
			)
			( pin "@baseboard_fab2_lib.baseboard_fab2(sch_1):page270_i9:gnd(9)"
				( attribute "PN" "12"
					( Origin gPackager )
				)
				( objectStatus "T1D6.12" )
			)
			( pin "@baseboard_fab2_lib.baseboard_fab2(sch_1):page270_i12:dn"
				( attribute "PN" "2"
					( Origin gPackager )
				)
				( objectStatus "T1D5.2" )
			)
			( pin "@baseboard_fab2_lib.baseboard_fab2(sch_1):page270_i12:dp"
				( attribute "PN" "1"
					( Origin gPackager )
				)
				( objectStatus "T1D5.1" )
			)
			( pin "@baseboard_fab2_lib.baseboard_fab2(sch_1):page270_i12:gnd(0)"
				( attribute "PN" "3"
					( Origin gPackager )
				)
				( objectStatus "T1D5.3" )
			)
			( pin "@baseboard_fab2_lib.baseboard_fab2(sch_1):page270_i12:gnd(1)"
				( attribute "PN" "4"
					( Origin gPackager )
				)
				( objectStatus "T1D5.4" )
			)
			( pin "@baseboard_fab2_lib.baseboard_fab2(sch_1):page270_i12:gnd(2)"
				( attribute "PN" "5"
					( Origin gPackager )
				)
				( objectStatus "T1D5.5" )
			)
			( pin "@baseboard_fab2_lib.baseboard_fab2(sch_1):page270_i12:gnd(3)"
				( attribute "PN" "6"
					( Origin gPackager )
				)
				( objectStatus "T1D5.6" )
			)
			( pin "@baseboard_fab2_lib.baseboard_fab2(sch_1):page270_i12:gnd(4)"
				( attribute "PN" "7"
					( Origin gPackager )
				)
				( objectStatus "T1D5.7" )
			)
			( pin "@baseboard_fab2_lib.baseboard_fab2(sch_1):page270_i12:gnd(5)"
				( attribute "PN" "8"
					( Origin gPackager )
				)
				( objectStatus "T1D5.8" )
			)
			( pin "@baseboard_fab2_lib.baseboard_fab2(sch_1):page270_i12:gnd(6)"
				( attribute "PN" "9"
					( Origin gPackager )
				)
				( objectStatus "T1D5.9" )
			)
			( pin "@baseboard_fab2_lib.baseboard_fab2(sch_1):page270_i12:gnd(7)"
				( attribute "PN" "10"
					( Origin gPackager )
				)
				( objectStatus "T1D5.10" )
			)
			( pin "@baseboard_fab2_lib.baseboard_fab2(sch_1):page270_i12:gnd(8)"
				( attribute "PN" "11"
					( Origin gPackager )
				)
				( objectStatus "T1D5.11" )
			)
			( pin "@baseboard_fab2_lib.baseboard_fab2(sch_1):page270_i12:gnd(9)"
				( attribute "PN" "12"
					( Origin gPackager )
				)
				( objectStatus "T1D5.12" )
			)
			( pin "@baseboard_fab2_lib.baseboard_fab2(sch_1):page270_i13:dn"
				( attribute "PN" "2"
					( Origin gPackager )
				)
				( objectStatus "T1D8.2" )
			)
			( pin "@baseboard_fab2_lib.baseboard_fab2(sch_1):page270_i13:dp"
				( attribute "PN" "1"
					( Origin gPackager )
				)
				( objectStatus "T1D8.1" )
			)
			( pin "@baseboard_fab2_lib.baseboard_fab2(sch_1):page270_i13:gnd(0)"
				( attribute "PN" "3"
					( Origin gPackager )
				)
				( objectStatus "T1D8.3" )
			)
			( pin "@baseboard_fab2_lib.baseboard_fab2(sch_1):page270_i13:gnd(1)"
				( attribute "PN" "4"
					( Origin gPackager )
				)
				( objectStatus "T1D8.4" )
			)
			( pin "@baseboard_fab2_lib.baseboard_fab2(sch_1):page270_i13:gnd(2)"
				( attribute "PN" "5"
					( Origin gPackager )
				)
				( objectStatus "T1D8.5" )
			)
			( pin "@baseboard_fab2_lib.baseboard_fab2(sch_1):page270_i13:gnd(3)"
				( attribute "PN" "6"
					( Origin gPackager )
				)
				( objectStatus "T1D8.6" )
			)
			( pin "@baseboard_fab2_lib.baseboard_fab2(sch_1):page270_i13:gnd(4)"
				( attribute "PN" "7"
					( Origin gPackager )
				)
				( objectStatus "T1D8.7" )
			)
			( pin "@baseboard_fab2_lib.baseboard_fab2(sch_1):page270_i13:gnd(5)"
				( attribute "PN" "8"
					( Origin gPackager )
				)
				( objectStatus "T1D8.8" )
			)
			( pin "@baseboard_fab2_lib.baseboard_fab2(sch_1):page270_i13:gnd(6)"
				( attribute "PN" "9"
					( Origin gPackager )
				)
				( objectStatus "T1D8.9" )
			)
			( pin "@baseboard_fab2_lib.baseboard_fab2(sch_1):page270_i13:gnd(7)"
				( attribute "PN" "10"
					( Origin gPackager )
				)
				( objectStatus "T1D8.10" )
			)
			( pin "@baseboard_fab2_lib.baseboard_fab2(sch_1):page270_i13:gnd(8)"
				( attribute "PN" "11"
					( Origin gPackager )
				)
				( objectStatus "T1D8.11" )
			)
			( pin "@baseboard_fab2_lib.baseboard_fab2(sch_1):page270_i13:gnd(9)"
				( attribute "PN" "12"
					( Origin gPackager )
				)
				( objectStatus "T1D8.12" )
			)
			( pin "@baseboard_fab2_lib.baseboard_fab2(sch_1):page270_i16:dn"
				( attribute "PN" "2"
					( Origin gPackager )
				)
				( objectStatus "T1D7.2" )
			)
			( pin "@baseboard_fab2_lib.baseboard_fab2(sch_1):page270_i16:dp"
				( attribute "PN" "1"
					( Origin gPackager )
				)
				( objectStatus "T1D7.1" )
			)
			( pin "@baseboard_fab2_lib.baseboard_fab2(sch_1):page270_i16:gnd(0)"
				( attribute "PN" "3"
					( Origin gPackager )
				)
				( objectStatus "T1D7.3" )
			)
			( pin "@baseboard_fab2_lib.baseboard_fab2(sch_1):page270_i16:gnd(1)"
				( attribute "PN" "4"
					( Origin gPackager )
				)
				( objectStatus "T1D7.4" )
			)
			( pin "@baseboard_fab2_lib.baseboard_fab2(sch_1):page270_i16:gnd(2)"
				( attribute "PN" "5"
					( Origin gPackager )
				)
				( objectStatus "T1D7.5" )
			)
			( pin "@baseboard_fab2_lib.baseboard_fab2(sch_1):page270_i16:gnd(3)"
				( attribute "PN" "6"
					( Origin gPackager )
				)
				( objectStatus "T1D7.6" )
			)
			( pin "@baseboard_fab2_lib.baseboard_fab2(sch_1):page270_i16:gnd(4)"
				( attribute "PN" "7"
					( Origin gPackager )
				)
				( objectStatus "T1D7.7" )
			)
			( pin "@baseboard_fab2_lib.baseboard_fab2(sch_1):page270_i16:gnd(5)"
				( attribute "PN" "8"
					( Origin gPackager )
				)
				( objectStatus "T1D7.8" )
			)
			( pin "@baseboard_fab2_lib.baseboard_fab2(sch_1):page270_i16:gnd(6)"
				( attribute "PN" "9"
					( Origin gPackager )
				)
				( objectStatus "T1D7.9" )
			)
			( pin "@baseboard_fab2_lib.baseboard_fab2(sch_1):page270_i16:gnd(7)"
				( attribute "PN" "10"
					( Origin gPackager )
				)
				( objectStatus "T1D7.10" )
			)
			( pin "@baseboard_fab2_lib.baseboard_fab2(sch_1):page270_i16:gnd(8)"
				( attribute "PN" "11"
					( Origin gPackager )
				)
				( objectStatus "T1D7.11" )
			)
			( pin "@baseboard_fab2_lib.baseboard_fab2(sch_1):page270_i16:gnd(9)"
				( attribute "PN" "12"
					( Origin gPackager )
				)
				( objectStatus "T1D7.12" )
			)
			( pin "@baseboard_fab2_lib.baseboard_fab2(sch_1):page270_i18:dn"
				( attribute "PN" "2"
					( Origin gPackager )
				)
				( objectStatus "T1D9.2" )
			)
			( pin "@baseboard_fab2_lib.baseboard_fab2(sch_1):page270_i18:dp"
				( attribute "PN" "1"
					( Origin gPackager )
				)
				( objectStatus "T1D9.1" )
			)
			( pin "@baseboard_fab2_lib.baseboard_fab2(sch_1):page270_i18:gnd(0)"
				( attribute "PN" "3"
					( Origin gPackager )
				)
				( objectStatus "T1D9.3" )
			)
			( pin "@baseboard_fab2_lib.baseboard_fab2(sch_1):page270_i18:gnd(1)"
				( attribute "PN" "4"
					( Origin gPackager )
				)
				( objectStatus "T1D9.4" )
			)
			( pin "@baseboard_fab2_lib.baseboard_fab2(sch_1):page270_i18:gnd(2)"
				( attribute "PN" "5"
					( Origin gPackager )
				)
				( objectStatus "T1D9.5" )
			)
			( pin "@baseboard_fab2_lib.baseboard_fab2(sch_1):page270_i18:gnd(3)"
				( attribute "PN" "6"
					( Origin gPackager )
				)
				( objectStatus "T1D9.6" )
			)
			( pin "@baseboard_fab2_lib.baseboard_fab2(sch_1):page270_i18:gnd(4)"
				( attribute "PN" "7"
					( Origin gPackager )
				)
				( objectStatus "T1D9.7" )
			)
			( pin "@baseboard_fab2_lib.baseboard_fab2(sch_1):page270_i18:gnd(5)"
				( attribute "PN" "8"
					( Origin gPackager )
				)
				( objectStatus "T1D9.8" )
			)
			( pin "@baseboard_fab2_lib.baseboard_fab2(sch_1):page270_i18:gnd(6)"
				( attribute "PN" "9"
					( Origin gPackager )
				)
				( objectStatus "T1D9.9" )
			)
			( pin "@baseboard_fab2_lib.baseboard_fab2(sch_1):page270_i18:gnd(7)"
				( attribute "PN" "10"
					( Origin gPackager )
				)
				( objectStatus "T1D9.10" )
			)
			( pin "@baseboard_fab2_lib.baseboard_fab2(sch_1):page270_i18:gnd(8)"
				( attribute "PN" "11"
					( Origin gPackager )
				)
				( objectStatus "T1D9.11" )
			)
			( pin "@baseboard_fab2_lib.baseboard_fab2(sch_1):page270_i18:gnd(9)"
				( attribute "PN" "12"
					( Origin gPackager )
				)
				( objectStatus "T1D9.12" )
			)
			( pin "@baseboard_fab2_lib.baseboard_fab2(sch_1):page270_i21:dn"
				( attribute "PN" "2"
					( Origin gPackager )
				)
				( objectStatus "T1D12.2" )
			)
			( pin "@baseboard_fab2_lib.baseboard_fab2(sch_1):page270_i21:dp"
				( attribute "PN" "1"
					( Origin gPackager )
				)
				( objectStatus "T1D12.1" )
			)
			( pin "@baseboard_fab2_lib.baseboard_fab2(sch_1):page270_i21:gnd(0)"
				( attribute "PN" "3"
					( Origin gPackager )
				)
				( objectStatus "T1D12.3" )
			)
			( pin "@baseboard_fab2_lib.baseboard_fab2(sch_1):page270_i21:gnd(1)"
				( attribute "PN" "4"
					( Origin gPackager )
				)
				( objectStatus "T1D12.4" )
			)
			( pin "@baseboard_fab2_lib.baseboard_fab2(sch_1):page270_i21:gnd(2)"
				( attribute "PN" "5"
					( Origin gPackager )
				)
				( objectStatus "T1D12.5" )
			)
			( pin "@baseboard_fab2_lib.baseboard_fab2(sch_1):page270_i21:gnd(3)"
				( attribute "PN" "6"
					( Origin gPackager )
				)
				( objectStatus "T1D12.6" )
			)
			( pin "@baseboard_fab2_lib.baseboard_fab2(sch_1):page270_i21:gnd(4)"
				( attribute "PN" "7"
					( Origin gPackager )
				)
				( objectStatus "T1D12.7" )
			)
			( pin "@baseboard_fab2_lib.baseboard_fab2(sch_1):page270_i21:gnd(5)"
				( attribute "PN" "8"
					( Origin gPackager )
				)
				( objectStatus "T1D12.8" )
			)
			( pin "@baseboard_fab2_lib.baseboard_fab2(sch_1):page270_i21:gnd(6)"
				( attribute "PN" "9"
					( Origin gPackager )
				)
				( objectStatus "T1D12.9" )
			)
			( pin "@baseboard_fab2_lib.baseboard_fab2(sch_1):page270_i21:gnd(7)"
				( attribute "PN" "10"
					( Origin gPackager )
				)
				( objectStatus "T1D12.10" )
			)
			( pin "@baseboard_fab2_lib.baseboard_fab2(sch_1):page270_i21:gnd(8)"
				( attribute "PN" "11"
					( Origin gPackager )
				)
				( objectStatus "T1D12.11" )
			)
			( pin "@baseboard_fab2_lib.baseboard_fab2(sch_1):page270_i21:gnd(9)"
				( attribute "PN" "12"
					( Origin gPackager )
				)
				( objectStatus "T1D12.12" )
			)
			( pin "@baseboard_fab2_lib.baseboard_fab2(sch_1):page270_i24:dn"
				( attribute "PN" "2"
					( Origin gPackager )
				)
				( objectStatus "T1D11.2" )
			)
			( pin "@baseboard_fab2_lib.baseboard_fab2(sch_1):page270_i24:dp"
				( attribute "PN" "1"
					( Origin gPackager )
				)
				( objectStatus "T1D11.1" )
			)
			( pin "@baseboard_fab2_lib.baseboard_fab2(sch_1):page270_i24:gnd(0)"
				( attribute "PN" "3"
					( Origin gPackager )
				)
				( objectStatus "T1D11.3" )
			)
			( pin "@baseboard_fab2_lib.baseboard_fab2(sch_1):page270_i24:gnd(1)"
				( attribute "PN" "4"
					( Origin gPackager )
				)
				( objectStatus "T1D11.4" )
			)
			( pin "@baseboard_fab2_lib.baseboard_fab2(sch_1):page270_i24:gnd(2)"
				( attribute "PN" "5"
					( Origin gPackager )
				)
				( objectStatus "T1D11.5" )
			)
			( pin "@baseboard_fab2_lib.baseboard_fab2(sch_1):page270_i24:gnd(3)"
				( attribute "PN" "6"
					( Origin gPackager )
				)
				( objectStatus "T1D11.6" )
			)
			( pin "@baseboard_fab2_lib.baseboard_fab2(sch_1):page270_i24:gnd(4)"
				( attribute "PN" "7"
					( Origin gPackager )
				)
				( objectStatus "T1D11.7" )
			)
			( pin "@baseboard_fab2_lib.baseboard_fab2(sch_1):page270_i24:gnd(5)"
				( attribute "PN" "8"
					( Origin gPackager )
				)
				( objectStatus "T1D11.8" )
			)
			( pin "@baseboard_fab2_lib.baseboard_fab2(sch_1):page270_i24:gnd(6)"
				( attribute "PN" "9"
					( Origin gPackager )
				)
				( objectStatus "T1D11.9" )
			)
			( pin "@baseboard_fab2_lib.baseboard_fab2(sch_1):page270_i24:gnd(7)"
				( attribute "PN" "10"
					( Origin gPackager )
				)
				( objectStatus "T1D11.10" )
			)
			( pin "@baseboard_fab2_lib.baseboard_fab2(sch_1):page270_i24:gnd(8)"
				( attribute "PN" "11"
					( Origin gPackager )
				)
				( objectStatus "T1D11.11" )
			)
			( pin "@baseboard_fab2_lib.baseboard_fab2(sch_1):page270_i24:gnd(9)"
				( attribute "PN" "12"
					( Origin gPackager )
				)
				( objectStatus "T1D11.12" )
			)
			( pin "@baseboard_fab2_lib.baseboard_fab2(sch_1):page272_i1:dn"
				( attribute "PN" "2"
					( Origin gPackager )
				)
				( objectStatus "T1D17.2" )
			)
			( pin "@baseboard_fab2_lib.baseboard_fab2(sch_1):page272_i1:dp"
				( attribute "PN" "1"
					( Origin gPackager )
				)
				( objectStatus "T1D17.1" )
			)
			( pin "@baseboard_fab2_lib.baseboard_fab2(sch_1):page272_i1:gnd(0)"
				( attribute "PN" "3"
					( Origin gPackager )
				)
				( objectStatus "T1D17.3" )
			)
			( pin "@baseboard_fab2_lib.baseboard_fab2(sch_1):page272_i1:gnd(1)"
				( attribute "PN" "4"
					( Origin gPackager )
				)
				( objectStatus "T1D17.4" )
			)
			( pin "@baseboard_fab2_lib.baseboard_fab2(sch_1):page272_i1:gnd(2)"
				( attribute "PN" "5"
					( Origin gPackager )
				)
				( objectStatus "T1D17.5" )
			)
			( pin "@baseboard_fab2_lib.baseboard_fab2(sch_1):page272_i1:gnd(3)"
				( attribute "PN" "6"
					( Origin gPackager )
				)
				( objectStatus "T1D17.6" )
			)
			( pin "@baseboard_fab2_lib.baseboard_fab2(sch_1):page272_i1:gnd(4)"
				( attribute "PN" "7"
					( Origin gPackager )
				)
				( objectStatus "T1D17.7" )
			)
			( pin "@baseboard_fab2_lib.baseboard_fab2(sch_1):page272_i1:gnd(5)"
				( attribute "PN" "8"
					( Origin gPackager )
				)
				( objectStatus "T1D17.8" )
			)
			( pin "@baseboard_fab2_lib.baseboard_fab2(sch_1):page272_i1:gnd(6)"
				( attribute "PN" "9"
					( Origin gPackager )
				)
				( objectStatus "T1D17.9" )
			)
			( pin "@baseboard_fab2_lib.baseboard_fab2(sch_1):page272_i1:gnd(7)"
				( attribute "PN" "10"
					( Origin gPackager )
				)
				( objectStatus "T1D17.10" )
			)
			( pin "@baseboard_fab2_lib.baseboard_fab2(sch_1):page272_i1:gnd(8)"
				( attribute "PN" "11"
					( Origin gPackager )
				)
				( objectStatus "T1D17.11" )
			)
			( pin "@baseboard_fab2_lib.baseboard_fab2(sch_1):page272_i1:gnd(9)"
				( attribute "PN" "12"
					( Origin gPackager )
				)
				( objectStatus "T1D17.12" )
			)
			( pin "@baseboard_fab2_lib.baseboard_fab2(sch_1):page272_i3:dn"
				( attribute "PN" "2"
					( Origin gPackager )
				)
				( objectStatus "T1D15.2" )
			)
			( pin "@baseboard_fab2_lib.baseboard_fab2(sch_1):page272_i3:dp"
				( attribute "PN" "1"
					( Origin gPackager )
				)
				( objectStatus "T1D15.1" )
			)
			( pin "@baseboard_fab2_lib.baseboard_fab2(sch_1):page272_i3:gnd(0)"
				( attribute "PN" "3"
					( Origin gPackager )
				)
				( objectStatus "T1D15.3" )
			)
			( pin "@baseboard_fab2_lib.baseboard_fab2(sch_1):page272_i3:gnd(1)"
				( attribute "PN" "4"
					( Origin gPackager )
				)
				( objectStatus "T1D15.4" )
			)
			( pin "@baseboard_fab2_lib.baseboard_fab2(sch_1):page272_i3:gnd(2)"
				( attribute "PN" "5"
					( Origin gPackager )
				)
				( objectStatus "T1D15.5" )
			)
			( pin "@baseboard_fab2_lib.baseboard_fab2(sch_1):page272_i3:gnd(3)"
				( attribute "PN" "6"
					( Origin gPackager )
				)
				( objectStatus "T1D15.6" )
			)
			( pin "@baseboard_fab2_lib.baseboard_fab2(sch_1):page272_i3:gnd(4)"
				( attribute "PN" "7"
					( Origin gPackager )
				)
				( objectStatus "T1D15.7" )
			)
			( pin "@baseboard_fab2_lib.baseboard_fab2(sch_1):page272_i3:gnd(5)"
				( attribute "PN" "8"
					( Origin gPackager )
				)
				( objectStatus "T1D15.8" )
			)
			( pin "@baseboard_fab2_lib.baseboard_fab2(sch_1):page272_i3:gnd(6)"
				( attribute "PN" "9"
					( Origin gPackager )
				)
				( objectStatus "T1D15.9" )
			)
			( pin "@baseboard_fab2_lib.baseboard_fab2(sch_1):page272_i3:gnd(7)"
				( attribute "PN" "10"
					( Origin gPackager )
				)
				( objectStatus "T1D15.10" )
			)
			( pin "@baseboard_fab2_lib.baseboard_fab2(sch_1):page272_i3:gnd(8)"
				( attribute "PN" "11"
					( Origin gPackager )
				)
				( objectStatus "T1D15.11" )
			)
			( pin "@baseboard_fab2_lib.baseboard_fab2(sch_1):page272_i3:gnd(9)"
				( attribute "PN" "12"
					( Origin gPackager )
				)
				( objectStatus "T1D15.12" )
			)
			( pin "@baseboard_fab2_lib.baseboard_fab2(sch_1):page272_i5:dn"
				( attribute "PN" "2"
					( Origin gPackager )
				)
				( objectStatus "T1D13.2" )
			)
			( pin "@baseboard_fab2_lib.baseboard_fab2(sch_1):page272_i5:dp"
				( attribute "PN" "1"
					( Origin gPackager )
				)
				( objectStatus "T1D13.1" )
			)
			( pin "@baseboard_fab2_lib.baseboard_fab2(sch_1):page272_i5:gnd(0)"
				( attribute "PN" "3"
					( Origin gPackager )
				)
				( objectStatus "T1D13.3" )
			)
			( pin "@baseboard_fab2_lib.baseboard_fab2(sch_1):page272_i5:gnd(1)"
				( attribute "PN" "4"
					( Origin gPackager )
				)
				( objectStatus "T1D13.4" )
			)
			( pin "@baseboard_fab2_lib.baseboard_fab2(sch_1):page272_i5:gnd(2)"
				( attribute "PN" "5"
					( Origin gPackager )
				)
				( objectStatus "T1D13.5" )
			)
			( pin "@baseboard_fab2_lib.baseboard_fab2(sch_1):page272_i5:gnd(3)"
				( attribute "PN" "6"
					( Origin gPackager )
				)
				( objectStatus "T1D13.6" )
			)
			( pin "@baseboard_fab2_lib.baseboard_fab2(sch_1):page272_i5:gnd(4)"
				( attribute "PN" "7"
					( Origin gPackager )
				)
				( objectStatus "T1D13.7" )
			)
			( pin "@baseboard_fab2_lib.baseboard_fab2(sch_1):page272_i5:gnd(5)"
				( attribute "PN" "8"
					( Origin gPackager )
				)
				( objectStatus "T1D13.8" )
			)
			( pin "@baseboard_fab2_lib.baseboard_fab2(sch_1):page272_i5:gnd(6)"
				( attribute "PN" "9"
					( Origin gPackager )
				)
				( objectStatus "T1D13.9" )
			)
			( pin "@baseboard_fab2_lib.baseboard_fab2(sch_1):page272_i5:gnd(7)"
				( attribute "PN" "10"
					( Origin gPackager )
				)
				( objectStatus "T1D13.10" )
			)
			( pin "@baseboard_fab2_lib.baseboard_fab2(sch_1):page272_i5:gnd(8)"
				( attribute "PN" "11"
					( Origin gPackager )
				)
				( objectStatus "T1D13.11" )
			)
			( pin "@baseboard_fab2_lib.baseboard_fab2(sch_1):page272_i5:gnd(9)"
				( attribute "PN" "12"
					( Origin gPackager )
				)
				( objectStatus "T1D13.12" )
			)
			( pin "@baseboard_fab2_lib.baseboard_fab2(sch_1):page272_i8:dn"
				( attribute "PN" "2"
					( Origin gPackager )
				)
				( objectStatus "T1D18.2" )
			)
			( pin "@baseboard_fab2_lib.baseboard_fab2(sch_1):page272_i8:dp"
				( attribute "PN" "1"
					( Origin gPackager )
				)
				( objectStatus "T1D18.1" )
			)
			( pin "@baseboard_fab2_lib.baseboard_fab2(sch_1):page272_i8:gnd(0)"
				( attribute "PN" "3"
					( Origin gPackager )
				)
				( objectStatus "T1D18.3" )
			)
			( pin "@baseboard_fab2_lib.baseboard_fab2(sch_1):page272_i8:gnd(1)"
				( attribute "PN" "4"
					( Origin gPackager )
				)
				( objectStatus "T1D18.4" )
			)
			( pin "@baseboard_fab2_lib.baseboard_fab2(sch_1):page272_i8:gnd(2)"
				( attribute "PN" "5"
					( Origin gPackager )
				)
				( objectStatus "T1D18.5" )
			)
			( pin "@baseboard_fab2_lib.baseboard_fab2(sch_1):page272_i8:gnd(3)"
				( attribute "PN" "6"
					( Origin gPackager )
				)
				( objectStatus "T1D18.6" )
			)
			( pin "@baseboard_fab2_lib.baseboard_fab2(sch_1):page272_i8:gnd(4)"
				( attribute "PN" "7"
					( Origin gPackager )
				)
				( objectStatus "T1D18.7" )
			)
			( pin "@baseboard_fab2_lib.baseboard_fab2(sch_1):page272_i8:gnd(5)"
				( attribute "PN" "8"
					( Origin gPackager )
				)
				( objectStatus "T1D18.8" )
			)
			( pin "@baseboard_fab2_lib.baseboard_fab2(sch_1):page272_i8:gnd(6)"
				( attribute "PN" "9"
					( Origin gPackager )
				)
				( objectStatus "T1D18.9" )
			)
			( pin "@baseboard_fab2_lib.baseboard_fab2(sch_1):page272_i8:gnd(7)"
				( attribute "PN" "10"
					( Origin gPackager )
				)
				( objectStatus "T1D18.10" )
			)
			( pin "@baseboard_fab2_lib.baseboard_fab2(sch_1):page272_i8:gnd(8)"
				( attribute "PN" "11"
					( Origin gPackager )
				)
				( objectStatus "T1D18.11" )
			)
			( pin "@baseboard_fab2_lib.baseboard_fab2(sch_1):page272_i8:gnd(9)"
				( attribute "PN" "12"
					( Origin gPackager )
				)
				( objectStatus "T1D18.12" )
			)
			( pin "@baseboard_fab2_lib.baseboard_fab2(sch_1):page272_i9:dn"
				( attribute "PN" "2"
					( Origin gPackager )
				)
				( objectStatus "T1D23.2" )
			)
			( pin "@baseboard_fab2_lib.baseboard_fab2(sch_1):page272_i9:dp"
				( attribute "PN" "1"
					( Origin gPackager )
				)
				( objectStatus "T1D23.1" )
			)
			( pin "@baseboard_fab2_lib.baseboard_fab2(sch_1):page272_i9:gnd(0)"
				( attribute "PN" "3"
					( Origin gPackager )
				)
				( objectStatus "T1D23.3" )
			)
			( pin "@baseboard_fab2_lib.baseboard_fab2(sch_1):page272_i9:gnd(1)"
				( attribute "PN" "4"
					( Origin gPackager )
				)
				( objectStatus "T1D23.4" )
			)
			( pin "@baseboard_fab2_lib.baseboard_fab2(sch_1):page272_i9:gnd(2)"
				( attribute "PN" "5"
					( Origin gPackager )
				)
				( objectStatus "T1D23.5" )
			)
			( pin "@baseboard_fab2_lib.baseboard_fab2(sch_1):page272_i9:gnd(3)"
				( attribute "PN" "6"
					( Origin gPackager )
				)
				( objectStatus "T1D23.6" )
			)
			( pin "@baseboard_fab2_lib.baseboard_fab2(sch_1):page272_i9:gnd(4)"
				( attribute "PN" "7"
					( Origin gPackager )
				)
				( objectStatus "T1D23.7" )
			)
			( pin "@baseboard_fab2_lib.baseboard_fab2(sch_1):page272_i9:gnd(5)"
				( attribute "PN" "8"
					( Origin gPackager )
				)
				( objectStatus "T1D23.8" )
			)
			( pin "@baseboard_fab2_lib.baseboard_fab2(sch_1):page272_i9:gnd(6)"
				( attribute "PN" "9"
					( Origin gPackager )
				)
				( objectStatus "T1D23.9" )
			)
			( pin "@baseboard_fab2_lib.baseboard_fab2(sch_1):page272_i9:gnd(7)"
				( attribute "PN" "10"
					( Origin gPackager )
				)
				( objectStatus "T1D23.10" )
			)
			( pin "@baseboard_fab2_lib.baseboard_fab2(sch_1):page272_i9:gnd(8)"
				( attribute "PN" "11"
					( Origin gPackager )
				)
				( objectStatus "T1D23.11" )
			)
			( pin "@baseboard_fab2_lib.baseboard_fab2(sch_1):page272_i9:gnd(9)"
				( attribute "PN" "12"
					( Origin gPackager )
				)
				( objectStatus "T1D23.12" )
			)
			( pin "@baseboard_fab2_lib.baseboard_fab2(sch_1):page272_i12:dn"
				( attribute "PN" "2"
					( Origin gPackager )
				)
				( objectStatus "T1D24.2" )
			)
			( pin "@baseboard_fab2_lib.baseboard_fab2(sch_1):page272_i12:dp"
				( attribute "PN" "1"
					( Origin gPackager )
				)
				( objectStatus "T1D24.1" )
			)
			( pin "@baseboard_fab2_lib.baseboard_fab2(sch_1):page272_i12:gnd(0)"
				( attribute "PN" "3"
					( Origin gPackager )
				)
				( objectStatus "T1D24.3" )
			)
			( pin "@baseboard_fab2_lib.baseboard_fab2(sch_1):page272_i12:gnd(1)"
				( attribute "PN" "4"
					( Origin gPackager )
				)
				( objectStatus "T1D24.4" )
			)
			( pin "@baseboard_fab2_lib.baseboard_fab2(sch_1):page272_i12:gnd(2)"
				( attribute "PN" "5"
					( Origin gPackager )
				)
				( objectStatus "T1D24.5" )
			)
			( pin "@baseboard_fab2_lib.baseboard_fab2(sch_1):page272_i12:gnd(3)"
				( attribute "PN" "6"
					( Origin gPackager )
				)
				( objectStatus "T1D24.6" )
			)
			( pin "@baseboard_fab2_lib.baseboard_fab2(sch_1):page272_i12:gnd(4)"
				( attribute "PN" "7"
					( Origin gPackager )
				)
				( objectStatus "T1D24.7" )
			)
			( pin "@baseboard_fab2_lib.baseboard_fab2(sch_1):page272_i12:gnd(5)"
				( attribute "PN" "8"
					( Origin gPackager )
				)
				( objectStatus "T1D24.8" )
			)
			( pin "@baseboard_fab2_lib.baseboard_fab2(sch_1):page272_i12:gnd(6)"
				( attribute "PN" "9"
					( Origin gPackager )
				)
				( objectStatus "T1D24.9" )
			)
			( pin "@baseboard_fab2_lib.baseboard_fab2(sch_1):page272_i12:gnd(7)"
				( attribute "PN" "10"
					( Origin gPackager )
				)
				( objectStatus "T1D24.10" )
			)
			( pin "@baseboard_fab2_lib.baseboard_fab2(sch_1):page272_i12:gnd(8)"
				( attribute "PN" "11"
					( Origin gPackager )
				)
				( objectStatus "T1D24.11" )
			)
			( pin "@baseboard_fab2_lib.baseboard_fab2(sch_1):page272_i12:gnd(9)"
				( attribute "PN" "12"
					( Origin gPackager )
				)
				( objectStatus "T1D24.12" )
			)
			( pin "@baseboard_fab2_lib.baseboard_fab2(sch_1):page272_i14:dn"
				( attribute "PN" "2"
					( Origin gPackager )
				)
				( objectStatus "T1D16.2" )
			)
			( pin "@baseboard_fab2_lib.baseboard_fab2(sch_1):page272_i14:dp"
				( attribute "PN" "1"
					( Origin gPackager )
				)
				( objectStatus "T1D16.1" )
			)
			( pin "@baseboard_fab2_lib.baseboard_fab2(sch_1):page272_i14:gnd(0)"
				( attribute "PN" "3"
					( Origin gPackager )
				)
				( objectStatus "T1D16.3" )
			)
			( pin "@baseboard_fab2_lib.baseboard_fab2(sch_1):page272_i14:gnd(1)"
				( attribute "PN" "4"
					( Origin gPackager )
				)
				( objectStatus "T1D16.4" )
			)
			( pin "@baseboard_fab2_lib.baseboard_fab2(sch_1):page272_i14:gnd(2)"
				( attribute "PN" "5"
					( Origin gPackager )
				)
				( objectStatus "T1D16.5" )
			)
			( pin "@baseboard_fab2_lib.baseboard_fab2(sch_1):page272_i14:gnd(3)"
				( attribute "PN" "6"
					( Origin gPackager )
				)
				( objectStatus "T1D16.6" )
			)
			( pin "@baseboard_fab2_lib.baseboard_fab2(sch_1):page272_i14:gnd(4)"
				( attribute "PN" "7"
					( Origin gPackager )
				)
				( objectStatus "T1D16.7" )
			)
			( pin "@baseboard_fab2_lib.baseboard_fab2(sch_1):page272_i14:gnd(5)"
				( attribute "PN" "8"
					( Origin gPackager )
				)
				( objectStatus "T1D16.8" )
			)
			( pin "@baseboard_fab2_lib.baseboard_fab2(sch_1):page272_i14:gnd(6)"
				( attribute "PN" "9"
					( Origin gPackager )
				)
				( objectStatus "T1D16.9" )
			)
			( pin "@baseboard_fab2_lib.baseboard_fab2(sch_1):page272_i14:gnd(7)"
				( attribute "PN" "10"
					( Origin gPackager )
				)
				( objectStatus "T1D16.10" )
			)
			( pin "@baseboard_fab2_lib.baseboard_fab2(sch_1):page272_i14:gnd(8)"
				( attribute "PN" "11"
					( Origin gPackager )
				)
				( objectStatus "T1D16.11" )
			)
			( pin "@baseboard_fab2_lib.baseboard_fab2(sch_1):page272_i14:gnd(9)"
				( attribute "PN" "12"
					( Origin gPackager )
				)
				( objectStatus "T1D16.12" )
			)
			( pin "@baseboard_fab2_lib.baseboard_fab2(sch_1):page272_i16:dn"
				( attribute "PN" "2"
					( Origin gPackager )
				)
				( objectStatus "T1D21.2" )
			)
			( pin "@baseboard_fab2_lib.baseboard_fab2(sch_1):page272_i16:dp"
				( attribute "PN" "1"
					( Origin gPackager )
				)
				( objectStatus "T1D21.1" )
			)
			( pin "@baseboard_fab2_lib.baseboard_fab2(sch_1):page272_i16:gnd(0)"
				( attribute "PN" "3"
					( Origin gPackager )
				)
				( objectStatus "T1D21.3" )
			)
			( pin "@baseboard_fab2_lib.baseboard_fab2(sch_1):page272_i16:gnd(1)"
				( attribute "PN" "4"
					( Origin gPackager )
				)
				( objectStatus "T1D21.4" )
			)
			( pin "@baseboard_fab2_lib.baseboard_fab2(sch_1):page272_i16:gnd(2)"
				( attribute "PN" "5"
					( Origin gPackager )
				)
				( objectStatus "T1D21.5" )
			)
			( pin "@baseboard_fab2_lib.baseboard_fab2(sch_1):page272_i16:gnd(3)"
				( attribute "PN" "6"
					( Origin gPackager )
				)
				( objectStatus "T1D21.6" )
			)
			( pin "@baseboard_fab2_lib.baseboard_fab2(sch_1):page272_i16:gnd(4)"
				( attribute "PN" "7"
					( Origin gPackager )
				)
				( objectStatus "T1D21.7" )
			)
			( pin "@baseboard_fab2_lib.baseboard_fab2(sch_1):page272_i16:gnd(5)"
				( attribute "PN" "8"
					( Origin gPackager )
				)
				( objectStatus "T1D21.8" )
			)
			( pin "@baseboard_fab2_lib.baseboard_fab2(sch_1):page272_i16:gnd(6)"
				( attribute "PN" "9"
					( Origin gPackager )
				)
				( objectStatus "T1D21.9" )
			)
			( pin "@baseboard_fab2_lib.baseboard_fab2(sch_1):page272_i16:gnd(7)"
				( attribute "PN" "10"
					( Origin gPackager )
				)
				( objectStatus "T1D21.10" )
			)
			( pin "@baseboard_fab2_lib.baseboard_fab2(sch_1):page272_i16:gnd(8)"
				( attribute "PN" "11"
					( Origin gPackager )
				)
				( objectStatus "T1D21.11" )
			)
			( pin "@baseboard_fab2_lib.baseboard_fab2(sch_1):page272_i16:gnd(9)"
				( attribute "PN" "12"
					( Origin gPackager )
				)
				( objectStatus "T1D21.12" )
			)
			( pin "@baseboard_fab2_lib.baseboard_fab2(sch_1):page272_i21:dn"
				( attribute "PN" "2"
					( Origin gPackager )
				)
				( objectStatus "T1D22.2" )
			)
			( pin "@baseboard_fab2_lib.baseboard_fab2(sch_1):page272_i21:dp"
				( attribute "PN" "1"
					( Origin gPackager )
				)
				( objectStatus "T1D22.1" )
			)
			( pin "@baseboard_fab2_lib.baseboard_fab2(sch_1):page272_i21:gnd(0)"
				( attribute "PN" "3"
					( Origin gPackager )
				)
				( objectStatus "T1D22.3" )
			)
			( pin "@baseboard_fab2_lib.baseboard_fab2(sch_1):page272_i21:gnd(1)"
				( attribute "PN" "4"
					( Origin gPackager )
				)
				( objectStatus "T1D22.4" )
			)
			( pin "@baseboard_fab2_lib.baseboard_fab2(sch_1):page272_i21:gnd(2)"
				( attribute "PN" "5"
					( Origin gPackager )
				)
				( objectStatus "T1D22.5" )
			)
			( pin "@baseboard_fab2_lib.baseboard_fab2(sch_1):page272_i21:gnd(3)"
				( attribute "PN" "6"
					( Origin gPackager )
				)
				( objectStatus "T1D22.6" )
			)
			( pin "@baseboard_fab2_lib.baseboard_fab2(sch_1):page272_i21:gnd(4)"
				( attribute "PN" "7"
					( Origin gPackager )
				)
				( objectStatus "T1D22.7" )
			)
			( pin "@baseboard_fab2_lib.baseboard_fab2(sch_1):page272_i21:gnd(5)"
				( attribute "PN" "8"
					( Origin gPackager )
				)
				( objectStatus "T1D22.8" )
			)
			( pin "@baseboard_fab2_lib.baseboard_fab2(sch_1):page272_i21:gnd(6)"
				( attribute "PN" "9"
					( Origin gPackager )
				)
				( objectStatus "T1D22.9" )
			)
			( pin "@baseboard_fab2_lib.baseboard_fab2(sch_1):page272_i21:gnd(7)"
				( attribute "PN" "10"
					( Origin gPackager )
				)
				( objectStatus "T1D22.10" )
			)
			( pin "@baseboard_fab2_lib.baseboard_fab2(sch_1):page272_i21:gnd(8)"
				( attribute "PN" "11"
					( Origin gPackager )
				)
				( objectStatus "T1D22.11" )
			)
			( pin "@baseboard_fab2_lib.baseboard_fab2(sch_1):page272_i21:gnd(9)"
				( attribute "PN" "12"
					( Origin gPackager )
				)
				( objectStatus "T1D22.12" )
			)
			( pin "@baseboard_fab2_lib.baseboard_fab2(sch_1):page272_i22:dn"
				( attribute "PN" "2"
					( Origin gPackager )
				)
				( objectStatus "T1D14.2" )
			)
			( pin "@baseboard_fab2_lib.baseboard_fab2(sch_1):page272_i22:dp"
				( attribute "PN" "1"
					( Origin gPackager )
				)
				( objectStatus "T1D14.1" )
			)
			( pin "@baseboard_fab2_lib.baseboard_fab2(sch_1):page272_i22:gnd(0)"
				( attribute "PN" "3"
					( Origin gPackager )
				)
				( objectStatus "T1D14.3" )
			)
			( pin "@baseboard_fab2_lib.baseboard_fab2(sch_1):page272_i22:gnd(1)"
				( attribute "PN" "4"
					( Origin gPackager )
				)
				( objectStatus "T1D14.4" )
			)
			( pin "@baseboard_fab2_lib.baseboard_fab2(sch_1):page272_i22:gnd(2)"
				( attribute "PN" "5"
					( Origin gPackager )
				)
				( objectStatus "T1D14.5" )
			)
			( pin "@baseboard_fab2_lib.baseboard_fab2(sch_1):page272_i22:gnd(3)"
				( attribute "PN" "6"
					( Origin gPackager )
				)
				( objectStatus "T1D14.6" )
			)
			( pin "@baseboard_fab2_lib.baseboard_fab2(sch_1):page272_i22:gnd(4)"
				( attribute "PN" "7"
					( Origin gPackager )
				)
				( objectStatus "T1D14.7" )
			)
			( pin "@baseboard_fab2_lib.baseboard_fab2(sch_1):page272_i22:gnd(5)"
				( attribute "PN" "8"
					( Origin gPackager )
				)
				( objectStatus "T1D14.8" )
			)
			( pin "@baseboard_fab2_lib.baseboard_fab2(sch_1):page272_i22:gnd(6)"
				( attribute "PN" "9"
					( Origin gPackager )
				)
				( objectStatus "T1D14.9" )
			)
			( pin "@baseboard_fab2_lib.baseboard_fab2(sch_1):page272_i22:gnd(7)"
				( attribute "PN" "10"
					( Origin gPackager )
				)
				( objectStatus "T1D14.10" )
			)
			( pin "@baseboard_fab2_lib.baseboard_fab2(sch_1):page272_i22:gnd(8)"
				( attribute "PN" "11"
					( Origin gPackager )
				)
				( objectStatus "T1D14.11" )
			)
			( pin "@baseboard_fab2_lib.baseboard_fab2(sch_1):page272_i22:gnd(9)"
				( attribute "PN" "12"
					( Origin gPackager )
				)
				( objectStatus "T1D14.12" )
			)
			( pin "@baseboard_fab2_lib.baseboard_fab2(sch_1):page272_i23:dn"
				( attribute "PN" "2"
					( Origin gPackager )
				)
				( objectStatus "T1D19.2" )
			)
			( pin "@baseboard_fab2_lib.baseboard_fab2(sch_1):page272_i23:dp"
				( attribute "PN" "1"
					( Origin gPackager )
				)
				( objectStatus "T1D19.1" )
			)
			( pin "@baseboard_fab2_lib.baseboard_fab2(sch_1):page272_i23:gnd(0)"
				( attribute "PN" "3"
					( Origin gPackager )
				)
				( objectStatus "T1D19.3" )
			)
			( pin "@baseboard_fab2_lib.baseboard_fab2(sch_1):page272_i23:gnd(1)"
				( attribute "PN" "4"
					( Origin gPackager )
				)
				( objectStatus "T1D19.4" )
			)
			( pin "@baseboard_fab2_lib.baseboard_fab2(sch_1):page272_i23:gnd(2)"
				( attribute "PN" "5"
					( Origin gPackager )
				)
				( objectStatus "T1D19.5" )
			)
			( pin "@baseboard_fab2_lib.baseboard_fab2(sch_1):page272_i23:gnd(3)"
				( attribute "PN" "6"
					( Origin gPackager )
				)
				( objectStatus "T1D19.6" )
			)
			( pin "@baseboard_fab2_lib.baseboard_fab2(sch_1):page272_i23:gnd(4)"
				( attribute "PN" "7"
					( Origin gPackager )
				)
				( objectStatus "T1D19.7" )
			)
			( pin "@baseboard_fab2_lib.baseboard_fab2(sch_1):page272_i23:gnd(5)"
				( attribute "PN" "8"
					( Origin gPackager )
				)
				( objectStatus "T1D19.8" )
			)
			( pin "@baseboard_fab2_lib.baseboard_fab2(sch_1):page272_i23:gnd(6)"
				( attribute "PN" "9"
					( Origin gPackager )
				)
				( objectStatus "T1D19.9" )
			)
			( pin "@baseboard_fab2_lib.baseboard_fab2(sch_1):page272_i23:gnd(7)"
				( attribute "PN" "10"
					( Origin gPackager )
				)
				( objectStatus "T1D19.10" )
			)
			( pin "@baseboard_fab2_lib.baseboard_fab2(sch_1):page272_i23:gnd(8)"
				( attribute "PN" "11"
					( Origin gPackager )
				)
				( objectStatus "T1D19.11" )
			)
			( pin "@baseboard_fab2_lib.baseboard_fab2(sch_1):page272_i23:gnd(9)"
				( attribute "PN" "12"
					( Origin gPackager )
				)
				( objectStatus "T1D19.12" )
			)
			( pin "@baseboard_fab2_lib.baseboard_fab2(sch_1):page272_i24:dn"
				( attribute "PN" "2"
					( Origin gPackager )
				)
				( objectStatus "T1D20.2" )
			)
			( pin "@baseboard_fab2_lib.baseboard_fab2(sch_1):page272_i24:dp"
				( attribute "PN" "1"
					( Origin gPackager )
				)
				( objectStatus "T1D20.1" )
			)
			( pin "@baseboard_fab2_lib.baseboard_fab2(sch_1):page272_i24:gnd(0)"
				( attribute "PN" "3"
					( Origin gPackager )
				)
				( objectStatus "T1D20.3" )
			)
			( pin "@baseboard_fab2_lib.baseboard_fab2(sch_1):page272_i24:gnd(1)"
				( attribute "PN" "4"
					( Origin gPackager )
				)
				( objectStatus "T1D20.4" )
			)
			( pin "@baseboard_fab2_lib.baseboard_fab2(sch_1):page272_i24:gnd(2)"
				( attribute "PN" "5"
					( Origin gPackager )
				)
				( objectStatus "T1D20.5" )
			)
			( pin "@baseboard_fab2_lib.baseboard_fab2(sch_1):page272_i24:gnd(3)"
				( attribute "PN" "6"
					( Origin gPackager )
				)
				( objectStatus "T1D20.6" )
			)
			( pin "@baseboard_fab2_lib.baseboard_fab2(sch_1):page272_i24:gnd(4)"
				( attribute "PN" "7"
					( Origin gPackager )
				)
				( objectStatus "T1D20.7" )
			)
			( pin "@baseboard_fab2_lib.baseboard_fab2(sch_1):page272_i24:gnd(5)"
				( attribute "PN" "8"
					( Origin gPackager )
				)
				( objectStatus "T1D20.8" )
			)
			( pin "@baseboard_fab2_lib.baseboard_fab2(sch_1):page272_i24:gnd(6)"
				( attribute "PN" "9"
					( Origin gPackager )
				)
				( objectStatus "T1D20.9" )
			)
			( pin "@baseboard_fab2_lib.baseboard_fab2(sch_1):page272_i24:gnd(7)"
				( attribute "PN" "10"
					( Origin gPackager )
				)
				( objectStatus "T1D20.10" )
			)
			( pin "@baseboard_fab2_lib.baseboard_fab2(sch_1):page272_i24:gnd(8)"
				( attribute "PN" "11"
					( Origin gPackager )
				)
				( objectStatus "T1D20.11" )
			)
			( pin "@baseboard_fab2_lib.baseboard_fab2(sch_1):page272_i24:gnd(9)"
				( attribute "PN" "12"
					( Origin gPackager )
				)
				( objectStatus "T1D20.12" )
			)
			( pin "@baseboard_fab2_lib.baseboard_fab2(sch_1):page271_i5:\1\"
				( attribute "PN" "1"
					( Origin gPackager )
				)
				( objectStatus "T1P2.1" )
			)
			( pin "@baseboard_fab2_lib.baseboard_fab2(sch_1):page271_i5:\2\"
				( attribute "PN" "2"
					( Origin gPackager )
				)
				( objectStatus "T1P2.2" )
			)
			( pin "@baseboard_fab2_lib.baseboard_fab2(sch_1):page271_i5:gnd1"
				( attribute "PN" "GND1"
					( Origin gPackager )
				)
				( objectStatus "T1P2.GND1" )
			)
			( pin "@baseboard_fab2_lib.baseboard_fab2(sch_1):page271_i5:gnd2"
				( attribute "PN" "GND2"
					( Origin gPackager )
				)
				( objectStatus "T1P2.GND2" )
			)
			( pin "@baseboard_fab2_lib.baseboard_fab2(sch_1):page271_i7:\1\"
				( attribute "PN" "1"
					( Origin gPackager )
				)
				( objectStatus "T1P4.1" )
			)
			( pin "@baseboard_fab2_lib.baseboard_fab2(sch_1):page271_i7:\2\"
				( attribute "PN" "2"
					( Origin gPackager )
				)
				( objectStatus "T1P4.2" )
			)
			( pin "@baseboard_fab2_lib.baseboard_fab2(sch_1):page271_i7:gnd1"
				( attribute "PN" "GND1"
					( Origin gPackager )
				)
				( objectStatus "T1P4.GND1" )
			)
			( pin "@baseboard_fab2_lib.baseboard_fab2(sch_1):page271_i7:gnd2"
				( attribute "PN" "GND2"
					( Origin gPackager )
				)
				( objectStatus "T1P4.GND2" )
			)
			( pin "@baseboard_fab2_lib.baseboard_fab2(sch_1):page271_i8:\1\"
				( attribute "PN" "1"
					( Origin gPackager )
				)
				( objectStatus "T1P3.1" )
			)
			( pin "@baseboard_fab2_lib.baseboard_fab2(sch_1):page271_i8:\2\"
				( attribute "PN" "2"
					( Origin gPackager )
				)
				( objectStatus "T1P3.2" )
			)
			( pin "@baseboard_fab2_lib.baseboard_fab2(sch_1):page271_i8:gnd1"
				( attribute "PN" "GND1"
					( Origin gPackager )
				)
				( objectStatus "T1P3.GND1" )
			)
			( pin "@baseboard_fab2_lib.baseboard_fab2(sch_1):page271_i8:gnd2"
				( attribute "PN" "GND2"
					( Origin gPackager )
				)
				( objectStatus "T1P3.GND2" )
			)
			( pin "@baseboard_fab2_lib.baseboard_fab2(sch_1):page271_i11:\1\"
				( attribute "PN" "1"
					( Origin gPackager )
				)
				( objectStatus "T1P5.1" )
			)
			( pin "@baseboard_fab2_lib.baseboard_fab2(sch_1):page271_i11:\2\"
				( attribute "PN" "2"
					( Origin gPackager )
				)
				( objectStatus "T1P5.2" )
			)
			( pin "@baseboard_fab2_lib.baseboard_fab2(sch_1):page271_i11:gnd1"
				( attribute "PN" "GND1"
					( Origin gPackager )
				)
				( objectStatus "T1P5.GND1" )
			)
			( pin "@baseboard_fab2_lib.baseboard_fab2(sch_1):page271_i11:gnd2"
				( attribute "PN" "GND2"
					( Origin gPackager )
				)
				( objectStatus "T1P5.GND2" )
			)
			( pin "@baseboard_fab2_lib.baseboard_fab2(sch_1):page271_i13:\1\"
				( attribute "PN" "1"
					( Origin gPackager )
				)
				( objectStatus "T1P6.1" )
			)
			( pin "@baseboard_fab2_lib.baseboard_fab2(sch_1):page271_i13:\2\"
				( attribute "PN" "2"
					( Origin gPackager )
				)
				( objectStatus "T1P6.2" )
			)
			( pin "@baseboard_fab2_lib.baseboard_fab2(sch_1):page271_i13:gnd1"
				( attribute "PN" "GND1"
					( Origin gPackager )
				)
				( objectStatus "T1P6.GND1" )
			)
			( pin "@baseboard_fab2_lib.baseboard_fab2(sch_1):page271_i13:gnd2"
				( attribute "PN" "GND2"
					( Origin gPackager )
				)
				( objectStatus "T1P6.GND2" )
			)
			( pin "@baseboard_fab2_lib.baseboard_fab2(sch_1):page271_i15:\1\"
				( attribute "PN" "1"
					( Origin gPackager )
				)
				( objectStatus "T1P10.1" )
			)
			( pin "@baseboard_fab2_lib.baseboard_fab2(sch_1):page271_i15:\2\"
				( attribute "PN" "2"
					( Origin gPackager )
				)
				( objectStatus "T1P10.2" )
			)
			( pin "@baseboard_fab2_lib.baseboard_fab2(sch_1):page271_i15:gnd1"
				( attribute "PN" "GND1"
					( Origin gPackager )
				)
				( objectStatus "T1P10.GND1" )
			)
			( pin "@baseboard_fab2_lib.baseboard_fab2(sch_1):page271_i15:gnd2"
				( attribute "PN" "GND2"
					( Origin gPackager )
				)
				( objectStatus "T1P10.GND2" )
			)
			( pin "@baseboard_fab2_lib.baseboard_fab2(sch_1):page271_i16:\1\"
				( attribute "PN" "1"
					( Origin gPackager )
				)
				( objectStatus "T1P8.1" )
			)
			( pin "@baseboard_fab2_lib.baseboard_fab2(sch_1):page271_i16:\2\"
				( attribute "PN" "2"
					( Origin gPackager )
				)
				( objectStatus "T1P8.2" )
			)
			( pin "@baseboard_fab2_lib.baseboard_fab2(sch_1):page271_i16:gnd1"
				( attribute "PN" "GND1"
					( Origin gPackager )
				)
				( objectStatus "T1P8.GND1" )
			)
			( pin "@baseboard_fab2_lib.baseboard_fab2(sch_1):page271_i16:gnd2"
				( attribute "PN" "GND2"
					( Origin gPackager )
				)
				( objectStatus "T1P8.GND2" )
			)
			( pin "@baseboard_fab2_lib.baseboard_fab2(sch_1):page271_i17:\1\"
				( attribute "PN" "1"
					( Origin gPackager )
				)
				( objectStatus "T1P7.1" )
			)
			( pin "@baseboard_fab2_lib.baseboard_fab2(sch_1):page271_i17:\2\"
				( attribute "PN" "2"
					( Origin gPackager )
				)
				( objectStatus "T1P7.2" )
			)
			( pin "@baseboard_fab2_lib.baseboard_fab2(sch_1):page271_i17:gnd1"
				( attribute "PN" "GND1"
					( Origin gPackager )
				)
				( objectStatus "T1P7.GND1" )
			)
			( pin "@baseboard_fab2_lib.baseboard_fab2(sch_1):page271_i17:gnd2"
				( attribute "PN" "GND2"
					( Origin gPackager )
				)
				( objectStatus "T1P7.GND2" )
			)
			( pin "@baseboard_fab2_lib.baseboard_fab2(sch_1):page271_i19:\1\"
				( attribute "PN" "1"
					( Origin gPackager )
				)
				( objectStatus "T1P9.1" )
			)
			( pin "@baseboard_fab2_lib.baseboard_fab2(sch_1):page271_i19:\2\"
				( attribute "PN" "2"
					( Origin gPackager )
				)
				( objectStatus "T1P9.2" )
			)
			( pin "@baseboard_fab2_lib.baseboard_fab2(sch_1):page271_i19:gnd1"
				( attribute "PN" "GND1"
					( Origin gPackager )
				)
				( objectStatus "T1P9.GND1" )
			)
			( pin "@baseboard_fab2_lib.baseboard_fab2(sch_1):page271_i19:gnd2"
				( attribute "PN" "GND2"
					( Origin gPackager )
				)
				( objectStatus "T1P9.GND2" )
			)
			( pin "@baseboard_fab2_lib.baseboard_fab2(sch_1):page271_i23:\1\"
				( attribute "PN" "1"
					( Origin gPackager )
				)
				( objectStatus "T1P11.1" )
			)
			( pin "@baseboard_fab2_lib.baseboard_fab2(sch_1):page271_i23:\2\"
				( attribute "PN" "2"
					( Origin gPackager )
				)
				( objectStatus "T1P11.2" )
			)
			( pin "@baseboard_fab2_lib.baseboard_fab2(sch_1):page271_i23:gnd1"
				( attribute "PN" "GND1"
					( Origin gPackager )
				)
				( objectStatus "T1P11.GND1" )
			)
			( pin "@baseboard_fab2_lib.baseboard_fab2(sch_1):page271_i23:gnd2"
				( attribute "PN" "GND2"
					( Origin gPackager )
				)
				( objectStatus "T1P11.GND2" )
			)
			( pin "@baseboard_fab2_lib.baseboard_fab2(sch_1):page271_i24:\1\"
				( attribute "PN" "1"
					( Origin gPackager )
				)
				( objectStatus "T1P12.1" )
			)
			( pin "@baseboard_fab2_lib.baseboard_fab2(sch_1):page271_i24:\2\"
				( attribute "PN" "2"
					( Origin gPackager )
				)
				( objectStatus "T1P12.2" )
			)
			( pin "@baseboard_fab2_lib.baseboard_fab2(sch_1):page271_i24:gnd1"
				( attribute "PN" "GND1"
					( Origin gPackager )
				)
				( objectStatus "T1P12.GND1" )
			)
			( pin "@baseboard_fab2_lib.baseboard_fab2(sch_1):page271_i24:gnd2"
				( attribute "PN" "GND2"
					( Origin gPackager )
				)
				( objectStatus "T1P12.GND2" )
			)
			( pin "@baseboard_fab2_lib.baseboard_fab2(sch_1):page271_i36:\1\"
				( attribute "PN" "1"
					( Origin gPackager )
				)
				( objectStatus "T1P17.1" )
			)
			( pin "@baseboard_fab2_lib.baseboard_fab2(sch_1):page271_i36:\2\"
				( attribute "PN" "2"
					( Origin gPackager )
				)
				( objectStatus "T1P17.2" )
			)
			( pin "@baseboard_fab2_lib.baseboard_fab2(sch_1):page271_i36:gnd1"
				( attribute "PN" "GND1"
					( Origin gPackager )
				)
				( objectStatus "T1P17.GND1" )
			)
			( pin "@baseboard_fab2_lib.baseboard_fab2(sch_1):page271_i36:gnd2"
				( attribute "PN" "GND2"
					( Origin gPackager )
				)
				( objectStatus "T1P17.GND2" )
			)
			( pin "@baseboard_fab2_lib.baseboard_fab2(sch_1):page271_i38:\1\"
				( attribute "PN" "1"
					( Origin gPackager )
				)
				( objectStatus "T1P24.1" )
			)
			( pin "@baseboard_fab2_lib.baseboard_fab2(sch_1):page271_i38:\2\"
				( attribute "PN" "2"
					( Origin gPackager )
				)
				( objectStatus "T1P24.2" )
			)
			( pin "@baseboard_fab2_lib.baseboard_fab2(sch_1):page271_i38:gnd1"
				( attribute "PN" "GND1"
					( Origin gPackager )
				)
				( objectStatus "T1P24.GND1" )
			)
			( pin "@baseboard_fab2_lib.baseboard_fab2(sch_1):page271_i38:gnd2"
				( attribute "PN" "GND2"
					( Origin gPackager )
				)
				( objectStatus "T1P24.GND2" )
			)
			( pin "@baseboard_fab2_lib.baseboard_fab2(sch_1):page271_i39:\1\"
				( attribute "PN" "1"
					( Origin gPackager )
				)
				( objectStatus "T1P19.1" )
			)
			( pin "@baseboard_fab2_lib.baseboard_fab2(sch_1):page271_i39:\2\"
				( attribute "PN" "2"
					( Origin gPackager )
				)
				( objectStatus "T1P19.2" )
			)
			( pin "@baseboard_fab2_lib.baseboard_fab2(sch_1):page271_i39:gnd1"
				( attribute "PN" "GND1"
					( Origin gPackager )
				)
				( objectStatus "T1P19.GND1" )
			)
			( pin "@baseboard_fab2_lib.baseboard_fab2(sch_1):page271_i39:gnd2"
				( attribute "PN" "GND2"
					( Origin gPackager )
				)
				( objectStatus "T1P19.GND2" )
			)
			( pin "@baseboard_fab2_lib.baseboard_fab2(sch_1):page271_i45:\1\"
				( attribute "PN" "1"
					( Origin gPackager )
				)
				( objectStatus "T1P22.1" )
			)
			( pin "@baseboard_fab2_lib.baseboard_fab2(sch_1):page271_i45:\2\"
				( attribute "PN" "2"
					( Origin gPackager )
				)
				( objectStatus "T1P22.2" )
			)
			( pin "@baseboard_fab2_lib.baseboard_fab2(sch_1):page271_i45:gnd1"
				( attribute "PN" "GND1"
					( Origin gPackager )
				)
				( objectStatus "T1P22.GND1" )
			)
			( pin "@baseboard_fab2_lib.baseboard_fab2(sch_1):page271_i45:gnd2"
				( attribute "PN" "GND2"
					( Origin gPackager )
				)
				( objectStatus "T1P22.GND2" )
			)
			( pin "@baseboard_fab2_lib.baseboard_fab2(sch_1):page271_i47:\1\"
				( attribute "PN" "1"
					( Origin gPackager )
				)
				( objectStatus "T1P23.1" )
			)
			( pin "@baseboard_fab2_lib.baseboard_fab2(sch_1):page271_i47:\2\"
				( attribute "PN" "2"
					( Origin gPackager )
				)
				( objectStatus "T1P23.2" )
			)
			( pin "@baseboard_fab2_lib.baseboard_fab2(sch_1):page271_i47:gnd1"
				( attribute "PN" "GND1"
					( Origin gPackager )
				)
				( objectStatus "T1P23.GND1" )
			)
			( pin "@baseboard_fab2_lib.baseboard_fab2(sch_1):page271_i47:gnd2"
				( attribute "PN" "GND2"
					( Origin gPackager )
				)
				( objectStatus "T1P23.GND2" )
			)
			( pin "@baseboard_fab2_lib.baseboard_fab2(sch_1):page271_i50:\1\"
				( attribute "PN" "1"
					( Origin gPackager )
				)
				( objectStatus "T1P25.1" )
			)
			( pin "@baseboard_fab2_lib.baseboard_fab2(sch_1):page271_i50:gnd1"
				( attribute "PN" "GND1"
					( Origin gPackager )
				)
				( objectStatus "T1P25.GND1" )
			)
			( pin "@baseboard_fab2_lib.baseboard_fab2(sch_1):page271_i52:\1\"
				( attribute "PN" "1"
					( Origin gPackager )
				)
				( objectStatus "T1P26.1" )
			)
			( pin "@baseboard_fab2_lib.baseboard_fab2(sch_1):page271_i52:gnd1"
				( attribute "PN" "GND1"
					( Origin gPackager )
				)
				( objectStatus "T1P26.GND1" )
			)
			( pin "@baseboard_fab2_lib.baseboard_fab2(sch_1):page271_i54:\1\"
				( attribute "PN" "1"
					( Origin gPackager )
				)
				( objectStatus "T1P27.1" )
			)
			( pin "@baseboard_fab2_lib.baseboard_fab2(sch_1):page271_i54:gnd1"
				( attribute "PN" "GND1"
					( Origin gPackager )
				)
				( objectStatus "T1P27.GND1" )
			)
			( pin "@baseboard_fab2_lib.baseboard_fab2(sch_1):page271_i56:\1\"
				( attribute "PN" "1"
					( Origin gPackager )
				)
				( objectStatus "T1P29.1" )
			)
			( pin "@baseboard_fab2_lib.baseboard_fab2(sch_1):page271_i56:gnd1"
				( attribute "PN" "GND1"
					( Origin gPackager )
				)
				( objectStatus "T1P29.GND1" )
			)
			( pin "@baseboard_fab2_lib.baseboard_fab2(sch_1):page271_i60:\1\"
				( attribute "PN" "1"
					( Origin gPackager )
				)
				( objectStatus "T1P28.1" )
			)
			( pin "@baseboard_fab2_lib.baseboard_fab2(sch_1):page271_i60:gnd1"
				( attribute "PN" "GND1"
					( Origin gPackager )
				)
				( objectStatus "T1P28.GND1" )
			)
			( pin "@baseboard_fab2_lib.baseboard_fab2(sch_1):page271_i61:\1\"
				( attribute "PN" "1"
					( Origin gPackager )
				)
				( objectStatus "T1P30.1" )
			)
			( pin "@baseboard_fab2_lib.baseboard_fab2(sch_1):page271_i61:gnd1"
				( attribute "PN" "GND1"
					( Origin gPackager )
				)
				( objectStatus "T1P30.GND1" )
			)
			( pin "@baseboard_fab2_lib.baseboard_fab2(sch_1):page271_i62:\1\"
				( attribute "PN" "1"
					( Origin gPackager )
				)
				( objectStatus "T1P34.1" )
			)
			( pin "@baseboard_fab2_lib.baseboard_fab2(sch_1):page271_i62:gnd1"
				( attribute "PN" "GND1"
					( Origin gPackager )
				)
				( objectStatus "T1P34.GND1" )
			)
			( pin "@baseboard_fab2_lib.baseboard_fab2(sch_1):page271_i63:\1\"
				( attribute "PN" "1"
					( Origin gPackager )
				)
				( objectStatus "T1P36.1" )
			)
			( pin "@baseboard_fab2_lib.baseboard_fab2(sch_1):page271_i63:gnd1"
				( attribute "PN" "GND1"
					( Origin gPackager )
				)
				( objectStatus "T1P36.GND1" )
			)
			( pin "@baseboard_fab2_lib.baseboard_fab2(sch_1):page271_i67:\1\"
				( attribute "PN" "1"
					( Origin gPackager )
				)
				( objectStatus "T1P35.1" )
			)
			( pin "@baseboard_fab2_lib.baseboard_fab2(sch_1):page271_i67:gnd1"
				( attribute "PN" "GND1"
					( Origin gPackager )
				)
				( objectStatus "T1P35.GND1" )
			)
			( pin "@baseboard_fab2_lib.baseboard_fab2(sch_1):page271_i71:\1\"
				( attribute "PN" "1"
					( Origin gPackager )
				)
				( objectStatus "T1P31.1" )
			)
			( pin "@baseboard_fab2_lib.baseboard_fab2(sch_1):page271_i71:gnd1"
				( attribute "PN" "GND1"
					( Origin gPackager )
				)
				( objectStatus "T1P31.GND1" )
			)
			( pin "@baseboard_fab2_lib.baseboard_fab2(sch_1):page271_i72:\1\"
				( attribute "PN" "1"
					( Origin gPackager )
				)
				( objectStatus "T1P32.1" )
			)
			( pin "@baseboard_fab2_lib.baseboard_fab2(sch_1):page271_i72:gnd1"
				( attribute "PN" "GND1"
					( Origin gPackager )
				)
				( objectStatus "T1P32.GND1" )
			)
			( pin "@baseboard_fab2_lib.baseboard_fab2(sch_1):page271_i73:\1\"
				( attribute "PN" "1"
					( Origin gPackager )
				)
				( objectStatus "T1P33.1" )
			)
			( pin "@baseboard_fab2_lib.baseboard_fab2(sch_1):page271_i73:gnd1"
				( attribute "PN" "GND1"
					( Origin gPackager )
				)
				( objectStatus "T1P33.GND1" )
			)
			( pin "@baseboard_fab2_lib.baseboard_fab2(sch_1):page118_i176:a"
				( attribute "PN" "1"
					( Origin gPackager )
				)
				( objectStatus "R7W6.1" )
			)
			( pin "@baseboard_fab2_lib.baseboard_fab2(sch_1):page118_i176:b"
				( attribute "PN" "2"
					( Origin gPackager )
				)
				( objectStatus "R7W6.2" )
			)
			( pin "@baseboard_fab2_lib.baseboard_fab2(sch_1):page120_i269:a"
				( attribute "PN" "1"
					( Origin gPackager )
				)
				( objectStatus "R7W8.1" )
			)
			( pin "@baseboard_fab2_lib.baseboard_fab2(sch_1):page120_i269:b"
				( attribute "PN" "2"
					( Origin gPackager )
				)
				( objectStatus "R7W8.2" )
			)
			( pin "@baseboard_fab2_lib.baseboard_fab2(sch_1):page118_i177:a"
				( attribute "PN" "1"
					( Origin gPackager )
				)
				( objectStatus "R7W9.1" )
			)
			( pin "@baseboard_fab2_lib.baseboard_fab2(sch_1):page118_i177:b"
				( attribute "PN" "2"
					( Origin gPackager )
				)
				( objectStatus "R7W9.2" )
			)
			( pin "@baseboard_fab2_lib.baseboard_fab2(sch_1):page120_i270:a"
				( attribute "PN" "1"
					( Origin gPackager )
				)
				( objectStatus "R7W10.1" )
			)
			( pin "@baseboard_fab2_lib.baseboard_fab2(sch_1):page120_i270:b"
				( attribute "PN" "2"
					( Origin gPackager )
				)
				( objectStatus "R7W10.2" )
			)
			( pin "@baseboard_fab2_lib.baseboard_fab2(sch_1):page120_i271:a"
				( attribute "PN" "1"
					( Origin gPackager )
				)
				( objectStatus "R7W12.1" )
			)
			( pin "@baseboard_fab2_lib.baseboard_fab2(sch_1):page120_i271:b"
				( attribute "PN" "2"
					( Origin gPackager )
				)
				( objectStatus "R7W12.2" )
			)
			( pin "@baseboard_fab2_lib.baseboard_fab2(sch_1):page120_i273:a"
				( attribute "PN" "1"
					( Origin gPackager )
				)
				( objectStatus "R7W11.1" )
			)
			( pin "@baseboard_fab2_lib.baseboard_fab2(sch_1):page120_i273:b"
				( attribute "PN" "2"
					( Origin gPackager )
				)
				( objectStatus "R7W11.2" )
			)
			( pin "@baseboard_fab2_lib.baseboard_fab2(sch_1):page268_i66:a"
				( attribute "PN" "1"
					( Origin gPackager )
				)
				( objectStatus "R25W187.1" )
			)
			( pin "@baseboard_fab2_lib.baseboard_fab2(sch_1):page268_i66:b"
				( attribute "PN" "2"
					( Origin gPackager )
				)
				( objectStatus "R25W187.2" )
			)
			( pin "@baseboard_fab2_lib.baseboard_fab2(sch_1):page188_i128:a"
				( attribute "PN" "1"
					( Origin gPackager )
				)
				( objectStatus "R1W40.1" )
			)
			( pin "@baseboard_fab2_lib.baseboard_fab2(sch_1):page188_i128:b"
				( attribute "PN" "2"
					( Origin gPackager )
				)
				( objectStatus "R1W40.2" )
			)
			( pin "@baseboard_fab2_lib.baseboard_fab2(sch_1):page188_i129:a"
				( attribute "PN" "1"
					( Origin gPackager )
				)
				( objectStatus "R1W41.1" )
			)
			( pin "@baseboard_fab2_lib.baseboard_fab2(sch_1):page188_i129:b"
				( attribute "PN" "2"
					( Origin gPackager )
				)
				( objectStatus "R1W41.2" )
			)
			( pin "@baseboard_fab2_lib.baseboard_fab2(sch_1):page119_i226:a"
				( attribute "PN" "1"
					( Origin gPackager )
				)
				( objectStatus "R7W13.1" )
			)
			( pin "@baseboard_fab2_lib.baseboard_fab2(sch_1):page119_i226:b"
				( attribute "PN" "2"
					( Origin gPackager )
				)
				( objectStatus "R7W13.2" )
			)
			( pin "@baseboard_fab2_lib.baseboard_fab2(sch_1):page120_i274:a"
				( attribute "PN" "1"
					( Origin gPackager )
				)
				( objectStatus "R7W14.1" )
			)
			( pin "@baseboard_fab2_lib.baseboard_fab2(sch_1):page120_i274:b"
				( attribute "PN" "2"
					( Origin gPackager )
				)
				( objectStatus "R7W14.2" )
			)
			( pin "@baseboard_fab2_lib.baseboard_fab2(sch_1):page119_i227:a"
				( attribute "PN" "1"
					( Origin gPackager )
				)
				( objectStatus "R7W15.1" )
			)
			( pin "@baseboard_fab2_lib.baseboard_fab2(sch_1):page119_i227:b"
				( attribute "PN" "2"
					( Origin gPackager )
				)
				( objectStatus "R7W15.2" )
			)
			( pin "@baseboard_fab2_lib.baseboard_fab2(sch_1):page120_i275:a"
				( attribute "PN" "1"
					( Origin gPackager )
				)
				( objectStatus "R8C21.1" )
			)
			( pin "@baseboard_fab2_lib.baseboard_fab2(sch_1):page120_i275:b"
				( attribute "PN" "2"
					( Origin gPackager )
				)
				( objectStatus "R8C21.2" )
			)
			( pin "@baseboard_fab2_lib.baseboard_fab2(sch_1):page119_i228:a"
				( attribute "PN" "1"
					( Origin gPackager )
				)
				( objectStatus "R2U50.1" )
			)
			( pin "@baseboard_fab2_lib.baseboard_fab2(sch_1):page119_i228:b"
				( attribute "PN" "2"
					( Origin gPackager )
				)
				( objectStatus "R2U50.2" )
			)
			( pin "@baseboard_fab2_lib.baseboard_fab2(sch_1):page188_i131:a"
				( attribute "PN" "1"
					( Origin gPackager )
				)
				( objectStatus "R1W42.1" )
			)
			( pin "@baseboard_fab2_lib.baseboard_fab2(sch_1):page188_i131:b"
				( attribute "PN" "2"
					( Origin gPackager )
				)
				( objectStatus "R1W42.2" )
			)
			( pin "@baseboard_fab2_lib.baseboard_fab2(sch_1):page188_i132:a"
				( attribute "PN" "1"
					( Origin gPackager )
				)
				( objectStatus "R1W43.1" )
			)
			( pin "@baseboard_fab2_lib.baseboard_fab2(sch_1):page188_i132:b"
				( attribute "PN" "2"
					( Origin gPackager )
				)
				( objectStatus "R1W43.2" )
			)
			( pin "@baseboard_fab2_lib.baseboard_fab2(sch_1):page188_i133:a"
				( attribute "PN" "1"
					( Origin gPackager )
				)
				( objectStatus "R1W44.1" )
			)
			( pin "@baseboard_fab2_lib.baseboard_fab2(sch_1):page188_i133:b"
				( attribute "PN" "2"
					( Origin gPackager )
				)
				( objectStatus "R1W44.2" )
			)
			( pin "@baseboard_fab2_lib.baseboard_fab2(sch_1):page188_i134:a"
				( attribute "PN" "1"
					( Origin gPackager )
				)
				( objectStatus "R1W45.1" )
			)
			( pin "@baseboard_fab2_lib.baseboard_fab2(sch_1):page188_i134:b"
				( attribute "PN" "2"
					( Origin gPackager )
				)
				( objectStatus "R1W45.2" )
			)
			( pin "@baseboard_fab2_lib.baseboard_fab2(sch_1):page120_i277:a"
				( attribute "PN" "1"
					( Origin gPackager )
				)
				( objectStatus "R7W18.1" )
			)
			( pin "@baseboard_fab2_lib.baseboard_fab2(sch_1):page120_i277:b"
				( attribute "PN" "2"
					( Origin gPackager )
				)
				( objectStatus "R7W18.2" )
			)
			( pin "@baseboard_fab2_lib.baseboard_fab2(sch_1):page200_i252:a"
				( attribute "PN" "1"
					( Origin gPackager )
				)
				( objectStatus "R9P7.1" )
			)
			( pin "@baseboard_fab2_lib.baseboard_fab2(sch_1):page200_i252:b"
				( attribute "PN" "2"
					( Origin gPackager )
				)
				( objectStatus "R9P7.2" )
			)
			( pin "@baseboard_fab2_lib.baseboard_fab2(sch_1):page176_i181:a1"
				( attribute "PN" "1"
					( Origin gPackager )
				)
				( objectStatus "L1M2.1" )
			)
			( pin "@baseboard_fab2_lib.baseboard_fab2(sch_1):page176_i181:a2"
				( attribute "PN" "2"
					( Origin gPackager )
				)
				( objectStatus "L1M2.2" )
			)
			( pin "@baseboard_fab2_lib.baseboard_fab2(sch_1):page176_i181:b1"
				( attribute "PN" "3"
					( Origin gPackager )
				)
				( objectStatus "L1M2.3" )
			)
			( pin "@baseboard_fab2_lib.baseboard_fab2(sch_1):page176_i181:b2"
				( attribute "PN" "4"
					( Origin gPackager )
				)
				( objectStatus "L1M2.4" )
			)
			( pin "@baseboard_fab2_lib.baseboard_fab2(sch_1):page216_i155:f"
				( attribute "PN" "2"
					( Origin gPackager )
				)
				( objectStatus "L7G2.2" )
			)
			( pin "@baseboard_fab2_lib.baseboard_fab2(sch_1):page216_i155:s"
				( attribute "PN" "1"
					( Origin gPackager )
				)
				( objectStatus "L7G2.1" )
			)
			( pin "@baseboard_fab2_lib.baseboard_fab2(sch_1):page200_i253:a"
				( attribute "PN" "1"
					( Origin gPackager )
				)
				( objectStatus "R1D20.1" )
			)
			( pin "@baseboard_fab2_lib.baseboard_fab2(sch_1):page200_i253:b"
				( attribute "PN" "2"
					( Origin gPackager )
				)
				( objectStatus "R1D20.2" )
			)
			( pin "@baseboard_fab2_lib.baseboard_fab2(sch_1):page227_i154:a"
				( attribute "PN" "1"
					( Origin gPackager )
				)
				( objectStatus "R9L9.1" )
			)
			( pin "@baseboard_fab2_lib.baseboard_fab2(sch_1):page227_i154:b"
				( attribute "PN" "2"
					( Origin gPackager )
				)
				( objectStatus "R9L9.2" )
			)
			( pin "@baseboard_fab2_lib.baseboard_fab2(sch_1):page227_i155:a"
				( attribute "PN" "1"
					( Origin gPackager )
				)
				( objectStatus "R9L4.1" )
			)
			( pin "@baseboard_fab2_lib.baseboard_fab2(sch_1):page227_i155:b"
				( attribute "PN" "2"
					( Origin gPackager )
				)
				( objectStatus "R9L4.2" )
			)
			( pin "@baseboard_fab2_lib.baseboard_fab2(sch_1):page118_i178:a"
				( attribute "PN" "1"
					( Origin gPackager )
				)
				( objectStatus "C8C1.1" )
			)
			( pin "@baseboard_fab2_lib.baseboard_fab2(sch_1):page118_i178:b"
				( attribute "PN" "2"
					( Origin gPackager )
				)
				( objectStatus "C8C1.2" )
			)
			( pin "@baseboard_fab2_lib.baseboard_fab2(sch_1):page118_i179:a"
				( attribute "PN" "1"
					( Origin gPackager )
				)
				( objectStatus "C8C2.1" )
			)
			( pin "@baseboard_fab2_lib.baseboard_fab2(sch_1):page118_i179:b"
				( attribute "PN" "2"
					( Origin gPackager )
				)
				( objectStatus "C8C2.2" )
			)
			( pin "@baseboard_fab2_lib.baseboard_fab2(sch_1):page181_i137:a"
				( attribute "PN" "1"
					( Origin gPackager )
				)
				( objectStatus "R9T8.1" )
			)
			( pin "@baseboard_fab2_lib.baseboard_fab2(sch_1):page181_i137:b"
				( attribute "PN" "2"
					( Origin gPackager )
				)
				( objectStatus "R9T8.2" )
			)
			( pin "@baseboard_fab2_lib.baseboard_fab2(sch_1):page269_i79:a"
				( attribute "PN" "1"
					( Origin gPackager )
				)
				( objectStatus "C25W101.1" )
			)
			( pin "@baseboard_fab2_lib.baseboard_fab2(sch_1):page269_i79:b"
				( attribute "PN" "2"
					( Origin gPackager )
				)
				( objectStatus "C25W101.2" )
			)
			( pin "@baseboard_fab2_lib.baseboard_fab2(sch_1):page245_i56:a"
				( attribute "PN" "1"
					( Origin gPackager )
				)
				( objectStatus "R8W10.1" )
			)
			( pin "@baseboard_fab2_lib.baseboard_fab2(sch_1):page245_i56:b"
				( attribute "PN" "2"
					( Origin gPackager )
				)
				( objectStatus "R8W10.2" )
			)
			( pin "@baseboard_fab2_lib.baseboard_fab2(sch_1):page245_i57:a"
				( attribute "PN" "1"
					( Origin gPackager )
				)
				( objectStatus "R8W11.1" )
			)
			( pin "@baseboard_fab2_lib.baseboard_fab2(sch_1):page245_i57:b"
				( attribute "PN" "2"
					( Origin gPackager )
				)
				( objectStatus "R8W11.2" )
			)
			( pin "@baseboard_fab2_lib.baseboard_fab2(sch_1):page245_i58:a"
				( attribute "PN" "1"
					( Origin gPackager )
				)
				( objectStatus "R8W12.1" )
			)
			( pin "@baseboard_fab2_lib.baseboard_fab2(sch_1):page245_i58:b"
				( attribute "PN" "2"
					( Origin gPackager )
				)
				( objectStatus "R8W12.2" )
			)
			( pin "@baseboard_fab2_lib.baseboard_fab2(sch_1):page245_i59:a"
				( attribute "PN" "1"
					( Origin gPackager )
				)
				( objectStatus "R8W13.1" )
			)
			( pin "@baseboard_fab2_lib.baseboard_fab2(sch_1):page245_i59:b"
				( attribute "PN" "2"
					( Origin gPackager )
				)
				( objectStatus "R8W13.2" )
			)
			( pin "@baseboard_fab2_lib.baseboard_fab2(sch_1):page245_i60:a"
				( attribute "PN" "1"
					( Origin gPackager )
				)
				( objectStatus "R8W14.1" )
			)
			( pin "@baseboard_fab2_lib.baseboard_fab2(sch_1):page245_i60:b"
				( attribute "PN" "2"
					( Origin gPackager )
				)
				( objectStatus "R8W14.2" )
			)
			( pin "@baseboard_fab2_lib.baseboard_fab2(sch_1):page245_i64:a"
				( attribute "PN" "2"
					( Origin gPackager )
				)
				( objectStatus "U8W1.2" )
			)
			( pin "@baseboard_fab2_lib.baseboard_fab2(sch_1):page245_i64:b"
				( attribute "PN" "4"
					( Origin gPackager )
				)
				( objectStatus "U8W1.4" )
			)
			( pin "@baseboard_fab2_lib.baseboard_fab2(sch_1):page245_i64:oe_n"
				( attribute "PN" "1"
					( Origin gPackager )
				)
				( objectStatus "U8W1.1" )
			)
			( pin "@baseboard_fab2_lib.baseboard_fab2(sch_1):page245_i66:a"
				( attribute "PN" "4"
					( Origin gPackager )
				)
				( objectStatus "U8W2.4" )
			)
			( pin "@baseboard_fab2_lib.baseboard_fab2(sch_1):page245_i66:b0"
				( attribute "PN" "3"
					( Origin gPackager )
				)
				( objectStatus "U8W2.3" )
			)
			( pin "@baseboard_fab2_lib.baseboard_fab2(sch_1):page245_i66:b1"
				( attribute "PN" "1"
					( Origin gPackager )
				)
				( objectStatus "U8W2.1" )
			)
			( pin "@baseboard_fab2_lib.baseboard_fab2(sch_1):page245_i66:gnd"
				( attribute "PN" "2"
					( Origin gPackager )
				)
				( objectStatus "U8W2.2" )
			)
			( pin "@baseboard_fab2_lib.baseboard_fab2(sch_1):page245_i66:s"
				( attribute "PN" "6"
					( Origin gPackager )
				)
				( objectStatus "U8W2.6" )
			)
			( pin "@baseboard_fab2_lib.baseboard_fab2(sch_1):page245_i66:vcc"
				( attribute "PN" "5"
					( Origin gPackager )
				)
				( objectStatus "U8W2.5" )
			)
			( pin "@baseboard_fab2_lib.baseboard_fab2(sch_1):page245_i71:a"
				( attribute "PN" "1"
					( Origin gPackager )
				)
				( objectStatus "C8W6.1" )
			)
			( pin "@baseboard_fab2_lib.baseboard_fab2(sch_1):page245_i71:b"
				( attribute "PN" "2"
					( Origin gPackager )
				)
				( objectStatus "C8W6.2" )
			)
			( pin "@baseboard_fab2_lib.baseboard_fab2(sch_1):page245_i74:a"
				( attribute "PN" "1"
					( Origin gPackager )
				)
				( objectStatus "C8W5.1" )
			)
			( pin "@baseboard_fab2_lib.baseboard_fab2(sch_1):page245_i74:b"
				( attribute "PN" "2"
					( Origin gPackager )
				)
				( objectStatus "C8W5.2" )
			)
			( pin "@baseboard_fab2_lib.baseboard_fab2(sch_1):page245_i78:a"
				( attribute "PN" "1"
					( Origin gPackager )
				)
				( objectStatus "R8W15.1" )
			)
			( pin "@baseboard_fab2_lib.baseboard_fab2(sch_1):page245_i78:b"
				( attribute "PN" "2"
					( Origin gPackager )
				)
				( objectStatus "R8W15.2" )
			)
			( pin "@baseboard_fab2_lib.baseboard_fab2(sch_1):page118_i180:a"
				( attribute "PN" "1"
					( Origin gPackager )
				)
				( objectStatus "R7W19.1" )
			)
			( pin "@baseboard_fab2_lib.baseboard_fab2(sch_1):page118_i180:b"
				( attribute "PN" "2"
					( Origin gPackager )
				)
				( objectStatus "R7W19.2" )
			)
			( pin "@baseboard_fab2_lib.baseboard_fab2(sch_1):page120_i278:a"
				( attribute "PN" "1"
					( Origin gPackager )
				)
				( objectStatus "R7W20.1" )
			)
			( pin "@baseboard_fab2_lib.baseboard_fab2(sch_1):page120_i278:b"
				( attribute "PN" "2"
					( Origin gPackager )
				)
				( objectStatus "R7W20.2" )
			)
			( pin "@baseboard_fab2_lib.baseboard_fab2(sch_1):page164_i100:a"
				( attribute "PN" "1"
					( Origin gPackager )
				)
				( objectStatus "R1T4.1" )
			)
			( pin "@baseboard_fab2_lib.baseboard_fab2(sch_1):page164_i100:b"
				( attribute "PN" "2"
					( Origin gPackager )
				)
				( objectStatus "R1T4.2" )
			)
			( pin "@baseboard_fab2_lib.baseboard_fab2(sch_1):page150_i241:a"
				( attribute "PN" "1"
					( Origin gPackager )
				)
				( objectStatus "R25W101.1" )
			)
			( pin "@baseboard_fab2_lib.baseboard_fab2(sch_1):page150_i241:b"
				( attribute "PN" "2"
					( Origin gPackager )
				)
				( objectStatus "R25W101.2" )
			)
			( pin "@baseboard_fab2_lib.baseboard_fab2(sch_1):page176_i182:a"
				( attribute "PN" "4"
					( Origin gPackager )
				)
				( objectStatus "U6W12.4" )
			)
			( pin "@baseboard_fab2_lib.baseboard_fab2(sch_1):page176_i182:b0"
				( attribute "PN" "3"
					( Origin gPackager )
				)
				( objectStatus "U6W12.3" )
			)
			( pin "@baseboard_fab2_lib.baseboard_fab2(sch_1):page176_i182:b1"
				( attribute "PN" "1"
					( Origin gPackager )
				)
				( objectStatus "U6W12.1" )
			)
			( pin "@baseboard_fab2_lib.baseboard_fab2(sch_1):page176_i182:gnd"
				( attribute "PN" "2"
					( Origin gPackager )
				)
				( objectStatus "U6W12.2" )
			)
			( pin "@baseboard_fab2_lib.baseboard_fab2(sch_1):page176_i182:s"
				( attribute "PN" "6"
					( Origin gPackager )
				)
				( objectStatus "U6W12.6" )
			)
			( pin "@baseboard_fab2_lib.baseboard_fab2(sch_1):page176_i182:vcc"
				( attribute "PN" "5"
					( Origin gPackager )
				)
				( objectStatus "U6W12.5" )
			)
			( pin "@baseboard_fab2_lib.baseboard_fab2(sch_1):page253_i44:\1\"
				( attribute "PN" "1"
					( Origin gPackager )
				)
				( objectStatus "F30W1.1" )
			)
			( pin "@baseboard_fab2_lib.baseboard_fab2(sch_1):page253_i44:\2\"
				( attribute "PN" "2"
					( Origin gPackager )
				)
				( objectStatus "F30W1.2" )
			)
			( pin "@baseboard_fab2_lib.baseboard_fab2(sch_1):page119_i230:a"
				( attribute "PN" "1"
					( Origin gPackager )
				)
				( objectStatus "R7W22.1" )
			)
			( pin "@baseboard_fab2_lib.baseboard_fab2(sch_1):page119_i230:b"
				( attribute "PN" "2"
					( Origin gPackager )
				)
				( objectStatus "R7W22.2" )
			)
			( pin "@baseboard_fab2_lib.baseboard_fab2(sch_1):page118_i183:a"
				( attribute "PN" "1"
					( Origin gPackager )
				)
				( objectStatus "R7W21.1" )
			)
			( pin "@baseboard_fab2_lib.baseboard_fab2(sch_1):page118_i183:b"
				( attribute "PN" "2"
					( Origin gPackager )
				)
				( objectStatus "R7W21.2" )
			)
			( pin "@baseboard_fab2_lib.baseboard_fab2(sch_1):page150_i242:a"
				( attribute "PN" "1"
					( Origin gPackager )
				)
				( objectStatus "R25W115.1" )
			)
			( pin "@baseboard_fab2_lib.baseboard_fab2(sch_1):page150_i242:b"
				( attribute "PN" "2"
					( Origin gPackager )
				)
				( objectStatus "R25W115.2" )
			)
			( pin "@baseboard_fab2_lib.baseboard_fab2(sch_1):page102_i115:a"
				( attribute "PN" "1"
					( Origin gPackager )
				)
				( objectStatus "R6P48.1" )
			)
			( pin "@baseboard_fab2_lib.baseboard_fab2(sch_1):page102_i115:b"
				( attribute "PN" "2"
					( Origin gPackager )
				)
				( objectStatus "R6P48.2" )
			)
			( bus "@baseboard_fab2_lib.baseboard_fab2(sch_1):m_a_ba"
				( memberType ( signal ) )
				( member ( signalRef "@baseboard_fab2_lib.baseboard_fab2(sch_1):m_a_ba(0)") )
				( member ( signalRef "@baseboard_fab2_lib.baseboard_fab2(sch_1):m_a_ba(1)") )
				( objectStatus "M_A_BA" )
			)
			( bus "@baseboard_fab2_lib.baseboard_fab2(sch_1):m_a_bg"
				( memberType ( signal ) )
				( member ( signalRef "@baseboard_fab2_lib.baseboard_fab2(sch_1):m_a_bg(0)") )
				( member ( signalRef "@baseboard_fab2_lib.baseboard_fab2(sch_1):m_a_bg(1)") )
				( objectStatus "M_A_BG" )
			)
			( bus "@baseboard_fab2_lib.baseboard_fab2(sch_1):m_a_c"
				( memberType ( signal ) )
				( member ( signalRef "@baseboard_fab2_lib.baseboard_fab2(sch_1):m_a_c(2)") )
				( objectStatus "M_A_C" )
			)
			( bus "@baseboard_fab2_lib.baseboard_fab2(sch_1):m_a_cke"
				( memberType ( signal ) )
				( member ( signalRef "@baseboard_fab2_lib.baseboard_fab2(sch_1):m_a_cke(0)") )
				( member ( signalRef "@baseboard_fab2_lib.baseboard_fab2(sch_1):m_a_cke(1)") )
				( member ( signalRef "@baseboard_fab2_lib.baseboard_fab2(sch_1):m_a_cke(2)") )
				( member ( signalRef "@baseboard_fab2_lib.baseboard_fab2(sch_1):m_a_cke(3)") )
				( objectStatus "M_A_CKE" )
			)
			( bus "@baseboard_fab2_lib.baseboard_fab2(sch_1):m_a_clk_dn"
				( memberType ( signal ) )
				( member ( signalRef "@baseboard_fab2_lib.baseboard_fab2(sch_1):m_a_clk_dn(0)") )
				( member ( signalRef "@baseboard_fab2_lib.baseboard_fab2(sch_1):m_a_clk_dn(1)") )
				( member ( signalRef "@baseboard_fab2_lib.baseboard_fab2(sch_1):m_a_clk_dn(2)") )
				( member ( signalRef "@baseboard_fab2_lib.baseboard_fab2(sch_1):m_a_clk_dn(3)") )
				( objectStatus "M_A_CLK_DN" )
			)
			( bus "@baseboard_fab2_lib.baseboard_fab2(sch_1):m_a_clk_dp"
				( memberType ( signal ) )
				( member ( signalRef "@baseboard_fab2_lib.baseboard_fab2(sch_1):m_a_clk_dp(0)") )
				( member ( signalRef "@baseboard_fab2_lib.baseboard_fab2(sch_1):m_a_clk_dp(1)") )
				( member ( signalRef "@baseboard_fab2_lib.baseboard_fab2(sch_1):m_a_clk_dp(2)") )
				( member ( signalRef "@baseboard_fab2_lib.baseboard_fab2(sch_1):m_a_clk_dp(3)") )
				( objectStatus "M_A_CLK_DP" )
			)
			( bus "@baseboard_fab2_lib.baseboard_fab2(sch_1):m_a_cs_n"
				( memberType ( signal ) )
				( member ( signalRef "@baseboard_fab2_lib.baseboard_fab2(sch_1):m_a_cs_n(0)") )
				( member ( signalRef "@baseboard_fab2_lib.baseboard_fab2(sch_1):m_a_cs_n(1)") )
				( member ( signalRef "@baseboard_fab2_lib.baseboard_fab2(sch_1):m_a_cs_n(2)") )
				( member ( signalRef "@baseboard_fab2_lib.baseboard_fab2(sch_1):m_a_cs_n(3)") )
				( member ( signalRef "@baseboard_fab2_lib.baseboard_fab2(sch_1):m_a_cs_n(4)") )
				( member ( signalRef "@baseboard_fab2_lib.baseboard_fab2(sch_1):m_a_cs_n(5)") )
				( member ( signalRef "@baseboard_fab2_lib.baseboard_fab2(sch_1):m_a_cs_n(6)") )
				( member ( signalRef "@baseboard_fab2_lib.baseboard_fab2(sch_1):m_a_cs_n(7)") )
				( objectStatus "M_A_CS_N" )
			)
			( bus "@baseboard_fab2_lib.baseboard_fab2(sch_1):m_a_dq"
				( memberType ( signal ) )
				( member ( signalRef "@baseboard_fab2_lib.baseboard_fab2(sch_1):m_a_dq(0)") )
				( member ( signalRef "@baseboard_fab2_lib.baseboard_fab2(sch_1):m_a_dq(1)") )
				( member ( signalRef "@baseboard_fab2_lib.baseboard_fab2(sch_1):m_a_dq(2)") )
				( member ( signalRef "@baseboard_fab2_lib.baseboard_fab2(sch_1):m_a_dq(3)") )
				( member ( signalRef "@baseboard_fab2_lib.baseboard_fab2(sch_1):m_a_dq(4)") )
				( member ( signalRef "@baseboard_fab2_lib.baseboard_fab2(sch_1):m_a_dq(5)") )
				( member ( signalRef "@baseboard_fab2_lib.baseboard_fab2(sch_1):m_a_dq(6)") )
				( member ( signalRef "@baseboard_fab2_lib.baseboard_fab2(sch_1):m_a_dq(7)") )
				( member ( signalRef "@baseboard_fab2_lib.baseboard_fab2(sch_1):m_a_dq(8)") )
				( member ( signalRef "@baseboard_fab2_lib.baseboard_fab2(sch_1):m_a_dq(9)") )
				( member ( signalRef "@baseboard_fab2_lib.baseboard_fab2(sch_1):m_a_dq(10)") )
				( member ( signalRef "@baseboard_fab2_lib.baseboard_fab2(sch_1):m_a_dq(11)") )
				( member ( signalRef "@baseboard_fab2_lib.baseboard_fab2(sch_1):m_a_dq(12)") )
				( member ( signalRef "@baseboard_fab2_lib.baseboard_fab2(sch_1):m_a_dq(13)") )
				( member ( signalRef "@baseboard_fab2_lib.baseboard_fab2(sch_1):m_a_dq(14)") )
				( member ( signalRef "@baseboard_fab2_lib.baseboard_fab2(sch_1):m_a_dq(15)") )
				( member ( signalRef "@baseboard_fab2_lib.baseboard_fab2(sch_1):m_a_dq(16)") )
				( member ( signalRef "@baseboard_fab2_lib.baseboard_fab2(sch_1):m_a_dq(17)") )
				( member ( signalRef "@baseboard_fab2_lib.baseboard_fab2(sch_1):m_a_dq(18)") )
				( member ( signalRef "@baseboard_fab2_lib.baseboard_fab2(sch_1):m_a_dq(19)") )
				( member ( signalRef "@baseboard_fab2_lib.baseboard_fab2(sch_1):m_a_dq(20)") )
				( member ( signalRef "@baseboard_fab2_lib.baseboard_fab2(sch_1):m_a_dq(21)") )
				( member ( signalRef "@baseboard_fab2_lib.baseboard_fab2(sch_1):m_a_dq(22)") )
				( member ( signalRef "@baseboard_fab2_lib.baseboard_fab2(sch_1):m_a_dq(23)") )
				( member ( signalRef "@baseboard_fab2_lib.baseboard_fab2(sch_1):m_a_dq(24)") )
				( member ( signalRef "@baseboard_fab2_lib.baseboard_fab2(sch_1):m_a_dq(25)") )
				( member ( signalRef "@baseboard_fab2_lib.baseboard_fab2(sch_1):m_a_dq(26)") )
				( member ( signalRef "@baseboard_fab2_lib.baseboard_fab2(sch_1):m_a_dq(27)") )
				( member ( signalRef "@baseboard_fab2_lib.baseboard_fab2(sch_1):m_a_dq(28)") )
				( member ( signalRef "@baseboard_fab2_lib.baseboard_fab2(sch_1):m_a_dq(29)") )
				( member ( signalRef "@baseboard_fab2_lib.baseboard_fab2(sch_1):m_a_dq(30)") )
				( member ( signalRef "@baseboard_fab2_lib.baseboard_fab2(sch_1):m_a_dq(31)") )
				( member ( signalRef "@baseboard_fab2_lib.baseboard_fab2(sch_1):m_a_dq(32)") )
				( member ( signalRef "@baseboard_fab2_lib.baseboard_fab2(sch_1):m_a_dq(33)") )
				( member ( signalRef "@baseboard_fab2_lib.baseboard_fab2(sch_1):m_a_dq(34)") )
				( member ( signalRef "@baseboard_fab2_lib.baseboard_fab2(sch_1):m_a_dq(35)") )
				( member ( signalRef "@baseboard_fab2_lib.baseboard_fab2(sch_1):m_a_dq(36)") )
				( member ( signalRef "@baseboard_fab2_lib.baseboard_fab2(sch_1):m_a_dq(37)") )
				( member ( signalRef "@baseboard_fab2_lib.baseboard_fab2(sch_1):m_a_dq(38)") )
				( member ( signalRef "@baseboard_fab2_lib.baseboard_fab2(sch_1):m_a_dq(39)") )
				( member ( signalRef "@baseboard_fab2_lib.baseboard_fab2(sch_1):m_a_dq(40)") )
				( member ( signalRef "@baseboard_fab2_lib.baseboard_fab2(sch_1):m_a_dq(41)") )
				( member ( signalRef "@baseboard_fab2_lib.baseboard_fab2(sch_1):m_a_dq(42)") )
				( member ( signalRef "@baseboard_fab2_lib.baseboard_fab2(sch_1):m_a_dq(43)") )
				( member ( signalRef "@baseboard_fab2_lib.baseboard_fab2(sch_1):m_a_dq(44)") )
				( member ( signalRef "@baseboard_fab2_lib.baseboard_fab2(sch_1):m_a_dq(45)") )
				( member ( signalRef "@baseboard_fab2_lib.baseboard_fab2(sch_1):m_a_dq(46)") )
				( member ( signalRef "@baseboard_fab2_lib.baseboard_fab2(sch_1):m_a_dq(47)") )
				( member ( signalRef "@baseboard_fab2_lib.baseboard_fab2(sch_1):m_a_dq(48)") )
				( member ( signalRef "@baseboard_fab2_lib.baseboard_fab2(sch_1):m_a_dq(49)") )
				( member ( signalRef "@baseboard_fab2_lib.baseboard_fab2(sch_1):m_a_dq(50)") )
				( member ( signalRef "@baseboard_fab2_lib.baseboard_fab2(sch_1):m_a_dq(51)") )
				( member ( signalRef "@baseboard_fab2_lib.baseboard_fab2(sch_1):m_a_dq(52)") )
				( member ( signalRef "@baseboard_fab2_lib.baseboard_fab2(sch_1):m_a_dq(53)") )
				( member ( signalRef "@baseboard_fab2_lib.baseboard_fab2(sch_1):m_a_dq(54)") )
				( member ( signalRef "@baseboard_fab2_lib.baseboard_fab2(sch_1):m_a_dq(55)") )
				( member ( signalRef "@baseboard_fab2_lib.baseboard_fab2(sch_1):m_a_dq(56)") )
				( member ( signalRef "@baseboard_fab2_lib.baseboard_fab2(sch_1):m_a_dq(57)") )
				( member ( signalRef "@baseboard_fab2_lib.baseboard_fab2(sch_1):m_a_dq(58)") )
				( member ( signalRef "@baseboard_fab2_lib.baseboard_fab2(sch_1):m_a_dq(59)") )
				( member ( signalRef "@baseboard_fab2_lib.baseboard_fab2(sch_1):m_a_dq(60)") )
				( member ( signalRef "@baseboard_fab2_lib.baseboard_fab2(sch_1):m_a_dq(61)") )
				( member ( signalRef "@baseboard_fab2_lib.baseboard_fab2(sch_1):m_a_dq(62)") )
				( member ( signalRef "@baseboard_fab2_lib.baseboard_fab2(sch_1):m_a_dq(63)") )
				( objectStatus "M_A_DQ" )
			)
			( bus "@baseboard_fab2_lib.baseboard_fab2(sch_1):m_a_dqs_dn"
				( memberType ( signal ) )
				( member ( signalRef "@baseboard_fab2_lib.baseboard_fab2(sch_1):m_a_dqs_dn(0)") )
				( member ( signalRef "@baseboard_fab2_lib.baseboard_fab2(sch_1):m_a_dqs_dn(1)") )
				( member ( signalRef "@baseboard_fab2_lib.baseboard_fab2(sch_1):m_a_dqs_dn(2)") )
				( member ( signalRef "@baseboard_fab2_lib.baseboard_fab2(sch_1):m_a_dqs_dn(3)") )
				( member ( signalRef "@baseboard_fab2_lib.baseboard_fab2(sch_1):m_a_dqs_dn(4)") )
				( member ( signalRef "@baseboard_fab2_lib.baseboard_fab2(sch_1):m_a_dqs_dn(5)") )
				( member ( signalRef "@baseboard_fab2_lib.baseboard_fab2(sch_1):m_a_dqs_dn(6)") )
				( member ( signalRef "@baseboard_fab2_lib.baseboard_fab2(sch_1):m_a_dqs_dn(7)") )
				( member ( signalRef "@baseboard_fab2_lib.baseboard_fab2(sch_1):m_a_dqs_dn(8)") )
				( member ( signalRef "@baseboard_fab2_lib.baseboard_fab2(sch_1):m_a_dqs_dn(9)") )
				( member ( signalRef "@baseboard_fab2_lib.baseboard_fab2(sch_1):m_a_dqs_dn(10)") )
				( member ( signalRef "@baseboard_fab2_lib.baseboard_fab2(sch_1):m_a_dqs_dn(11)") )
				( member ( signalRef "@baseboard_fab2_lib.baseboard_fab2(sch_1):m_a_dqs_dn(12)") )
				( member ( signalRef "@baseboard_fab2_lib.baseboard_fab2(sch_1):m_a_dqs_dn(13)") )
				( member ( signalRef "@baseboard_fab2_lib.baseboard_fab2(sch_1):m_a_dqs_dn(14)") )
				( member ( signalRef "@baseboard_fab2_lib.baseboard_fab2(sch_1):m_a_dqs_dn(15)") )
				( member ( signalRef "@baseboard_fab2_lib.baseboard_fab2(sch_1):m_a_dqs_dn(16)") )
				( member ( signalRef "@baseboard_fab2_lib.baseboard_fab2(sch_1):m_a_dqs_dn(17)") )
				( objectStatus "M_A_DQS_DN" )
			)
			( bus "@baseboard_fab2_lib.baseboard_fab2(sch_1):m_a_dqs_dp"
				( memberType ( signal ) )
				( member ( signalRef "@baseboard_fab2_lib.baseboard_fab2(sch_1):m_a_dqs_dp(0)") )
				( member ( signalRef "@baseboard_fab2_lib.baseboard_fab2(sch_1):m_a_dqs_dp(1)") )
				( member ( signalRef "@baseboard_fab2_lib.baseboard_fab2(sch_1):m_a_dqs_dp(2)") )
				( member ( signalRef "@baseboard_fab2_lib.baseboard_fab2(sch_1):m_a_dqs_dp(3)") )
				( member ( signalRef "@baseboard_fab2_lib.baseboard_fab2(sch_1):m_a_dqs_dp(4)") )
				( member ( signalRef "@baseboard_fab2_lib.baseboard_fab2(sch_1):m_a_dqs_dp(5)") )
				( member ( signalRef "@baseboard_fab2_lib.baseboard_fab2(sch_1):m_a_dqs_dp(6)") )
				( member ( signalRef "@baseboard_fab2_lib.baseboard_fab2(sch_1):m_a_dqs_dp(7)") )
				( member ( signalRef "@baseboard_fab2_lib.baseboard_fab2(sch_1):m_a_dqs_dp(8)") )
				( member ( signalRef "@baseboard_fab2_lib.baseboard_fab2(sch_1):m_a_dqs_dp(9)") )
				( member ( signalRef "@baseboard_fab2_lib.baseboard_fab2(sch_1):m_a_dqs_dp(10)") )
				( member ( signalRef "@baseboard_fab2_lib.baseboard_fab2(sch_1):m_a_dqs_dp(11)") )
				( member ( signalRef "@baseboard_fab2_lib.baseboard_fab2(sch_1):m_a_dqs_dp(12)") )
				( member ( signalRef "@baseboard_fab2_lib.baseboard_fab2(sch_1):m_a_dqs_dp(13)") )
				( member ( signalRef "@baseboard_fab2_lib.baseboard_fab2(sch_1):m_a_dqs_dp(14)") )
				( member ( signalRef "@baseboard_fab2_lib.baseboard_fab2(sch_1):m_a_dqs_dp(15)") )
				( member ( signalRef "@baseboard_fab2_lib.baseboard_fab2(sch_1):m_a_dqs_dp(16)") )
				( member ( signalRef "@baseboard_fab2_lib.baseboard_fab2(sch_1):m_a_dqs_dp(17)") )
				( objectStatus "M_A_DQS_DP" )
			)
			( bus "@baseboard_fab2_lib.baseboard_fab2(sch_1):m_a_ecc"
				( memberType ( signal ) )
				( member ( signalRef "@baseboard_fab2_lib.baseboard_fab2(sch_1):m_a_ecc(0)") )
				( member ( signalRef "@baseboard_fab2_lib.baseboard_fab2(sch_1):m_a_ecc(1)") )
				( member ( signalRef "@baseboard_fab2_lib.baseboard_fab2(sch_1):m_a_ecc(2)") )
				( member ( signalRef "@baseboard_fab2_lib.baseboard_fab2(sch_1):m_a_ecc(3)") )
				( member ( signalRef "@baseboard_fab2_lib.baseboard_fab2(sch_1):m_a_ecc(4)") )
				( member ( signalRef "@baseboard_fab2_lib.baseboard_fab2(sch_1):m_a_ecc(5)") )
				( member ( signalRef "@baseboard_fab2_lib.baseboard_fab2(sch_1):m_a_ecc(6)") )
				( member ( signalRef "@baseboard_fab2_lib.baseboard_fab2(sch_1):m_a_ecc(7)") )
				( objectStatus "M_A_ECC" )
			)
			( bus "@baseboard_fab2_lib.baseboard_fab2(sch_1):m_a_ma"
				( memberType ( signal ) )
				( member ( signalRef "@baseboard_fab2_lib.baseboard_fab2(sch_1):m_a_ma(0)") )
				( member ( signalRef "@baseboard_fab2_lib.baseboard_fab2(sch_1):m_a_ma(1)") )
				( member ( signalRef "@baseboard_fab2_lib.baseboard_fab2(sch_1):m_a_ma(2)") )
				( member ( signalRef "@baseboard_fab2_lib.baseboard_fab2(sch_1):m_a_ma(3)") )
				( member ( signalRef "@baseboard_fab2_lib.baseboard_fab2(sch_1):m_a_ma(4)") )
				( member ( signalRef "@baseboard_fab2_lib.baseboard_fab2(sch_1):m_a_ma(5)") )
				( member ( signalRef "@baseboard_fab2_lib.baseboard_fab2(sch_1):m_a_ma(6)") )
				( member ( signalRef "@baseboard_fab2_lib.baseboard_fab2(sch_1):m_a_ma(7)") )
				( member ( signalRef "@baseboard_fab2_lib.baseboard_fab2(sch_1):m_a_ma(8)") )
				( member ( signalRef "@baseboard_fab2_lib.baseboard_fab2(sch_1):m_a_ma(9)") )
				( member ( signalRef "@baseboard_fab2_lib.baseboard_fab2(sch_1):m_a_ma(10)") )
				( member ( signalRef "@baseboard_fab2_lib.baseboard_fab2(sch_1):m_a_ma(11)") )
				( member ( signalRef "@baseboard_fab2_lib.baseboard_fab2(sch_1):m_a_ma(12)") )
				( member ( signalRef "@baseboard_fab2_lib.baseboard_fab2(sch_1):m_a_ma(13)") )
				( member ( signalRef "@baseboard_fab2_lib.baseboard_fab2(sch_1):m_a_ma(14)") )
				( member ( signalRef "@baseboard_fab2_lib.baseboard_fab2(sch_1):m_a_ma(15)") )
				( member ( signalRef "@baseboard_fab2_lib.baseboard_fab2(sch_1):m_a_ma(16)") )
				( member ( signalRef "@baseboard_fab2_lib.baseboard_fab2(sch_1):m_a_ma(17)") )
				( objectStatus "M_A_MA" )
			)
			( bus "@baseboard_fab2_lib.baseboard_fab2(sch_1):m_a_odt"
				( memberType ( signal ) )
				( member ( signalRef "@baseboard_fab2_lib.baseboard_fab2(sch_1):m_a_odt(0)") )
				( member ( signalRef "@baseboard_fab2_lib.baseboard_fab2(sch_1):m_a_odt(1)") )
				( member ( signalRef "@baseboard_fab2_lib.baseboard_fab2(sch_1):m_a_odt(2)") )
				( member ( signalRef "@baseboard_fab2_lib.baseboard_fab2(sch_1):m_a_odt(3)") )
				( objectStatus "M_A_ODT" )
			)
			( bus "@baseboard_fab2_lib.baseboard_fab2(sch_1):m_b_ba"
				( memberType ( signal ) )
				( member ( signalRef "@baseboard_fab2_lib.baseboard_fab2(sch_1):m_b_ba(0)") )
				( member ( signalRef "@baseboard_fab2_lib.baseboard_fab2(sch_1):m_b_ba(1)") )
				( objectStatus "M_B_BA" )
			)
			( bus "@baseboard_fab2_lib.baseboard_fab2(sch_1):m_b_bg"
				( memberType ( signal ) )
				( member ( signalRef "@baseboard_fab2_lib.baseboard_fab2(sch_1):m_b_bg(0)") )
				( member ( signalRef "@baseboard_fab2_lib.baseboard_fab2(sch_1):m_b_bg(1)") )
				( objectStatus "M_B_BG" )
			)
			( bus "@baseboard_fab2_lib.baseboard_fab2(sch_1):m_b_c"
				( memberType ( signal ) )
				( member ( signalRef "@baseboard_fab2_lib.baseboard_fab2(sch_1):m_b_c(2)") )
				( objectStatus "M_B_C" )
			)
			( bus "@baseboard_fab2_lib.baseboard_fab2(sch_1):m_b_cke"
				( memberType ( signal ) )
				( member ( signalRef "@baseboard_fab2_lib.baseboard_fab2(sch_1):m_b_cke(0)") )
				( member ( signalRef "@baseboard_fab2_lib.baseboard_fab2(sch_1):m_b_cke(1)") )
				( member ( signalRef "@baseboard_fab2_lib.baseboard_fab2(sch_1):m_b_cke(2)") )
				( member ( signalRef "@baseboard_fab2_lib.baseboard_fab2(sch_1):m_b_cke(3)") )
				( objectStatus "M_B_CKE" )
			)
			( bus "@baseboard_fab2_lib.baseboard_fab2(sch_1):m_b_clk_dn"
				( memberType ( signal ) )
				( member ( signalRef "@baseboard_fab2_lib.baseboard_fab2(sch_1):m_b_clk_dn(0)") )
				( member ( signalRef "@baseboard_fab2_lib.baseboard_fab2(sch_1):m_b_clk_dn(1)") )
				( member ( signalRef "@baseboard_fab2_lib.baseboard_fab2(sch_1):m_b_clk_dn(2)") )
				( member ( signalRef "@baseboard_fab2_lib.baseboard_fab2(sch_1):m_b_clk_dn(3)") )
				( objectStatus "M_B_CLK_DN" )
			)
			( bus "@baseboard_fab2_lib.baseboard_fab2(sch_1):m_b_clk_dp"
				( memberType ( signal ) )
				( member ( signalRef "@baseboard_fab2_lib.baseboard_fab2(sch_1):m_b_clk_dp(0)") )
				( member ( signalRef "@baseboard_fab2_lib.baseboard_fab2(sch_1):m_b_clk_dp(1)") )
				( member ( signalRef "@baseboard_fab2_lib.baseboard_fab2(sch_1):m_b_clk_dp(2)") )
				( member ( signalRef "@baseboard_fab2_lib.baseboard_fab2(sch_1):m_b_clk_dp(3)") )
				( objectStatus "M_B_CLK_DP" )
			)
			( bus "@baseboard_fab2_lib.baseboard_fab2(sch_1):m_b_cs_n"
				( memberType ( signal ) )
				( member ( signalRef "@baseboard_fab2_lib.baseboard_fab2(sch_1):m_b_cs_n(0)") )
				( member ( signalRef "@baseboard_fab2_lib.baseboard_fab2(sch_1):m_b_cs_n(1)") )
				( member ( signalRef "@baseboard_fab2_lib.baseboard_fab2(sch_1):m_b_cs_n(2)") )
				( member ( signalRef "@baseboard_fab2_lib.baseboard_fab2(sch_1):m_b_cs_n(3)") )
				( member ( signalRef "@baseboard_fab2_lib.baseboard_fab2(sch_1):m_b_cs_n(4)") )
				( member ( signalRef "@baseboard_fab2_lib.baseboard_fab2(sch_1):m_b_cs_n(5)") )
				( member ( signalRef "@baseboard_fab2_lib.baseboard_fab2(sch_1):m_b_cs_n(6)") )
				( member ( signalRef "@baseboard_fab2_lib.baseboard_fab2(sch_1):m_b_cs_n(7)") )
				( objectStatus "M_B_CS_N" )
			)
			( bus "@baseboard_fab2_lib.baseboard_fab2(sch_1):m_b_dq"
				( memberType ( signal ) )
				( member ( signalRef "@baseboard_fab2_lib.baseboard_fab2(sch_1):m_b_dq(0)") )
				( member ( signalRef "@baseboard_fab2_lib.baseboard_fab2(sch_1):m_b_dq(1)") )
				( member ( signalRef "@baseboard_fab2_lib.baseboard_fab2(sch_1):m_b_dq(2)") )
				( member ( signalRef "@baseboard_fab2_lib.baseboard_fab2(sch_1):m_b_dq(3)") )
				( member ( signalRef "@baseboard_fab2_lib.baseboard_fab2(sch_1):m_b_dq(4)") )
				( member ( signalRef "@baseboard_fab2_lib.baseboard_fab2(sch_1):m_b_dq(5)") )
				( member ( signalRef "@baseboard_fab2_lib.baseboard_fab2(sch_1):m_b_dq(6)") )
				( member ( signalRef "@baseboard_fab2_lib.baseboard_fab2(sch_1):m_b_dq(7)") )
				( member ( signalRef "@baseboard_fab2_lib.baseboard_fab2(sch_1):m_b_dq(8)") )
				( member ( signalRef "@baseboard_fab2_lib.baseboard_fab2(sch_1):m_b_dq(9)") )
				( member ( signalRef "@baseboard_fab2_lib.baseboard_fab2(sch_1):m_b_dq(10)") )
				( member ( signalRef "@baseboard_fab2_lib.baseboard_fab2(sch_1):m_b_dq(11)") )
				( member ( signalRef "@baseboard_fab2_lib.baseboard_fab2(sch_1):m_b_dq(12)") )
				( member ( signalRef "@baseboard_fab2_lib.baseboard_fab2(sch_1):m_b_dq(13)") )
				( member ( signalRef "@baseboard_fab2_lib.baseboard_fab2(sch_1):m_b_dq(14)") )
				( member ( signalRef "@baseboard_fab2_lib.baseboard_fab2(sch_1):m_b_dq(15)") )
				( member ( signalRef "@baseboard_fab2_lib.baseboard_fab2(sch_1):m_b_dq(16)") )
				( member ( signalRef "@baseboard_fab2_lib.baseboard_fab2(sch_1):m_b_dq(17)") )
				( member ( signalRef "@baseboard_fab2_lib.baseboard_fab2(sch_1):m_b_dq(18)") )
				( member ( signalRef "@baseboard_fab2_lib.baseboard_fab2(sch_1):m_b_dq(19)") )
				( member ( signalRef "@baseboard_fab2_lib.baseboard_fab2(sch_1):m_b_dq(20)") )
				( member ( signalRef "@baseboard_fab2_lib.baseboard_fab2(sch_1):m_b_dq(21)") )
				( member ( signalRef "@baseboard_fab2_lib.baseboard_fab2(sch_1):m_b_dq(22)") )
				( member ( signalRef "@baseboard_fab2_lib.baseboard_fab2(sch_1):m_b_dq(23)") )
				( member ( signalRef "@baseboard_fab2_lib.baseboard_fab2(sch_1):m_b_dq(24)") )
				( member ( signalRef "@baseboard_fab2_lib.baseboard_fab2(sch_1):m_b_dq(25)") )
				( member ( signalRef "@baseboard_fab2_lib.baseboard_fab2(sch_1):m_b_dq(26)") )
				( member ( signalRef "@baseboard_fab2_lib.baseboard_fab2(sch_1):m_b_dq(27)") )
				( member ( signalRef "@baseboard_fab2_lib.baseboard_fab2(sch_1):m_b_dq(28)") )
				( member ( signalRef "@baseboard_fab2_lib.baseboard_fab2(sch_1):m_b_dq(29)") )
				( member ( signalRef "@baseboard_fab2_lib.baseboard_fab2(sch_1):m_b_dq(30)") )
				( member ( signalRef "@baseboard_fab2_lib.baseboard_fab2(sch_1):m_b_dq(31)") )
				( member ( signalRef "@baseboard_fab2_lib.baseboard_fab2(sch_1):m_b_dq(32)") )
				( member ( signalRef "@baseboard_fab2_lib.baseboard_fab2(sch_1):m_b_dq(33)") )
				( member ( signalRef "@baseboard_fab2_lib.baseboard_fab2(sch_1):m_b_dq(34)") )
				( member ( signalRef "@baseboard_fab2_lib.baseboard_fab2(sch_1):m_b_dq(35)") )
				( member ( signalRef "@baseboard_fab2_lib.baseboard_fab2(sch_1):m_b_dq(36)") )
				( member ( signalRef "@baseboard_fab2_lib.baseboard_fab2(sch_1):m_b_dq(37)") )
				( member ( signalRef "@baseboard_fab2_lib.baseboard_fab2(sch_1):m_b_dq(38)") )
				( member ( signalRef "@baseboard_fab2_lib.baseboard_fab2(sch_1):m_b_dq(39)") )
				( member ( signalRef "@baseboard_fab2_lib.baseboard_fab2(sch_1):m_b_dq(40)") )
				( member ( signalRef "@baseboard_fab2_lib.baseboard_fab2(sch_1):m_b_dq(41)") )
				( member ( signalRef "@baseboard_fab2_lib.baseboard_fab2(sch_1):m_b_dq(42)") )
				( member ( signalRef "@baseboard_fab2_lib.baseboard_fab2(sch_1):m_b_dq(43)") )
				( member ( signalRef "@baseboard_fab2_lib.baseboard_fab2(sch_1):m_b_dq(44)") )
				( member ( signalRef "@baseboard_fab2_lib.baseboard_fab2(sch_1):m_b_dq(45)") )
				( member ( signalRef "@baseboard_fab2_lib.baseboard_fab2(sch_1):m_b_dq(46)") )
				( member ( signalRef "@baseboard_fab2_lib.baseboard_fab2(sch_1):m_b_dq(47)") )
				( member ( signalRef "@baseboard_fab2_lib.baseboard_fab2(sch_1):m_b_dq(48)") )
				( member ( signalRef "@baseboard_fab2_lib.baseboard_fab2(sch_1):m_b_dq(49)") )
				( member ( signalRef "@baseboard_fab2_lib.baseboard_fab2(sch_1):m_b_dq(50)") )
				( member ( signalRef "@baseboard_fab2_lib.baseboard_fab2(sch_1):m_b_dq(51)") )
				( member ( signalRef "@baseboard_fab2_lib.baseboard_fab2(sch_1):m_b_dq(52)") )
				( member ( signalRef "@baseboard_fab2_lib.baseboard_fab2(sch_1):m_b_dq(53)") )
				( member ( signalRef "@baseboard_fab2_lib.baseboard_fab2(sch_1):m_b_dq(54)") )
				( member ( signalRef "@baseboard_fab2_lib.baseboard_fab2(sch_1):m_b_dq(55)") )
				( member ( signalRef "@baseboard_fab2_lib.baseboard_fab2(sch_1):m_b_dq(56)") )
				( member ( signalRef "@baseboard_fab2_lib.baseboard_fab2(sch_1):m_b_dq(57)") )
				( member ( signalRef "@baseboard_fab2_lib.baseboard_fab2(sch_1):m_b_dq(58)") )
				( member ( signalRef "@baseboard_fab2_lib.baseboard_fab2(sch_1):m_b_dq(59)") )
				( member ( signalRef "@baseboard_fab2_lib.baseboard_fab2(sch_1):m_b_dq(60)") )
				( member ( signalRef "@baseboard_fab2_lib.baseboard_fab2(sch_1):m_b_dq(61)") )
				( member ( signalRef "@baseboard_fab2_lib.baseboard_fab2(sch_1):m_b_dq(62)") )
				( member ( signalRef "@baseboard_fab2_lib.baseboard_fab2(sch_1):m_b_dq(63)") )
				( objectStatus "M_B_DQ" )
			)
			( bus "@baseboard_fab2_lib.baseboard_fab2(sch_1):m_b_dqs_dn"
				( memberType ( signal ) )
				( member ( signalRef "@baseboard_fab2_lib.baseboard_fab2(sch_1):m_b_dqs_dn(0)") )
				( member ( signalRef "@baseboard_fab2_lib.baseboard_fab2(sch_1):m_b_dqs_dn(1)") )
				( member ( signalRef "@baseboard_fab2_lib.baseboard_fab2(sch_1):m_b_dqs_dn(2)") )
				( member ( signalRef "@baseboard_fab2_lib.baseboard_fab2(sch_1):m_b_dqs_dn(3)") )
				( member ( signalRef "@baseboard_fab2_lib.baseboard_fab2(sch_1):m_b_dqs_dn(4)") )
				( member ( signalRef "@baseboard_fab2_lib.baseboard_fab2(sch_1):m_b_dqs_dn(5)") )
				( member ( signalRef "@baseboard_fab2_lib.baseboard_fab2(sch_1):m_b_dqs_dn(6)") )
				( member ( signalRef "@baseboard_fab2_lib.baseboard_fab2(sch_1):m_b_dqs_dn(7)") )
				( member ( signalRef "@baseboard_fab2_lib.baseboard_fab2(sch_1):m_b_dqs_dn(8)") )
				( member ( signalRef "@baseboard_fab2_lib.baseboard_fab2(sch_1):m_b_dqs_dn(9)") )
				( member ( signalRef "@baseboard_fab2_lib.baseboard_fab2(sch_1):m_b_dqs_dn(10)") )
				( member ( signalRef "@baseboard_fab2_lib.baseboard_fab2(sch_1):m_b_dqs_dn(11)") )
				( member ( signalRef "@baseboard_fab2_lib.baseboard_fab2(sch_1):m_b_dqs_dn(12)") )
				( member ( signalRef "@baseboard_fab2_lib.baseboard_fab2(sch_1):m_b_dqs_dn(13)") )
				( member ( signalRef "@baseboard_fab2_lib.baseboard_fab2(sch_1):m_b_dqs_dn(14)") )
				( member ( signalRef "@baseboard_fab2_lib.baseboard_fab2(sch_1):m_b_dqs_dn(15)") )
				( member ( signalRef "@baseboard_fab2_lib.baseboard_fab2(sch_1):m_b_dqs_dn(16)") )
				( member ( signalRef "@baseboard_fab2_lib.baseboard_fab2(sch_1):m_b_dqs_dn(17)") )
				( objectStatus "M_B_DQS_DN" )
			)
			( bus "@baseboard_fab2_lib.baseboard_fab2(sch_1):m_b_dqs_dp"
				( memberType ( signal ) )
				( member ( signalRef "@baseboard_fab2_lib.baseboard_fab2(sch_1):m_b_dqs_dp(0)") )
				( member ( signalRef "@baseboard_fab2_lib.baseboard_fab2(sch_1):m_b_dqs_dp(1)") )
				( member ( signalRef "@baseboard_fab2_lib.baseboard_fab2(sch_1):m_b_dqs_dp(2)") )
				( member ( signalRef "@baseboard_fab2_lib.baseboard_fab2(sch_1):m_b_dqs_dp(3)") )
				( member ( signalRef "@baseboard_fab2_lib.baseboard_fab2(sch_1):m_b_dqs_dp(4)") )
				( member ( signalRef "@baseboard_fab2_lib.baseboard_fab2(sch_1):m_b_dqs_dp(5)") )
				( member ( signalRef "@baseboard_fab2_lib.baseboard_fab2(sch_1):m_b_dqs_dp(6)") )
				( member ( signalRef "@baseboard_fab2_lib.baseboard_fab2(sch_1):m_b_dqs_dp(7)") )
				( member ( signalRef "@baseboard_fab2_lib.baseboard_fab2(sch_1):m_b_dqs_dp(8)") )
				( member ( signalRef "@baseboard_fab2_lib.baseboard_fab2(sch_1):m_b_dqs_dp(9)") )
				( member ( signalRef "@baseboard_fab2_lib.baseboard_fab2(sch_1):m_b_dqs_dp(10)") )
				( member ( signalRef "@baseboard_fab2_lib.baseboard_fab2(sch_1):m_b_dqs_dp(11)") )
				( member ( signalRef "@baseboard_fab2_lib.baseboard_fab2(sch_1):m_b_dqs_dp(12)") )
				( member ( signalRef "@baseboard_fab2_lib.baseboard_fab2(sch_1):m_b_dqs_dp(13)") )
				( member ( signalRef "@baseboard_fab2_lib.baseboard_fab2(sch_1):m_b_dqs_dp(14)") )
				( member ( signalRef "@baseboard_fab2_lib.baseboard_fab2(sch_1):m_b_dqs_dp(15)") )
				( member ( signalRef "@baseboard_fab2_lib.baseboard_fab2(sch_1):m_b_dqs_dp(16)") )
				( member ( signalRef "@baseboard_fab2_lib.baseboard_fab2(sch_1):m_b_dqs_dp(17)") )
				( objectStatus "M_B_DQS_DP" )
			)
			( bus "@baseboard_fab2_lib.baseboard_fab2(sch_1):m_b_ecc"
				( memberType ( signal ) )
				( member ( signalRef "@baseboard_fab2_lib.baseboard_fab2(sch_1):m_b_ecc(0)") )
				( member ( signalRef "@baseboard_fab2_lib.baseboard_fab2(sch_1):m_b_ecc(1)") )
				( member ( signalRef "@baseboard_fab2_lib.baseboard_fab2(sch_1):m_b_ecc(2)") )
				( member ( signalRef "@baseboard_fab2_lib.baseboard_fab2(sch_1):m_b_ecc(3)") )
				( member ( signalRef "@baseboard_fab2_lib.baseboard_fab2(sch_1):m_b_ecc(4)") )
				( member ( signalRef "@baseboard_fab2_lib.baseboard_fab2(sch_1):m_b_ecc(5)") )
				( member ( signalRef "@baseboard_fab2_lib.baseboard_fab2(sch_1):m_b_ecc(6)") )
				( member ( signalRef "@baseboard_fab2_lib.baseboard_fab2(sch_1):m_b_ecc(7)") )
				( objectStatus "M_B_ECC" )
			)
			( bus "@baseboard_fab2_lib.baseboard_fab2(sch_1):m_b_ma"
				( memberType ( signal ) )
				( member ( signalRef "@baseboard_fab2_lib.baseboard_fab2(sch_1):m_b_ma(0)") )
				( member ( signalRef "@baseboard_fab2_lib.baseboard_fab2(sch_1):m_b_ma(1)") )
				( member ( signalRef "@baseboard_fab2_lib.baseboard_fab2(sch_1):m_b_ma(2)") )
				( member ( signalRef "@baseboard_fab2_lib.baseboard_fab2(sch_1):m_b_ma(3)") )
				( member ( signalRef "@baseboard_fab2_lib.baseboard_fab2(sch_1):m_b_ma(4)") )
				( member ( signalRef "@baseboard_fab2_lib.baseboard_fab2(sch_1):m_b_ma(5)") )
				( member ( signalRef "@baseboard_fab2_lib.baseboard_fab2(sch_1):m_b_ma(6)") )
				( member ( signalRef "@baseboard_fab2_lib.baseboard_fab2(sch_1):m_b_ma(7)") )
				( member ( signalRef "@baseboard_fab2_lib.baseboard_fab2(sch_1):m_b_ma(8)") )
				( member ( signalRef "@baseboard_fab2_lib.baseboard_fab2(sch_1):m_b_ma(9)") )
				( member ( signalRef "@baseboard_fab2_lib.baseboard_fab2(sch_1):m_b_ma(10)") )
				( member ( signalRef "@baseboard_fab2_lib.baseboard_fab2(sch_1):m_b_ma(11)") )
				( member ( signalRef "@baseboard_fab2_lib.baseboard_fab2(sch_1):m_b_ma(12)") )
				( member ( signalRef "@baseboard_fab2_lib.baseboard_fab2(sch_1):m_b_ma(13)") )
				( member ( signalRef "@baseboard_fab2_lib.baseboard_fab2(sch_1):m_b_ma(14)") )
				( member ( signalRef "@baseboard_fab2_lib.baseboard_fab2(sch_1):m_b_ma(15)") )
				( member ( signalRef "@baseboard_fab2_lib.baseboard_fab2(sch_1):m_b_ma(16)") )
				( member ( signalRef "@baseboard_fab2_lib.baseboard_fab2(sch_1):m_b_ma(17)") )
				( objectStatus "M_B_MA" )
			)
			( bus "@baseboard_fab2_lib.baseboard_fab2(sch_1):m_b_odt"
				( memberType ( signal ) )
				( member ( signalRef "@baseboard_fab2_lib.baseboard_fab2(sch_1):m_b_odt(0)") )
				( member ( signalRef "@baseboard_fab2_lib.baseboard_fab2(sch_1):m_b_odt(1)") )
				( member ( signalRef "@baseboard_fab2_lib.baseboard_fab2(sch_1):m_b_odt(2)") )
				( member ( signalRef "@baseboard_fab2_lib.baseboard_fab2(sch_1):m_b_odt(3)") )
				( objectStatus "M_B_ODT" )
			)
			( bus "@baseboard_fab2_lib.baseboard_fab2(sch_1):m_c_ba"
				( memberType ( signal ) )
				( member ( signalRef "@baseboard_fab2_lib.baseboard_fab2(sch_1):m_c_ba(0)") )
				( member ( signalRef "@baseboard_fab2_lib.baseboard_fab2(sch_1):m_c_ba(1)") )
				( objectStatus "M_C_BA" )
			)
			( bus "@baseboard_fab2_lib.baseboard_fab2(sch_1):m_c_bg"
				( memberType ( signal ) )
				( member ( signalRef "@baseboard_fab2_lib.baseboard_fab2(sch_1):m_c_bg(0)") )
				( member ( signalRef "@baseboard_fab2_lib.baseboard_fab2(sch_1):m_c_bg(1)") )
				( objectStatus "M_C_BG" )
			)
			( bus "@baseboard_fab2_lib.baseboard_fab2(sch_1):m_c_c"
				( memberType ( signal ) )
				( member ( signalRef "@baseboard_fab2_lib.baseboard_fab2(sch_1):m_c_c(2)") )
				( objectStatus "M_C_C" )
			)
			( bus "@baseboard_fab2_lib.baseboard_fab2(sch_1):m_c_cke"
				( memberType ( signal ) )
				( member ( signalRef "@baseboard_fab2_lib.baseboard_fab2(sch_1):m_c_cke(0)") )
				( member ( signalRef "@baseboard_fab2_lib.baseboard_fab2(sch_1):m_c_cke(1)") )
				( member ( signalRef "@baseboard_fab2_lib.baseboard_fab2(sch_1):m_c_cke(2)") )
				( member ( signalRef "@baseboard_fab2_lib.baseboard_fab2(sch_1):m_c_cke(3)") )
				( objectStatus "M_C_CKE" )
			)
			( bus "@baseboard_fab2_lib.baseboard_fab2(sch_1):m_c_clk_dn"
				( memberType ( signal ) )
				( member ( signalRef "@baseboard_fab2_lib.baseboard_fab2(sch_1):m_c_clk_dn(0)") )
				( member ( signalRef "@baseboard_fab2_lib.baseboard_fab2(sch_1):m_c_clk_dn(1)") )
				( member ( signalRef "@baseboard_fab2_lib.baseboard_fab2(sch_1):m_c_clk_dn(2)") )
				( member ( signalRef "@baseboard_fab2_lib.baseboard_fab2(sch_1):m_c_clk_dn(3)") )
				( objectStatus "M_C_CLK_DN" )
			)
			( bus "@baseboard_fab2_lib.baseboard_fab2(sch_1):m_c_clk_dp"
				( memberType ( signal ) )
				( member ( signalRef "@baseboard_fab2_lib.baseboard_fab2(sch_1):m_c_clk_dp(0)") )
				( member ( signalRef "@baseboard_fab2_lib.baseboard_fab2(sch_1):m_c_clk_dp(1)") )
				( member ( signalRef "@baseboard_fab2_lib.baseboard_fab2(sch_1):m_c_clk_dp(2)") )
				( member ( signalRef "@baseboard_fab2_lib.baseboard_fab2(sch_1):m_c_clk_dp(3)") )
				( objectStatus "M_C_CLK_DP" )
			)
			( bus "@baseboard_fab2_lib.baseboard_fab2(sch_1):m_c_cs_n"
				( memberType ( signal ) )
				( member ( signalRef "@baseboard_fab2_lib.baseboard_fab2(sch_1):m_c_cs_n(0)") )
				( member ( signalRef "@baseboard_fab2_lib.baseboard_fab2(sch_1):m_c_cs_n(1)") )
				( member ( signalRef "@baseboard_fab2_lib.baseboard_fab2(sch_1):m_c_cs_n(2)") )
				( member ( signalRef "@baseboard_fab2_lib.baseboard_fab2(sch_1):m_c_cs_n(3)") )
				( member ( signalRef "@baseboard_fab2_lib.baseboard_fab2(sch_1):m_c_cs_n(4)") )
				( member ( signalRef "@baseboard_fab2_lib.baseboard_fab2(sch_1):m_c_cs_n(5)") )
				( member ( signalRef "@baseboard_fab2_lib.baseboard_fab2(sch_1):m_c_cs_n(6)") )
				( member ( signalRef "@baseboard_fab2_lib.baseboard_fab2(sch_1):m_c_cs_n(7)") )
				( objectStatus "M_C_CS_N" )
			)
			( bus "@baseboard_fab2_lib.baseboard_fab2(sch_1):m_c_dq"
				( memberType ( signal ) )
				( member ( signalRef "@baseboard_fab2_lib.baseboard_fab2(sch_1):m_c_dq(0)") )
				( member ( signalRef "@baseboard_fab2_lib.baseboard_fab2(sch_1):m_c_dq(1)") )
				( member ( signalRef "@baseboard_fab2_lib.baseboard_fab2(sch_1):m_c_dq(2)") )
				( member ( signalRef "@baseboard_fab2_lib.baseboard_fab2(sch_1):m_c_dq(3)") )
				( member ( signalRef "@baseboard_fab2_lib.baseboard_fab2(sch_1):m_c_dq(4)") )
				( member ( signalRef "@baseboard_fab2_lib.baseboard_fab2(sch_1):m_c_dq(5)") )
				( member ( signalRef "@baseboard_fab2_lib.baseboard_fab2(sch_1):m_c_dq(6)") )
				( member ( signalRef "@baseboard_fab2_lib.baseboard_fab2(sch_1):m_c_dq(7)") )
				( member ( signalRef "@baseboard_fab2_lib.baseboard_fab2(sch_1):m_c_dq(8)") )
				( member ( signalRef "@baseboard_fab2_lib.baseboard_fab2(sch_1):m_c_dq(9)") )
				( member ( signalRef "@baseboard_fab2_lib.baseboard_fab2(sch_1):m_c_dq(10)") )
				( member ( signalRef "@baseboard_fab2_lib.baseboard_fab2(sch_1):m_c_dq(11)") )
				( member ( signalRef "@baseboard_fab2_lib.baseboard_fab2(sch_1):m_c_dq(12)") )
				( member ( signalRef "@baseboard_fab2_lib.baseboard_fab2(sch_1):m_c_dq(13)") )
				( member ( signalRef "@baseboard_fab2_lib.baseboard_fab2(sch_1):m_c_dq(14)") )
				( member ( signalRef "@baseboard_fab2_lib.baseboard_fab2(sch_1):m_c_dq(15)") )
				( member ( signalRef "@baseboard_fab2_lib.baseboard_fab2(sch_1):m_c_dq(16)") )
				( member ( signalRef "@baseboard_fab2_lib.baseboard_fab2(sch_1):m_c_dq(17)") )
				( member ( signalRef "@baseboard_fab2_lib.baseboard_fab2(sch_1):m_c_dq(18)") )
				( member ( signalRef "@baseboard_fab2_lib.baseboard_fab2(sch_1):m_c_dq(19)") )
				( member ( signalRef "@baseboard_fab2_lib.baseboard_fab2(sch_1):m_c_dq(20)") )
				( member ( signalRef "@baseboard_fab2_lib.baseboard_fab2(sch_1):m_c_dq(21)") )
				( member ( signalRef "@baseboard_fab2_lib.baseboard_fab2(sch_1):m_c_dq(22)") )
				( member ( signalRef "@baseboard_fab2_lib.baseboard_fab2(sch_1):m_c_dq(23)") )
				( member ( signalRef "@baseboard_fab2_lib.baseboard_fab2(sch_1):m_c_dq(24)") )
				( member ( signalRef "@baseboard_fab2_lib.baseboard_fab2(sch_1):m_c_dq(25)") )
				( member ( signalRef "@baseboard_fab2_lib.baseboard_fab2(sch_1):m_c_dq(26)") )
				( member ( signalRef "@baseboard_fab2_lib.baseboard_fab2(sch_1):m_c_dq(27)") )
				( member ( signalRef "@baseboard_fab2_lib.baseboard_fab2(sch_1):m_c_dq(28)") )
				( member ( signalRef "@baseboard_fab2_lib.baseboard_fab2(sch_1):m_c_dq(29)") )
				( member ( signalRef "@baseboard_fab2_lib.baseboard_fab2(sch_1):m_c_dq(30)") )
				( member ( signalRef "@baseboard_fab2_lib.baseboard_fab2(sch_1):m_c_dq(31)") )
				( member ( signalRef "@baseboard_fab2_lib.baseboard_fab2(sch_1):m_c_dq(32)") )
				( member ( signalRef "@baseboard_fab2_lib.baseboard_fab2(sch_1):m_c_dq(33)") )
				( member ( signalRef "@baseboard_fab2_lib.baseboard_fab2(sch_1):m_c_dq(34)") )
				( member ( signalRef "@baseboard_fab2_lib.baseboard_fab2(sch_1):m_c_dq(35)") )
				( member ( signalRef "@baseboard_fab2_lib.baseboard_fab2(sch_1):m_c_dq(36)") )
				( member ( signalRef "@baseboard_fab2_lib.baseboard_fab2(sch_1):m_c_dq(37)") )
				( member ( signalRef "@baseboard_fab2_lib.baseboard_fab2(sch_1):m_c_dq(38)") )
				( member ( signalRef "@baseboard_fab2_lib.baseboard_fab2(sch_1):m_c_dq(39)") )
				( member ( signalRef "@baseboard_fab2_lib.baseboard_fab2(sch_1):m_c_dq(40)") )
				( member ( signalRef "@baseboard_fab2_lib.baseboard_fab2(sch_1):m_c_dq(41)") )
				( member ( signalRef "@baseboard_fab2_lib.baseboard_fab2(sch_1):m_c_dq(42)") )
				( member ( signalRef "@baseboard_fab2_lib.baseboard_fab2(sch_1):m_c_dq(43)") )
				( member ( signalRef "@baseboard_fab2_lib.baseboard_fab2(sch_1):m_c_dq(44)") )
				( member ( signalRef "@baseboard_fab2_lib.baseboard_fab2(sch_1):m_c_dq(45)") )
				( member ( signalRef "@baseboard_fab2_lib.baseboard_fab2(sch_1):m_c_dq(46)") )
				( member ( signalRef "@baseboard_fab2_lib.baseboard_fab2(sch_1):m_c_dq(47)") )
				( member ( signalRef "@baseboard_fab2_lib.baseboard_fab2(sch_1):m_c_dq(48)") )
				( member ( signalRef "@baseboard_fab2_lib.baseboard_fab2(sch_1):m_c_dq(49)") )
				( member ( signalRef "@baseboard_fab2_lib.baseboard_fab2(sch_1):m_c_dq(50)") )
				( member ( signalRef "@baseboard_fab2_lib.baseboard_fab2(sch_1):m_c_dq(51)") )
				( member ( signalRef "@baseboard_fab2_lib.baseboard_fab2(sch_1):m_c_dq(52)") )
				( member ( signalRef "@baseboard_fab2_lib.baseboard_fab2(sch_1):m_c_dq(53)") )
				( member ( signalRef "@baseboard_fab2_lib.baseboard_fab2(sch_1):m_c_dq(54)") )
				( member ( signalRef "@baseboard_fab2_lib.baseboard_fab2(sch_1):m_c_dq(55)") )
				( member ( signalRef "@baseboard_fab2_lib.baseboard_fab2(sch_1):m_c_dq(56)") )
				( member ( signalRef "@baseboard_fab2_lib.baseboard_fab2(sch_1):m_c_dq(57)") )
				( member ( signalRef "@baseboard_fab2_lib.baseboard_fab2(sch_1):m_c_dq(58)") )
				( member ( signalRef "@baseboard_fab2_lib.baseboard_fab2(sch_1):m_c_dq(59)") )
				( member ( signalRef "@baseboard_fab2_lib.baseboard_fab2(sch_1):m_c_dq(60)") )
				( member ( signalRef "@baseboard_fab2_lib.baseboard_fab2(sch_1):m_c_dq(61)") )
				( member ( signalRef "@baseboard_fab2_lib.baseboard_fab2(sch_1):m_c_dq(62)") )
				( member ( signalRef "@baseboard_fab2_lib.baseboard_fab2(sch_1):m_c_dq(63)") )
				( objectStatus "M_C_DQ" )
			)
			( bus "@baseboard_fab2_lib.baseboard_fab2(sch_1):m_c_dqs_dn"
				( memberType ( signal ) )
				( member ( signalRef "@baseboard_fab2_lib.baseboard_fab2(sch_1):m_c_dqs_dn(0)") )
				( member ( signalRef "@baseboard_fab2_lib.baseboard_fab2(sch_1):m_c_dqs_dn(1)") )
				( member ( signalRef "@baseboard_fab2_lib.baseboard_fab2(sch_1):m_c_dqs_dn(2)") )
				( member ( signalRef "@baseboard_fab2_lib.baseboard_fab2(sch_1):m_c_dqs_dn(3)") )
				( member ( signalRef "@baseboard_fab2_lib.baseboard_fab2(sch_1):m_c_dqs_dn(4)") )
				( member ( signalRef "@baseboard_fab2_lib.baseboard_fab2(sch_1):m_c_dqs_dn(5)") )
				( member ( signalRef "@baseboard_fab2_lib.baseboard_fab2(sch_1):m_c_dqs_dn(6)") )
				( member ( signalRef "@baseboard_fab2_lib.baseboard_fab2(sch_1):m_c_dqs_dn(7)") )
				( member ( signalRef "@baseboard_fab2_lib.baseboard_fab2(sch_1):m_c_dqs_dn(8)") )
				( member ( signalRef "@baseboard_fab2_lib.baseboard_fab2(sch_1):m_c_dqs_dn(9)") )
				( member ( signalRef "@baseboard_fab2_lib.baseboard_fab2(sch_1):m_c_dqs_dn(10)") )
				( member ( signalRef "@baseboard_fab2_lib.baseboard_fab2(sch_1):m_c_dqs_dn(11)") )
				( member ( signalRef "@baseboard_fab2_lib.baseboard_fab2(sch_1):m_c_dqs_dn(12)") )
				( member ( signalRef "@baseboard_fab2_lib.baseboard_fab2(sch_1):m_c_dqs_dn(13)") )
				( member ( signalRef "@baseboard_fab2_lib.baseboard_fab2(sch_1):m_c_dqs_dn(14)") )
				( member ( signalRef "@baseboard_fab2_lib.baseboard_fab2(sch_1):m_c_dqs_dn(15)") )
				( member ( signalRef "@baseboard_fab2_lib.baseboard_fab2(sch_1):m_c_dqs_dn(16)") )
				( member ( signalRef "@baseboard_fab2_lib.baseboard_fab2(sch_1):m_c_dqs_dn(17)") )
				( objectStatus "M_C_DQS_DN" )
			)
			( bus "@baseboard_fab2_lib.baseboard_fab2(sch_1):m_c_dqs_dp"
				( memberType ( signal ) )
				( member ( signalRef "@baseboard_fab2_lib.baseboard_fab2(sch_1):m_c_dqs_dp(0)") )
				( member ( signalRef "@baseboard_fab2_lib.baseboard_fab2(sch_1):m_c_dqs_dp(1)") )
				( member ( signalRef "@baseboard_fab2_lib.baseboard_fab2(sch_1):m_c_dqs_dp(2)") )
				( member ( signalRef "@baseboard_fab2_lib.baseboard_fab2(sch_1):m_c_dqs_dp(3)") )
				( member ( signalRef "@baseboard_fab2_lib.baseboard_fab2(sch_1):m_c_dqs_dp(4)") )
				( member ( signalRef "@baseboard_fab2_lib.baseboard_fab2(sch_1):m_c_dqs_dp(5)") )
				( member ( signalRef "@baseboard_fab2_lib.baseboard_fab2(sch_1):m_c_dqs_dp(6)") )
				( member ( signalRef "@baseboard_fab2_lib.baseboard_fab2(sch_1):m_c_dqs_dp(7)") )
				( member ( signalRef "@baseboard_fab2_lib.baseboard_fab2(sch_1):m_c_dqs_dp(8)") )
				( member ( signalRef "@baseboard_fab2_lib.baseboard_fab2(sch_1):m_c_dqs_dp(9)") )
				( member ( signalRef "@baseboard_fab2_lib.baseboard_fab2(sch_1):m_c_dqs_dp(10)") )
				( member ( signalRef "@baseboard_fab2_lib.baseboard_fab2(sch_1):m_c_dqs_dp(11)") )
				( member ( signalRef "@baseboard_fab2_lib.baseboard_fab2(sch_1):m_c_dqs_dp(12)") )
				( member ( signalRef "@baseboard_fab2_lib.baseboard_fab2(sch_1):m_c_dqs_dp(13)") )
				( member ( signalRef "@baseboard_fab2_lib.baseboard_fab2(sch_1):m_c_dqs_dp(14)") )
				( member ( signalRef "@baseboard_fab2_lib.baseboard_fab2(sch_1):m_c_dqs_dp(15)") )
				( member ( signalRef "@baseboard_fab2_lib.baseboard_fab2(sch_1):m_c_dqs_dp(16)") )
				( member ( signalRef "@baseboard_fab2_lib.baseboard_fab2(sch_1):m_c_dqs_dp(17)") )
				( objectStatus "M_C_DQS_DP" )
			)
			( bus "@baseboard_fab2_lib.baseboard_fab2(sch_1):m_c_ecc"
				( memberType ( signal ) )
				( member ( signalRef "@baseboard_fab2_lib.baseboard_fab2(sch_1):m_c_ecc(0)") )
				( member ( signalRef "@baseboard_fab2_lib.baseboard_fab2(sch_1):m_c_ecc(1)") )
				( member ( signalRef "@baseboard_fab2_lib.baseboard_fab2(sch_1):m_c_ecc(2)") )
				( member ( signalRef "@baseboard_fab2_lib.baseboard_fab2(sch_1):m_c_ecc(3)") )
				( member ( signalRef "@baseboard_fab2_lib.baseboard_fab2(sch_1):m_c_ecc(4)") )
				( member ( signalRef "@baseboard_fab2_lib.baseboard_fab2(sch_1):m_c_ecc(5)") )
				( member ( signalRef "@baseboard_fab2_lib.baseboard_fab2(sch_1):m_c_ecc(6)") )
				( member ( signalRef "@baseboard_fab2_lib.baseboard_fab2(sch_1):m_c_ecc(7)") )
				( objectStatus "M_C_ECC" )
			)
			( bus "@baseboard_fab2_lib.baseboard_fab2(sch_1):m_c_ma"
				( memberType ( signal ) )
				( member ( signalRef "@baseboard_fab2_lib.baseboard_fab2(sch_1):m_c_ma(0)") )
				( member ( signalRef "@baseboard_fab2_lib.baseboard_fab2(sch_1):m_c_ma(1)") )
				( member ( signalRef "@baseboard_fab2_lib.baseboard_fab2(sch_1):m_c_ma(2)") )
				( member ( signalRef "@baseboard_fab2_lib.baseboard_fab2(sch_1):m_c_ma(3)") )
				( member ( signalRef "@baseboard_fab2_lib.baseboard_fab2(sch_1):m_c_ma(4)") )
				( member ( signalRef "@baseboard_fab2_lib.baseboard_fab2(sch_1):m_c_ma(5)") )
				( member ( signalRef "@baseboard_fab2_lib.baseboard_fab2(sch_1):m_c_ma(6)") )
				( member ( signalRef "@baseboard_fab2_lib.baseboard_fab2(sch_1):m_c_ma(7)") )
				( member ( signalRef "@baseboard_fab2_lib.baseboard_fab2(sch_1):m_c_ma(8)") )
				( member ( signalRef "@baseboard_fab2_lib.baseboard_fab2(sch_1):m_c_ma(9)") )
				( member ( signalRef "@baseboard_fab2_lib.baseboard_fab2(sch_1):m_c_ma(10)") )
				( member ( signalRef "@baseboard_fab2_lib.baseboard_fab2(sch_1):m_c_ma(11)") )
				( member ( signalRef "@baseboard_fab2_lib.baseboard_fab2(sch_1):m_c_ma(12)") )
				( member ( signalRef "@baseboard_fab2_lib.baseboard_fab2(sch_1):m_c_ma(13)") )
				( member ( signalRef "@baseboard_fab2_lib.baseboard_fab2(sch_1):m_c_ma(14)") )
				( member ( signalRef "@baseboard_fab2_lib.baseboard_fab2(sch_1):m_c_ma(15)") )
				( member ( signalRef "@baseboard_fab2_lib.baseboard_fab2(sch_1):m_c_ma(16)") )
				( member ( signalRef "@baseboard_fab2_lib.baseboard_fab2(sch_1):m_c_ma(17)") )
				( objectStatus "M_C_MA" )
			)
			( bus "@baseboard_fab2_lib.baseboard_fab2(sch_1):m_c_odt"
				( memberType ( signal ) )
				( member ( signalRef "@baseboard_fab2_lib.baseboard_fab2(sch_1):m_c_odt(0)") )
				( member ( signalRef "@baseboard_fab2_lib.baseboard_fab2(sch_1):m_c_odt(1)") )
				( member ( signalRef "@baseboard_fab2_lib.baseboard_fab2(sch_1):m_c_odt(2)") )
				( member ( signalRef "@baseboard_fab2_lib.baseboard_fab2(sch_1):m_c_odt(3)") )
				( objectStatus "M_C_ODT" )
			)
			( bus "@baseboard_fab2_lib.baseboard_fab2(sch_1):m_d_ba"
				( memberType ( signal ) )
				( member ( signalRef "@baseboard_fab2_lib.baseboard_fab2(sch_1):m_d_ba(0)") )
				( member ( signalRef "@baseboard_fab2_lib.baseboard_fab2(sch_1):m_d_ba(1)") )
				( objectStatus "M_D_BA" )
			)
			( bus "@baseboard_fab2_lib.baseboard_fab2(sch_1):m_d_bg"
				( memberType ( signal ) )
				( member ( signalRef "@baseboard_fab2_lib.baseboard_fab2(sch_1):m_d_bg(0)") )
				( member ( signalRef "@baseboard_fab2_lib.baseboard_fab2(sch_1):m_d_bg(1)") )
				( objectStatus "M_D_BG" )
			)
			( bus "@baseboard_fab2_lib.baseboard_fab2(sch_1):m_d_c"
				( memberType ( signal ) )
				( member ( signalRef "@baseboard_fab2_lib.baseboard_fab2(sch_1):m_d_c(2)") )
				( objectStatus "M_D_C" )
			)
			( bus "@baseboard_fab2_lib.baseboard_fab2(sch_1):m_d_cke"
				( memberType ( signal ) )
				( member ( signalRef "@baseboard_fab2_lib.baseboard_fab2(sch_1):m_d_cke(0)") )
				( member ( signalRef "@baseboard_fab2_lib.baseboard_fab2(sch_1):m_d_cke(1)") )
				( member ( signalRef "@baseboard_fab2_lib.baseboard_fab2(sch_1):m_d_cke(2)") )
				( member ( signalRef "@baseboard_fab2_lib.baseboard_fab2(sch_1):m_d_cke(3)") )
				( objectStatus "M_D_CKE" )
			)
			( bus "@baseboard_fab2_lib.baseboard_fab2(sch_1):m_d_clk_dn"
				( memberType ( signal ) )
				( member ( signalRef "@baseboard_fab2_lib.baseboard_fab2(sch_1):m_d_clk_dn(0)") )
				( member ( signalRef "@baseboard_fab2_lib.baseboard_fab2(sch_1):m_d_clk_dn(1)") )
				( member ( signalRef "@baseboard_fab2_lib.baseboard_fab2(sch_1):m_d_clk_dn(2)") )
				( member ( signalRef "@baseboard_fab2_lib.baseboard_fab2(sch_1):m_d_clk_dn(3)") )
				( objectStatus "M_D_CLK_DN" )
			)
			( bus "@baseboard_fab2_lib.baseboard_fab2(sch_1):m_d_clk_dp"
				( memberType ( signal ) )
				( member ( signalRef "@baseboard_fab2_lib.baseboard_fab2(sch_1):m_d_clk_dp(0)") )
				( member ( signalRef "@baseboard_fab2_lib.baseboard_fab2(sch_1):m_d_clk_dp(1)") )
				( member ( signalRef "@baseboard_fab2_lib.baseboard_fab2(sch_1):m_d_clk_dp(2)") )
				( member ( signalRef "@baseboard_fab2_lib.baseboard_fab2(sch_1):m_d_clk_dp(3)") )
				( objectStatus "M_D_CLK_DP" )
			)
			( bus "@baseboard_fab2_lib.baseboard_fab2(sch_1):m_d_cs_n"
				( memberType ( signal ) )
				( member ( signalRef "@baseboard_fab2_lib.baseboard_fab2(sch_1):m_d_cs_n(0)") )
				( member ( signalRef "@baseboard_fab2_lib.baseboard_fab2(sch_1):m_d_cs_n(1)") )
				( member ( signalRef "@baseboard_fab2_lib.baseboard_fab2(sch_1):m_d_cs_n(2)") )
				( member ( signalRef "@baseboard_fab2_lib.baseboard_fab2(sch_1):m_d_cs_n(3)") )
				( member ( signalRef "@baseboard_fab2_lib.baseboard_fab2(sch_1):m_d_cs_n(4)") )
				( member ( signalRef "@baseboard_fab2_lib.baseboard_fab2(sch_1):m_d_cs_n(5)") )
				( member ( signalRef "@baseboard_fab2_lib.baseboard_fab2(sch_1):m_d_cs_n(6)") )
				( member ( signalRef "@baseboard_fab2_lib.baseboard_fab2(sch_1):m_d_cs_n(7)") )
				( objectStatus "M_D_CS_N" )
			)
			( bus "@baseboard_fab2_lib.baseboard_fab2(sch_1):m_d_dq"
				( memberType ( signal ) )
				( member ( signalRef "@baseboard_fab2_lib.baseboard_fab2(sch_1):m_d_dq(0)") )
				( member ( signalRef "@baseboard_fab2_lib.baseboard_fab2(sch_1):m_d_dq(1)") )
				( member ( signalRef "@baseboard_fab2_lib.baseboard_fab2(sch_1):m_d_dq(2)") )
				( member ( signalRef "@baseboard_fab2_lib.baseboard_fab2(sch_1):m_d_dq(3)") )
				( member ( signalRef "@baseboard_fab2_lib.baseboard_fab2(sch_1):m_d_dq(4)") )
				( member ( signalRef "@baseboard_fab2_lib.baseboard_fab2(sch_1):m_d_dq(5)") )
				( member ( signalRef "@baseboard_fab2_lib.baseboard_fab2(sch_1):m_d_dq(6)") )
				( member ( signalRef "@baseboard_fab2_lib.baseboard_fab2(sch_1):m_d_dq(7)") )
				( member ( signalRef "@baseboard_fab2_lib.baseboard_fab2(sch_1):m_d_dq(8)") )
				( member ( signalRef "@baseboard_fab2_lib.baseboard_fab2(sch_1):m_d_dq(9)") )
				( member ( signalRef "@baseboard_fab2_lib.baseboard_fab2(sch_1):m_d_dq(10)") )
				( member ( signalRef "@baseboard_fab2_lib.baseboard_fab2(sch_1):m_d_dq(11)") )
				( member ( signalRef "@baseboard_fab2_lib.baseboard_fab2(sch_1):m_d_dq(12)") )
				( member ( signalRef "@baseboard_fab2_lib.baseboard_fab2(sch_1):m_d_dq(13)") )
				( member ( signalRef "@baseboard_fab2_lib.baseboard_fab2(sch_1):m_d_dq(14)") )
				( member ( signalRef "@baseboard_fab2_lib.baseboard_fab2(sch_1):m_d_dq(15)") )
				( member ( signalRef "@baseboard_fab2_lib.baseboard_fab2(sch_1):m_d_dq(16)") )
				( member ( signalRef "@baseboard_fab2_lib.baseboard_fab2(sch_1):m_d_dq(17)") )
				( member ( signalRef "@baseboard_fab2_lib.baseboard_fab2(sch_1):m_d_dq(18)") )
				( member ( signalRef "@baseboard_fab2_lib.baseboard_fab2(sch_1):m_d_dq(19)") )
				( member ( signalRef "@baseboard_fab2_lib.baseboard_fab2(sch_1):m_d_dq(20)") )
				( member ( signalRef "@baseboard_fab2_lib.baseboard_fab2(sch_1):m_d_dq(21)") )
				( member ( signalRef "@baseboard_fab2_lib.baseboard_fab2(sch_1):m_d_dq(22)") )
				( member ( signalRef "@baseboard_fab2_lib.baseboard_fab2(sch_1):m_d_dq(23)") )
				( member ( signalRef "@baseboard_fab2_lib.baseboard_fab2(sch_1):m_d_dq(24)") )
				( member ( signalRef "@baseboard_fab2_lib.baseboard_fab2(sch_1):m_d_dq(25)") )
				( member ( signalRef "@baseboard_fab2_lib.baseboard_fab2(sch_1):m_d_dq(26)") )
				( member ( signalRef "@baseboard_fab2_lib.baseboard_fab2(sch_1):m_d_dq(27)") )
				( member ( signalRef "@baseboard_fab2_lib.baseboard_fab2(sch_1):m_d_dq(28)") )
				( member ( signalRef "@baseboard_fab2_lib.baseboard_fab2(sch_1):m_d_dq(29)") )
				( member ( signalRef "@baseboard_fab2_lib.baseboard_fab2(sch_1):m_d_dq(30)") )
				( member ( signalRef "@baseboard_fab2_lib.baseboard_fab2(sch_1):m_d_dq(31)") )
				( member ( signalRef "@baseboard_fab2_lib.baseboard_fab2(sch_1):m_d_dq(32)") )
				( member ( signalRef "@baseboard_fab2_lib.baseboard_fab2(sch_1):m_d_dq(33)") )
				( member ( signalRef "@baseboard_fab2_lib.baseboard_fab2(sch_1):m_d_dq(34)") )
				( member ( signalRef "@baseboard_fab2_lib.baseboard_fab2(sch_1):m_d_dq(35)") )
				( member ( signalRef "@baseboard_fab2_lib.baseboard_fab2(sch_1):m_d_dq(36)") )
				( member ( signalRef "@baseboard_fab2_lib.baseboard_fab2(sch_1):m_d_dq(37)") )
				( member ( signalRef "@baseboard_fab2_lib.baseboard_fab2(sch_1):m_d_dq(38)") )
				( member ( signalRef "@baseboard_fab2_lib.baseboard_fab2(sch_1):m_d_dq(39)") )
				( member ( signalRef "@baseboard_fab2_lib.baseboard_fab2(sch_1):m_d_dq(40)") )
				( member ( signalRef "@baseboard_fab2_lib.baseboard_fab2(sch_1):m_d_dq(41)") )
				( member ( signalRef "@baseboard_fab2_lib.baseboard_fab2(sch_1):m_d_dq(42)") )
				( member ( signalRef "@baseboard_fab2_lib.baseboard_fab2(sch_1):m_d_dq(43)") )
				( member ( signalRef "@baseboard_fab2_lib.baseboard_fab2(sch_1):m_d_dq(44)") )
				( member ( signalRef "@baseboard_fab2_lib.baseboard_fab2(sch_1):m_d_dq(45)") )
				( member ( signalRef "@baseboard_fab2_lib.baseboard_fab2(sch_1):m_d_dq(46)") )
				( member ( signalRef "@baseboard_fab2_lib.baseboard_fab2(sch_1):m_d_dq(47)") )
				( member ( signalRef "@baseboard_fab2_lib.baseboard_fab2(sch_1):m_d_dq(48)") )
				( member ( signalRef "@baseboard_fab2_lib.baseboard_fab2(sch_1):m_d_dq(49)") )
				( member ( signalRef "@baseboard_fab2_lib.baseboard_fab2(sch_1):m_d_dq(50)") )
				( member ( signalRef "@baseboard_fab2_lib.baseboard_fab2(sch_1):m_d_dq(51)") )
				( member ( signalRef "@baseboard_fab2_lib.baseboard_fab2(sch_1):m_d_dq(52)") )
				( member ( signalRef "@baseboard_fab2_lib.baseboard_fab2(sch_1):m_d_dq(53)") )
				( member ( signalRef "@baseboard_fab2_lib.baseboard_fab2(sch_1):m_d_dq(54)") )
				( member ( signalRef "@baseboard_fab2_lib.baseboard_fab2(sch_1):m_d_dq(55)") )
				( member ( signalRef "@baseboard_fab2_lib.baseboard_fab2(sch_1):m_d_dq(56)") )
				( member ( signalRef "@baseboard_fab2_lib.baseboard_fab2(sch_1):m_d_dq(57)") )
				( member ( signalRef "@baseboard_fab2_lib.baseboard_fab2(sch_1):m_d_dq(58)") )
				( member ( signalRef "@baseboard_fab2_lib.baseboard_fab2(sch_1):m_d_dq(59)") )
				( member ( signalRef "@baseboard_fab2_lib.baseboard_fab2(sch_1):m_d_dq(60)") )
				( member ( signalRef "@baseboard_fab2_lib.baseboard_fab2(sch_1):m_d_dq(61)") )
				( member ( signalRef "@baseboard_fab2_lib.baseboard_fab2(sch_1):m_d_dq(62)") )
				( member ( signalRef "@baseboard_fab2_lib.baseboard_fab2(sch_1):m_d_dq(63)") )
				( objectStatus "M_D_DQ" )
			)
			( bus "@baseboard_fab2_lib.baseboard_fab2(sch_1):m_d_dqs_dn"
				( memberType ( signal ) )
				( member ( signalRef "@baseboard_fab2_lib.baseboard_fab2(sch_1):m_d_dqs_dn(0)") )
				( member ( signalRef "@baseboard_fab2_lib.baseboard_fab2(sch_1):m_d_dqs_dn(1)") )
				( member ( signalRef "@baseboard_fab2_lib.baseboard_fab2(sch_1):m_d_dqs_dn(2)") )
				( member ( signalRef "@baseboard_fab2_lib.baseboard_fab2(sch_1):m_d_dqs_dn(3)") )
				( member ( signalRef "@baseboard_fab2_lib.baseboard_fab2(sch_1):m_d_dqs_dn(4)") )
				( member ( signalRef "@baseboard_fab2_lib.baseboard_fab2(sch_1):m_d_dqs_dn(5)") )
				( member ( signalRef "@baseboard_fab2_lib.baseboard_fab2(sch_1):m_d_dqs_dn(6)") )
				( member ( signalRef "@baseboard_fab2_lib.baseboard_fab2(sch_1):m_d_dqs_dn(7)") )
				( member ( signalRef "@baseboard_fab2_lib.baseboard_fab2(sch_1):m_d_dqs_dn(8)") )
				( member ( signalRef "@baseboard_fab2_lib.baseboard_fab2(sch_1):m_d_dqs_dn(9)") )
				( member ( signalRef "@baseboard_fab2_lib.baseboard_fab2(sch_1):m_d_dqs_dn(10)") )
				( member ( signalRef "@baseboard_fab2_lib.baseboard_fab2(sch_1):m_d_dqs_dn(11)") )
				( member ( signalRef "@baseboard_fab2_lib.baseboard_fab2(sch_1):m_d_dqs_dn(12)") )
				( member ( signalRef "@baseboard_fab2_lib.baseboard_fab2(sch_1):m_d_dqs_dn(13)") )
				( member ( signalRef "@baseboard_fab2_lib.baseboard_fab2(sch_1):m_d_dqs_dn(14)") )
				( member ( signalRef "@baseboard_fab2_lib.baseboard_fab2(sch_1):m_d_dqs_dn(15)") )
				( member ( signalRef "@baseboard_fab2_lib.baseboard_fab2(sch_1):m_d_dqs_dn(16)") )
				( member ( signalRef "@baseboard_fab2_lib.baseboard_fab2(sch_1):m_d_dqs_dn(17)") )
				( objectStatus "M_D_DQS_DN" )
			)
			( bus "@baseboard_fab2_lib.baseboard_fab2(sch_1):m_d_dqs_dp"
				( memberType ( signal ) )
				( member ( signalRef "@baseboard_fab2_lib.baseboard_fab2(sch_1):m_d_dqs_dp(0)") )
				( member ( signalRef "@baseboard_fab2_lib.baseboard_fab2(sch_1):m_d_dqs_dp(1)") )
				( member ( signalRef "@baseboard_fab2_lib.baseboard_fab2(sch_1):m_d_dqs_dp(2)") )
				( member ( signalRef "@baseboard_fab2_lib.baseboard_fab2(sch_1):m_d_dqs_dp(3)") )
				( member ( signalRef "@baseboard_fab2_lib.baseboard_fab2(sch_1):m_d_dqs_dp(4)") )
				( member ( signalRef "@baseboard_fab2_lib.baseboard_fab2(sch_1):m_d_dqs_dp(5)") )
				( member ( signalRef "@baseboard_fab2_lib.baseboard_fab2(sch_1):m_d_dqs_dp(6)") )
				( member ( signalRef "@baseboard_fab2_lib.baseboard_fab2(sch_1):m_d_dqs_dp(7)") )
				( member ( signalRef "@baseboard_fab2_lib.baseboard_fab2(sch_1):m_d_dqs_dp(8)") )
				( member ( signalRef "@baseboard_fab2_lib.baseboard_fab2(sch_1):m_d_dqs_dp(9)") )
				( member ( signalRef "@baseboard_fab2_lib.baseboard_fab2(sch_1):m_d_dqs_dp(10)") )
				( member ( signalRef "@baseboard_fab2_lib.baseboard_fab2(sch_1):m_d_dqs_dp(11)") )
				( member ( signalRef "@baseboard_fab2_lib.baseboard_fab2(sch_1):m_d_dqs_dp(12)") )
				( member ( signalRef "@baseboard_fab2_lib.baseboard_fab2(sch_1):m_d_dqs_dp(13)") )
				( member ( signalRef "@baseboard_fab2_lib.baseboard_fab2(sch_1):m_d_dqs_dp(14)") )
				( member ( signalRef "@baseboard_fab2_lib.baseboard_fab2(sch_1):m_d_dqs_dp(15)") )
				( member ( signalRef "@baseboard_fab2_lib.baseboard_fab2(sch_1):m_d_dqs_dp(16)") )
				( member ( signalRef "@baseboard_fab2_lib.baseboard_fab2(sch_1):m_d_dqs_dp(17)") )
				( objectStatus "M_D_DQS_DP" )
			)
			( bus "@baseboard_fab2_lib.baseboard_fab2(sch_1):m_d_ecc"
				( memberType ( signal ) )
				( member ( signalRef "@baseboard_fab2_lib.baseboard_fab2(sch_1):m_d_ecc(0)") )
				( member ( signalRef "@baseboard_fab2_lib.baseboard_fab2(sch_1):m_d_ecc(1)") )
				( member ( signalRef "@baseboard_fab2_lib.baseboard_fab2(sch_1):m_d_ecc(2)") )
				( member ( signalRef "@baseboard_fab2_lib.baseboard_fab2(sch_1):m_d_ecc(3)") )
				( member ( signalRef "@baseboard_fab2_lib.baseboard_fab2(sch_1):m_d_ecc(4)") )
				( member ( signalRef "@baseboard_fab2_lib.baseboard_fab2(sch_1):m_d_ecc(5)") )
				( member ( signalRef "@baseboard_fab2_lib.baseboard_fab2(sch_1):m_d_ecc(6)") )
				( member ( signalRef "@baseboard_fab2_lib.baseboard_fab2(sch_1):m_d_ecc(7)") )
				( objectStatus "M_D_ECC" )
			)
			( bus "@baseboard_fab2_lib.baseboard_fab2(sch_1):m_d_ma"
				( memberType ( signal ) )
				( member ( signalRef "@baseboard_fab2_lib.baseboard_fab2(sch_1):m_d_ma(0)") )
				( member ( signalRef "@baseboard_fab2_lib.baseboard_fab2(sch_1):m_d_ma(1)") )
				( member ( signalRef "@baseboard_fab2_lib.baseboard_fab2(sch_1):m_d_ma(2)") )
				( member ( signalRef "@baseboard_fab2_lib.baseboard_fab2(sch_1):m_d_ma(3)") )
				( member ( signalRef "@baseboard_fab2_lib.baseboard_fab2(sch_1):m_d_ma(4)") )
				( member ( signalRef "@baseboard_fab2_lib.baseboard_fab2(sch_1):m_d_ma(5)") )
				( member ( signalRef "@baseboard_fab2_lib.baseboard_fab2(sch_1):m_d_ma(6)") )
				( member ( signalRef "@baseboard_fab2_lib.baseboard_fab2(sch_1):m_d_ma(7)") )
				( member ( signalRef "@baseboard_fab2_lib.baseboard_fab2(sch_1):m_d_ma(8)") )
				( member ( signalRef "@baseboard_fab2_lib.baseboard_fab2(sch_1):m_d_ma(9)") )
				( member ( signalRef "@baseboard_fab2_lib.baseboard_fab2(sch_1):m_d_ma(10)") )
				( member ( signalRef "@baseboard_fab2_lib.baseboard_fab2(sch_1):m_d_ma(11)") )
				( member ( signalRef "@baseboard_fab2_lib.baseboard_fab2(sch_1):m_d_ma(12)") )
				( member ( signalRef "@baseboard_fab2_lib.baseboard_fab2(sch_1):m_d_ma(13)") )
				( member ( signalRef "@baseboard_fab2_lib.baseboard_fab2(sch_1):m_d_ma(14)") )
				( member ( signalRef "@baseboard_fab2_lib.baseboard_fab2(sch_1):m_d_ma(15)") )
				( member ( signalRef "@baseboard_fab2_lib.baseboard_fab2(sch_1):m_d_ma(16)") )
				( member ( signalRef "@baseboard_fab2_lib.baseboard_fab2(sch_1):m_d_ma(17)") )
				( objectStatus "M_D_MA" )
			)
			( bus "@baseboard_fab2_lib.baseboard_fab2(sch_1):m_d_odt"
				( memberType ( signal ) )
				( member ( signalRef "@baseboard_fab2_lib.baseboard_fab2(sch_1):m_d_odt(0)") )
				( member ( signalRef "@baseboard_fab2_lib.baseboard_fab2(sch_1):m_d_odt(1)") )
				( member ( signalRef "@baseboard_fab2_lib.baseboard_fab2(sch_1):m_d_odt(2)") )
				( member ( signalRef "@baseboard_fab2_lib.baseboard_fab2(sch_1):m_d_odt(3)") )
				( objectStatus "M_D_ODT" )
			)
			( bus "@baseboard_fab2_lib.baseboard_fab2(sch_1):m_e_ba"
				( memberType ( signal ) )
				( member ( signalRef "@baseboard_fab2_lib.baseboard_fab2(sch_1):m_e_ba(0)") )
				( member ( signalRef "@baseboard_fab2_lib.baseboard_fab2(sch_1):m_e_ba(1)") )
				( objectStatus "M_E_BA" )
			)
			( bus "@baseboard_fab2_lib.baseboard_fab2(sch_1):m_e_bg"
				( memberType ( signal ) )
				( member ( signalRef "@baseboard_fab2_lib.baseboard_fab2(sch_1):m_e_bg(0)") )
				( member ( signalRef "@baseboard_fab2_lib.baseboard_fab2(sch_1):m_e_bg(1)") )
				( objectStatus "M_E_BG" )
			)
			( bus "@baseboard_fab2_lib.baseboard_fab2(sch_1):m_e_c"
				( memberType ( signal ) )
				( member ( signalRef "@baseboard_fab2_lib.baseboard_fab2(sch_1):m_e_c(2)") )
				( objectStatus "M_E_C" )
			)
			( bus "@baseboard_fab2_lib.baseboard_fab2(sch_1):m_e_cke"
				( memberType ( signal ) )
				( member ( signalRef "@baseboard_fab2_lib.baseboard_fab2(sch_1):m_e_cke(0)") )
				( member ( signalRef "@baseboard_fab2_lib.baseboard_fab2(sch_1):m_e_cke(1)") )
				( member ( signalRef "@baseboard_fab2_lib.baseboard_fab2(sch_1):m_e_cke(2)") )
				( member ( signalRef "@baseboard_fab2_lib.baseboard_fab2(sch_1):m_e_cke(3)") )
				( objectStatus "M_E_CKE" )
			)
			( bus "@baseboard_fab2_lib.baseboard_fab2(sch_1):m_e_clk_dn"
				( memberType ( signal ) )
				( member ( signalRef "@baseboard_fab2_lib.baseboard_fab2(sch_1):m_e_clk_dn(0)") )
				( member ( signalRef "@baseboard_fab2_lib.baseboard_fab2(sch_1):m_e_clk_dn(1)") )
				( member ( signalRef "@baseboard_fab2_lib.baseboard_fab2(sch_1):m_e_clk_dn(2)") )
				( member ( signalRef "@baseboard_fab2_lib.baseboard_fab2(sch_1):m_e_clk_dn(3)") )
				( objectStatus "M_E_CLK_DN" )
			)
			( bus "@baseboard_fab2_lib.baseboard_fab2(sch_1):m_e_clk_dp"
				( memberType ( signal ) )
				( member ( signalRef "@baseboard_fab2_lib.baseboard_fab2(sch_1):m_e_clk_dp(0)") )
				( member ( signalRef "@baseboard_fab2_lib.baseboard_fab2(sch_1):m_e_clk_dp(1)") )
				( member ( signalRef "@baseboard_fab2_lib.baseboard_fab2(sch_1):m_e_clk_dp(2)") )
				( member ( signalRef "@baseboard_fab2_lib.baseboard_fab2(sch_1):m_e_clk_dp(3)") )
				( objectStatus "M_E_CLK_DP" )
			)
			( bus "@baseboard_fab2_lib.baseboard_fab2(sch_1):m_e_cs_n"
				( memberType ( signal ) )
				( member ( signalRef "@baseboard_fab2_lib.baseboard_fab2(sch_1):m_e_cs_n(0)") )
				( member ( signalRef "@baseboard_fab2_lib.baseboard_fab2(sch_1):m_e_cs_n(1)") )
				( member ( signalRef "@baseboard_fab2_lib.baseboard_fab2(sch_1):m_e_cs_n(2)") )
				( member ( signalRef "@baseboard_fab2_lib.baseboard_fab2(sch_1):m_e_cs_n(3)") )
				( member ( signalRef "@baseboard_fab2_lib.baseboard_fab2(sch_1):m_e_cs_n(4)") )
				( member ( signalRef "@baseboard_fab2_lib.baseboard_fab2(sch_1):m_e_cs_n(5)") )
				( member ( signalRef "@baseboard_fab2_lib.baseboard_fab2(sch_1):m_e_cs_n(6)") )
				( member ( signalRef "@baseboard_fab2_lib.baseboard_fab2(sch_1):m_e_cs_n(7)") )
				( objectStatus "M_E_CS_N" )
			)
			( bus "@baseboard_fab2_lib.baseboard_fab2(sch_1):m_e_dq"
				( memberType ( signal ) )
				( member ( signalRef "@baseboard_fab2_lib.baseboard_fab2(sch_1):m_e_dq(0)") )
				( member ( signalRef "@baseboard_fab2_lib.baseboard_fab2(sch_1):m_e_dq(1)") )
				( member ( signalRef "@baseboard_fab2_lib.baseboard_fab2(sch_1):m_e_dq(2)") )
				( member ( signalRef "@baseboard_fab2_lib.baseboard_fab2(sch_1):m_e_dq(3)") )
				( member ( signalRef "@baseboard_fab2_lib.baseboard_fab2(sch_1):m_e_dq(4)") )
				( member ( signalRef "@baseboard_fab2_lib.baseboard_fab2(sch_1):m_e_dq(5)") )
				( member ( signalRef "@baseboard_fab2_lib.baseboard_fab2(sch_1):m_e_dq(6)") )
				( member ( signalRef "@baseboard_fab2_lib.baseboard_fab2(sch_1):m_e_dq(7)") )
				( member ( signalRef "@baseboard_fab2_lib.baseboard_fab2(sch_1):m_e_dq(8)") )
				( member ( signalRef "@baseboard_fab2_lib.baseboard_fab2(sch_1):m_e_dq(9)") )
				( member ( signalRef "@baseboard_fab2_lib.baseboard_fab2(sch_1):m_e_dq(10)") )
				( member ( signalRef "@baseboard_fab2_lib.baseboard_fab2(sch_1):m_e_dq(11)") )
				( member ( signalRef "@baseboard_fab2_lib.baseboard_fab2(sch_1):m_e_dq(12)") )
				( member ( signalRef "@baseboard_fab2_lib.baseboard_fab2(sch_1):m_e_dq(13)") )
				( member ( signalRef "@baseboard_fab2_lib.baseboard_fab2(sch_1):m_e_dq(14)") )
				( member ( signalRef "@baseboard_fab2_lib.baseboard_fab2(sch_1):m_e_dq(15)") )
				( member ( signalRef "@baseboard_fab2_lib.baseboard_fab2(sch_1):m_e_dq(16)") )
				( member ( signalRef "@baseboard_fab2_lib.baseboard_fab2(sch_1):m_e_dq(17)") )
				( member ( signalRef "@baseboard_fab2_lib.baseboard_fab2(sch_1):m_e_dq(18)") )
				( member ( signalRef "@baseboard_fab2_lib.baseboard_fab2(sch_1):m_e_dq(19)") )
				( member ( signalRef "@baseboard_fab2_lib.baseboard_fab2(sch_1):m_e_dq(20)") )
				( member ( signalRef "@baseboard_fab2_lib.baseboard_fab2(sch_1):m_e_dq(21)") )
				( member ( signalRef "@baseboard_fab2_lib.baseboard_fab2(sch_1):m_e_dq(22)") )
				( member ( signalRef "@baseboard_fab2_lib.baseboard_fab2(sch_1):m_e_dq(23)") )
				( member ( signalRef "@baseboard_fab2_lib.baseboard_fab2(sch_1):m_e_dq(24)") )
				( member ( signalRef "@baseboard_fab2_lib.baseboard_fab2(sch_1):m_e_dq(25)") )
				( member ( signalRef "@baseboard_fab2_lib.baseboard_fab2(sch_1):m_e_dq(26)") )
				( member ( signalRef "@baseboard_fab2_lib.baseboard_fab2(sch_1):m_e_dq(27)") )
				( member ( signalRef "@baseboard_fab2_lib.baseboard_fab2(sch_1):m_e_dq(28)") )
				( member ( signalRef "@baseboard_fab2_lib.baseboard_fab2(sch_1):m_e_dq(29)") )
				( member ( signalRef "@baseboard_fab2_lib.baseboard_fab2(sch_1):m_e_dq(30)") )
				( member ( signalRef "@baseboard_fab2_lib.baseboard_fab2(sch_1):m_e_dq(31)") )
				( member ( signalRef "@baseboard_fab2_lib.baseboard_fab2(sch_1):m_e_dq(32)") )
				( member ( signalRef "@baseboard_fab2_lib.baseboard_fab2(sch_1):m_e_dq(33)") )
				( member ( signalRef "@baseboard_fab2_lib.baseboard_fab2(sch_1):m_e_dq(34)") )
				( member ( signalRef "@baseboard_fab2_lib.baseboard_fab2(sch_1):m_e_dq(35)") )
				( member ( signalRef "@baseboard_fab2_lib.baseboard_fab2(sch_1):m_e_dq(36)") )
				( member ( signalRef "@baseboard_fab2_lib.baseboard_fab2(sch_1):m_e_dq(37)") )
				( member ( signalRef "@baseboard_fab2_lib.baseboard_fab2(sch_1):m_e_dq(38)") )
				( member ( signalRef "@baseboard_fab2_lib.baseboard_fab2(sch_1):m_e_dq(39)") )
				( member ( signalRef "@baseboard_fab2_lib.baseboard_fab2(sch_1):m_e_dq(40)") )
				( member ( signalRef "@baseboard_fab2_lib.baseboard_fab2(sch_1):m_e_dq(41)") )
				( member ( signalRef "@baseboard_fab2_lib.baseboard_fab2(sch_1):m_e_dq(42)") )
				( member ( signalRef "@baseboard_fab2_lib.baseboard_fab2(sch_1):m_e_dq(43)") )
				( member ( signalRef "@baseboard_fab2_lib.baseboard_fab2(sch_1):m_e_dq(44)") )
				( member ( signalRef "@baseboard_fab2_lib.baseboard_fab2(sch_1):m_e_dq(45)") )
				( member ( signalRef "@baseboard_fab2_lib.baseboard_fab2(sch_1):m_e_dq(46)") )
				( member ( signalRef "@baseboard_fab2_lib.baseboard_fab2(sch_1):m_e_dq(47)") )
				( member ( signalRef "@baseboard_fab2_lib.baseboard_fab2(sch_1):m_e_dq(48)") )
				( member ( signalRef "@baseboard_fab2_lib.baseboard_fab2(sch_1):m_e_dq(49)") )
				( member ( signalRef "@baseboard_fab2_lib.baseboard_fab2(sch_1):m_e_dq(50)") )
				( member ( signalRef "@baseboard_fab2_lib.baseboard_fab2(sch_1):m_e_dq(51)") )
				( member ( signalRef "@baseboard_fab2_lib.baseboard_fab2(sch_1):m_e_dq(52)") )
				( member ( signalRef "@baseboard_fab2_lib.baseboard_fab2(sch_1):m_e_dq(53)") )
				( member ( signalRef "@baseboard_fab2_lib.baseboard_fab2(sch_1):m_e_dq(54)") )
				( member ( signalRef "@baseboard_fab2_lib.baseboard_fab2(sch_1):m_e_dq(55)") )
				( member ( signalRef "@baseboard_fab2_lib.baseboard_fab2(sch_1):m_e_dq(56)") )
				( member ( signalRef "@baseboard_fab2_lib.baseboard_fab2(sch_1):m_e_dq(57)") )
				( member ( signalRef "@baseboard_fab2_lib.baseboard_fab2(sch_1):m_e_dq(58)") )
				( member ( signalRef "@baseboard_fab2_lib.baseboard_fab2(sch_1):m_e_dq(59)") )
				( member ( signalRef "@baseboard_fab2_lib.baseboard_fab2(sch_1):m_e_dq(60)") )
				( member ( signalRef "@baseboard_fab2_lib.baseboard_fab2(sch_1):m_e_dq(61)") )
				( member ( signalRef "@baseboard_fab2_lib.baseboard_fab2(sch_1):m_e_dq(62)") )
				( member ( signalRef "@baseboard_fab2_lib.baseboard_fab2(sch_1):m_e_dq(63)") )
				( objectStatus "M_E_DQ" )
			)
			( bus "@baseboard_fab2_lib.baseboard_fab2(sch_1):m_e_dqs_dn"
				( memberType ( signal ) )
				( member ( signalRef "@baseboard_fab2_lib.baseboard_fab2(sch_1):m_e_dqs_dn(0)") )
				( member ( signalRef "@baseboard_fab2_lib.baseboard_fab2(sch_1):m_e_dqs_dn(1)") )
				( member ( signalRef "@baseboard_fab2_lib.baseboard_fab2(sch_1):m_e_dqs_dn(2)") )
				( member ( signalRef "@baseboard_fab2_lib.baseboard_fab2(sch_1):m_e_dqs_dn(3)") )
				( member ( signalRef "@baseboard_fab2_lib.baseboard_fab2(sch_1):m_e_dqs_dn(4)") )
				( member ( signalRef "@baseboard_fab2_lib.baseboard_fab2(sch_1):m_e_dqs_dn(5)") )
				( member ( signalRef "@baseboard_fab2_lib.baseboard_fab2(sch_1):m_e_dqs_dn(6)") )
				( member ( signalRef "@baseboard_fab2_lib.baseboard_fab2(sch_1):m_e_dqs_dn(7)") )
				( member ( signalRef "@baseboard_fab2_lib.baseboard_fab2(sch_1):m_e_dqs_dn(8)") )
				( member ( signalRef "@baseboard_fab2_lib.baseboard_fab2(sch_1):m_e_dqs_dn(9)") )
				( member ( signalRef "@baseboard_fab2_lib.baseboard_fab2(sch_1):m_e_dqs_dn(10)") )
				( member ( signalRef "@baseboard_fab2_lib.baseboard_fab2(sch_1):m_e_dqs_dn(11)") )
				( member ( signalRef "@baseboard_fab2_lib.baseboard_fab2(sch_1):m_e_dqs_dn(12)") )
				( member ( signalRef "@baseboard_fab2_lib.baseboard_fab2(sch_1):m_e_dqs_dn(13)") )
				( member ( signalRef "@baseboard_fab2_lib.baseboard_fab2(sch_1):m_e_dqs_dn(14)") )
				( member ( signalRef "@baseboard_fab2_lib.baseboard_fab2(sch_1):m_e_dqs_dn(15)") )
				( member ( signalRef "@baseboard_fab2_lib.baseboard_fab2(sch_1):m_e_dqs_dn(16)") )
				( member ( signalRef "@baseboard_fab2_lib.baseboard_fab2(sch_1):m_e_dqs_dn(17)") )
				( objectStatus "M_E_DQS_DN" )
			)
			( bus "@baseboard_fab2_lib.baseboard_fab2(sch_1):m_e_dqs_dp"
				( memberType ( signal ) )
				( member ( signalRef "@baseboard_fab2_lib.baseboard_fab2(sch_1):m_e_dqs_dp(0)") )
				( member ( signalRef "@baseboard_fab2_lib.baseboard_fab2(sch_1):m_e_dqs_dp(1)") )
				( member ( signalRef "@baseboard_fab2_lib.baseboard_fab2(sch_1):m_e_dqs_dp(2)") )
				( member ( signalRef "@baseboard_fab2_lib.baseboard_fab2(sch_1):m_e_dqs_dp(3)") )
				( member ( signalRef "@baseboard_fab2_lib.baseboard_fab2(sch_1):m_e_dqs_dp(4)") )
				( member ( signalRef "@baseboard_fab2_lib.baseboard_fab2(sch_1):m_e_dqs_dp(5)") )
				( member ( signalRef "@baseboard_fab2_lib.baseboard_fab2(sch_1):m_e_dqs_dp(6)") )
				( member ( signalRef "@baseboard_fab2_lib.baseboard_fab2(sch_1):m_e_dqs_dp(7)") )
				( member ( signalRef "@baseboard_fab2_lib.baseboard_fab2(sch_1):m_e_dqs_dp(8)") )
				( member ( signalRef "@baseboard_fab2_lib.baseboard_fab2(sch_1):m_e_dqs_dp(9)") )
				( member ( signalRef "@baseboard_fab2_lib.baseboard_fab2(sch_1):m_e_dqs_dp(10)") )
				( member ( signalRef "@baseboard_fab2_lib.baseboard_fab2(sch_1):m_e_dqs_dp(11)") )
				( member ( signalRef "@baseboard_fab2_lib.baseboard_fab2(sch_1):m_e_dqs_dp(12)") )
				( member ( signalRef "@baseboard_fab2_lib.baseboard_fab2(sch_1):m_e_dqs_dp(13)") )
				( member ( signalRef "@baseboard_fab2_lib.baseboard_fab2(sch_1):m_e_dqs_dp(14)") )
				( member ( signalRef "@baseboard_fab2_lib.baseboard_fab2(sch_1):m_e_dqs_dp(15)") )
				( member ( signalRef "@baseboard_fab2_lib.baseboard_fab2(sch_1):m_e_dqs_dp(16)") )
				( member ( signalRef "@baseboard_fab2_lib.baseboard_fab2(sch_1):m_e_dqs_dp(17)") )
				( objectStatus "M_E_DQS_DP" )
			)
			( bus "@baseboard_fab2_lib.baseboard_fab2(sch_1):m_e_ecc"
				( memberType ( signal ) )
				( member ( signalRef "@baseboard_fab2_lib.baseboard_fab2(sch_1):m_e_ecc(0)") )
				( member ( signalRef "@baseboard_fab2_lib.baseboard_fab2(sch_1):m_e_ecc(1)") )
				( member ( signalRef "@baseboard_fab2_lib.baseboard_fab2(sch_1):m_e_ecc(2)") )
				( member ( signalRef "@baseboard_fab2_lib.baseboard_fab2(sch_1):m_e_ecc(3)") )
				( member ( signalRef "@baseboard_fab2_lib.baseboard_fab2(sch_1):m_e_ecc(4)") )
				( member ( signalRef "@baseboard_fab2_lib.baseboard_fab2(sch_1):m_e_ecc(5)") )
				( member ( signalRef "@baseboard_fab2_lib.baseboard_fab2(sch_1):m_e_ecc(6)") )
				( member ( signalRef "@baseboard_fab2_lib.baseboard_fab2(sch_1):m_e_ecc(7)") )
				( objectStatus "M_E_ECC" )
			)
			( bus "@baseboard_fab2_lib.baseboard_fab2(sch_1):m_e_ma"
				( memberType ( signal ) )
				( member ( signalRef "@baseboard_fab2_lib.baseboard_fab2(sch_1):m_e_ma(0)") )
				( member ( signalRef "@baseboard_fab2_lib.baseboard_fab2(sch_1):m_e_ma(1)") )
				( member ( signalRef "@baseboard_fab2_lib.baseboard_fab2(sch_1):m_e_ma(2)") )
				( member ( signalRef "@baseboard_fab2_lib.baseboard_fab2(sch_1):m_e_ma(3)") )
				( member ( signalRef "@baseboard_fab2_lib.baseboard_fab2(sch_1):m_e_ma(4)") )
				( member ( signalRef "@baseboard_fab2_lib.baseboard_fab2(sch_1):m_e_ma(5)") )
				( member ( signalRef "@baseboard_fab2_lib.baseboard_fab2(sch_1):m_e_ma(6)") )
				( member ( signalRef "@baseboard_fab2_lib.baseboard_fab2(sch_1):m_e_ma(7)") )
				( member ( signalRef "@baseboard_fab2_lib.baseboard_fab2(sch_1):m_e_ma(8)") )
				( member ( signalRef "@baseboard_fab2_lib.baseboard_fab2(sch_1):m_e_ma(9)") )
				( member ( signalRef "@baseboard_fab2_lib.baseboard_fab2(sch_1):m_e_ma(10)") )
				( member ( signalRef "@baseboard_fab2_lib.baseboard_fab2(sch_1):m_e_ma(11)") )
				( member ( signalRef "@baseboard_fab2_lib.baseboard_fab2(sch_1):m_e_ma(12)") )
				( member ( signalRef "@baseboard_fab2_lib.baseboard_fab2(sch_1):m_e_ma(13)") )
				( member ( signalRef "@baseboard_fab2_lib.baseboard_fab2(sch_1):m_e_ma(14)") )
				( member ( signalRef "@baseboard_fab2_lib.baseboard_fab2(sch_1):m_e_ma(15)") )
				( member ( signalRef "@baseboard_fab2_lib.baseboard_fab2(sch_1):m_e_ma(16)") )
				( member ( signalRef "@baseboard_fab2_lib.baseboard_fab2(sch_1):m_e_ma(17)") )
				( objectStatus "M_E_MA" )
			)
			( bus "@baseboard_fab2_lib.baseboard_fab2(sch_1):m_e_odt"
				( memberType ( signal ) )
				( member ( signalRef "@baseboard_fab2_lib.baseboard_fab2(sch_1):m_e_odt(0)") )
				( member ( signalRef "@baseboard_fab2_lib.baseboard_fab2(sch_1):m_e_odt(1)") )
				( member ( signalRef "@baseboard_fab2_lib.baseboard_fab2(sch_1):m_e_odt(2)") )
				( member ( signalRef "@baseboard_fab2_lib.baseboard_fab2(sch_1):m_e_odt(3)") )
				( objectStatus "M_E_ODT" )
			)
			( bus "@baseboard_fab2_lib.baseboard_fab2(sch_1):m_f_ba"
				( memberType ( signal ) )
				( member ( signalRef "@baseboard_fab2_lib.baseboard_fab2(sch_1):m_f_ba(0)") )
				( member ( signalRef "@baseboard_fab2_lib.baseboard_fab2(sch_1):m_f_ba(1)") )
				( objectStatus "M_F_BA" )
			)
			( bus "@baseboard_fab2_lib.baseboard_fab2(sch_1):m_f_bg"
				( memberType ( signal ) )
				( member ( signalRef "@baseboard_fab2_lib.baseboard_fab2(sch_1):m_f_bg(0)") )
				( member ( signalRef "@baseboard_fab2_lib.baseboard_fab2(sch_1):m_f_bg(1)") )
				( objectStatus "M_F_BG" )
			)
			( bus "@baseboard_fab2_lib.baseboard_fab2(sch_1):m_f_c"
				( memberType ( signal ) )
				( member ( signalRef "@baseboard_fab2_lib.baseboard_fab2(sch_1):m_f_c(2)") )
				( objectStatus "M_F_C" )
			)
			( bus "@baseboard_fab2_lib.baseboard_fab2(sch_1):m_f_cke"
				( memberType ( signal ) )
				( member ( signalRef "@baseboard_fab2_lib.baseboard_fab2(sch_1):m_f_cke(0)") )
				( member ( signalRef "@baseboard_fab2_lib.baseboard_fab2(sch_1):m_f_cke(1)") )
				( member ( signalRef "@baseboard_fab2_lib.baseboard_fab2(sch_1):m_f_cke(2)") )
				( member ( signalRef "@baseboard_fab2_lib.baseboard_fab2(sch_1):m_f_cke(3)") )
				( objectStatus "M_F_CKE" )
			)
			( bus "@baseboard_fab2_lib.baseboard_fab2(sch_1):m_f_clk_dn"
				( memberType ( signal ) )
				( member ( signalRef "@baseboard_fab2_lib.baseboard_fab2(sch_1):m_f_clk_dn(0)") )
				( member ( signalRef "@baseboard_fab2_lib.baseboard_fab2(sch_1):m_f_clk_dn(1)") )
				( member ( signalRef "@baseboard_fab2_lib.baseboard_fab2(sch_1):m_f_clk_dn(2)") )
				( member ( signalRef "@baseboard_fab2_lib.baseboard_fab2(sch_1):m_f_clk_dn(3)") )
				( objectStatus "M_F_CLK_DN" )
			)
			( bus "@baseboard_fab2_lib.baseboard_fab2(sch_1):m_f_clk_dp"
				( memberType ( signal ) )
				( member ( signalRef "@baseboard_fab2_lib.baseboard_fab2(sch_1):m_f_clk_dp(0)") )
				( member ( signalRef "@baseboard_fab2_lib.baseboard_fab2(sch_1):m_f_clk_dp(1)") )
				( member ( signalRef "@baseboard_fab2_lib.baseboard_fab2(sch_1):m_f_clk_dp(2)") )
				( member ( signalRef "@baseboard_fab2_lib.baseboard_fab2(sch_1):m_f_clk_dp(3)") )
				( objectStatus "M_F_CLK_DP" )
			)
			( bus "@baseboard_fab2_lib.baseboard_fab2(sch_1):m_f_cs_n"
				( memberType ( signal ) )
				( member ( signalRef "@baseboard_fab2_lib.baseboard_fab2(sch_1):m_f_cs_n(0)") )
				( member ( signalRef "@baseboard_fab2_lib.baseboard_fab2(sch_1):m_f_cs_n(1)") )
				( member ( signalRef "@baseboard_fab2_lib.baseboard_fab2(sch_1):m_f_cs_n(2)") )
				( member ( signalRef "@baseboard_fab2_lib.baseboard_fab2(sch_1):m_f_cs_n(3)") )
				( member ( signalRef "@baseboard_fab2_lib.baseboard_fab2(sch_1):m_f_cs_n(4)") )
				( member ( signalRef "@baseboard_fab2_lib.baseboard_fab2(sch_1):m_f_cs_n(5)") )
				( member ( signalRef "@baseboard_fab2_lib.baseboard_fab2(sch_1):m_f_cs_n(6)") )
				( member ( signalRef "@baseboard_fab2_lib.baseboard_fab2(sch_1):m_f_cs_n(7)") )
				( objectStatus "M_F_CS_N" )
			)
			( bus "@baseboard_fab2_lib.baseboard_fab2(sch_1):m_f_dq"
				( memberType ( signal ) )
				( member ( signalRef "@baseboard_fab2_lib.baseboard_fab2(sch_1):m_f_dq(0)") )
				( member ( signalRef "@baseboard_fab2_lib.baseboard_fab2(sch_1):m_f_dq(1)") )
				( member ( signalRef "@baseboard_fab2_lib.baseboard_fab2(sch_1):m_f_dq(2)") )
				( member ( signalRef "@baseboard_fab2_lib.baseboard_fab2(sch_1):m_f_dq(3)") )
				( member ( signalRef "@baseboard_fab2_lib.baseboard_fab2(sch_1):m_f_dq(4)") )
				( member ( signalRef "@baseboard_fab2_lib.baseboard_fab2(sch_1):m_f_dq(5)") )
				( member ( signalRef "@baseboard_fab2_lib.baseboard_fab2(sch_1):m_f_dq(6)") )
				( member ( signalRef "@baseboard_fab2_lib.baseboard_fab2(sch_1):m_f_dq(7)") )
				( member ( signalRef "@baseboard_fab2_lib.baseboard_fab2(sch_1):m_f_dq(8)") )
				( member ( signalRef "@baseboard_fab2_lib.baseboard_fab2(sch_1):m_f_dq(9)") )
				( member ( signalRef "@baseboard_fab2_lib.baseboard_fab2(sch_1):m_f_dq(10)") )
				( member ( signalRef "@baseboard_fab2_lib.baseboard_fab2(sch_1):m_f_dq(11)") )
				( member ( signalRef "@baseboard_fab2_lib.baseboard_fab2(sch_1):m_f_dq(12)") )
				( member ( signalRef "@baseboard_fab2_lib.baseboard_fab2(sch_1):m_f_dq(13)") )
				( member ( signalRef "@baseboard_fab2_lib.baseboard_fab2(sch_1):m_f_dq(14)") )
				( member ( signalRef "@baseboard_fab2_lib.baseboard_fab2(sch_1):m_f_dq(15)") )
				( member ( signalRef "@baseboard_fab2_lib.baseboard_fab2(sch_1):m_f_dq(16)") )
				( member ( signalRef "@baseboard_fab2_lib.baseboard_fab2(sch_1):m_f_dq(17)") )
				( member ( signalRef "@baseboard_fab2_lib.baseboard_fab2(sch_1):m_f_dq(18)") )
				( member ( signalRef "@baseboard_fab2_lib.baseboard_fab2(sch_1):m_f_dq(19)") )
				( member ( signalRef "@baseboard_fab2_lib.baseboard_fab2(sch_1):m_f_dq(20)") )
				( member ( signalRef "@baseboard_fab2_lib.baseboard_fab2(sch_1):m_f_dq(21)") )
				( member ( signalRef "@baseboard_fab2_lib.baseboard_fab2(sch_1):m_f_dq(22)") )
				( member ( signalRef "@baseboard_fab2_lib.baseboard_fab2(sch_1):m_f_dq(23)") )
				( member ( signalRef "@baseboard_fab2_lib.baseboard_fab2(sch_1):m_f_dq(24)") )
				( member ( signalRef "@baseboard_fab2_lib.baseboard_fab2(sch_1):m_f_dq(25)") )
				( member ( signalRef "@baseboard_fab2_lib.baseboard_fab2(sch_1):m_f_dq(26)") )
				( member ( signalRef "@baseboard_fab2_lib.baseboard_fab2(sch_1):m_f_dq(27)") )
				( member ( signalRef "@baseboard_fab2_lib.baseboard_fab2(sch_1):m_f_dq(28)") )
				( member ( signalRef "@baseboard_fab2_lib.baseboard_fab2(sch_1):m_f_dq(29)") )
				( member ( signalRef "@baseboard_fab2_lib.baseboard_fab2(sch_1):m_f_dq(30)") )
				( member ( signalRef "@baseboard_fab2_lib.baseboard_fab2(sch_1):m_f_dq(31)") )
				( member ( signalRef "@baseboard_fab2_lib.baseboard_fab2(sch_1):m_f_dq(32)") )
				( member ( signalRef "@baseboard_fab2_lib.baseboard_fab2(sch_1):m_f_dq(33)") )
				( member ( signalRef "@baseboard_fab2_lib.baseboard_fab2(sch_1):m_f_dq(34)") )
				( member ( signalRef "@baseboard_fab2_lib.baseboard_fab2(sch_1):m_f_dq(35)") )
				( member ( signalRef "@baseboard_fab2_lib.baseboard_fab2(sch_1):m_f_dq(36)") )
				( member ( signalRef "@baseboard_fab2_lib.baseboard_fab2(sch_1):m_f_dq(37)") )
				( member ( signalRef "@baseboard_fab2_lib.baseboard_fab2(sch_1):m_f_dq(38)") )
				( member ( signalRef "@baseboard_fab2_lib.baseboard_fab2(sch_1):m_f_dq(39)") )
				( member ( signalRef "@baseboard_fab2_lib.baseboard_fab2(sch_1):m_f_dq(40)") )
				( member ( signalRef "@baseboard_fab2_lib.baseboard_fab2(sch_1):m_f_dq(41)") )
				( member ( signalRef "@baseboard_fab2_lib.baseboard_fab2(sch_1):m_f_dq(42)") )
				( member ( signalRef "@baseboard_fab2_lib.baseboard_fab2(sch_1):m_f_dq(43)") )
				( member ( signalRef "@baseboard_fab2_lib.baseboard_fab2(sch_1):m_f_dq(44)") )
				( member ( signalRef "@baseboard_fab2_lib.baseboard_fab2(sch_1):m_f_dq(45)") )
				( member ( signalRef "@baseboard_fab2_lib.baseboard_fab2(sch_1):m_f_dq(46)") )
				( member ( signalRef "@baseboard_fab2_lib.baseboard_fab2(sch_1):m_f_dq(47)") )
				( member ( signalRef "@baseboard_fab2_lib.baseboard_fab2(sch_1):m_f_dq(48)") )
				( member ( signalRef "@baseboard_fab2_lib.baseboard_fab2(sch_1):m_f_dq(49)") )
				( member ( signalRef "@baseboard_fab2_lib.baseboard_fab2(sch_1):m_f_dq(50)") )
				( member ( signalRef "@baseboard_fab2_lib.baseboard_fab2(sch_1):m_f_dq(51)") )
				( member ( signalRef "@baseboard_fab2_lib.baseboard_fab2(sch_1):m_f_dq(52)") )
				( member ( signalRef "@baseboard_fab2_lib.baseboard_fab2(sch_1):m_f_dq(53)") )
				( member ( signalRef "@baseboard_fab2_lib.baseboard_fab2(sch_1):m_f_dq(54)") )
				( member ( signalRef "@baseboard_fab2_lib.baseboard_fab2(sch_1):m_f_dq(55)") )
				( member ( signalRef "@baseboard_fab2_lib.baseboard_fab2(sch_1):m_f_dq(56)") )
				( member ( signalRef "@baseboard_fab2_lib.baseboard_fab2(sch_1):m_f_dq(57)") )
				( member ( signalRef "@baseboard_fab2_lib.baseboard_fab2(sch_1):m_f_dq(58)") )
				( member ( signalRef "@baseboard_fab2_lib.baseboard_fab2(sch_1):m_f_dq(59)") )
				( member ( signalRef "@baseboard_fab2_lib.baseboard_fab2(sch_1):m_f_dq(60)") )
				( member ( signalRef "@baseboard_fab2_lib.baseboard_fab2(sch_1):m_f_dq(61)") )
				( member ( signalRef "@baseboard_fab2_lib.baseboard_fab2(sch_1):m_f_dq(62)") )
				( member ( signalRef "@baseboard_fab2_lib.baseboard_fab2(sch_1):m_f_dq(63)") )
				( objectStatus "M_F_DQ" )
			)
			( bus "@baseboard_fab2_lib.baseboard_fab2(sch_1):m_f_dqs_dn"
				( memberType ( signal ) )
				( member ( signalRef "@baseboard_fab2_lib.baseboard_fab2(sch_1):m_f_dqs_dn(0)") )
				( member ( signalRef "@baseboard_fab2_lib.baseboard_fab2(sch_1):m_f_dqs_dn(1)") )
				( member ( signalRef "@baseboard_fab2_lib.baseboard_fab2(sch_1):m_f_dqs_dn(2)") )
				( member ( signalRef "@baseboard_fab2_lib.baseboard_fab2(sch_1):m_f_dqs_dn(3)") )
				( member ( signalRef "@baseboard_fab2_lib.baseboard_fab2(sch_1):m_f_dqs_dn(4)") )
				( member ( signalRef "@baseboard_fab2_lib.baseboard_fab2(sch_1):m_f_dqs_dn(5)") )
				( member ( signalRef "@baseboard_fab2_lib.baseboard_fab2(sch_1):m_f_dqs_dn(6)") )
				( member ( signalRef "@baseboard_fab2_lib.baseboard_fab2(sch_1):m_f_dqs_dn(7)") )
				( member ( signalRef "@baseboard_fab2_lib.baseboard_fab2(sch_1):m_f_dqs_dn(8)") )
				( member ( signalRef "@baseboard_fab2_lib.baseboard_fab2(sch_1):m_f_dqs_dn(9)") )
				( member ( signalRef "@baseboard_fab2_lib.baseboard_fab2(sch_1):m_f_dqs_dn(10)") )
				( member ( signalRef "@baseboard_fab2_lib.baseboard_fab2(sch_1):m_f_dqs_dn(11)") )
				( member ( signalRef "@baseboard_fab2_lib.baseboard_fab2(sch_1):m_f_dqs_dn(12)") )
				( member ( signalRef "@baseboard_fab2_lib.baseboard_fab2(sch_1):m_f_dqs_dn(13)") )
				( member ( signalRef "@baseboard_fab2_lib.baseboard_fab2(sch_1):m_f_dqs_dn(14)") )
				( member ( signalRef "@baseboard_fab2_lib.baseboard_fab2(sch_1):m_f_dqs_dn(15)") )
				( member ( signalRef "@baseboard_fab2_lib.baseboard_fab2(sch_1):m_f_dqs_dn(16)") )
				( member ( signalRef "@baseboard_fab2_lib.baseboard_fab2(sch_1):m_f_dqs_dn(17)") )
				( objectStatus "M_F_DQS_DN" )
			)
			( bus "@baseboard_fab2_lib.baseboard_fab2(sch_1):m_f_dqs_dp"
				( memberType ( signal ) )
				( member ( signalRef "@baseboard_fab2_lib.baseboard_fab2(sch_1):m_f_dqs_dp(0)") )
				( member ( signalRef "@baseboard_fab2_lib.baseboard_fab2(sch_1):m_f_dqs_dp(1)") )
				( member ( signalRef "@baseboard_fab2_lib.baseboard_fab2(sch_1):m_f_dqs_dp(2)") )
				( member ( signalRef "@baseboard_fab2_lib.baseboard_fab2(sch_1):m_f_dqs_dp(3)") )
				( member ( signalRef "@baseboard_fab2_lib.baseboard_fab2(sch_1):m_f_dqs_dp(4)") )
				( member ( signalRef "@baseboard_fab2_lib.baseboard_fab2(sch_1):m_f_dqs_dp(5)") )
				( member ( signalRef "@baseboard_fab2_lib.baseboard_fab2(sch_1):m_f_dqs_dp(6)") )
				( member ( signalRef "@baseboard_fab2_lib.baseboard_fab2(sch_1):m_f_dqs_dp(7)") )
				( member ( signalRef "@baseboard_fab2_lib.baseboard_fab2(sch_1):m_f_dqs_dp(8)") )
				( member ( signalRef "@baseboard_fab2_lib.baseboard_fab2(sch_1):m_f_dqs_dp(9)") )
				( member ( signalRef "@baseboard_fab2_lib.baseboard_fab2(sch_1):m_f_dqs_dp(10)") )
				( member ( signalRef "@baseboard_fab2_lib.baseboard_fab2(sch_1):m_f_dqs_dp(11)") )
				( member ( signalRef "@baseboard_fab2_lib.baseboard_fab2(sch_1):m_f_dqs_dp(12)") )
				( member ( signalRef "@baseboard_fab2_lib.baseboard_fab2(sch_1):m_f_dqs_dp(13)") )
				( member ( signalRef "@baseboard_fab2_lib.baseboard_fab2(sch_1):m_f_dqs_dp(14)") )
				( member ( signalRef "@baseboard_fab2_lib.baseboard_fab2(sch_1):m_f_dqs_dp(15)") )
				( member ( signalRef "@baseboard_fab2_lib.baseboard_fab2(sch_1):m_f_dqs_dp(16)") )
				( member ( signalRef "@baseboard_fab2_lib.baseboard_fab2(sch_1):m_f_dqs_dp(17)") )
				( objectStatus "M_F_DQS_DP" )
			)
			( bus "@baseboard_fab2_lib.baseboard_fab2(sch_1):m_f_ecc"
				( memberType ( signal ) )
				( member ( signalRef "@baseboard_fab2_lib.baseboard_fab2(sch_1):m_f_ecc(0)") )
				( member ( signalRef "@baseboard_fab2_lib.baseboard_fab2(sch_1):m_f_ecc(1)") )
				( member ( signalRef "@baseboard_fab2_lib.baseboard_fab2(sch_1):m_f_ecc(2)") )
				( member ( signalRef "@baseboard_fab2_lib.baseboard_fab2(sch_1):m_f_ecc(3)") )
				( member ( signalRef "@baseboard_fab2_lib.baseboard_fab2(sch_1):m_f_ecc(4)") )
				( member ( signalRef "@baseboard_fab2_lib.baseboard_fab2(sch_1):m_f_ecc(5)") )
				( member ( signalRef "@baseboard_fab2_lib.baseboard_fab2(sch_1):m_f_ecc(6)") )
				( member ( signalRef "@baseboard_fab2_lib.baseboard_fab2(sch_1):m_f_ecc(7)") )
				( objectStatus "M_F_ECC" )
			)
			( bus "@baseboard_fab2_lib.baseboard_fab2(sch_1):m_f_ma"
				( memberType ( signal ) )
				( member ( signalRef "@baseboard_fab2_lib.baseboard_fab2(sch_1):m_f_ma(0)") )
				( member ( signalRef "@baseboard_fab2_lib.baseboard_fab2(sch_1):m_f_ma(1)") )
				( member ( signalRef "@baseboard_fab2_lib.baseboard_fab2(sch_1):m_f_ma(2)") )
				( member ( signalRef "@baseboard_fab2_lib.baseboard_fab2(sch_1):m_f_ma(3)") )
				( member ( signalRef "@baseboard_fab2_lib.baseboard_fab2(sch_1):m_f_ma(4)") )
				( member ( signalRef "@baseboard_fab2_lib.baseboard_fab2(sch_1):m_f_ma(5)") )
				( member ( signalRef "@baseboard_fab2_lib.baseboard_fab2(sch_1):m_f_ma(6)") )
				( member ( signalRef "@baseboard_fab2_lib.baseboard_fab2(sch_1):m_f_ma(7)") )
				( member ( signalRef "@baseboard_fab2_lib.baseboard_fab2(sch_1):m_f_ma(8)") )
				( member ( signalRef "@baseboard_fab2_lib.baseboard_fab2(sch_1):m_f_ma(9)") )
				( member ( signalRef "@baseboard_fab2_lib.baseboard_fab2(sch_1):m_f_ma(10)") )
				( member ( signalRef "@baseboard_fab2_lib.baseboard_fab2(sch_1):m_f_ma(11)") )
				( member ( signalRef "@baseboard_fab2_lib.baseboard_fab2(sch_1):m_f_ma(12)") )
				( member ( signalRef "@baseboard_fab2_lib.baseboard_fab2(sch_1):m_f_ma(13)") )
				( member ( signalRef "@baseboard_fab2_lib.baseboard_fab2(sch_1):m_f_ma(14)") )
				( member ( signalRef "@baseboard_fab2_lib.baseboard_fab2(sch_1):m_f_ma(15)") )
				( member ( signalRef "@baseboard_fab2_lib.baseboard_fab2(sch_1):m_f_ma(16)") )
				( member ( signalRef "@baseboard_fab2_lib.baseboard_fab2(sch_1):m_f_ma(17)") )
				( objectStatus "M_F_MA" )
			)
			( bus "@baseboard_fab2_lib.baseboard_fab2(sch_1):m_f_odt"
				( memberType ( signal ) )
				( member ( signalRef "@baseboard_fab2_lib.baseboard_fab2(sch_1):m_f_odt(0)") )
				( member ( signalRef "@baseboard_fab2_lib.baseboard_fab2(sch_1):m_f_odt(1)") )
				( member ( signalRef "@baseboard_fab2_lib.baseboard_fab2(sch_1):m_f_odt(2)") )
				( member ( signalRef "@baseboard_fab2_lib.baseboard_fab2(sch_1):m_f_odt(3)") )
				( objectStatus "M_F_ODT" )
			)
			( bus "@baseboard_fab2_lib.baseboard_fab2(sch_1):dmi_cpu0_pch_rx_c_dn"
				( memberType ( signal ) )
				( member ( signalRef "@baseboard_fab2_lib.baseboard_fab2(sch_1):dmi_cpu0_pch_rx_c_dn(0)") )
				( member ( signalRef "@baseboard_fab2_lib.baseboard_fab2(sch_1):dmi_cpu0_pch_rx_c_dn(1)") )
				( member ( signalRef "@baseboard_fab2_lib.baseboard_fab2(sch_1):dmi_cpu0_pch_rx_c_dn(2)") )
				( member ( signalRef "@baseboard_fab2_lib.baseboard_fab2(sch_1):dmi_cpu0_pch_rx_c_dn(3)") )
				( objectStatus "DMI_CPU0_PCH_RX_C_DN" )
			)
			( bus "@baseboard_fab2_lib.baseboard_fab2(sch_1):dmi_cpu0_pch_rx_c_dp"
				( memberType ( signal ) )
				( member ( signalRef "@baseboard_fab2_lib.baseboard_fab2(sch_1):dmi_cpu0_pch_rx_c_dp(0)") )
				( member ( signalRef "@baseboard_fab2_lib.baseboard_fab2(sch_1):dmi_cpu0_pch_rx_c_dp(1)") )
				( member ( signalRef "@baseboard_fab2_lib.baseboard_fab2(sch_1):dmi_cpu0_pch_rx_c_dp(2)") )
				( member ( signalRef "@baseboard_fab2_lib.baseboard_fab2(sch_1):dmi_cpu0_pch_rx_c_dp(3)") )
				( objectStatus "DMI_CPU0_PCH_RX_C_DP" )
			)
			( bus "@baseboard_fab2_lib.baseboard_fab2(sch_1):dmi_cpu0_pch_tx_dn"
				( memberType ( signal ) )
				( member ( signalRef "@baseboard_fab2_lib.baseboard_fab2(sch_1):dmi_cpu0_pch_tx_dn(0)") )
				( member ( signalRef "@baseboard_fab2_lib.baseboard_fab2(sch_1):dmi_cpu0_pch_tx_dn(1)") )
				( member ( signalRef "@baseboard_fab2_lib.baseboard_fab2(sch_1):dmi_cpu0_pch_tx_dn(2)") )
				( member ( signalRef "@baseboard_fab2_lib.baseboard_fab2(sch_1):dmi_cpu0_pch_tx_dn(3)") )
				( objectStatus "DMI_CPU0_PCH_TX_DN" )
			)
			( bus "@baseboard_fab2_lib.baseboard_fab2(sch_1):dmi_cpu0_pch_tx_dp"
				( memberType ( signal ) )
				( member ( signalRef "@baseboard_fab2_lib.baseboard_fab2(sch_1):dmi_cpu0_pch_tx_dp(0)") )
				( member ( signalRef "@baseboard_fab2_lib.baseboard_fab2(sch_1):dmi_cpu0_pch_tx_dp(1)") )
				( member ( signalRef "@baseboard_fab2_lib.baseboard_fab2(sch_1):dmi_cpu0_pch_tx_dp(2)") )
				( member ( signalRef "@baseboard_fab2_lib.baseboard_fab2(sch_1):dmi_cpu0_pch_tx_dp(3)") )
				( objectStatus "DMI_CPU0_PCH_TX_DP" )
			)
			( bus "@baseboard_fab2_lib.baseboard_fab2(sch_1):p3e_cpu0_pe1_pch_rxn"
				( memberType ( signal ) )
				( member ( signalRef "@baseboard_fab2_lib.baseboard_fab2(sch_1):p3e_cpu0_pe1_pch_rxn(8)") )
				( member ( signalRef "@baseboard_fab2_lib.baseboard_fab2(sch_1):p3e_cpu0_pe1_pch_rxn(9)") )
				( member ( signalRef "@baseboard_fab2_lib.baseboard_fab2(sch_1):p3e_cpu0_pe1_pch_rxn(10)") )
				( member ( signalRef "@baseboard_fab2_lib.baseboard_fab2(sch_1):p3e_cpu0_pe1_pch_rxn(11)") )
				( member ( signalRef "@baseboard_fab2_lib.baseboard_fab2(sch_1):p3e_cpu0_pe1_pch_rxn(12)") )
				( member ( signalRef "@baseboard_fab2_lib.baseboard_fab2(sch_1):p3e_cpu0_pe1_pch_rxn(13)") )
				( member ( signalRef "@baseboard_fab2_lib.baseboard_fab2(sch_1):p3e_cpu0_pe1_pch_rxn(14)") )
				( member ( signalRef "@baseboard_fab2_lib.baseboard_fab2(sch_1):p3e_cpu0_pe1_pch_rxn(15)") )
				( member ( signalRef "@baseboard_fab2_lib.baseboard_fab2(sch_1):p3e_cpu0_pe1_pch_rxn(0)") )
				( member ( signalRef "@baseboard_fab2_lib.baseboard_fab2(sch_1):p3e_cpu0_pe1_pch_rxn(1)") )
				( member ( signalRef "@baseboard_fab2_lib.baseboard_fab2(sch_1):p3e_cpu0_pe1_pch_rxn(2)") )
				( member ( signalRef "@baseboard_fab2_lib.baseboard_fab2(sch_1):p3e_cpu0_pe1_pch_rxn(3)") )
				( member ( signalRef "@baseboard_fab2_lib.baseboard_fab2(sch_1):p3e_cpu0_pe1_pch_rxn(4)") )
				( member ( signalRef "@baseboard_fab2_lib.baseboard_fab2(sch_1):p3e_cpu0_pe1_pch_rxn(5)") )
				( member ( signalRef "@baseboard_fab2_lib.baseboard_fab2(sch_1):p3e_cpu0_pe1_pch_rxn(6)") )
				( member ( signalRef "@baseboard_fab2_lib.baseboard_fab2(sch_1):p3e_cpu0_pe1_pch_rxn(7)") )
				( objectStatus "P3E_CPU0_PE1_PCH_RXN" )
			)
			( bus "@baseboard_fab2_lib.baseboard_fab2(sch_1):p3e_cpu0_pe1_pch_rxp"
				( memberType ( signal ) )
				( member ( signalRef "@baseboard_fab2_lib.baseboard_fab2(sch_1):p3e_cpu0_pe1_pch_rxp(8)") )
				( member ( signalRef "@baseboard_fab2_lib.baseboard_fab2(sch_1):p3e_cpu0_pe1_pch_rxp(9)") )
				( member ( signalRef "@baseboard_fab2_lib.baseboard_fab2(sch_1):p3e_cpu0_pe1_pch_rxp(10)") )
				( member ( signalRef "@baseboard_fab2_lib.baseboard_fab2(sch_1):p3e_cpu0_pe1_pch_rxp(11)") )
				( member ( signalRef "@baseboard_fab2_lib.baseboard_fab2(sch_1):p3e_cpu0_pe1_pch_rxp(12)") )
				( member ( signalRef "@baseboard_fab2_lib.baseboard_fab2(sch_1):p3e_cpu0_pe1_pch_rxp(13)") )
				( member ( signalRef "@baseboard_fab2_lib.baseboard_fab2(sch_1):p3e_cpu0_pe1_pch_rxp(14)") )
				( member ( signalRef "@baseboard_fab2_lib.baseboard_fab2(sch_1):p3e_cpu0_pe1_pch_rxp(15)") )
				( member ( signalRef "@baseboard_fab2_lib.baseboard_fab2(sch_1):p3e_cpu0_pe1_pch_rxp(0)") )
				( member ( signalRef "@baseboard_fab2_lib.baseboard_fab2(sch_1):p3e_cpu0_pe1_pch_rxp(1)") )
				( member ( signalRef "@baseboard_fab2_lib.baseboard_fab2(sch_1):p3e_cpu0_pe1_pch_rxp(2)") )
				( member ( signalRef "@baseboard_fab2_lib.baseboard_fab2(sch_1):p3e_cpu0_pe1_pch_rxp(3)") )
				( member ( signalRef "@baseboard_fab2_lib.baseboard_fab2(sch_1):p3e_cpu0_pe1_pch_rxp(4)") )
				( member ( signalRef "@baseboard_fab2_lib.baseboard_fab2(sch_1):p3e_cpu0_pe1_pch_rxp(5)") )
				( member ( signalRef "@baseboard_fab2_lib.baseboard_fab2(sch_1):p3e_cpu0_pe1_pch_rxp(6)") )
				( member ( signalRef "@baseboard_fab2_lib.baseboard_fab2(sch_1):p3e_cpu0_pe1_pch_rxp(7)") )
				( objectStatus "P3E_CPU0_PE1_PCH_RXP" )
			)
			( bus "@baseboard_fab2_lib.baseboard_fab2(sch_1):p3e_cpu0_pe1_pch_txn"
				( memberType ( signal ) )
				( member ( signalRef "@baseboard_fab2_lib.baseboard_fab2(sch_1):p3e_cpu0_pe1_pch_txn(8)") )
				( member ( signalRef "@baseboard_fab2_lib.baseboard_fab2(sch_1):p3e_cpu0_pe1_pch_txn(9)") )
				( member ( signalRef "@baseboard_fab2_lib.baseboard_fab2(sch_1):p3e_cpu0_pe1_pch_txn(10)") )
				( member ( signalRef "@baseboard_fab2_lib.baseboard_fab2(sch_1):p3e_cpu0_pe1_pch_txn(11)") )
				( member ( signalRef "@baseboard_fab2_lib.baseboard_fab2(sch_1):p3e_cpu0_pe1_pch_txn(12)") )
				( member ( signalRef "@baseboard_fab2_lib.baseboard_fab2(sch_1):p3e_cpu0_pe1_pch_txn(13)") )
				( member ( signalRef "@baseboard_fab2_lib.baseboard_fab2(sch_1):p3e_cpu0_pe1_pch_txn(14)") )
				( member ( signalRef "@baseboard_fab2_lib.baseboard_fab2(sch_1):p3e_cpu0_pe1_pch_txn(15)") )
				( member ( signalRef "@baseboard_fab2_lib.baseboard_fab2(sch_1):p3e_cpu0_pe1_pch_txn(0)") )
				( member ( signalRef "@baseboard_fab2_lib.baseboard_fab2(sch_1):p3e_cpu0_pe1_pch_txn(1)") )
				( member ( signalRef "@baseboard_fab2_lib.baseboard_fab2(sch_1):p3e_cpu0_pe1_pch_txn(2)") )
				( member ( signalRef "@baseboard_fab2_lib.baseboard_fab2(sch_1):p3e_cpu0_pe1_pch_txn(3)") )
				( member ( signalRef "@baseboard_fab2_lib.baseboard_fab2(sch_1):p3e_cpu0_pe1_pch_txn(4)") )
				( member ( signalRef "@baseboard_fab2_lib.baseboard_fab2(sch_1):p3e_cpu0_pe1_pch_txn(5)") )
				( member ( signalRef "@baseboard_fab2_lib.baseboard_fab2(sch_1):p3e_cpu0_pe1_pch_txn(6)") )
				( member ( signalRef "@baseboard_fab2_lib.baseboard_fab2(sch_1):p3e_cpu0_pe1_pch_txn(7)") )
				( objectStatus "P3E_CPU0_PE1_PCH_TXN" )
			)
			( bus "@baseboard_fab2_lib.baseboard_fab2(sch_1):p3e_cpu0_pe1_pch_txp"
				( memberType ( signal ) )
				( member ( signalRef "@baseboard_fab2_lib.baseboard_fab2(sch_1):p3e_cpu0_pe1_pch_txp(8)") )
				( member ( signalRef "@baseboard_fab2_lib.baseboard_fab2(sch_1):p3e_cpu0_pe1_pch_txp(9)") )
				( member ( signalRef "@baseboard_fab2_lib.baseboard_fab2(sch_1):p3e_cpu0_pe1_pch_txp(10)") )
				( member ( signalRef "@baseboard_fab2_lib.baseboard_fab2(sch_1):p3e_cpu0_pe1_pch_txp(11)") )
				( member ( signalRef "@baseboard_fab2_lib.baseboard_fab2(sch_1):p3e_cpu0_pe1_pch_txp(12)") )
				( member ( signalRef "@baseboard_fab2_lib.baseboard_fab2(sch_1):p3e_cpu0_pe1_pch_txp(13)") )
				( member ( signalRef "@baseboard_fab2_lib.baseboard_fab2(sch_1):p3e_cpu0_pe1_pch_txp(14)") )
				( member ( signalRef "@baseboard_fab2_lib.baseboard_fab2(sch_1):p3e_cpu0_pe1_pch_txp(15)") )
				( member ( signalRef "@baseboard_fab2_lib.baseboard_fab2(sch_1):p3e_cpu0_pe1_pch_txp(0)") )
				( member ( signalRef "@baseboard_fab2_lib.baseboard_fab2(sch_1):p3e_cpu0_pe1_pch_txp(1)") )
				( member ( signalRef "@baseboard_fab2_lib.baseboard_fab2(sch_1):p3e_cpu0_pe1_pch_txp(2)") )
				( member ( signalRef "@baseboard_fab2_lib.baseboard_fab2(sch_1):p3e_cpu0_pe1_pch_txp(3)") )
				( member ( signalRef "@baseboard_fab2_lib.baseboard_fab2(sch_1):p3e_cpu0_pe1_pch_txp(4)") )
				( member ( signalRef "@baseboard_fab2_lib.baseboard_fab2(sch_1):p3e_cpu0_pe1_pch_txp(5)") )
				( member ( signalRef "@baseboard_fab2_lib.baseboard_fab2(sch_1):p3e_cpu0_pe1_pch_txp(6)") )
				( member ( signalRef "@baseboard_fab2_lib.baseboard_fab2(sch_1):p3e_cpu0_pe1_pch_txp(7)") )
				( objectStatus "P3E_CPU0_PE1_PCH_TXP" )
			)
			( bus "@baseboard_fab2_lib.baseboard_fab2(sch_1):p3e_cpu0_pe1_ss_rxn"
				( memberType ( signal ) )
				( member ( signalRef "@baseboard_fab2_lib.baseboard_fab2(sch_1):p3e_cpu0_pe1_ss_rxn(0)") )
				( member ( signalRef "@baseboard_fab2_lib.baseboard_fab2(sch_1):p3e_cpu0_pe1_ss_rxn(1)") )
				( member ( signalRef "@baseboard_fab2_lib.baseboard_fab2(sch_1):p3e_cpu0_pe1_ss_rxn(2)") )
				( member ( signalRef "@baseboard_fab2_lib.baseboard_fab2(sch_1):p3e_cpu0_pe1_ss_rxn(3)") )
				( member ( signalRef "@baseboard_fab2_lib.baseboard_fab2(sch_1):p3e_cpu0_pe1_ss_rxn(4)") )
				( member ( signalRef "@baseboard_fab2_lib.baseboard_fab2(sch_1):p3e_cpu0_pe1_ss_rxn(5)") )
				( member ( signalRef "@baseboard_fab2_lib.baseboard_fab2(sch_1):p3e_cpu0_pe1_ss_rxn(6)") )
				( member ( signalRef "@baseboard_fab2_lib.baseboard_fab2(sch_1):p3e_cpu0_pe1_ss_rxn(7)") )
				( objectStatus "P3E_CPU0_PE1_SS_RXN" )
			)
			( bus "@baseboard_fab2_lib.baseboard_fab2(sch_1):p3e_cpu0_pe1_ss_rxp"
				( memberType ( signal ) )
				( member ( signalRef "@baseboard_fab2_lib.baseboard_fab2(sch_1):p3e_cpu0_pe1_ss_rxp(0)") )
				( member ( signalRef "@baseboard_fab2_lib.baseboard_fab2(sch_1):p3e_cpu0_pe1_ss_rxp(1)") )
				( member ( signalRef "@baseboard_fab2_lib.baseboard_fab2(sch_1):p3e_cpu0_pe1_ss_rxp(2)") )
				( member ( signalRef "@baseboard_fab2_lib.baseboard_fab2(sch_1):p3e_cpu0_pe1_ss_rxp(3)") )
				( member ( signalRef "@baseboard_fab2_lib.baseboard_fab2(sch_1):p3e_cpu0_pe1_ss_rxp(4)") )
				( member ( signalRef "@baseboard_fab2_lib.baseboard_fab2(sch_1):p3e_cpu0_pe1_ss_rxp(5)") )
				( member ( signalRef "@baseboard_fab2_lib.baseboard_fab2(sch_1):p3e_cpu0_pe1_ss_rxp(6)") )
				( member ( signalRef "@baseboard_fab2_lib.baseboard_fab2(sch_1):p3e_cpu0_pe1_ss_rxp(7)") )
				( objectStatus "P3E_CPU0_PE1_SS_RXP" )
			)
			( bus "@baseboard_fab2_lib.baseboard_fab2(sch_1):p3e_cpu0_pe1_ss_txn"
				( memberType ( signal ) )
				( member ( signalRef "@baseboard_fab2_lib.baseboard_fab2(sch_1):p3e_cpu0_pe1_ss_txn(0)") )
				( member ( signalRef "@baseboard_fab2_lib.baseboard_fab2(sch_1):p3e_cpu0_pe1_ss_txn(1)") )
				( member ( signalRef "@baseboard_fab2_lib.baseboard_fab2(sch_1):p3e_cpu0_pe1_ss_txn(2)") )
				( member ( signalRef "@baseboard_fab2_lib.baseboard_fab2(sch_1):p3e_cpu0_pe1_ss_txn(3)") )
				( member ( signalRef "@baseboard_fab2_lib.baseboard_fab2(sch_1):p3e_cpu0_pe1_ss_txn(4)") )
				( member ( signalRef "@baseboard_fab2_lib.baseboard_fab2(sch_1):p3e_cpu0_pe1_ss_txn(5)") )
				( member ( signalRef "@baseboard_fab2_lib.baseboard_fab2(sch_1):p3e_cpu0_pe1_ss_txn(6)") )
				( member ( signalRef "@baseboard_fab2_lib.baseboard_fab2(sch_1):p3e_cpu0_pe1_ss_txn(7)") )
				( objectStatus "P3E_CPU0_PE1_SS_TXN" )
			)
			( bus "@baseboard_fab2_lib.baseboard_fab2(sch_1):p3e_cpu0_pe1_ss_txp"
				( memberType ( signal ) )
				( member ( signalRef "@baseboard_fab2_lib.baseboard_fab2(sch_1):p3e_cpu0_pe1_ss_txp(0)") )
				( member ( signalRef "@baseboard_fab2_lib.baseboard_fab2(sch_1):p3e_cpu0_pe1_ss_txp(1)") )
				( member ( signalRef "@baseboard_fab2_lib.baseboard_fab2(sch_1):p3e_cpu0_pe1_ss_txp(2)") )
				( member ( signalRef "@baseboard_fab2_lib.baseboard_fab2(sch_1):p3e_cpu0_pe1_ss_txp(3)") )
				( member ( signalRef "@baseboard_fab2_lib.baseboard_fab2(sch_1):p3e_cpu0_pe1_ss_txp(4)") )
				( member ( signalRef "@baseboard_fab2_lib.baseboard_fab2(sch_1):p3e_cpu0_pe1_ss_txp(5)") )
				( member ( signalRef "@baseboard_fab2_lib.baseboard_fab2(sch_1):p3e_cpu0_pe1_ss_txp(6)") )
				( member ( signalRef "@baseboard_fab2_lib.baseboard_fab2(sch_1):p3e_cpu0_pe1_ss_txp(7)") )
				( objectStatus "P3E_CPU0_PE1_SS_TXP" )
			)
			( bus "@baseboard_fab2_lib.baseboard_fab2(sch_1):p3e_cpu0_pe2_ss_rxn"
				( memberType ( signal ) )
				( member ( signalRef "@baseboard_fab2_lib.baseboard_fab2(sch_1):p3e_cpu0_pe2_ss_rxn(0)") )
				( member ( signalRef "@baseboard_fab2_lib.baseboard_fab2(sch_1):p3e_cpu0_pe2_ss_rxn(1)") )
				( member ( signalRef "@baseboard_fab2_lib.baseboard_fab2(sch_1):p3e_cpu0_pe2_ss_rxn(2)") )
				( member ( signalRef "@baseboard_fab2_lib.baseboard_fab2(sch_1):p3e_cpu0_pe2_ss_rxn(3)") )
				( member ( signalRef "@baseboard_fab2_lib.baseboard_fab2(sch_1):p3e_cpu0_pe2_ss_rxn(4)") )
				( member ( signalRef "@baseboard_fab2_lib.baseboard_fab2(sch_1):p3e_cpu0_pe2_ss_rxn(5)") )
				( member ( signalRef "@baseboard_fab2_lib.baseboard_fab2(sch_1):p3e_cpu0_pe2_ss_rxn(6)") )
				( member ( signalRef "@baseboard_fab2_lib.baseboard_fab2(sch_1):p3e_cpu0_pe2_ss_rxn(7)") )
				( member ( signalRef "@baseboard_fab2_lib.baseboard_fab2(sch_1):p3e_cpu0_pe2_ss_rxn(8)") )
				( member ( signalRef "@baseboard_fab2_lib.baseboard_fab2(sch_1):p3e_cpu0_pe2_ss_rxn(9)") )
				( member ( signalRef "@baseboard_fab2_lib.baseboard_fab2(sch_1):p3e_cpu0_pe2_ss_rxn(10)") )
				( member ( signalRef "@baseboard_fab2_lib.baseboard_fab2(sch_1):p3e_cpu0_pe2_ss_rxn(11)") )
				( member ( signalRef "@baseboard_fab2_lib.baseboard_fab2(sch_1):p3e_cpu0_pe2_ss_rxn(12)") )
				( member ( signalRef "@baseboard_fab2_lib.baseboard_fab2(sch_1):p3e_cpu0_pe2_ss_rxn(13)") )
				( member ( signalRef "@baseboard_fab2_lib.baseboard_fab2(sch_1):p3e_cpu0_pe2_ss_rxn(14)") )
				( member ( signalRef "@baseboard_fab2_lib.baseboard_fab2(sch_1):p3e_cpu0_pe2_ss_rxn(15)") )
				( objectStatus "P3E_CPU0_PE2_SS_RXN" )
			)
			( bus "@baseboard_fab2_lib.baseboard_fab2(sch_1):p3e_cpu0_pe2_ss_rxp"
				( memberType ( signal ) )
				( member ( signalRef "@baseboard_fab2_lib.baseboard_fab2(sch_1):p3e_cpu0_pe2_ss_rxp(0)") )
				( member ( signalRef "@baseboard_fab2_lib.baseboard_fab2(sch_1):p3e_cpu0_pe2_ss_rxp(1)") )
				( member ( signalRef "@baseboard_fab2_lib.baseboard_fab2(sch_1):p3e_cpu0_pe2_ss_rxp(2)") )
				( member ( signalRef "@baseboard_fab2_lib.baseboard_fab2(sch_1):p3e_cpu0_pe2_ss_rxp(3)") )
				( member ( signalRef "@baseboard_fab2_lib.baseboard_fab2(sch_1):p3e_cpu0_pe2_ss_rxp(4)") )
				( member ( signalRef "@baseboard_fab2_lib.baseboard_fab2(sch_1):p3e_cpu0_pe2_ss_rxp(5)") )
				( member ( signalRef "@baseboard_fab2_lib.baseboard_fab2(sch_1):p3e_cpu0_pe2_ss_rxp(6)") )
				( member ( signalRef "@baseboard_fab2_lib.baseboard_fab2(sch_1):p3e_cpu0_pe2_ss_rxp(7)") )
				( member ( signalRef "@baseboard_fab2_lib.baseboard_fab2(sch_1):p3e_cpu0_pe2_ss_rxp(8)") )
				( member ( signalRef "@baseboard_fab2_lib.baseboard_fab2(sch_1):p3e_cpu0_pe2_ss_rxp(9)") )
				( member ( signalRef "@baseboard_fab2_lib.baseboard_fab2(sch_1):p3e_cpu0_pe2_ss_rxp(10)") )
				( member ( signalRef "@baseboard_fab2_lib.baseboard_fab2(sch_1):p3e_cpu0_pe2_ss_rxp(11)") )
				( member ( signalRef "@baseboard_fab2_lib.baseboard_fab2(sch_1):p3e_cpu0_pe2_ss_rxp(12)") )
				( member ( signalRef "@baseboard_fab2_lib.baseboard_fab2(sch_1):p3e_cpu0_pe2_ss_rxp(13)") )
				( member ( signalRef "@baseboard_fab2_lib.baseboard_fab2(sch_1):p3e_cpu0_pe2_ss_rxp(14)") )
				( member ( signalRef "@baseboard_fab2_lib.baseboard_fab2(sch_1):p3e_cpu0_pe2_ss_rxp(15)") )
				( objectStatus "P3E_CPU0_PE2_SS_RXP" )
			)
			( bus "@baseboard_fab2_lib.baseboard_fab2(sch_1):p3e_cpu0_pe2_ss_txn"
				( memberType ( signal ) )
				( member ( signalRef "@baseboard_fab2_lib.baseboard_fab2(sch_1):p3e_cpu0_pe2_ss_txn(0)") )
				( member ( signalRef "@baseboard_fab2_lib.baseboard_fab2(sch_1):p3e_cpu0_pe2_ss_txn(1)") )
				( member ( signalRef "@baseboard_fab2_lib.baseboard_fab2(sch_1):p3e_cpu0_pe2_ss_txn(2)") )
				( member ( signalRef "@baseboard_fab2_lib.baseboard_fab2(sch_1):p3e_cpu0_pe2_ss_txn(3)") )
				( member ( signalRef "@baseboard_fab2_lib.baseboard_fab2(sch_1):p3e_cpu0_pe2_ss_txn(4)") )
				( member ( signalRef "@baseboard_fab2_lib.baseboard_fab2(sch_1):p3e_cpu0_pe2_ss_txn(5)") )
				( member ( signalRef "@baseboard_fab2_lib.baseboard_fab2(sch_1):p3e_cpu0_pe2_ss_txn(6)") )
				( member ( signalRef "@baseboard_fab2_lib.baseboard_fab2(sch_1):p3e_cpu0_pe2_ss_txn(7)") )
				( member ( signalRef "@baseboard_fab2_lib.baseboard_fab2(sch_1):p3e_cpu0_pe2_ss_txn(8)") )
				( member ( signalRef "@baseboard_fab2_lib.baseboard_fab2(sch_1):p3e_cpu0_pe2_ss_txn(9)") )
				( member ( signalRef "@baseboard_fab2_lib.baseboard_fab2(sch_1):p3e_cpu0_pe2_ss_txn(10)") )
				( member ( signalRef "@baseboard_fab2_lib.baseboard_fab2(sch_1):p3e_cpu0_pe2_ss_txn(11)") )
				( member ( signalRef "@baseboard_fab2_lib.baseboard_fab2(sch_1):p3e_cpu0_pe2_ss_txn(12)") )
				( member ( signalRef "@baseboard_fab2_lib.baseboard_fab2(sch_1):p3e_cpu0_pe2_ss_txn(13)") )
				( member ( signalRef "@baseboard_fab2_lib.baseboard_fab2(sch_1):p3e_cpu0_pe2_ss_txn(14)") )
				( member ( signalRef "@baseboard_fab2_lib.baseboard_fab2(sch_1):p3e_cpu0_pe2_ss_txn(15)") )
				( objectStatus "P3E_CPU0_PE2_SS_TXN" )
			)
			( bus "@baseboard_fab2_lib.baseboard_fab2(sch_1):p3e_cpu0_pe2_ss_txp"
				( memberType ( signal ) )
				( member ( signalRef "@baseboard_fab2_lib.baseboard_fab2(sch_1):p3e_cpu0_pe2_ss_txp(0)") )
				( member ( signalRef "@baseboard_fab2_lib.baseboard_fab2(sch_1):p3e_cpu0_pe2_ss_txp(1)") )
				( member ( signalRef "@baseboard_fab2_lib.baseboard_fab2(sch_1):p3e_cpu0_pe2_ss_txp(2)") )
				( member ( signalRef "@baseboard_fab2_lib.baseboard_fab2(sch_1):p3e_cpu0_pe2_ss_txp(3)") )
				( member ( signalRef "@baseboard_fab2_lib.baseboard_fab2(sch_1):p3e_cpu0_pe2_ss_txp(4)") )
				( member ( signalRef "@baseboard_fab2_lib.baseboard_fab2(sch_1):p3e_cpu0_pe2_ss_txp(5)") )
				( member ( signalRef "@baseboard_fab2_lib.baseboard_fab2(sch_1):p3e_cpu0_pe2_ss_txp(6)") )
				( member ( signalRef "@baseboard_fab2_lib.baseboard_fab2(sch_1):p3e_cpu0_pe2_ss_txp(7)") )
				( member ( signalRef "@baseboard_fab2_lib.baseboard_fab2(sch_1):p3e_cpu0_pe2_ss_txp(8)") )
				( member ( signalRef "@baseboard_fab2_lib.baseboard_fab2(sch_1):p3e_cpu0_pe2_ss_txp(9)") )
				( member ( signalRef "@baseboard_fab2_lib.baseboard_fab2(sch_1):p3e_cpu0_pe2_ss_txp(10)") )
				( member ( signalRef "@baseboard_fab2_lib.baseboard_fab2(sch_1):p3e_cpu0_pe2_ss_txp(11)") )
				( member ( signalRef "@baseboard_fab2_lib.baseboard_fab2(sch_1):p3e_cpu0_pe2_ss_txp(12)") )
				( member ( signalRef "@baseboard_fab2_lib.baseboard_fab2(sch_1):p3e_cpu0_pe2_ss_txp(13)") )
				( member ( signalRef "@baseboard_fab2_lib.baseboard_fab2(sch_1):p3e_cpu0_pe2_ss_txp(14)") )
				( member ( signalRef "@baseboard_fab2_lib.baseboard_fab2(sch_1):p3e_cpu0_pe2_ss_txp(15)") )
				( objectStatus "P3E_CPU0_PE2_SS_TXP" )
			)
			( bus "@baseboard_fab2_lib.baseboard_fab2(sch_1):p3e_cpu0_pe3_ocp_rxn"
				( memberType ( signal ) )
				( member ( signalRef "@baseboard_fab2_lib.baseboard_fab2(sch_1):p3e_cpu0_pe3_ocp_rxn(0)") )
				( member ( signalRef "@baseboard_fab2_lib.baseboard_fab2(sch_1):p3e_cpu0_pe3_ocp_rxn(1)") )
				( member ( signalRef "@baseboard_fab2_lib.baseboard_fab2(sch_1):p3e_cpu0_pe3_ocp_rxn(2)") )
				( member ( signalRef "@baseboard_fab2_lib.baseboard_fab2(sch_1):p3e_cpu0_pe3_ocp_rxn(3)") )
				( member ( signalRef "@baseboard_fab2_lib.baseboard_fab2(sch_1):p3e_cpu0_pe3_ocp_rxn(4)") )
				( member ( signalRef "@baseboard_fab2_lib.baseboard_fab2(sch_1):p3e_cpu0_pe3_ocp_rxn(5)") )
				( member ( signalRef "@baseboard_fab2_lib.baseboard_fab2(sch_1):p3e_cpu0_pe3_ocp_rxn(6)") )
				( member ( signalRef "@baseboard_fab2_lib.baseboard_fab2(sch_1):p3e_cpu0_pe3_ocp_rxn(7)") )
				( member ( signalRef "@baseboard_fab2_lib.baseboard_fab2(sch_1):p3e_cpu0_pe3_ocp_rxn(8)") )
				( member ( signalRef "@baseboard_fab2_lib.baseboard_fab2(sch_1):p3e_cpu0_pe3_ocp_rxn(9)") )
				( member ( signalRef "@baseboard_fab2_lib.baseboard_fab2(sch_1):p3e_cpu0_pe3_ocp_rxn(10)") )
				( member ( signalRef "@baseboard_fab2_lib.baseboard_fab2(sch_1):p3e_cpu0_pe3_ocp_rxn(11)") )
				( member ( signalRef "@baseboard_fab2_lib.baseboard_fab2(sch_1):p3e_cpu0_pe3_ocp_rxn(12)") )
				( member ( signalRef "@baseboard_fab2_lib.baseboard_fab2(sch_1):p3e_cpu0_pe3_ocp_rxn(13)") )
				( member ( signalRef "@baseboard_fab2_lib.baseboard_fab2(sch_1):p3e_cpu0_pe3_ocp_rxn(14)") )
				( member ( signalRef "@baseboard_fab2_lib.baseboard_fab2(sch_1):p3e_cpu0_pe3_ocp_rxn(15)") )
				( objectStatus "P3E_CPU0_PE3_OCP_RXN" )
			)
			( bus "@baseboard_fab2_lib.baseboard_fab2(sch_1):p3e_cpu0_pe3_ocp_rxp"
				( memberType ( signal ) )
				( member ( signalRef "@baseboard_fab2_lib.baseboard_fab2(sch_1):p3e_cpu0_pe3_ocp_rxp(0)") )
				( member ( signalRef "@baseboard_fab2_lib.baseboard_fab2(sch_1):p3e_cpu0_pe3_ocp_rxp(1)") )
				( member ( signalRef "@baseboard_fab2_lib.baseboard_fab2(sch_1):p3e_cpu0_pe3_ocp_rxp(2)") )
				( member ( signalRef "@baseboard_fab2_lib.baseboard_fab2(sch_1):p3e_cpu0_pe3_ocp_rxp(3)") )
				( member ( signalRef "@baseboard_fab2_lib.baseboard_fab2(sch_1):p3e_cpu0_pe3_ocp_rxp(4)") )
				( member ( signalRef "@baseboard_fab2_lib.baseboard_fab2(sch_1):p3e_cpu0_pe3_ocp_rxp(5)") )
				( member ( signalRef "@baseboard_fab2_lib.baseboard_fab2(sch_1):p3e_cpu0_pe3_ocp_rxp(6)") )
				( member ( signalRef "@baseboard_fab2_lib.baseboard_fab2(sch_1):p3e_cpu0_pe3_ocp_rxp(7)") )
				( member ( signalRef "@baseboard_fab2_lib.baseboard_fab2(sch_1):p3e_cpu0_pe3_ocp_rxp(8)") )
				( member ( signalRef "@baseboard_fab2_lib.baseboard_fab2(sch_1):p3e_cpu0_pe3_ocp_rxp(9)") )
				( member ( signalRef "@baseboard_fab2_lib.baseboard_fab2(sch_1):p3e_cpu0_pe3_ocp_rxp(10)") )
				( member ( signalRef "@baseboard_fab2_lib.baseboard_fab2(sch_1):p3e_cpu0_pe3_ocp_rxp(11)") )
				( member ( signalRef "@baseboard_fab2_lib.baseboard_fab2(sch_1):p3e_cpu0_pe3_ocp_rxp(12)") )
				( member ( signalRef "@baseboard_fab2_lib.baseboard_fab2(sch_1):p3e_cpu0_pe3_ocp_rxp(13)") )
				( member ( signalRef "@baseboard_fab2_lib.baseboard_fab2(sch_1):p3e_cpu0_pe3_ocp_rxp(14)") )
				( member ( signalRef "@baseboard_fab2_lib.baseboard_fab2(sch_1):p3e_cpu0_pe3_ocp_rxp(15)") )
				( objectStatus "P3E_CPU0_PE3_OCP_RXP" )
			)
			( bus "@baseboard_fab2_lib.baseboard_fab2(sch_1):p3e_cpu0_pe3_ocp_txn"
				( memberType ( signal ) )
				( member ( signalRef "@baseboard_fab2_lib.baseboard_fab2(sch_1):p3e_cpu0_pe3_ocp_txn(0)") )
				( member ( signalRef "@baseboard_fab2_lib.baseboard_fab2(sch_1):p3e_cpu0_pe3_ocp_txn(1)") )
				( member ( signalRef "@baseboard_fab2_lib.baseboard_fab2(sch_1):p3e_cpu0_pe3_ocp_txn(2)") )
				( member ( signalRef "@baseboard_fab2_lib.baseboard_fab2(sch_1):p3e_cpu0_pe3_ocp_txn(3)") )
				( member ( signalRef "@baseboard_fab2_lib.baseboard_fab2(sch_1):p3e_cpu0_pe3_ocp_txn(4)") )
				( member ( signalRef "@baseboard_fab2_lib.baseboard_fab2(sch_1):p3e_cpu0_pe3_ocp_txn(5)") )
				( member ( signalRef "@baseboard_fab2_lib.baseboard_fab2(sch_1):p3e_cpu0_pe3_ocp_txn(6)") )
				( member ( signalRef "@baseboard_fab2_lib.baseboard_fab2(sch_1):p3e_cpu0_pe3_ocp_txn(7)") )
				( member ( signalRef "@baseboard_fab2_lib.baseboard_fab2(sch_1):p3e_cpu0_pe3_ocp_txn(8)") )
				( member ( signalRef "@baseboard_fab2_lib.baseboard_fab2(sch_1):p3e_cpu0_pe3_ocp_txn(9)") )
				( member ( signalRef "@baseboard_fab2_lib.baseboard_fab2(sch_1):p3e_cpu0_pe3_ocp_txn(10)") )
				( member ( signalRef "@baseboard_fab2_lib.baseboard_fab2(sch_1):p3e_cpu0_pe3_ocp_txn(11)") )
				( member ( signalRef "@baseboard_fab2_lib.baseboard_fab2(sch_1):p3e_cpu0_pe3_ocp_txn(12)") )
				( member ( signalRef "@baseboard_fab2_lib.baseboard_fab2(sch_1):p3e_cpu0_pe3_ocp_txn(13)") )
				( member ( signalRef "@baseboard_fab2_lib.baseboard_fab2(sch_1):p3e_cpu0_pe3_ocp_txn(14)") )
				( member ( signalRef "@baseboard_fab2_lib.baseboard_fab2(sch_1):p3e_cpu0_pe3_ocp_txn(15)") )
				( objectStatus "P3E_CPU0_PE3_OCP_TXN" )
			)
			( bus "@baseboard_fab2_lib.baseboard_fab2(sch_1):p3e_cpu0_pe3_ocp_txp"
				( memberType ( signal ) )
				( member ( signalRef "@baseboard_fab2_lib.baseboard_fab2(sch_1):p3e_cpu0_pe3_ocp_txp(0)") )
				( member ( signalRef "@baseboard_fab2_lib.baseboard_fab2(sch_1):p3e_cpu0_pe3_ocp_txp(1)") )
				( member ( signalRef "@baseboard_fab2_lib.baseboard_fab2(sch_1):p3e_cpu0_pe3_ocp_txp(2)") )
				( member ( signalRef "@baseboard_fab2_lib.baseboard_fab2(sch_1):p3e_cpu0_pe3_ocp_txp(3)") )
				( member ( signalRef "@baseboard_fab2_lib.baseboard_fab2(sch_1):p3e_cpu0_pe3_ocp_txp(4)") )
				( member ( signalRef "@baseboard_fab2_lib.baseboard_fab2(sch_1):p3e_cpu0_pe3_ocp_txp(5)") )
				( member ( signalRef "@baseboard_fab2_lib.baseboard_fab2(sch_1):p3e_cpu0_pe3_ocp_txp(6)") )
				( member ( signalRef "@baseboard_fab2_lib.baseboard_fab2(sch_1):p3e_cpu0_pe3_ocp_txp(7)") )
				( member ( signalRef "@baseboard_fab2_lib.baseboard_fab2(sch_1):p3e_cpu0_pe3_ocp_txp(8)") )
				( member ( signalRef "@baseboard_fab2_lib.baseboard_fab2(sch_1):p3e_cpu0_pe3_ocp_txp(9)") )
				( member ( signalRef "@baseboard_fab2_lib.baseboard_fab2(sch_1):p3e_cpu0_pe3_ocp_txp(10)") )
				( member ( signalRef "@baseboard_fab2_lib.baseboard_fab2(sch_1):p3e_cpu0_pe3_ocp_txp(11)") )
				( member ( signalRef "@baseboard_fab2_lib.baseboard_fab2(sch_1):p3e_cpu0_pe3_ocp_txp(12)") )
				( member ( signalRef "@baseboard_fab2_lib.baseboard_fab2(sch_1):p3e_cpu0_pe3_ocp_txp(13)") )
				( member ( signalRef "@baseboard_fab2_lib.baseboard_fab2(sch_1):p3e_cpu0_pe3_ocp_txp(14)") )
				( member ( signalRef "@baseboard_fab2_lib.baseboard_fab2(sch_1):p3e_cpu0_pe3_ocp_txp(15)") )
				( objectStatus "P3E_CPU0_PE3_OCP_TXP" )
			)
			( bus "@baseboard_fab2_lib.baseboard_fab2(sch_1):upi_cpu0_cpu1_p0p0_dn"
				( memberType ( signal ) )
				( member ( signalRef "@baseboard_fab2_lib.baseboard_fab2(sch_1):upi_cpu0_cpu1_p0p0_dn(0)") )
				( member ( signalRef "@baseboard_fab2_lib.baseboard_fab2(sch_1):upi_cpu0_cpu1_p0p0_dn(1)") )
				( member ( signalRef "@baseboard_fab2_lib.baseboard_fab2(sch_1):upi_cpu0_cpu1_p0p0_dn(2)") )
				( member ( signalRef "@baseboard_fab2_lib.baseboard_fab2(sch_1):upi_cpu0_cpu1_p0p0_dn(3)") )
				( member ( signalRef "@baseboard_fab2_lib.baseboard_fab2(sch_1):upi_cpu0_cpu1_p0p0_dn(4)") )
				( member ( signalRef "@baseboard_fab2_lib.baseboard_fab2(sch_1):upi_cpu0_cpu1_p0p0_dn(5)") )
				( member ( signalRef "@baseboard_fab2_lib.baseboard_fab2(sch_1):upi_cpu0_cpu1_p0p0_dn(6)") )
				( member ( signalRef "@baseboard_fab2_lib.baseboard_fab2(sch_1):upi_cpu0_cpu1_p0p0_dn(7)") )
				( member ( signalRef "@baseboard_fab2_lib.baseboard_fab2(sch_1):upi_cpu0_cpu1_p0p0_dn(8)") )
				( member ( signalRef "@baseboard_fab2_lib.baseboard_fab2(sch_1):upi_cpu0_cpu1_p0p0_dn(9)") )
				( member ( signalRef "@baseboard_fab2_lib.baseboard_fab2(sch_1):upi_cpu0_cpu1_p0p0_dn(10)") )
				( member ( signalRef "@baseboard_fab2_lib.baseboard_fab2(sch_1):upi_cpu0_cpu1_p0p0_dn(11)") )
				( member ( signalRef "@baseboard_fab2_lib.baseboard_fab2(sch_1):upi_cpu0_cpu1_p0p0_dn(12)") )
				( member ( signalRef "@baseboard_fab2_lib.baseboard_fab2(sch_1):upi_cpu0_cpu1_p0p0_dn(13)") )
				( member ( signalRef "@baseboard_fab2_lib.baseboard_fab2(sch_1):upi_cpu0_cpu1_p0p0_dn(14)") )
				( member ( signalRef "@baseboard_fab2_lib.baseboard_fab2(sch_1):upi_cpu0_cpu1_p0p0_dn(15)") )
				( member ( signalRef "@baseboard_fab2_lib.baseboard_fab2(sch_1):upi_cpu0_cpu1_p0p0_dn(16)") )
				( member ( signalRef "@baseboard_fab2_lib.baseboard_fab2(sch_1):upi_cpu0_cpu1_p0p0_dn(17)") )
				( member ( signalRef "@baseboard_fab2_lib.baseboard_fab2(sch_1):upi_cpu0_cpu1_p0p0_dn(18)") )
				( member ( signalRef "@baseboard_fab2_lib.baseboard_fab2(sch_1):upi_cpu0_cpu1_p0p0_dn(19)") )
				( objectStatus "UPI_CPU0_CPU1_P0P0_DN" )
			)
			( bus "@baseboard_fab2_lib.baseboard_fab2(sch_1):upi_cpu0_cpu1_p0p0_dp"
				( memberType ( signal ) )
				( member ( signalRef "@baseboard_fab2_lib.baseboard_fab2(sch_1):upi_cpu0_cpu1_p0p0_dp(0)") )
				( member ( signalRef "@baseboard_fab2_lib.baseboard_fab2(sch_1):upi_cpu0_cpu1_p0p0_dp(1)") )
				( member ( signalRef "@baseboard_fab2_lib.baseboard_fab2(sch_1):upi_cpu0_cpu1_p0p0_dp(2)") )
				( member ( signalRef "@baseboard_fab2_lib.baseboard_fab2(sch_1):upi_cpu0_cpu1_p0p0_dp(3)") )
				( member ( signalRef "@baseboard_fab2_lib.baseboard_fab2(sch_1):upi_cpu0_cpu1_p0p0_dp(4)") )
				( member ( signalRef "@baseboard_fab2_lib.baseboard_fab2(sch_1):upi_cpu0_cpu1_p0p0_dp(5)") )
				( member ( signalRef "@baseboard_fab2_lib.baseboard_fab2(sch_1):upi_cpu0_cpu1_p0p0_dp(6)") )
				( member ( signalRef "@baseboard_fab2_lib.baseboard_fab2(sch_1):upi_cpu0_cpu1_p0p0_dp(7)") )
				( member ( signalRef "@baseboard_fab2_lib.baseboard_fab2(sch_1):upi_cpu0_cpu1_p0p0_dp(8)") )
				( member ( signalRef "@baseboard_fab2_lib.baseboard_fab2(sch_1):upi_cpu0_cpu1_p0p0_dp(9)") )
				( member ( signalRef "@baseboard_fab2_lib.baseboard_fab2(sch_1):upi_cpu0_cpu1_p0p0_dp(10)") )
				( member ( signalRef "@baseboard_fab2_lib.baseboard_fab2(sch_1):upi_cpu0_cpu1_p0p0_dp(11)") )
				( member ( signalRef "@baseboard_fab2_lib.baseboard_fab2(sch_1):upi_cpu0_cpu1_p0p0_dp(12)") )
				( member ( signalRef "@baseboard_fab2_lib.baseboard_fab2(sch_1):upi_cpu0_cpu1_p0p0_dp(13)") )
				( member ( signalRef "@baseboard_fab2_lib.baseboard_fab2(sch_1):upi_cpu0_cpu1_p0p0_dp(14)") )
				( member ( signalRef "@baseboard_fab2_lib.baseboard_fab2(sch_1):upi_cpu0_cpu1_p0p0_dp(15)") )
				( member ( signalRef "@baseboard_fab2_lib.baseboard_fab2(sch_1):upi_cpu0_cpu1_p0p0_dp(16)") )
				( member ( signalRef "@baseboard_fab2_lib.baseboard_fab2(sch_1):upi_cpu0_cpu1_p0p0_dp(17)") )
				( member ( signalRef "@baseboard_fab2_lib.baseboard_fab2(sch_1):upi_cpu0_cpu1_p0p0_dp(18)") )
				( member ( signalRef "@baseboard_fab2_lib.baseboard_fab2(sch_1):upi_cpu0_cpu1_p0p0_dp(19)") )
				( objectStatus "UPI_CPU0_CPU1_P0P0_DP" )
			)
			( bus "@baseboard_fab2_lib.baseboard_fab2(sch_1):upi_cpu1_cpu0_p0p0_dn"
				( memberType ( signal ) )
				( member ( signalRef "@baseboard_fab2_lib.baseboard_fab2(sch_1):upi_cpu1_cpu0_p0p0_dn(0)") )
				( member ( signalRef "@baseboard_fab2_lib.baseboard_fab2(sch_1):upi_cpu1_cpu0_p0p0_dn(1)") )
				( member ( signalRef "@baseboard_fab2_lib.baseboard_fab2(sch_1):upi_cpu1_cpu0_p0p0_dn(2)") )
				( member ( signalRef "@baseboard_fab2_lib.baseboard_fab2(sch_1):upi_cpu1_cpu0_p0p0_dn(3)") )
				( member ( signalRef "@baseboard_fab2_lib.baseboard_fab2(sch_1):upi_cpu1_cpu0_p0p0_dn(4)") )
				( member ( signalRef "@baseboard_fab2_lib.baseboard_fab2(sch_1):upi_cpu1_cpu0_p0p0_dn(5)") )
				( member ( signalRef "@baseboard_fab2_lib.baseboard_fab2(sch_1):upi_cpu1_cpu0_p0p0_dn(6)") )
				( member ( signalRef "@baseboard_fab2_lib.baseboard_fab2(sch_1):upi_cpu1_cpu0_p0p0_dn(7)") )
				( member ( signalRef "@baseboard_fab2_lib.baseboard_fab2(sch_1):upi_cpu1_cpu0_p0p0_dn(8)") )
				( member ( signalRef "@baseboard_fab2_lib.baseboard_fab2(sch_1):upi_cpu1_cpu0_p0p0_dn(9)") )
				( member ( signalRef "@baseboard_fab2_lib.baseboard_fab2(sch_1):upi_cpu1_cpu0_p0p0_dn(10)") )
				( member ( signalRef "@baseboard_fab2_lib.baseboard_fab2(sch_1):upi_cpu1_cpu0_p0p0_dn(11)") )
				( member ( signalRef "@baseboard_fab2_lib.baseboard_fab2(sch_1):upi_cpu1_cpu0_p0p0_dn(12)") )
				( member ( signalRef "@baseboard_fab2_lib.baseboard_fab2(sch_1):upi_cpu1_cpu0_p0p0_dn(13)") )
				( member ( signalRef "@baseboard_fab2_lib.baseboard_fab2(sch_1):upi_cpu1_cpu0_p0p0_dn(14)") )
				( member ( signalRef "@baseboard_fab2_lib.baseboard_fab2(sch_1):upi_cpu1_cpu0_p0p0_dn(15)") )
				( member ( signalRef "@baseboard_fab2_lib.baseboard_fab2(sch_1):upi_cpu1_cpu0_p0p0_dn(16)") )
				( member ( signalRef "@baseboard_fab2_lib.baseboard_fab2(sch_1):upi_cpu1_cpu0_p0p0_dn(17)") )
				( member ( signalRef "@baseboard_fab2_lib.baseboard_fab2(sch_1):upi_cpu1_cpu0_p0p0_dn(18)") )
				( member ( signalRef "@baseboard_fab2_lib.baseboard_fab2(sch_1):upi_cpu1_cpu0_p0p0_dn(19)") )
				( objectStatus "UPI_CPU1_CPU0_P0P0_DN" )
			)
			( bus "@baseboard_fab2_lib.baseboard_fab2(sch_1):upi_cpu1_cpu0_p0p0_dp"
				( memberType ( signal ) )
				( member ( signalRef "@baseboard_fab2_lib.baseboard_fab2(sch_1):upi_cpu1_cpu0_p0p0_dp(0)") )
				( member ( signalRef "@baseboard_fab2_lib.baseboard_fab2(sch_1):upi_cpu1_cpu0_p0p0_dp(1)") )
				( member ( signalRef "@baseboard_fab2_lib.baseboard_fab2(sch_1):upi_cpu1_cpu0_p0p0_dp(2)") )
				( member ( signalRef "@baseboard_fab2_lib.baseboard_fab2(sch_1):upi_cpu1_cpu0_p0p0_dp(3)") )
				( member ( signalRef "@baseboard_fab2_lib.baseboard_fab2(sch_1):upi_cpu1_cpu0_p0p0_dp(4)") )
				( member ( signalRef "@baseboard_fab2_lib.baseboard_fab2(sch_1):upi_cpu1_cpu0_p0p0_dp(5)") )
				( member ( signalRef "@baseboard_fab2_lib.baseboard_fab2(sch_1):upi_cpu1_cpu0_p0p0_dp(6)") )
				( member ( signalRef "@baseboard_fab2_lib.baseboard_fab2(sch_1):upi_cpu1_cpu0_p0p0_dp(7)") )
				( member ( signalRef "@baseboard_fab2_lib.baseboard_fab2(sch_1):upi_cpu1_cpu0_p0p0_dp(8)") )
				( member ( signalRef "@baseboard_fab2_lib.baseboard_fab2(sch_1):upi_cpu1_cpu0_p0p0_dp(9)") )
				( member ( signalRef "@baseboard_fab2_lib.baseboard_fab2(sch_1):upi_cpu1_cpu0_p0p0_dp(10)") )
				( member ( signalRef "@baseboard_fab2_lib.baseboard_fab2(sch_1):upi_cpu1_cpu0_p0p0_dp(11)") )
				( member ( signalRef "@baseboard_fab2_lib.baseboard_fab2(sch_1):upi_cpu1_cpu0_p0p0_dp(12)") )
				( member ( signalRef "@baseboard_fab2_lib.baseboard_fab2(sch_1):upi_cpu1_cpu0_p0p0_dp(13)") )
				( member ( signalRef "@baseboard_fab2_lib.baseboard_fab2(sch_1):upi_cpu1_cpu0_p0p0_dp(14)") )
				( member ( signalRef "@baseboard_fab2_lib.baseboard_fab2(sch_1):upi_cpu1_cpu0_p0p0_dp(15)") )
				( member ( signalRef "@baseboard_fab2_lib.baseboard_fab2(sch_1):upi_cpu1_cpu0_p0p0_dp(16)") )
				( member ( signalRef "@baseboard_fab2_lib.baseboard_fab2(sch_1):upi_cpu1_cpu0_p0p0_dp(17)") )
				( member ( signalRef "@baseboard_fab2_lib.baseboard_fab2(sch_1):upi_cpu1_cpu0_p0p0_dp(18)") )
				( member ( signalRef "@baseboard_fab2_lib.baseboard_fab2(sch_1):upi_cpu1_cpu0_p0p0_dp(19)") )
				( objectStatus "UPI_CPU1_CPU0_P0P0_DP" )
			)
			( bus "@baseboard_fab2_lib.baseboard_fab2(sch_1):upi_cpu0_cpu1_p1p1_dn"
				( memberType ( signal ) )
				( member ( signalRef "@baseboard_fab2_lib.baseboard_fab2(sch_1):upi_cpu0_cpu1_p1p1_dn(0)") )
				( member ( signalRef "@baseboard_fab2_lib.baseboard_fab2(sch_1):upi_cpu0_cpu1_p1p1_dn(1)") )
				( member ( signalRef "@baseboard_fab2_lib.baseboard_fab2(sch_1):upi_cpu0_cpu1_p1p1_dn(2)") )
				( member ( signalRef "@baseboard_fab2_lib.baseboard_fab2(sch_1):upi_cpu0_cpu1_p1p1_dn(3)") )
				( member ( signalRef "@baseboard_fab2_lib.baseboard_fab2(sch_1):upi_cpu0_cpu1_p1p1_dn(4)") )
				( member ( signalRef "@baseboard_fab2_lib.baseboard_fab2(sch_1):upi_cpu0_cpu1_p1p1_dn(5)") )
				( member ( signalRef "@baseboard_fab2_lib.baseboard_fab2(sch_1):upi_cpu0_cpu1_p1p1_dn(6)") )
				( member ( signalRef "@baseboard_fab2_lib.baseboard_fab2(sch_1):upi_cpu0_cpu1_p1p1_dn(7)") )
				( member ( signalRef "@baseboard_fab2_lib.baseboard_fab2(sch_1):upi_cpu0_cpu1_p1p1_dn(8)") )
				( member ( signalRef "@baseboard_fab2_lib.baseboard_fab2(sch_1):upi_cpu0_cpu1_p1p1_dn(9)") )
				( member ( signalRef "@baseboard_fab2_lib.baseboard_fab2(sch_1):upi_cpu0_cpu1_p1p1_dn(10)") )
				( member ( signalRef "@baseboard_fab2_lib.baseboard_fab2(sch_1):upi_cpu0_cpu1_p1p1_dn(11)") )
				( member ( signalRef "@baseboard_fab2_lib.baseboard_fab2(sch_1):upi_cpu0_cpu1_p1p1_dn(12)") )
				( member ( signalRef "@baseboard_fab2_lib.baseboard_fab2(sch_1):upi_cpu0_cpu1_p1p1_dn(13)") )
				( member ( signalRef "@baseboard_fab2_lib.baseboard_fab2(sch_1):upi_cpu0_cpu1_p1p1_dn(14)") )
				( member ( signalRef "@baseboard_fab2_lib.baseboard_fab2(sch_1):upi_cpu0_cpu1_p1p1_dn(15)") )
				( member ( signalRef "@baseboard_fab2_lib.baseboard_fab2(sch_1):upi_cpu0_cpu1_p1p1_dn(16)") )
				( member ( signalRef "@baseboard_fab2_lib.baseboard_fab2(sch_1):upi_cpu0_cpu1_p1p1_dn(17)") )
				( member ( signalRef "@baseboard_fab2_lib.baseboard_fab2(sch_1):upi_cpu0_cpu1_p1p1_dn(18)") )
				( member ( signalRef "@baseboard_fab2_lib.baseboard_fab2(sch_1):upi_cpu0_cpu1_p1p1_dn(19)") )
				( objectStatus "UPI_CPU0_CPU1_P1P1_DN" )
			)
			( bus "@baseboard_fab2_lib.baseboard_fab2(sch_1):upi_cpu0_cpu1_p1p1_dp"
				( memberType ( signal ) )
				( member ( signalRef "@baseboard_fab2_lib.baseboard_fab2(sch_1):upi_cpu0_cpu1_p1p1_dp(0)") )
				( member ( signalRef "@baseboard_fab2_lib.baseboard_fab2(sch_1):upi_cpu0_cpu1_p1p1_dp(1)") )
				( member ( signalRef "@baseboard_fab2_lib.baseboard_fab2(sch_1):upi_cpu0_cpu1_p1p1_dp(2)") )
				( member ( signalRef "@baseboard_fab2_lib.baseboard_fab2(sch_1):upi_cpu0_cpu1_p1p1_dp(3)") )
				( member ( signalRef "@baseboard_fab2_lib.baseboard_fab2(sch_1):upi_cpu0_cpu1_p1p1_dp(4)") )
				( member ( signalRef "@baseboard_fab2_lib.baseboard_fab2(sch_1):upi_cpu0_cpu1_p1p1_dp(5)") )
				( member ( signalRef "@baseboard_fab2_lib.baseboard_fab2(sch_1):upi_cpu0_cpu1_p1p1_dp(6)") )
				( member ( signalRef "@baseboard_fab2_lib.baseboard_fab2(sch_1):upi_cpu0_cpu1_p1p1_dp(7)") )
				( member ( signalRef "@baseboard_fab2_lib.baseboard_fab2(sch_1):upi_cpu0_cpu1_p1p1_dp(8)") )
				( member ( signalRef "@baseboard_fab2_lib.baseboard_fab2(sch_1):upi_cpu0_cpu1_p1p1_dp(9)") )
				( member ( signalRef "@baseboard_fab2_lib.baseboard_fab2(sch_1):upi_cpu0_cpu1_p1p1_dp(10)") )
				( member ( signalRef "@baseboard_fab2_lib.baseboard_fab2(sch_1):upi_cpu0_cpu1_p1p1_dp(11)") )
				( member ( signalRef "@baseboard_fab2_lib.baseboard_fab2(sch_1):upi_cpu0_cpu1_p1p1_dp(12)") )
				( member ( signalRef "@baseboard_fab2_lib.baseboard_fab2(sch_1):upi_cpu0_cpu1_p1p1_dp(13)") )
				( member ( signalRef "@baseboard_fab2_lib.baseboard_fab2(sch_1):upi_cpu0_cpu1_p1p1_dp(14)") )
				( member ( signalRef "@baseboard_fab2_lib.baseboard_fab2(sch_1):upi_cpu0_cpu1_p1p1_dp(15)") )
				( member ( signalRef "@baseboard_fab2_lib.baseboard_fab2(sch_1):upi_cpu0_cpu1_p1p1_dp(16)") )
				( member ( signalRef "@baseboard_fab2_lib.baseboard_fab2(sch_1):upi_cpu0_cpu1_p1p1_dp(17)") )
				( member ( signalRef "@baseboard_fab2_lib.baseboard_fab2(sch_1):upi_cpu0_cpu1_p1p1_dp(18)") )
				( member ( signalRef "@baseboard_fab2_lib.baseboard_fab2(sch_1):upi_cpu0_cpu1_p1p1_dp(19)") )
				( objectStatus "UPI_CPU0_CPU1_P1P1_DP" )
			)
			( bus "@baseboard_fab2_lib.baseboard_fab2(sch_1):upi_cpu1_cpu0_p1p1_dn"
				( memberType ( signal ) )
				( member ( signalRef "@baseboard_fab2_lib.baseboard_fab2(sch_1):upi_cpu1_cpu0_p1p1_dn(0)") )
				( member ( signalRef "@baseboard_fab2_lib.baseboard_fab2(sch_1):upi_cpu1_cpu0_p1p1_dn(1)") )
				( member ( signalRef "@baseboard_fab2_lib.baseboard_fab2(sch_1):upi_cpu1_cpu0_p1p1_dn(2)") )
				( member ( signalRef "@baseboard_fab2_lib.baseboard_fab2(sch_1):upi_cpu1_cpu0_p1p1_dn(3)") )
				( member ( signalRef "@baseboard_fab2_lib.baseboard_fab2(sch_1):upi_cpu1_cpu0_p1p1_dn(4)") )
				( member ( signalRef "@baseboard_fab2_lib.baseboard_fab2(sch_1):upi_cpu1_cpu0_p1p1_dn(5)") )
				( member ( signalRef "@baseboard_fab2_lib.baseboard_fab2(sch_1):upi_cpu1_cpu0_p1p1_dn(6)") )
				( member ( signalRef "@baseboard_fab2_lib.baseboard_fab2(sch_1):upi_cpu1_cpu0_p1p1_dn(7)") )
				( member ( signalRef "@baseboard_fab2_lib.baseboard_fab2(sch_1):upi_cpu1_cpu0_p1p1_dn(8)") )
				( member ( signalRef "@baseboard_fab2_lib.baseboard_fab2(sch_1):upi_cpu1_cpu0_p1p1_dn(9)") )
				( member ( signalRef "@baseboard_fab2_lib.baseboard_fab2(sch_1):upi_cpu1_cpu0_p1p1_dn(10)") )
				( member ( signalRef "@baseboard_fab2_lib.baseboard_fab2(sch_1):upi_cpu1_cpu0_p1p1_dn(11)") )
				( member ( signalRef "@baseboard_fab2_lib.baseboard_fab2(sch_1):upi_cpu1_cpu0_p1p1_dn(12)") )
				( member ( signalRef "@baseboard_fab2_lib.baseboard_fab2(sch_1):upi_cpu1_cpu0_p1p1_dn(13)") )
				( member ( signalRef "@baseboard_fab2_lib.baseboard_fab2(sch_1):upi_cpu1_cpu0_p1p1_dn(14)") )
				( member ( signalRef "@baseboard_fab2_lib.baseboard_fab2(sch_1):upi_cpu1_cpu0_p1p1_dn(15)") )
				( member ( signalRef "@baseboard_fab2_lib.baseboard_fab2(sch_1):upi_cpu1_cpu0_p1p1_dn(16)") )
				( member ( signalRef "@baseboard_fab2_lib.baseboard_fab2(sch_1):upi_cpu1_cpu0_p1p1_dn(17)") )
				( member ( signalRef "@baseboard_fab2_lib.baseboard_fab2(sch_1):upi_cpu1_cpu0_p1p1_dn(18)") )
				( member ( signalRef "@baseboard_fab2_lib.baseboard_fab2(sch_1):upi_cpu1_cpu0_p1p1_dn(19)") )
				( objectStatus "UPI_CPU1_CPU0_P1P1_DN" )
			)
			( bus "@baseboard_fab2_lib.baseboard_fab2(sch_1):upi_cpu1_cpu0_p1p1_dp"
				( memberType ( signal ) )
				( member ( signalRef "@baseboard_fab2_lib.baseboard_fab2(sch_1):upi_cpu1_cpu0_p1p1_dp(0)") )
				( member ( signalRef "@baseboard_fab2_lib.baseboard_fab2(sch_1):upi_cpu1_cpu0_p1p1_dp(1)") )
				( member ( signalRef "@baseboard_fab2_lib.baseboard_fab2(sch_1):upi_cpu1_cpu0_p1p1_dp(2)") )
				( member ( signalRef "@baseboard_fab2_lib.baseboard_fab2(sch_1):upi_cpu1_cpu0_p1p1_dp(3)") )
				( member ( signalRef "@baseboard_fab2_lib.baseboard_fab2(sch_1):upi_cpu1_cpu0_p1p1_dp(4)") )
				( member ( signalRef "@baseboard_fab2_lib.baseboard_fab2(sch_1):upi_cpu1_cpu0_p1p1_dp(5)") )
				( member ( signalRef "@baseboard_fab2_lib.baseboard_fab2(sch_1):upi_cpu1_cpu0_p1p1_dp(6)") )
				( member ( signalRef "@baseboard_fab2_lib.baseboard_fab2(sch_1):upi_cpu1_cpu0_p1p1_dp(7)") )
				( member ( signalRef "@baseboard_fab2_lib.baseboard_fab2(sch_1):upi_cpu1_cpu0_p1p1_dp(8)") )
				( member ( signalRef "@baseboard_fab2_lib.baseboard_fab2(sch_1):upi_cpu1_cpu0_p1p1_dp(9)") )
				( member ( signalRef "@baseboard_fab2_lib.baseboard_fab2(sch_1):upi_cpu1_cpu0_p1p1_dp(10)") )
				( member ( signalRef "@baseboard_fab2_lib.baseboard_fab2(sch_1):upi_cpu1_cpu0_p1p1_dp(11)") )
				( member ( signalRef "@baseboard_fab2_lib.baseboard_fab2(sch_1):upi_cpu1_cpu0_p1p1_dp(12)") )
				( member ( signalRef "@baseboard_fab2_lib.baseboard_fab2(sch_1):upi_cpu1_cpu0_p1p1_dp(13)") )
				( member ( signalRef "@baseboard_fab2_lib.baseboard_fab2(sch_1):upi_cpu1_cpu0_p1p1_dp(14)") )
				( member ( signalRef "@baseboard_fab2_lib.baseboard_fab2(sch_1):upi_cpu1_cpu0_p1p1_dp(15)") )
				( member ( signalRef "@baseboard_fab2_lib.baseboard_fab2(sch_1):upi_cpu1_cpu0_p1p1_dp(16)") )
				( member ( signalRef "@baseboard_fab2_lib.baseboard_fab2(sch_1):upi_cpu1_cpu0_p1p1_dp(17)") )
				( member ( signalRef "@baseboard_fab2_lib.baseboard_fab2(sch_1):upi_cpu1_cpu0_p1p1_dp(18)") )
				( member ( signalRef "@baseboard_fab2_lib.baseboard_fab2(sch_1):upi_cpu1_cpu0_p1p1_dp(19)") )
				( objectStatus "UPI_CPU1_CPU0_P1P1_DP" )
			)
			( bus "@baseboard_fab2_lib.baseboard_fab2(sch_1):m_g_ba"
				( memberType ( signal ) )
				( member ( signalRef "@baseboard_fab2_lib.baseboard_fab2(sch_1):m_g_ba(0)") )
				( member ( signalRef "@baseboard_fab2_lib.baseboard_fab2(sch_1):m_g_ba(1)") )
				( objectStatus "M_G_BA" )
			)
			( bus "@baseboard_fab2_lib.baseboard_fab2(sch_1):m_g_bg"
				( memberType ( signal ) )
				( member ( signalRef "@baseboard_fab2_lib.baseboard_fab2(sch_1):m_g_bg(0)") )
				( member ( signalRef "@baseboard_fab2_lib.baseboard_fab2(sch_1):m_g_bg(1)") )
				( objectStatus "M_G_BG" )
			)
			( bus "@baseboard_fab2_lib.baseboard_fab2(sch_1):m_g_c"
				( memberType ( signal ) )
				( member ( signalRef "@baseboard_fab2_lib.baseboard_fab2(sch_1):m_g_c(2)") )
				( objectStatus "M_G_C" )
			)
			( bus "@baseboard_fab2_lib.baseboard_fab2(sch_1):m_g_cke"
				( memberType ( signal ) )
				( member ( signalRef "@baseboard_fab2_lib.baseboard_fab2(sch_1):m_g_cke(0)") )
				( member ( signalRef "@baseboard_fab2_lib.baseboard_fab2(sch_1):m_g_cke(1)") )
				( member ( signalRef "@baseboard_fab2_lib.baseboard_fab2(sch_1):m_g_cke(2)") )
				( member ( signalRef "@baseboard_fab2_lib.baseboard_fab2(sch_1):m_g_cke(3)") )
				( objectStatus "M_G_CKE" )
			)
			( bus "@baseboard_fab2_lib.baseboard_fab2(sch_1):m_g_clk_dn"
				( memberType ( signal ) )
				( member ( signalRef "@baseboard_fab2_lib.baseboard_fab2(sch_1):m_g_clk_dn(0)") )
				( member ( signalRef "@baseboard_fab2_lib.baseboard_fab2(sch_1):m_g_clk_dn(1)") )
				( member ( signalRef "@baseboard_fab2_lib.baseboard_fab2(sch_1):m_g_clk_dn(2)") )
				( member ( signalRef "@baseboard_fab2_lib.baseboard_fab2(sch_1):m_g_clk_dn(3)") )
				( objectStatus "M_G_CLK_DN" )
			)
			( bus "@baseboard_fab2_lib.baseboard_fab2(sch_1):m_g_clk_dp"
				( memberType ( signal ) )
				( member ( signalRef "@baseboard_fab2_lib.baseboard_fab2(sch_1):m_g_clk_dp(0)") )
				( member ( signalRef "@baseboard_fab2_lib.baseboard_fab2(sch_1):m_g_clk_dp(1)") )
				( member ( signalRef "@baseboard_fab2_lib.baseboard_fab2(sch_1):m_g_clk_dp(2)") )
				( member ( signalRef "@baseboard_fab2_lib.baseboard_fab2(sch_1):m_g_clk_dp(3)") )
				( objectStatus "M_G_CLK_DP" )
			)
			( bus "@baseboard_fab2_lib.baseboard_fab2(sch_1):m_g_cs_n"
				( memberType ( signal ) )
				( member ( signalRef "@baseboard_fab2_lib.baseboard_fab2(sch_1):m_g_cs_n(0)") )
				( member ( signalRef "@baseboard_fab2_lib.baseboard_fab2(sch_1):m_g_cs_n(1)") )
				( member ( signalRef "@baseboard_fab2_lib.baseboard_fab2(sch_1):m_g_cs_n(2)") )
				( member ( signalRef "@baseboard_fab2_lib.baseboard_fab2(sch_1):m_g_cs_n(3)") )
				( member ( signalRef "@baseboard_fab2_lib.baseboard_fab2(sch_1):m_g_cs_n(4)") )
				( member ( signalRef "@baseboard_fab2_lib.baseboard_fab2(sch_1):m_g_cs_n(5)") )
				( member ( signalRef "@baseboard_fab2_lib.baseboard_fab2(sch_1):m_g_cs_n(6)") )
				( member ( signalRef "@baseboard_fab2_lib.baseboard_fab2(sch_1):m_g_cs_n(7)") )
				( objectStatus "M_G_CS_N" )
			)
			( bus "@baseboard_fab2_lib.baseboard_fab2(sch_1):m_g_dq"
				( memberType ( signal ) )
				( member ( signalRef "@baseboard_fab2_lib.baseboard_fab2(sch_1):m_g_dq(0)") )
				( member ( signalRef "@baseboard_fab2_lib.baseboard_fab2(sch_1):m_g_dq(1)") )
				( member ( signalRef "@baseboard_fab2_lib.baseboard_fab2(sch_1):m_g_dq(2)") )
				( member ( signalRef "@baseboard_fab2_lib.baseboard_fab2(sch_1):m_g_dq(3)") )
				( member ( signalRef "@baseboard_fab2_lib.baseboard_fab2(sch_1):m_g_dq(4)") )
				( member ( signalRef "@baseboard_fab2_lib.baseboard_fab2(sch_1):m_g_dq(5)") )
				( member ( signalRef "@baseboard_fab2_lib.baseboard_fab2(sch_1):m_g_dq(6)") )
				( member ( signalRef "@baseboard_fab2_lib.baseboard_fab2(sch_1):m_g_dq(7)") )
				( member ( signalRef "@baseboard_fab2_lib.baseboard_fab2(sch_1):m_g_dq(8)") )
				( member ( signalRef "@baseboard_fab2_lib.baseboard_fab2(sch_1):m_g_dq(9)") )
				( member ( signalRef "@baseboard_fab2_lib.baseboard_fab2(sch_1):m_g_dq(10)") )
				( member ( signalRef "@baseboard_fab2_lib.baseboard_fab2(sch_1):m_g_dq(11)") )
				( member ( signalRef "@baseboard_fab2_lib.baseboard_fab2(sch_1):m_g_dq(12)") )
				( member ( signalRef "@baseboard_fab2_lib.baseboard_fab2(sch_1):m_g_dq(13)") )
				( member ( signalRef "@baseboard_fab2_lib.baseboard_fab2(sch_1):m_g_dq(14)") )
				( member ( signalRef "@baseboard_fab2_lib.baseboard_fab2(sch_1):m_g_dq(15)") )
				( member ( signalRef "@baseboard_fab2_lib.baseboard_fab2(sch_1):m_g_dq(16)") )
				( member ( signalRef "@baseboard_fab2_lib.baseboard_fab2(sch_1):m_g_dq(17)") )
				( member ( signalRef "@baseboard_fab2_lib.baseboard_fab2(sch_1):m_g_dq(18)") )
				( member ( signalRef "@baseboard_fab2_lib.baseboard_fab2(sch_1):m_g_dq(19)") )
				( member ( signalRef "@baseboard_fab2_lib.baseboard_fab2(sch_1):m_g_dq(20)") )
				( member ( signalRef "@baseboard_fab2_lib.baseboard_fab2(sch_1):m_g_dq(21)") )
				( member ( signalRef "@baseboard_fab2_lib.baseboard_fab2(sch_1):m_g_dq(22)") )
				( member ( signalRef "@baseboard_fab2_lib.baseboard_fab2(sch_1):m_g_dq(23)") )
				( member ( signalRef "@baseboard_fab2_lib.baseboard_fab2(sch_1):m_g_dq(24)") )
				( member ( signalRef "@baseboard_fab2_lib.baseboard_fab2(sch_1):m_g_dq(25)") )
				( member ( signalRef "@baseboard_fab2_lib.baseboard_fab2(sch_1):m_g_dq(26)") )
				( member ( signalRef "@baseboard_fab2_lib.baseboard_fab2(sch_1):m_g_dq(27)") )
				( member ( signalRef "@baseboard_fab2_lib.baseboard_fab2(sch_1):m_g_dq(28)") )
				( member ( signalRef "@baseboard_fab2_lib.baseboard_fab2(sch_1):m_g_dq(29)") )
				( member ( signalRef "@baseboard_fab2_lib.baseboard_fab2(sch_1):m_g_dq(30)") )
				( member ( signalRef "@baseboard_fab2_lib.baseboard_fab2(sch_1):m_g_dq(31)") )
				( member ( signalRef "@baseboard_fab2_lib.baseboard_fab2(sch_1):m_g_dq(32)") )
				( member ( signalRef "@baseboard_fab2_lib.baseboard_fab2(sch_1):m_g_dq(33)") )
				( member ( signalRef "@baseboard_fab2_lib.baseboard_fab2(sch_1):m_g_dq(34)") )
				( member ( signalRef "@baseboard_fab2_lib.baseboard_fab2(sch_1):m_g_dq(35)") )
				( member ( signalRef "@baseboard_fab2_lib.baseboard_fab2(sch_1):m_g_dq(36)") )
				( member ( signalRef "@baseboard_fab2_lib.baseboard_fab2(sch_1):m_g_dq(37)") )
				( member ( signalRef "@baseboard_fab2_lib.baseboard_fab2(sch_1):m_g_dq(38)") )
				( member ( signalRef "@baseboard_fab2_lib.baseboard_fab2(sch_1):m_g_dq(39)") )
				( member ( signalRef "@baseboard_fab2_lib.baseboard_fab2(sch_1):m_g_dq(40)") )
				( member ( signalRef "@baseboard_fab2_lib.baseboard_fab2(sch_1):m_g_dq(41)") )
				( member ( signalRef "@baseboard_fab2_lib.baseboard_fab2(sch_1):m_g_dq(42)") )
				( member ( signalRef "@baseboard_fab2_lib.baseboard_fab2(sch_1):m_g_dq(43)") )
				( member ( signalRef "@baseboard_fab2_lib.baseboard_fab2(sch_1):m_g_dq(44)") )
				( member ( signalRef "@baseboard_fab2_lib.baseboard_fab2(sch_1):m_g_dq(45)") )
				( member ( signalRef "@baseboard_fab2_lib.baseboard_fab2(sch_1):m_g_dq(46)") )
				( member ( signalRef "@baseboard_fab2_lib.baseboard_fab2(sch_1):m_g_dq(47)") )
				( member ( signalRef "@baseboard_fab2_lib.baseboard_fab2(sch_1):m_g_dq(48)") )
				( member ( signalRef "@baseboard_fab2_lib.baseboard_fab2(sch_1):m_g_dq(49)") )
				( member ( signalRef "@baseboard_fab2_lib.baseboard_fab2(sch_1):m_g_dq(50)") )
				( member ( signalRef "@baseboard_fab2_lib.baseboard_fab2(sch_1):m_g_dq(51)") )
				( member ( signalRef "@baseboard_fab2_lib.baseboard_fab2(sch_1):m_g_dq(52)") )
				( member ( signalRef "@baseboard_fab2_lib.baseboard_fab2(sch_1):m_g_dq(53)") )
				( member ( signalRef "@baseboard_fab2_lib.baseboard_fab2(sch_1):m_g_dq(54)") )
				( member ( signalRef "@baseboard_fab2_lib.baseboard_fab2(sch_1):m_g_dq(55)") )
				( member ( signalRef "@baseboard_fab2_lib.baseboard_fab2(sch_1):m_g_dq(56)") )
				( member ( signalRef "@baseboard_fab2_lib.baseboard_fab2(sch_1):m_g_dq(57)") )
				( member ( signalRef "@baseboard_fab2_lib.baseboard_fab2(sch_1):m_g_dq(58)") )
				( member ( signalRef "@baseboard_fab2_lib.baseboard_fab2(sch_1):m_g_dq(59)") )
				( member ( signalRef "@baseboard_fab2_lib.baseboard_fab2(sch_1):m_g_dq(60)") )
				( member ( signalRef "@baseboard_fab2_lib.baseboard_fab2(sch_1):m_g_dq(61)") )
				( member ( signalRef "@baseboard_fab2_lib.baseboard_fab2(sch_1):m_g_dq(62)") )
				( member ( signalRef "@baseboard_fab2_lib.baseboard_fab2(sch_1):m_g_dq(63)") )
				( objectStatus "M_G_DQ" )
			)
			( bus "@baseboard_fab2_lib.baseboard_fab2(sch_1):m_g_dqs_dn"
				( memberType ( signal ) )
				( member ( signalRef "@baseboard_fab2_lib.baseboard_fab2(sch_1):m_g_dqs_dn(0)") )
				( member ( signalRef "@baseboard_fab2_lib.baseboard_fab2(sch_1):m_g_dqs_dn(1)") )
				( member ( signalRef "@baseboard_fab2_lib.baseboard_fab2(sch_1):m_g_dqs_dn(2)") )
				( member ( signalRef "@baseboard_fab2_lib.baseboard_fab2(sch_1):m_g_dqs_dn(3)") )
				( member ( signalRef "@baseboard_fab2_lib.baseboard_fab2(sch_1):m_g_dqs_dn(4)") )
				( member ( signalRef "@baseboard_fab2_lib.baseboard_fab2(sch_1):m_g_dqs_dn(5)") )
				( member ( signalRef "@baseboard_fab2_lib.baseboard_fab2(sch_1):m_g_dqs_dn(6)") )
				( member ( signalRef "@baseboard_fab2_lib.baseboard_fab2(sch_1):m_g_dqs_dn(7)") )
				( member ( signalRef "@baseboard_fab2_lib.baseboard_fab2(sch_1):m_g_dqs_dn(8)") )
				( member ( signalRef "@baseboard_fab2_lib.baseboard_fab2(sch_1):m_g_dqs_dn(9)") )
				( member ( signalRef "@baseboard_fab2_lib.baseboard_fab2(sch_1):m_g_dqs_dn(10)") )
				( member ( signalRef "@baseboard_fab2_lib.baseboard_fab2(sch_1):m_g_dqs_dn(11)") )
				( member ( signalRef "@baseboard_fab2_lib.baseboard_fab2(sch_1):m_g_dqs_dn(12)") )
				( member ( signalRef "@baseboard_fab2_lib.baseboard_fab2(sch_1):m_g_dqs_dn(13)") )
				( member ( signalRef "@baseboard_fab2_lib.baseboard_fab2(sch_1):m_g_dqs_dn(14)") )
				( member ( signalRef "@baseboard_fab2_lib.baseboard_fab2(sch_1):m_g_dqs_dn(15)") )
				( member ( signalRef "@baseboard_fab2_lib.baseboard_fab2(sch_1):m_g_dqs_dn(16)") )
				( member ( signalRef "@baseboard_fab2_lib.baseboard_fab2(sch_1):m_g_dqs_dn(17)") )
				( objectStatus "M_G_DQS_DN" )
			)
			( bus "@baseboard_fab2_lib.baseboard_fab2(sch_1):m_g_dqs_dp"
				( memberType ( signal ) )
				( member ( signalRef "@baseboard_fab2_lib.baseboard_fab2(sch_1):m_g_dqs_dp(0)") )
				( member ( signalRef "@baseboard_fab2_lib.baseboard_fab2(sch_1):m_g_dqs_dp(1)") )
				( member ( signalRef "@baseboard_fab2_lib.baseboard_fab2(sch_1):m_g_dqs_dp(2)") )
				( member ( signalRef "@baseboard_fab2_lib.baseboard_fab2(sch_1):m_g_dqs_dp(3)") )
				( member ( signalRef "@baseboard_fab2_lib.baseboard_fab2(sch_1):m_g_dqs_dp(4)") )
				( member ( signalRef "@baseboard_fab2_lib.baseboard_fab2(sch_1):m_g_dqs_dp(5)") )
				( member ( signalRef "@baseboard_fab2_lib.baseboard_fab2(sch_1):m_g_dqs_dp(6)") )
				( member ( signalRef "@baseboard_fab2_lib.baseboard_fab2(sch_1):m_g_dqs_dp(7)") )
				( member ( signalRef "@baseboard_fab2_lib.baseboard_fab2(sch_1):m_g_dqs_dp(8)") )
				( member ( signalRef "@baseboard_fab2_lib.baseboard_fab2(sch_1):m_g_dqs_dp(9)") )
				( member ( signalRef "@baseboard_fab2_lib.baseboard_fab2(sch_1):m_g_dqs_dp(10)") )
				( member ( signalRef "@baseboard_fab2_lib.baseboard_fab2(sch_1):m_g_dqs_dp(11)") )
				( member ( signalRef "@baseboard_fab2_lib.baseboard_fab2(sch_1):m_g_dqs_dp(12)") )
				( member ( signalRef "@baseboard_fab2_lib.baseboard_fab2(sch_1):m_g_dqs_dp(13)") )
				( member ( signalRef "@baseboard_fab2_lib.baseboard_fab2(sch_1):m_g_dqs_dp(14)") )
				( member ( signalRef "@baseboard_fab2_lib.baseboard_fab2(sch_1):m_g_dqs_dp(15)") )
				( member ( signalRef "@baseboard_fab2_lib.baseboard_fab2(sch_1):m_g_dqs_dp(16)") )
				( member ( signalRef "@baseboard_fab2_lib.baseboard_fab2(sch_1):m_g_dqs_dp(17)") )
				( objectStatus "M_G_DQS_DP" )
			)
			( bus "@baseboard_fab2_lib.baseboard_fab2(sch_1):m_g_ecc"
				( memberType ( signal ) )
				( member ( signalRef "@baseboard_fab2_lib.baseboard_fab2(sch_1):m_g_ecc(0)") )
				( member ( signalRef "@baseboard_fab2_lib.baseboard_fab2(sch_1):m_g_ecc(1)") )
				( member ( signalRef "@baseboard_fab2_lib.baseboard_fab2(sch_1):m_g_ecc(2)") )
				( member ( signalRef "@baseboard_fab2_lib.baseboard_fab2(sch_1):m_g_ecc(3)") )
				( member ( signalRef "@baseboard_fab2_lib.baseboard_fab2(sch_1):m_g_ecc(4)") )
				( member ( signalRef "@baseboard_fab2_lib.baseboard_fab2(sch_1):m_g_ecc(5)") )
				( member ( signalRef "@baseboard_fab2_lib.baseboard_fab2(sch_1):m_g_ecc(6)") )
				( member ( signalRef "@baseboard_fab2_lib.baseboard_fab2(sch_1):m_g_ecc(7)") )
				( objectStatus "M_G_ECC" )
			)
			( bus "@baseboard_fab2_lib.baseboard_fab2(sch_1):m_g_ma"
				( memberType ( signal ) )
				( member ( signalRef "@baseboard_fab2_lib.baseboard_fab2(sch_1):m_g_ma(0)") )
				( member ( signalRef "@baseboard_fab2_lib.baseboard_fab2(sch_1):m_g_ma(1)") )
				( member ( signalRef "@baseboard_fab2_lib.baseboard_fab2(sch_1):m_g_ma(2)") )
				( member ( signalRef "@baseboard_fab2_lib.baseboard_fab2(sch_1):m_g_ma(3)") )
				( member ( signalRef "@baseboard_fab2_lib.baseboard_fab2(sch_1):m_g_ma(4)") )
				( member ( signalRef "@baseboard_fab2_lib.baseboard_fab2(sch_1):m_g_ma(5)") )
				( member ( signalRef "@baseboard_fab2_lib.baseboard_fab2(sch_1):m_g_ma(6)") )
				( member ( signalRef "@baseboard_fab2_lib.baseboard_fab2(sch_1):m_g_ma(7)") )
				( member ( signalRef "@baseboard_fab2_lib.baseboard_fab2(sch_1):m_g_ma(8)") )
				( member ( signalRef "@baseboard_fab2_lib.baseboard_fab2(sch_1):m_g_ma(9)") )
				( member ( signalRef "@baseboard_fab2_lib.baseboard_fab2(sch_1):m_g_ma(10)") )
				( member ( signalRef "@baseboard_fab2_lib.baseboard_fab2(sch_1):m_g_ma(11)") )
				( member ( signalRef "@baseboard_fab2_lib.baseboard_fab2(sch_1):m_g_ma(12)") )
				( member ( signalRef "@baseboard_fab2_lib.baseboard_fab2(sch_1):m_g_ma(13)") )
				( member ( signalRef "@baseboard_fab2_lib.baseboard_fab2(sch_1):m_g_ma(14)") )
				( member ( signalRef "@baseboard_fab2_lib.baseboard_fab2(sch_1):m_g_ma(15)") )
				( member ( signalRef "@baseboard_fab2_lib.baseboard_fab2(sch_1):m_g_ma(16)") )
				( member ( signalRef "@baseboard_fab2_lib.baseboard_fab2(sch_1):m_g_ma(17)") )
				( objectStatus "M_G_MA" )
			)
			( bus "@baseboard_fab2_lib.baseboard_fab2(sch_1):m_g_odt"
				( memberType ( signal ) )
				( member ( signalRef "@baseboard_fab2_lib.baseboard_fab2(sch_1):m_g_odt(0)") )
				( member ( signalRef "@baseboard_fab2_lib.baseboard_fab2(sch_1):m_g_odt(1)") )
				( member ( signalRef "@baseboard_fab2_lib.baseboard_fab2(sch_1):m_g_odt(2)") )
				( member ( signalRef "@baseboard_fab2_lib.baseboard_fab2(sch_1):m_g_odt(3)") )
				( objectStatus "M_G_ODT" )
			)
			( bus "@baseboard_fab2_lib.baseboard_fab2(sch_1):m_h_ba"
				( memberType ( signal ) )
				( member ( signalRef "@baseboard_fab2_lib.baseboard_fab2(sch_1):m_h_ba(0)") )
				( member ( signalRef "@baseboard_fab2_lib.baseboard_fab2(sch_1):m_h_ba(1)") )
				( objectStatus "M_H_BA" )
			)
			( bus "@baseboard_fab2_lib.baseboard_fab2(sch_1):m_h_bg"
				( memberType ( signal ) )
				( member ( signalRef "@baseboard_fab2_lib.baseboard_fab2(sch_1):m_h_bg(0)") )
				( member ( signalRef "@baseboard_fab2_lib.baseboard_fab2(sch_1):m_h_bg(1)") )
				( objectStatus "M_H_BG" )
			)
			( bus "@baseboard_fab2_lib.baseboard_fab2(sch_1):m_h_c"
				( memberType ( signal ) )
				( member ( signalRef "@baseboard_fab2_lib.baseboard_fab2(sch_1):m_h_c(2)") )
				( objectStatus "M_H_C" )
			)
			( bus "@baseboard_fab2_lib.baseboard_fab2(sch_1):m_h_cke"
				( memberType ( signal ) )
				( member ( signalRef "@baseboard_fab2_lib.baseboard_fab2(sch_1):m_h_cke(0)") )
				( member ( signalRef "@baseboard_fab2_lib.baseboard_fab2(sch_1):m_h_cke(1)") )
				( member ( signalRef "@baseboard_fab2_lib.baseboard_fab2(sch_1):m_h_cke(2)") )
				( member ( signalRef "@baseboard_fab2_lib.baseboard_fab2(sch_1):m_h_cke(3)") )
				( objectStatus "M_H_CKE" )
			)
			( bus "@baseboard_fab2_lib.baseboard_fab2(sch_1):m_h_clk_dn"
				( memberType ( signal ) )
				( member ( signalRef "@baseboard_fab2_lib.baseboard_fab2(sch_1):m_h_clk_dn(0)") )
				( member ( signalRef "@baseboard_fab2_lib.baseboard_fab2(sch_1):m_h_clk_dn(1)") )
				( member ( signalRef "@baseboard_fab2_lib.baseboard_fab2(sch_1):m_h_clk_dn(2)") )
				( member ( signalRef "@baseboard_fab2_lib.baseboard_fab2(sch_1):m_h_clk_dn(3)") )
				( objectStatus "M_H_CLK_DN" )
			)
			( bus "@baseboard_fab2_lib.baseboard_fab2(sch_1):m_h_clk_dp"
				( memberType ( signal ) )
				( member ( signalRef "@baseboard_fab2_lib.baseboard_fab2(sch_1):m_h_clk_dp(0)") )
				( member ( signalRef "@baseboard_fab2_lib.baseboard_fab2(sch_1):m_h_clk_dp(1)") )
				( member ( signalRef "@baseboard_fab2_lib.baseboard_fab2(sch_1):m_h_clk_dp(2)") )
				( member ( signalRef "@baseboard_fab2_lib.baseboard_fab2(sch_1):m_h_clk_dp(3)") )
				( objectStatus "M_H_CLK_DP" )
			)
			( bus "@baseboard_fab2_lib.baseboard_fab2(sch_1):m_h_cs_n"
				( memberType ( signal ) )
				( member ( signalRef "@baseboard_fab2_lib.baseboard_fab2(sch_1):m_h_cs_n(0)") )
				( member ( signalRef "@baseboard_fab2_lib.baseboard_fab2(sch_1):m_h_cs_n(1)") )
				( member ( signalRef "@baseboard_fab2_lib.baseboard_fab2(sch_1):m_h_cs_n(2)") )
				( member ( signalRef "@baseboard_fab2_lib.baseboard_fab2(sch_1):m_h_cs_n(3)") )
				( member ( signalRef "@baseboard_fab2_lib.baseboard_fab2(sch_1):m_h_cs_n(4)") )
				( member ( signalRef "@baseboard_fab2_lib.baseboard_fab2(sch_1):m_h_cs_n(5)") )
				( member ( signalRef "@baseboard_fab2_lib.baseboard_fab2(sch_1):m_h_cs_n(6)") )
				( member ( signalRef "@baseboard_fab2_lib.baseboard_fab2(sch_1):m_h_cs_n(7)") )
				( objectStatus "M_H_CS_N" )
			)
			( bus "@baseboard_fab2_lib.baseboard_fab2(sch_1):m_h_dq"
				( memberType ( signal ) )
				( member ( signalRef "@baseboard_fab2_lib.baseboard_fab2(sch_1):m_h_dq(0)") )
				( member ( signalRef "@baseboard_fab2_lib.baseboard_fab2(sch_1):m_h_dq(1)") )
				( member ( signalRef "@baseboard_fab2_lib.baseboard_fab2(sch_1):m_h_dq(2)") )
				( member ( signalRef "@baseboard_fab2_lib.baseboard_fab2(sch_1):m_h_dq(3)") )
				( member ( signalRef "@baseboard_fab2_lib.baseboard_fab2(sch_1):m_h_dq(4)") )
				( member ( signalRef "@baseboard_fab2_lib.baseboard_fab2(sch_1):m_h_dq(5)") )
				( member ( signalRef "@baseboard_fab2_lib.baseboard_fab2(sch_1):m_h_dq(6)") )
				( member ( signalRef "@baseboard_fab2_lib.baseboard_fab2(sch_1):m_h_dq(7)") )
				( member ( signalRef "@baseboard_fab2_lib.baseboard_fab2(sch_1):m_h_dq(8)") )
				( member ( signalRef "@baseboard_fab2_lib.baseboard_fab2(sch_1):m_h_dq(9)") )
				( member ( signalRef "@baseboard_fab2_lib.baseboard_fab2(sch_1):m_h_dq(10)") )
				( member ( signalRef "@baseboard_fab2_lib.baseboard_fab2(sch_1):m_h_dq(11)") )
				( member ( signalRef "@baseboard_fab2_lib.baseboard_fab2(sch_1):m_h_dq(12)") )
				( member ( signalRef "@baseboard_fab2_lib.baseboard_fab2(sch_1):m_h_dq(13)") )
				( member ( signalRef "@baseboard_fab2_lib.baseboard_fab2(sch_1):m_h_dq(14)") )
				( member ( signalRef "@baseboard_fab2_lib.baseboard_fab2(sch_1):m_h_dq(15)") )
				( member ( signalRef "@baseboard_fab2_lib.baseboard_fab2(sch_1):m_h_dq(16)") )
				( member ( signalRef "@baseboard_fab2_lib.baseboard_fab2(sch_1):m_h_dq(17)") )
				( member ( signalRef "@baseboard_fab2_lib.baseboard_fab2(sch_1):m_h_dq(18)") )
				( member ( signalRef "@baseboard_fab2_lib.baseboard_fab2(sch_1):m_h_dq(19)") )
				( member ( signalRef "@baseboard_fab2_lib.baseboard_fab2(sch_1):m_h_dq(20)") )
				( member ( signalRef "@baseboard_fab2_lib.baseboard_fab2(sch_1):m_h_dq(21)") )
				( member ( signalRef "@baseboard_fab2_lib.baseboard_fab2(sch_1):m_h_dq(22)") )
				( member ( signalRef "@baseboard_fab2_lib.baseboard_fab2(sch_1):m_h_dq(23)") )
				( member ( signalRef "@baseboard_fab2_lib.baseboard_fab2(sch_1):m_h_dq(24)") )
				( member ( signalRef "@baseboard_fab2_lib.baseboard_fab2(sch_1):m_h_dq(25)") )
				( member ( signalRef "@baseboard_fab2_lib.baseboard_fab2(sch_1):m_h_dq(26)") )
				( member ( signalRef "@baseboard_fab2_lib.baseboard_fab2(sch_1):m_h_dq(27)") )
				( member ( signalRef "@baseboard_fab2_lib.baseboard_fab2(sch_1):m_h_dq(28)") )
				( member ( signalRef "@baseboard_fab2_lib.baseboard_fab2(sch_1):m_h_dq(29)") )
				( member ( signalRef "@baseboard_fab2_lib.baseboard_fab2(sch_1):m_h_dq(30)") )
				( member ( signalRef "@baseboard_fab2_lib.baseboard_fab2(sch_1):m_h_dq(31)") )
				( member ( signalRef "@baseboard_fab2_lib.baseboard_fab2(sch_1):m_h_dq(32)") )
				( member ( signalRef "@baseboard_fab2_lib.baseboard_fab2(sch_1):m_h_dq(33)") )
				( member ( signalRef "@baseboard_fab2_lib.baseboard_fab2(sch_1):m_h_dq(34)") )
				( member ( signalRef "@baseboard_fab2_lib.baseboard_fab2(sch_1):m_h_dq(35)") )
				( member ( signalRef "@baseboard_fab2_lib.baseboard_fab2(sch_1):m_h_dq(36)") )
				( member ( signalRef "@baseboard_fab2_lib.baseboard_fab2(sch_1):m_h_dq(37)") )
				( member ( signalRef "@baseboard_fab2_lib.baseboard_fab2(sch_1):m_h_dq(38)") )
				( member ( signalRef "@baseboard_fab2_lib.baseboard_fab2(sch_1):m_h_dq(39)") )
				( member ( signalRef "@baseboard_fab2_lib.baseboard_fab2(sch_1):m_h_dq(40)") )
				( member ( signalRef "@baseboard_fab2_lib.baseboard_fab2(sch_1):m_h_dq(41)") )
				( member ( signalRef "@baseboard_fab2_lib.baseboard_fab2(sch_1):m_h_dq(42)") )
				( member ( signalRef "@baseboard_fab2_lib.baseboard_fab2(sch_1):m_h_dq(43)") )
				( member ( signalRef "@baseboard_fab2_lib.baseboard_fab2(sch_1):m_h_dq(44)") )
				( member ( signalRef "@baseboard_fab2_lib.baseboard_fab2(sch_1):m_h_dq(45)") )
				( member ( signalRef "@baseboard_fab2_lib.baseboard_fab2(sch_1):m_h_dq(46)") )
				( member ( signalRef "@baseboard_fab2_lib.baseboard_fab2(sch_1):m_h_dq(47)") )
				( member ( signalRef "@baseboard_fab2_lib.baseboard_fab2(sch_1):m_h_dq(48)") )
				( member ( signalRef "@baseboard_fab2_lib.baseboard_fab2(sch_1):m_h_dq(49)") )
				( member ( signalRef "@baseboard_fab2_lib.baseboard_fab2(sch_1):m_h_dq(50)") )
				( member ( signalRef "@baseboard_fab2_lib.baseboard_fab2(sch_1):m_h_dq(51)") )
				( member ( signalRef "@baseboard_fab2_lib.baseboard_fab2(sch_1):m_h_dq(52)") )
				( member ( signalRef "@baseboard_fab2_lib.baseboard_fab2(sch_1):m_h_dq(53)") )
				( member ( signalRef "@baseboard_fab2_lib.baseboard_fab2(sch_1):m_h_dq(54)") )
				( member ( signalRef "@baseboard_fab2_lib.baseboard_fab2(sch_1):m_h_dq(55)") )
				( member ( signalRef "@baseboard_fab2_lib.baseboard_fab2(sch_1):m_h_dq(56)") )
				( member ( signalRef "@baseboard_fab2_lib.baseboard_fab2(sch_1):m_h_dq(57)") )
				( member ( signalRef "@baseboard_fab2_lib.baseboard_fab2(sch_1):m_h_dq(58)") )
				( member ( signalRef "@baseboard_fab2_lib.baseboard_fab2(sch_1):m_h_dq(59)") )
				( member ( signalRef "@baseboard_fab2_lib.baseboard_fab2(sch_1):m_h_dq(60)") )
				( member ( signalRef "@baseboard_fab2_lib.baseboard_fab2(sch_1):m_h_dq(61)") )
				( member ( signalRef "@baseboard_fab2_lib.baseboard_fab2(sch_1):m_h_dq(62)") )
				( member ( signalRef "@baseboard_fab2_lib.baseboard_fab2(sch_1):m_h_dq(63)") )
				( objectStatus "M_H_DQ" )
			)
			( bus "@baseboard_fab2_lib.baseboard_fab2(sch_1):m_h_dqs_dn"
				( memberType ( signal ) )
				( member ( signalRef "@baseboard_fab2_lib.baseboard_fab2(sch_1):m_h_dqs_dn(0)") )
				( member ( signalRef "@baseboard_fab2_lib.baseboard_fab2(sch_1):m_h_dqs_dn(1)") )
				( member ( signalRef "@baseboard_fab2_lib.baseboard_fab2(sch_1):m_h_dqs_dn(2)") )
				( member ( signalRef "@baseboard_fab2_lib.baseboard_fab2(sch_1):m_h_dqs_dn(3)") )
				( member ( signalRef "@baseboard_fab2_lib.baseboard_fab2(sch_1):m_h_dqs_dn(4)") )
				( member ( signalRef "@baseboard_fab2_lib.baseboard_fab2(sch_1):m_h_dqs_dn(5)") )
				( member ( signalRef "@baseboard_fab2_lib.baseboard_fab2(sch_1):m_h_dqs_dn(6)") )
				( member ( signalRef "@baseboard_fab2_lib.baseboard_fab2(sch_1):m_h_dqs_dn(7)") )
				( member ( signalRef "@baseboard_fab2_lib.baseboard_fab2(sch_1):m_h_dqs_dn(8)") )
				( member ( signalRef "@baseboard_fab2_lib.baseboard_fab2(sch_1):m_h_dqs_dn(9)") )
				( member ( signalRef "@baseboard_fab2_lib.baseboard_fab2(sch_1):m_h_dqs_dn(10)") )
				( member ( signalRef "@baseboard_fab2_lib.baseboard_fab2(sch_1):m_h_dqs_dn(11)") )
				( member ( signalRef "@baseboard_fab2_lib.baseboard_fab2(sch_1):m_h_dqs_dn(12)") )
				( member ( signalRef "@baseboard_fab2_lib.baseboard_fab2(sch_1):m_h_dqs_dn(13)") )
				( member ( signalRef "@baseboard_fab2_lib.baseboard_fab2(sch_1):m_h_dqs_dn(14)") )
				( member ( signalRef "@baseboard_fab2_lib.baseboard_fab2(sch_1):m_h_dqs_dn(15)") )
				( member ( signalRef "@baseboard_fab2_lib.baseboard_fab2(sch_1):m_h_dqs_dn(16)") )
				( member ( signalRef "@baseboard_fab2_lib.baseboard_fab2(sch_1):m_h_dqs_dn(17)") )
				( objectStatus "M_H_DQS_DN" )
			)
			( bus "@baseboard_fab2_lib.baseboard_fab2(sch_1):m_h_dqs_dp"
				( memberType ( signal ) )
				( member ( signalRef "@baseboard_fab2_lib.baseboard_fab2(sch_1):m_h_dqs_dp(0)") )
				( member ( signalRef "@baseboard_fab2_lib.baseboard_fab2(sch_1):m_h_dqs_dp(1)") )
				( member ( signalRef "@baseboard_fab2_lib.baseboard_fab2(sch_1):m_h_dqs_dp(2)") )
				( member ( signalRef "@baseboard_fab2_lib.baseboard_fab2(sch_1):m_h_dqs_dp(3)") )
				( member ( signalRef "@baseboard_fab2_lib.baseboard_fab2(sch_1):m_h_dqs_dp(4)") )
				( member ( signalRef "@baseboard_fab2_lib.baseboard_fab2(sch_1):m_h_dqs_dp(5)") )
				( member ( signalRef "@baseboard_fab2_lib.baseboard_fab2(sch_1):m_h_dqs_dp(6)") )
				( member ( signalRef "@baseboard_fab2_lib.baseboard_fab2(sch_1):m_h_dqs_dp(7)") )
				( member ( signalRef "@baseboard_fab2_lib.baseboard_fab2(sch_1):m_h_dqs_dp(8)") )
				( member ( signalRef "@baseboard_fab2_lib.baseboard_fab2(sch_1):m_h_dqs_dp(9)") )
				( member ( signalRef "@baseboard_fab2_lib.baseboard_fab2(sch_1):m_h_dqs_dp(10)") )
				( member ( signalRef "@baseboard_fab2_lib.baseboard_fab2(sch_1):m_h_dqs_dp(11)") )
				( member ( signalRef "@baseboard_fab2_lib.baseboard_fab2(sch_1):m_h_dqs_dp(12)") )
				( member ( signalRef "@baseboard_fab2_lib.baseboard_fab2(sch_1):m_h_dqs_dp(13)") )
				( member ( signalRef "@baseboard_fab2_lib.baseboard_fab2(sch_1):m_h_dqs_dp(14)") )
				( member ( signalRef "@baseboard_fab2_lib.baseboard_fab2(sch_1):m_h_dqs_dp(15)") )
				( member ( signalRef "@baseboard_fab2_lib.baseboard_fab2(sch_1):m_h_dqs_dp(16)") )
				( member ( signalRef "@baseboard_fab2_lib.baseboard_fab2(sch_1):m_h_dqs_dp(17)") )
				( objectStatus "M_H_DQS_DP" )
			)
			( bus "@baseboard_fab2_lib.baseboard_fab2(sch_1):m_h_ecc"
				( memberType ( signal ) )
				( member ( signalRef "@baseboard_fab2_lib.baseboard_fab2(sch_1):m_h_ecc(0)") )
				( member ( signalRef "@baseboard_fab2_lib.baseboard_fab2(sch_1):m_h_ecc(1)") )
				( member ( signalRef "@baseboard_fab2_lib.baseboard_fab2(sch_1):m_h_ecc(2)") )
				( member ( signalRef "@baseboard_fab2_lib.baseboard_fab2(sch_1):m_h_ecc(3)") )
				( member ( signalRef "@baseboard_fab2_lib.baseboard_fab2(sch_1):m_h_ecc(4)") )
				( member ( signalRef "@baseboard_fab2_lib.baseboard_fab2(sch_1):m_h_ecc(5)") )
				( member ( signalRef "@baseboard_fab2_lib.baseboard_fab2(sch_1):m_h_ecc(6)") )
				( member ( signalRef "@baseboard_fab2_lib.baseboard_fab2(sch_1):m_h_ecc(7)") )
				( objectStatus "M_H_ECC" )
			)
			( bus "@baseboard_fab2_lib.baseboard_fab2(sch_1):m_h_ma"
				( memberType ( signal ) )
				( member ( signalRef "@baseboard_fab2_lib.baseboard_fab2(sch_1):m_h_ma(0)") )
				( member ( signalRef "@baseboard_fab2_lib.baseboard_fab2(sch_1):m_h_ma(1)") )
				( member ( signalRef "@baseboard_fab2_lib.baseboard_fab2(sch_1):m_h_ma(2)") )
				( member ( signalRef "@baseboard_fab2_lib.baseboard_fab2(sch_1):m_h_ma(3)") )
				( member ( signalRef "@baseboard_fab2_lib.baseboard_fab2(sch_1):m_h_ma(4)") )
				( member ( signalRef "@baseboard_fab2_lib.baseboard_fab2(sch_1):m_h_ma(5)") )
				( member ( signalRef "@baseboard_fab2_lib.baseboard_fab2(sch_1):m_h_ma(6)") )
				( member ( signalRef "@baseboard_fab2_lib.baseboard_fab2(sch_1):m_h_ma(7)") )
				( member ( signalRef "@baseboard_fab2_lib.baseboard_fab2(sch_1):m_h_ma(8)") )
				( member ( signalRef "@baseboard_fab2_lib.baseboard_fab2(sch_1):m_h_ma(9)") )
				( member ( signalRef "@baseboard_fab2_lib.baseboard_fab2(sch_1):m_h_ma(10)") )
				( member ( signalRef "@baseboard_fab2_lib.baseboard_fab2(sch_1):m_h_ma(11)") )
				( member ( signalRef "@baseboard_fab2_lib.baseboard_fab2(sch_1):m_h_ma(12)") )
				( member ( signalRef "@baseboard_fab2_lib.baseboard_fab2(sch_1):m_h_ma(13)") )
				( member ( signalRef "@baseboard_fab2_lib.baseboard_fab2(sch_1):m_h_ma(14)") )
				( member ( signalRef "@baseboard_fab2_lib.baseboard_fab2(sch_1):m_h_ma(15)") )
				( member ( signalRef "@baseboard_fab2_lib.baseboard_fab2(sch_1):m_h_ma(16)") )
				( member ( signalRef "@baseboard_fab2_lib.baseboard_fab2(sch_1):m_h_ma(17)") )
				( objectStatus "M_H_MA" )
			)
			( bus "@baseboard_fab2_lib.baseboard_fab2(sch_1):m_h_odt"
				( memberType ( signal ) )
				( member ( signalRef "@baseboard_fab2_lib.baseboard_fab2(sch_1):m_h_odt(0)") )
				( member ( signalRef "@baseboard_fab2_lib.baseboard_fab2(sch_1):m_h_odt(1)") )
				( member ( signalRef "@baseboard_fab2_lib.baseboard_fab2(sch_1):m_h_odt(2)") )
				( member ( signalRef "@baseboard_fab2_lib.baseboard_fab2(sch_1):m_h_odt(3)") )
				( objectStatus "M_H_ODT" )
			)
			( bus "@baseboard_fab2_lib.baseboard_fab2(sch_1):m_j_ba"
				( memberType ( signal ) )
				( member ( signalRef "@baseboard_fab2_lib.baseboard_fab2(sch_1):m_j_ba(0)") )
				( member ( signalRef "@baseboard_fab2_lib.baseboard_fab2(sch_1):m_j_ba(1)") )
				( objectStatus "M_J_BA" )
			)
			( bus "@baseboard_fab2_lib.baseboard_fab2(sch_1):m_j_bg"
				( memberType ( signal ) )
				( member ( signalRef "@baseboard_fab2_lib.baseboard_fab2(sch_1):m_j_bg(0)") )
				( member ( signalRef "@baseboard_fab2_lib.baseboard_fab2(sch_1):m_j_bg(1)") )
				( objectStatus "M_J_BG" )
			)
			( bus "@baseboard_fab2_lib.baseboard_fab2(sch_1):m_j_c"
				( memberType ( signal ) )
				( member ( signalRef "@baseboard_fab2_lib.baseboard_fab2(sch_1):m_j_c(2)") )
				( objectStatus "M_J_C" )
			)
			( bus "@baseboard_fab2_lib.baseboard_fab2(sch_1):m_j_cke"
				( memberType ( signal ) )
				( member ( signalRef "@baseboard_fab2_lib.baseboard_fab2(sch_1):m_j_cke(0)") )
				( member ( signalRef "@baseboard_fab2_lib.baseboard_fab2(sch_1):m_j_cke(1)") )
				( member ( signalRef "@baseboard_fab2_lib.baseboard_fab2(sch_1):m_j_cke(2)") )
				( member ( signalRef "@baseboard_fab2_lib.baseboard_fab2(sch_1):m_j_cke(3)") )
				( objectStatus "M_J_CKE" )
			)
			( bus "@baseboard_fab2_lib.baseboard_fab2(sch_1):m_j_clk_dn"
				( memberType ( signal ) )
				( member ( signalRef "@baseboard_fab2_lib.baseboard_fab2(sch_1):m_j_clk_dn(0)") )
				( member ( signalRef "@baseboard_fab2_lib.baseboard_fab2(sch_1):m_j_clk_dn(1)") )
				( member ( signalRef "@baseboard_fab2_lib.baseboard_fab2(sch_1):m_j_clk_dn(2)") )
				( member ( signalRef "@baseboard_fab2_lib.baseboard_fab2(sch_1):m_j_clk_dn(3)") )
				( objectStatus "M_J_CLK_DN" )
			)
			( bus "@baseboard_fab2_lib.baseboard_fab2(sch_1):m_j_clk_dp"
				( memberType ( signal ) )
				( member ( signalRef "@baseboard_fab2_lib.baseboard_fab2(sch_1):m_j_clk_dp(0)") )
				( member ( signalRef "@baseboard_fab2_lib.baseboard_fab2(sch_1):m_j_clk_dp(1)") )
				( member ( signalRef "@baseboard_fab2_lib.baseboard_fab2(sch_1):m_j_clk_dp(2)") )
				( member ( signalRef "@baseboard_fab2_lib.baseboard_fab2(sch_1):m_j_clk_dp(3)") )
				( objectStatus "M_J_CLK_DP" )
			)
			( bus "@baseboard_fab2_lib.baseboard_fab2(sch_1):m_j_cs_n"
				( memberType ( signal ) )
				( member ( signalRef "@baseboard_fab2_lib.baseboard_fab2(sch_1):m_j_cs_n(0)") )
				( member ( signalRef "@baseboard_fab2_lib.baseboard_fab2(sch_1):m_j_cs_n(1)") )
				( member ( signalRef "@baseboard_fab2_lib.baseboard_fab2(sch_1):m_j_cs_n(2)") )
				( member ( signalRef "@baseboard_fab2_lib.baseboard_fab2(sch_1):m_j_cs_n(3)") )
				( member ( signalRef "@baseboard_fab2_lib.baseboard_fab2(sch_1):m_j_cs_n(4)") )
				( member ( signalRef "@baseboard_fab2_lib.baseboard_fab2(sch_1):m_j_cs_n(5)") )
				( member ( signalRef "@baseboard_fab2_lib.baseboard_fab2(sch_1):m_j_cs_n(6)") )
				( member ( signalRef "@baseboard_fab2_lib.baseboard_fab2(sch_1):m_j_cs_n(7)") )
				( objectStatus "M_J_CS_N" )
			)
			( bus "@baseboard_fab2_lib.baseboard_fab2(sch_1):m_j_dq"
				( memberType ( signal ) )
				( member ( signalRef "@baseboard_fab2_lib.baseboard_fab2(sch_1):m_j_dq(0)") )
				( member ( signalRef "@baseboard_fab2_lib.baseboard_fab2(sch_1):m_j_dq(1)") )
				( member ( signalRef "@baseboard_fab2_lib.baseboard_fab2(sch_1):m_j_dq(2)") )
				( member ( signalRef "@baseboard_fab2_lib.baseboard_fab2(sch_1):m_j_dq(3)") )
				( member ( signalRef "@baseboard_fab2_lib.baseboard_fab2(sch_1):m_j_dq(4)") )
				( member ( signalRef "@baseboard_fab2_lib.baseboard_fab2(sch_1):m_j_dq(5)") )
				( member ( signalRef "@baseboard_fab2_lib.baseboard_fab2(sch_1):m_j_dq(6)") )
				( member ( signalRef "@baseboard_fab2_lib.baseboard_fab2(sch_1):m_j_dq(7)") )
				( member ( signalRef "@baseboard_fab2_lib.baseboard_fab2(sch_1):m_j_dq(8)") )
				( member ( signalRef "@baseboard_fab2_lib.baseboard_fab2(sch_1):m_j_dq(9)") )
				( member ( signalRef "@baseboard_fab2_lib.baseboard_fab2(sch_1):m_j_dq(10)") )
				( member ( signalRef "@baseboard_fab2_lib.baseboard_fab2(sch_1):m_j_dq(11)") )
				( member ( signalRef "@baseboard_fab2_lib.baseboard_fab2(sch_1):m_j_dq(12)") )
				( member ( signalRef "@baseboard_fab2_lib.baseboard_fab2(sch_1):m_j_dq(13)") )
				( member ( signalRef "@baseboard_fab2_lib.baseboard_fab2(sch_1):m_j_dq(14)") )
				( member ( signalRef "@baseboard_fab2_lib.baseboard_fab2(sch_1):m_j_dq(15)") )
				( member ( signalRef "@baseboard_fab2_lib.baseboard_fab2(sch_1):m_j_dq(16)") )
				( member ( signalRef "@baseboard_fab2_lib.baseboard_fab2(sch_1):m_j_dq(17)") )
				( member ( signalRef "@baseboard_fab2_lib.baseboard_fab2(sch_1):m_j_dq(18)") )
				( member ( signalRef "@baseboard_fab2_lib.baseboard_fab2(sch_1):m_j_dq(19)") )
				( member ( signalRef "@baseboard_fab2_lib.baseboard_fab2(sch_1):m_j_dq(20)") )
				( member ( signalRef "@baseboard_fab2_lib.baseboard_fab2(sch_1):m_j_dq(21)") )
				( member ( signalRef "@baseboard_fab2_lib.baseboard_fab2(sch_1):m_j_dq(22)") )
				( member ( signalRef "@baseboard_fab2_lib.baseboard_fab2(sch_1):m_j_dq(23)") )
				( member ( signalRef "@baseboard_fab2_lib.baseboard_fab2(sch_1):m_j_dq(24)") )
				( member ( signalRef "@baseboard_fab2_lib.baseboard_fab2(sch_1):m_j_dq(25)") )
				( member ( signalRef "@baseboard_fab2_lib.baseboard_fab2(sch_1):m_j_dq(26)") )
				( member ( signalRef "@baseboard_fab2_lib.baseboard_fab2(sch_1):m_j_dq(27)") )
				( member ( signalRef "@baseboard_fab2_lib.baseboard_fab2(sch_1):m_j_dq(28)") )
				( member ( signalRef "@baseboard_fab2_lib.baseboard_fab2(sch_1):m_j_dq(29)") )
				( member ( signalRef "@baseboard_fab2_lib.baseboard_fab2(sch_1):m_j_dq(30)") )
				( member ( signalRef "@baseboard_fab2_lib.baseboard_fab2(sch_1):m_j_dq(31)") )
				( member ( signalRef "@baseboard_fab2_lib.baseboard_fab2(sch_1):m_j_dq(32)") )
				( member ( signalRef "@baseboard_fab2_lib.baseboard_fab2(sch_1):m_j_dq(33)") )
				( member ( signalRef "@baseboard_fab2_lib.baseboard_fab2(sch_1):m_j_dq(34)") )
				( member ( signalRef "@baseboard_fab2_lib.baseboard_fab2(sch_1):m_j_dq(35)") )
				( member ( signalRef "@baseboard_fab2_lib.baseboard_fab2(sch_1):m_j_dq(36)") )
				( member ( signalRef "@baseboard_fab2_lib.baseboard_fab2(sch_1):m_j_dq(37)") )
				( member ( signalRef "@baseboard_fab2_lib.baseboard_fab2(sch_1):m_j_dq(38)") )
				( member ( signalRef "@baseboard_fab2_lib.baseboard_fab2(sch_1):m_j_dq(39)") )
				( member ( signalRef "@baseboard_fab2_lib.baseboard_fab2(sch_1):m_j_dq(40)") )
				( member ( signalRef "@baseboard_fab2_lib.baseboard_fab2(sch_1):m_j_dq(41)") )
				( member ( signalRef "@baseboard_fab2_lib.baseboard_fab2(sch_1):m_j_dq(42)") )
				( member ( signalRef "@baseboard_fab2_lib.baseboard_fab2(sch_1):m_j_dq(43)") )
				( member ( signalRef "@baseboard_fab2_lib.baseboard_fab2(sch_1):m_j_dq(44)") )
				( member ( signalRef "@baseboard_fab2_lib.baseboard_fab2(sch_1):m_j_dq(45)") )
				( member ( signalRef "@baseboard_fab2_lib.baseboard_fab2(sch_1):m_j_dq(46)") )
				( member ( signalRef "@baseboard_fab2_lib.baseboard_fab2(sch_1):m_j_dq(47)") )
				( member ( signalRef "@baseboard_fab2_lib.baseboard_fab2(sch_1):m_j_dq(48)") )
				( member ( signalRef "@baseboard_fab2_lib.baseboard_fab2(sch_1):m_j_dq(49)") )
				( member ( signalRef "@baseboard_fab2_lib.baseboard_fab2(sch_1):m_j_dq(50)") )
				( member ( signalRef "@baseboard_fab2_lib.baseboard_fab2(sch_1):m_j_dq(51)") )
				( member ( signalRef "@baseboard_fab2_lib.baseboard_fab2(sch_1):m_j_dq(52)") )
				( member ( signalRef "@baseboard_fab2_lib.baseboard_fab2(sch_1):m_j_dq(53)") )
				( member ( signalRef "@baseboard_fab2_lib.baseboard_fab2(sch_1):m_j_dq(54)") )
				( member ( signalRef "@baseboard_fab2_lib.baseboard_fab2(sch_1):m_j_dq(55)") )
				( member ( signalRef "@baseboard_fab2_lib.baseboard_fab2(sch_1):m_j_dq(56)") )
				( member ( signalRef "@baseboard_fab2_lib.baseboard_fab2(sch_1):m_j_dq(57)") )
				( member ( signalRef "@baseboard_fab2_lib.baseboard_fab2(sch_1):m_j_dq(58)") )
				( member ( signalRef "@baseboard_fab2_lib.baseboard_fab2(sch_1):m_j_dq(59)") )
				( member ( signalRef "@baseboard_fab2_lib.baseboard_fab2(sch_1):m_j_dq(60)") )
				( member ( signalRef "@baseboard_fab2_lib.baseboard_fab2(sch_1):m_j_dq(61)") )
				( member ( signalRef "@baseboard_fab2_lib.baseboard_fab2(sch_1):m_j_dq(62)") )
				( member ( signalRef "@baseboard_fab2_lib.baseboard_fab2(sch_1):m_j_dq(63)") )
				( objectStatus "M_J_DQ" )
			)
			( bus "@baseboard_fab2_lib.baseboard_fab2(sch_1):m_j_dqs_dn"
				( memberType ( signal ) )
				( member ( signalRef "@baseboard_fab2_lib.baseboard_fab2(sch_1):m_j_dqs_dn(0)") )
				( member ( signalRef "@baseboard_fab2_lib.baseboard_fab2(sch_1):m_j_dqs_dn(1)") )
				( member ( signalRef "@baseboard_fab2_lib.baseboard_fab2(sch_1):m_j_dqs_dn(2)") )
				( member ( signalRef "@baseboard_fab2_lib.baseboard_fab2(sch_1):m_j_dqs_dn(3)") )
				( member ( signalRef "@baseboard_fab2_lib.baseboard_fab2(sch_1):m_j_dqs_dn(4)") )
				( member ( signalRef "@baseboard_fab2_lib.baseboard_fab2(sch_1):m_j_dqs_dn(5)") )
				( member ( signalRef "@baseboard_fab2_lib.baseboard_fab2(sch_1):m_j_dqs_dn(6)") )
				( member ( signalRef "@baseboard_fab2_lib.baseboard_fab2(sch_1):m_j_dqs_dn(7)") )
				( member ( signalRef "@baseboard_fab2_lib.baseboard_fab2(sch_1):m_j_dqs_dn(8)") )
				( member ( signalRef "@baseboard_fab2_lib.baseboard_fab2(sch_1):m_j_dqs_dn(9)") )
				( member ( signalRef "@baseboard_fab2_lib.baseboard_fab2(sch_1):m_j_dqs_dn(10)") )
				( member ( signalRef "@baseboard_fab2_lib.baseboard_fab2(sch_1):m_j_dqs_dn(11)") )
				( member ( signalRef "@baseboard_fab2_lib.baseboard_fab2(sch_1):m_j_dqs_dn(12)") )
				( member ( signalRef "@baseboard_fab2_lib.baseboard_fab2(sch_1):m_j_dqs_dn(13)") )
				( member ( signalRef "@baseboard_fab2_lib.baseboard_fab2(sch_1):m_j_dqs_dn(14)") )
				( member ( signalRef "@baseboard_fab2_lib.baseboard_fab2(sch_1):m_j_dqs_dn(15)") )
				( member ( signalRef "@baseboard_fab2_lib.baseboard_fab2(sch_1):m_j_dqs_dn(16)") )
				( member ( signalRef "@baseboard_fab2_lib.baseboard_fab2(sch_1):m_j_dqs_dn(17)") )
				( objectStatus "M_J_DQS_DN" )
			)
			( bus "@baseboard_fab2_lib.baseboard_fab2(sch_1):m_j_dqs_dp"
				( memberType ( signal ) )
				( member ( signalRef "@baseboard_fab2_lib.baseboard_fab2(sch_1):m_j_dqs_dp(0)") )
				( member ( signalRef "@baseboard_fab2_lib.baseboard_fab2(sch_1):m_j_dqs_dp(1)") )
				( member ( signalRef "@baseboard_fab2_lib.baseboard_fab2(sch_1):m_j_dqs_dp(2)") )
				( member ( signalRef "@baseboard_fab2_lib.baseboard_fab2(sch_1):m_j_dqs_dp(3)") )
				( member ( signalRef "@baseboard_fab2_lib.baseboard_fab2(sch_1):m_j_dqs_dp(4)") )
				( member ( signalRef "@baseboard_fab2_lib.baseboard_fab2(sch_1):m_j_dqs_dp(5)") )
				( member ( signalRef "@baseboard_fab2_lib.baseboard_fab2(sch_1):m_j_dqs_dp(6)") )
				( member ( signalRef "@baseboard_fab2_lib.baseboard_fab2(sch_1):m_j_dqs_dp(7)") )
				( member ( signalRef "@baseboard_fab2_lib.baseboard_fab2(sch_1):m_j_dqs_dp(8)") )
				( member ( signalRef "@baseboard_fab2_lib.baseboard_fab2(sch_1):m_j_dqs_dp(9)") )
				( member ( signalRef "@baseboard_fab2_lib.baseboard_fab2(sch_1):m_j_dqs_dp(10)") )
				( member ( signalRef "@baseboard_fab2_lib.baseboard_fab2(sch_1):m_j_dqs_dp(11)") )
				( member ( signalRef "@baseboard_fab2_lib.baseboard_fab2(sch_1):m_j_dqs_dp(12)") )
				( member ( signalRef "@baseboard_fab2_lib.baseboard_fab2(sch_1):m_j_dqs_dp(13)") )
				( member ( signalRef "@baseboard_fab2_lib.baseboard_fab2(sch_1):m_j_dqs_dp(14)") )
				( member ( signalRef "@baseboard_fab2_lib.baseboard_fab2(sch_1):m_j_dqs_dp(15)") )
				( member ( signalRef "@baseboard_fab2_lib.baseboard_fab2(sch_1):m_j_dqs_dp(16)") )
				( member ( signalRef "@baseboard_fab2_lib.baseboard_fab2(sch_1):m_j_dqs_dp(17)") )
				( objectStatus "M_J_DQS_DP" )
			)
			( bus "@baseboard_fab2_lib.baseboard_fab2(sch_1):m_j_ecc"
				( memberType ( signal ) )
				( member ( signalRef "@baseboard_fab2_lib.baseboard_fab2(sch_1):m_j_ecc(0)") )
				( member ( signalRef "@baseboard_fab2_lib.baseboard_fab2(sch_1):m_j_ecc(1)") )
				( member ( signalRef "@baseboard_fab2_lib.baseboard_fab2(sch_1):m_j_ecc(2)") )
				( member ( signalRef "@baseboard_fab2_lib.baseboard_fab2(sch_1):m_j_ecc(3)") )
				( member ( signalRef "@baseboard_fab2_lib.baseboard_fab2(sch_1):m_j_ecc(4)") )
				( member ( signalRef "@baseboard_fab2_lib.baseboard_fab2(sch_1):m_j_ecc(5)") )
				( member ( signalRef "@baseboard_fab2_lib.baseboard_fab2(sch_1):m_j_ecc(6)") )
				( member ( signalRef "@baseboard_fab2_lib.baseboard_fab2(sch_1):m_j_ecc(7)") )
				( objectStatus "M_J_ECC" )
			)
			( bus "@baseboard_fab2_lib.baseboard_fab2(sch_1):m_j_ma"
				( memberType ( signal ) )
				( member ( signalRef "@baseboard_fab2_lib.baseboard_fab2(sch_1):m_j_ma(0)") )
				( member ( signalRef "@baseboard_fab2_lib.baseboard_fab2(sch_1):m_j_ma(1)") )
				( member ( signalRef "@baseboard_fab2_lib.baseboard_fab2(sch_1):m_j_ma(2)") )
				( member ( signalRef "@baseboard_fab2_lib.baseboard_fab2(sch_1):m_j_ma(3)") )
				( member ( signalRef "@baseboard_fab2_lib.baseboard_fab2(sch_1):m_j_ma(4)") )
				( member ( signalRef "@baseboard_fab2_lib.baseboard_fab2(sch_1):m_j_ma(5)") )
				( member ( signalRef "@baseboard_fab2_lib.baseboard_fab2(sch_1):m_j_ma(6)") )
				( member ( signalRef "@baseboard_fab2_lib.baseboard_fab2(sch_1):m_j_ma(7)") )
				( member ( signalRef "@baseboard_fab2_lib.baseboard_fab2(sch_1):m_j_ma(8)") )
				( member ( signalRef "@baseboard_fab2_lib.baseboard_fab2(sch_1):m_j_ma(9)") )
				( member ( signalRef "@baseboard_fab2_lib.baseboard_fab2(sch_1):m_j_ma(10)") )
				( member ( signalRef "@baseboard_fab2_lib.baseboard_fab2(sch_1):m_j_ma(11)") )
				( member ( signalRef "@baseboard_fab2_lib.baseboard_fab2(sch_1):m_j_ma(12)") )
				( member ( signalRef "@baseboard_fab2_lib.baseboard_fab2(sch_1):m_j_ma(13)") )
				( member ( signalRef "@baseboard_fab2_lib.baseboard_fab2(sch_1):m_j_ma(14)") )
				( member ( signalRef "@baseboard_fab2_lib.baseboard_fab2(sch_1):m_j_ma(15)") )
				( member ( signalRef "@baseboard_fab2_lib.baseboard_fab2(sch_1):m_j_ma(16)") )
				( member ( signalRef "@baseboard_fab2_lib.baseboard_fab2(sch_1):m_j_ma(17)") )
				( objectStatus "M_J_MA" )
			)
			( bus "@baseboard_fab2_lib.baseboard_fab2(sch_1):m_j_odt"
				( memberType ( signal ) )
				( member ( signalRef "@baseboard_fab2_lib.baseboard_fab2(sch_1):m_j_odt(0)") )
				( member ( signalRef "@baseboard_fab2_lib.baseboard_fab2(sch_1):m_j_odt(1)") )
				( member ( signalRef "@baseboard_fab2_lib.baseboard_fab2(sch_1):m_j_odt(2)") )
				( member ( signalRef "@baseboard_fab2_lib.baseboard_fab2(sch_1):m_j_odt(3)") )
				( objectStatus "M_J_ODT" )
			)
			( bus "@baseboard_fab2_lib.baseboard_fab2(sch_1):m_k_ba"
				( memberType ( signal ) )
				( member ( signalRef "@baseboard_fab2_lib.baseboard_fab2(sch_1):m_k_ba(0)") )
				( member ( signalRef "@baseboard_fab2_lib.baseboard_fab2(sch_1):m_k_ba(1)") )
				( objectStatus "M_K_BA" )
			)
			( bus "@baseboard_fab2_lib.baseboard_fab2(sch_1):m_k_bg"
				( memberType ( signal ) )
				( member ( signalRef "@baseboard_fab2_lib.baseboard_fab2(sch_1):m_k_bg(0)") )
				( member ( signalRef "@baseboard_fab2_lib.baseboard_fab2(sch_1):m_k_bg(1)") )
				( objectStatus "M_K_BG" )
			)
			( bus "@baseboard_fab2_lib.baseboard_fab2(sch_1):m_k_c"
				( memberType ( signal ) )
				( member ( signalRef "@baseboard_fab2_lib.baseboard_fab2(sch_1):m_k_c(2)") )
				( objectStatus "M_K_C" )
			)
			( bus "@baseboard_fab2_lib.baseboard_fab2(sch_1):m_k_cke"
				( memberType ( signal ) )
				( member ( signalRef "@baseboard_fab2_lib.baseboard_fab2(sch_1):m_k_cke(0)") )
				( member ( signalRef "@baseboard_fab2_lib.baseboard_fab2(sch_1):m_k_cke(1)") )
				( member ( signalRef "@baseboard_fab2_lib.baseboard_fab2(sch_1):m_k_cke(2)") )
				( member ( signalRef "@baseboard_fab2_lib.baseboard_fab2(sch_1):m_k_cke(3)") )
				( objectStatus "M_K_CKE" )
			)
			( bus "@baseboard_fab2_lib.baseboard_fab2(sch_1):m_k_clk_dn"
				( memberType ( signal ) )
				( member ( signalRef "@baseboard_fab2_lib.baseboard_fab2(sch_1):m_k_clk_dn(0)") )
				( member ( signalRef "@baseboard_fab2_lib.baseboard_fab2(sch_1):m_k_clk_dn(1)") )
				( member ( signalRef "@baseboard_fab2_lib.baseboard_fab2(sch_1):m_k_clk_dn(2)") )
				( member ( signalRef "@baseboard_fab2_lib.baseboard_fab2(sch_1):m_k_clk_dn(3)") )
				( objectStatus "M_K_CLK_DN" )
			)
			( bus "@baseboard_fab2_lib.baseboard_fab2(sch_1):m_k_clk_dp"
				( memberType ( signal ) )
				( member ( signalRef "@baseboard_fab2_lib.baseboard_fab2(sch_1):m_k_clk_dp(0)") )
				( member ( signalRef "@baseboard_fab2_lib.baseboard_fab2(sch_1):m_k_clk_dp(1)") )
				( member ( signalRef "@baseboard_fab2_lib.baseboard_fab2(sch_1):m_k_clk_dp(2)") )
				( member ( signalRef "@baseboard_fab2_lib.baseboard_fab2(sch_1):m_k_clk_dp(3)") )
				( objectStatus "M_K_CLK_DP" )
			)
			( bus "@baseboard_fab2_lib.baseboard_fab2(sch_1):m_k_cs_n"
				( memberType ( signal ) )
				( member ( signalRef "@baseboard_fab2_lib.baseboard_fab2(sch_1):m_k_cs_n(0)") )
				( member ( signalRef "@baseboard_fab2_lib.baseboard_fab2(sch_1):m_k_cs_n(1)") )
				( member ( signalRef "@baseboard_fab2_lib.baseboard_fab2(sch_1):m_k_cs_n(2)") )
				( member ( signalRef "@baseboard_fab2_lib.baseboard_fab2(sch_1):m_k_cs_n(3)") )
				( member ( signalRef "@baseboard_fab2_lib.baseboard_fab2(sch_1):m_k_cs_n(4)") )
				( member ( signalRef "@baseboard_fab2_lib.baseboard_fab2(sch_1):m_k_cs_n(5)") )
				( member ( signalRef "@baseboard_fab2_lib.baseboard_fab2(sch_1):m_k_cs_n(6)") )
				( member ( signalRef "@baseboard_fab2_lib.baseboard_fab2(sch_1):m_k_cs_n(7)") )
				( objectStatus "M_K_CS_N" )
			)
			( bus "@baseboard_fab2_lib.baseboard_fab2(sch_1):m_k_dq"
				( memberType ( signal ) )
				( member ( signalRef "@baseboard_fab2_lib.baseboard_fab2(sch_1):m_k_dq(0)") )
				( member ( signalRef "@baseboard_fab2_lib.baseboard_fab2(sch_1):m_k_dq(1)") )
				( member ( signalRef "@baseboard_fab2_lib.baseboard_fab2(sch_1):m_k_dq(2)") )
				( member ( signalRef "@baseboard_fab2_lib.baseboard_fab2(sch_1):m_k_dq(3)") )
				( member ( signalRef "@baseboard_fab2_lib.baseboard_fab2(sch_1):m_k_dq(4)") )
				( member ( signalRef "@baseboard_fab2_lib.baseboard_fab2(sch_1):m_k_dq(5)") )
				( member ( signalRef "@baseboard_fab2_lib.baseboard_fab2(sch_1):m_k_dq(6)") )
				( member ( signalRef "@baseboard_fab2_lib.baseboard_fab2(sch_1):m_k_dq(7)") )
				( member ( signalRef "@baseboard_fab2_lib.baseboard_fab2(sch_1):m_k_dq(8)") )
				( member ( signalRef "@baseboard_fab2_lib.baseboard_fab2(sch_1):m_k_dq(9)") )
				( member ( signalRef "@baseboard_fab2_lib.baseboard_fab2(sch_1):m_k_dq(10)") )
				( member ( signalRef "@baseboard_fab2_lib.baseboard_fab2(sch_1):m_k_dq(11)") )
				( member ( signalRef "@baseboard_fab2_lib.baseboard_fab2(sch_1):m_k_dq(12)") )
				( member ( signalRef "@baseboard_fab2_lib.baseboard_fab2(sch_1):m_k_dq(13)") )
				( member ( signalRef "@baseboard_fab2_lib.baseboard_fab2(sch_1):m_k_dq(14)") )
				( member ( signalRef "@baseboard_fab2_lib.baseboard_fab2(sch_1):m_k_dq(15)") )
				( member ( signalRef "@baseboard_fab2_lib.baseboard_fab2(sch_1):m_k_dq(16)") )
				( member ( signalRef "@baseboard_fab2_lib.baseboard_fab2(sch_1):m_k_dq(17)") )
				( member ( signalRef "@baseboard_fab2_lib.baseboard_fab2(sch_1):m_k_dq(18)") )
				( member ( signalRef "@baseboard_fab2_lib.baseboard_fab2(sch_1):m_k_dq(19)") )
				( member ( signalRef "@baseboard_fab2_lib.baseboard_fab2(sch_1):m_k_dq(20)") )
				( member ( signalRef "@baseboard_fab2_lib.baseboard_fab2(sch_1):m_k_dq(21)") )
				( member ( signalRef "@baseboard_fab2_lib.baseboard_fab2(sch_1):m_k_dq(22)") )
				( member ( signalRef "@baseboard_fab2_lib.baseboard_fab2(sch_1):m_k_dq(23)") )
				( member ( signalRef "@baseboard_fab2_lib.baseboard_fab2(sch_1):m_k_dq(24)") )
				( member ( signalRef "@baseboard_fab2_lib.baseboard_fab2(sch_1):m_k_dq(25)") )
				( member ( signalRef "@baseboard_fab2_lib.baseboard_fab2(sch_1):m_k_dq(26)") )
				( member ( signalRef "@baseboard_fab2_lib.baseboard_fab2(sch_1):m_k_dq(27)") )
				( member ( signalRef "@baseboard_fab2_lib.baseboard_fab2(sch_1):m_k_dq(28)") )
				( member ( signalRef "@baseboard_fab2_lib.baseboard_fab2(sch_1):m_k_dq(29)") )
				( member ( signalRef "@baseboard_fab2_lib.baseboard_fab2(sch_1):m_k_dq(30)") )
				( member ( signalRef "@baseboard_fab2_lib.baseboard_fab2(sch_1):m_k_dq(31)") )
				( member ( signalRef "@baseboard_fab2_lib.baseboard_fab2(sch_1):m_k_dq(32)") )
				( member ( signalRef "@baseboard_fab2_lib.baseboard_fab2(sch_1):m_k_dq(33)") )
				( member ( signalRef "@baseboard_fab2_lib.baseboard_fab2(sch_1):m_k_dq(34)") )
				( member ( signalRef "@baseboard_fab2_lib.baseboard_fab2(sch_1):m_k_dq(35)") )
				( member ( signalRef "@baseboard_fab2_lib.baseboard_fab2(sch_1):m_k_dq(36)") )
				( member ( signalRef "@baseboard_fab2_lib.baseboard_fab2(sch_1):m_k_dq(37)") )
				( member ( signalRef "@baseboard_fab2_lib.baseboard_fab2(sch_1):m_k_dq(38)") )
				( member ( signalRef "@baseboard_fab2_lib.baseboard_fab2(sch_1):m_k_dq(39)") )
				( member ( signalRef "@baseboard_fab2_lib.baseboard_fab2(sch_1):m_k_dq(40)") )
				( member ( signalRef "@baseboard_fab2_lib.baseboard_fab2(sch_1):m_k_dq(41)") )
				( member ( signalRef "@baseboard_fab2_lib.baseboard_fab2(sch_1):m_k_dq(42)") )
				( member ( signalRef "@baseboard_fab2_lib.baseboard_fab2(sch_1):m_k_dq(43)") )
				( member ( signalRef "@baseboard_fab2_lib.baseboard_fab2(sch_1):m_k_dq(44)") )
				( member ( signalRef "@baseboard_fab2_lib.baseboard_fab2(sch_1):m_k_dq(45)") )
				( member ( signalRef "@baseboard_fab2_lib.baseboard_fab2(sch_1):m_k_dq(46)") )
				( member ( signalRef "@baseboard_fab2_lib.baseboard_fab2(sch_1):m_k_dq(47)") )
				( member ( signalRef "@baseboard_fab2_lib.baseboard_fab2(sch_1):m_k_dq(48)") )
				( member ( signalRef "@baseboard_fab2_lib.baseboard_fab2(sch_1):m_k_dq(49)") )
				( member ( signalRef "@baseboard_fab2_lib.baseboard_fab2(sch_1):m_k_dq(50)") )
				( member ( signalRef "@baseboard_fab2_lib.baseboard_fab2(sch_1):m_k_dq(51)") )
				( member ( signalRef "@baseboard_fab2_lib.baseboard_fab2(sch_1):m_k_dq(52)") )
				( member ( signalRef "@baseboard_fab2_lib.baseboard_fab2(sch_1):m_k_dq(53)") )
				( member ( signalRef "@baseboard_fab2_lib.baseboard_fab2(sch_1):m_k_dq(54)") )
				( member ( signalRef "@baseboard_fab2_lib.baseboard_fab2(sch_1):m_k_dq(55)") )
				( member ( signalRef "@baseboard_fab2_lib.baseboard_fab2(sch_1):m_k_dq(56)") )
				( member ( signalRef "@baseboard_fab2_lib.baseboard_fab2(sch_1):m_k_dq(57)") )
				( member ( signalRef "@baseboard_fab2_lib.baseboard_fab2(sch_1):m_k_dq(58)") )
				( member ( signalRef "@baseboard_fab2_lib.baseboard_fab2(sch_1):m_k_dq(59)") )
				( member ( signalRef "@baseboard_fab2_lib.baseboard_fab2(sch_1):m_k_dq(60)") )
				( member ( signalRef "@baseboard_fab2_lib.baseboard_fab2(sch_1):m_k_dq(61)") )
				( member ( signalRef "@baseboard_fab2_lib.baseboard_fab2(sch_1):m_k_dq(62)") )
				( member ( signalRef "@baseboard_fab2_lib.baseboard_fab2(sch_1):m_k_dq(63)") )
				( objectStatus "M_K_DQ" )
			)
			( bus "@baseboard_fab2_lib.baseboard_fab2(sch_1):m_k_dqs_dn"
				( memberType ( signal ) )
				( member ( signalRef "@baseboard_fab2_lib.baseboard_fab2(sch_1):m_k_dqs_dn(0)") )
				( member ( signalRef "@baseboard_fab2_lib.baseboard_fab2(sch_1):m_k_dqs_dn(1)") )
				( member ( signalRef "@baseboard_fab2_lib.baseboard_fab2(sch_1):m_k_dqs_dn(2)") )
				( member ( signalRef "@baseboard_fab2_lib.baseboard_fab2(sch_1):m_k_dqs_dn(3)") )
				( member ( signalRef "@baseboard_fab2_lib.baseboard_fab2(sch_1):m_k_dqs_dn(4)") )
				( member ( signalRef "@baseboard_fab2_lib.baseboard_fab2(sch_1):m_k_dqs_dn(5)") )
				( member ( signalRef "@baseboard_fab2_lib.baseboard_fab2(sch_1):m_k_dqs_dn(6)") )
				( member ( signalRef "@baseboard_fab2_lib.baseboard_fab2(sch_1):m_k_dqs_dn(7)") )
				( member ( signalRef "@baseboard_fab2_lib.baseboard_fab2(sch_1):m_k_dqs_dn(8)") )
				( member ( signalRef "@baseboard_fab2_lib.baseboard_fab2(sch_1):m_k_dqs_dn(9)") )
				( member ( signalRef "@baseboard_fab2_lib.baseboard_fab2(sch_1):m_k_dqs_dn(10)") )
				( member ( signalRef "@baseboard_fab2_lib.baseboard_fab2(sch_1):m_k_dqs_dn(11)") )
				( member ( signalRef "@baseboard_fab2_lib.baseboard_fab2(sch_1):m_k_dqs_dn(12)") )
				( member ( signalRef "@baseboard_fab2_lib.baseboard_fab2(sch_1):m_k_dqs_dn(13)") )
				( member ( signalRef "@baseboard_fab2_lib.baseboard_fab2(sch_1):m_k_dqs_dn(14)") )
				( member ( signalRef "@baseboard_fab2_lib.baseboard_fab2(sch_1):m_k_dqs_dn(15)") )
				( member ( signalRef "@baseboard_fab2_lib.baseboard_fab2(sch_1):m_k_dqs_dn(16)") )
				( member ( signalRef "@baseboard_fab2_lib.baseboard_fab2(sch_1):m_k_dqs_dn(17)") )
				( objectStatus "M_K_DQS_DN" )
			)
			( bus "@baseboard_fab2_lib.baseboard_fab2(sch_1):m_k_dqs_dp"
				( memberType ( signal ) )
				( member ( signalRef "@baseboard_fab2_lib.baseboard_fab2(sch_1):m_k_dqs_dp(0)") )
				( member ( signalRef "@baseboard_fab2_lib.baseboard_fab2(sch_1):m_k_dqs_dp(1)") )
				( member ( signalRef "@baseboard_fab2_lib.baseboard_fab2(sch_1):m_k_dqs_dp(2)") )
				( member ( signalRef "@baseboard_fab2_lib.baseboard_fab2(sch_1):m_k_dqs_dp(3)") )
				( member ( signalRef "@baseboard_fab2_lib.baseboard_fab2(sch_1):m_k_dqs_dp(4)") )
				( member ( signalRef "@baseboard_fab2_lib.baseboard_fab2(sch_1):m_k_dqs_dp(5)") )
				( member ( signalRef "@baseboard_fab2_lib.baseboard_fab2(sch_1):m_k_dqs_dp(6)") )
				( member ( signalRef "@baseboard_fab2_lib.baseboard_fab2(sch_1):m_k_dqs_dp(7)") )
				( member ( signalRef "@baseboard_fab2_lib.baseboard_fab2(sch_1):m_k_dqs_dp(8)") )
				( member ( signalRef "@baseboard_fab2_lib.baseboard_fab2(sch_1):m_k_dqs_dp(9)") )
				( member ( signalRef "@baseboard_fab2_lib.baseboard_fab2(sch_1):m_k_dqs_dp(10)") )
				( member ( signalRef "@baseboard_fab2_lib.baseboard_fab2(sch_1):m_k_dqs_dp(11)") )
				( member ( signalRef "@baseboard_fab2_lib.baseboard_fab2(sch_1):m_k_dqs_dp(12)") )
				( member ( signalRef "@baseboard_fab2_lib.baseboard_fab2(sch_1):m_k_dqs_dp(13)") )
				( member ( signalRef "@baseboard_fab2_lib.baseboard_fab2(sch_1):m_k_dqs_dp(14)") )
				( member ( signalRef "@baseboard_fab2_lib.baseboard_fab2(sch_1):m_k_dqs_dp(15)") )
				( member ( signalRef "@baseboard_fab2_lib.baseboard_fab2(sch_1):m_k_dqs_dp(16)") )
				( member ( signalRef "@baseboard_fab2_lib.baseboard_fab2(sch_1):m_k_dqs_dp(17)") )
				( objectStatus "M_K_DQS_DP" )
			)
			( bus "@baseboard_fab2_lib.baseboard_fab2(sch_1):m_k_ecc"
				( memberType ( signal ) )
				( member ( signalRef "@baseboard_fab2_lib.baseboard_fab2(sch_1):m_k_ecc(0)") )
				( member ( signalRef "@baseboard_fab2_lib.baseboard_fab2(sch_1):m_k_ecc(1)") )
				( member ( signalRef "@baseboard_fab2_lib.baseboard_fab2(sch_1):m_k_ecc(2)") )
				( member ( signalRef "@baseboard_fab2_lib.baseboard_fab2(sch_1):m_k_ecc(3)") )
				( member ( signalRef "@baseboard_fab2_lib.baseboard_fab2(sch_1):m_k_ecc(4)") )
				( member ( signalRef "@baseboard_fab2_lib.baseboard_fab2(sch_1):m_k_ecc(5)") )
				( member ( signalRef "@baseboard_fab2_lib.baseboard_fab2(sch_1):m_k_ecc(6)") )
				( member ( signalRef "@baseboard_fab2_lib.baseboard_fab2(sch_1):m_k_ecc(7)") )
				( objectStatus "M_K_ECC" )
			)
			( bus "@baseboard_fab2_lib.baseboard_fab2(sch_1):m_k_ma"
				( memberType ( signal ) )
				( member ( signalRef "@baseboard_fab2_lib.baseboard_fab2(sch_1):m_k_ma(0)") )
				( member ( signalRef "@baseboard_fab2_lib.baseboard_fab2(sch_1):m_k_ma(1)") )
				( member ( signalRef "@baseboard_fab2_lib.baseboard_fab2(sch_1):m_k_ma(2)") )
				( member ( signalRef "@baseboard_fab2_lib.baseboard_fab2(sch_1):m_k_ma(3)") )
				( member ( signalRef "@baseboard_fab2_lib.baseboard_fab2(sch_1):m_k_ma(4)") )
				( member ( signalRef "@baseboard_fab2_lib.baseboard_fab2(sch_1):m_k_ma(5)") )
				( member ( signalRef "@baseboard_fab2_lib.baseboard_fab2(sch_1):m_k_ma(6)") )
				( member ( signalRef "@baseboard_fab2_lib.baseboard_fab2(sch_1):m_k_ma(7)") )
				( member ( signalRef "@baseboard_fab2_lib.baseboard_fab2(sch_1):m_k_ma(8)") )
				( member ( signalRef "@baseboard_fab2_lib.baseboard_fab2(sch_1):m_k_ma(9)") )
				( member ( signalRef "@baseboard_fab2_lib.baseboard_fab2(sch_1):m_k_ma(10)") )
				( member ( signalRef "@baseboard_fab2_lib.baseboard_fab2(sch_1):m_k_ma(11)") )
				( member ( signalRef "@baseboard_fab2_lib.baseboard_fab2(sch_1):m_k_ma(12)") )
				( member ( signalRef "@baseboard_fab2_lib.baseboard_fab2(sch_1):m_k_ma(13)") )
				( member ( signalRef "@baseboard_fab2_lib.baseboard_fab2(sch_1):m_k_ma(14)") )
				( member ( signalRef "@baseboard_fab2_lib.baseboard_fab2(sch_1):m_k_ma(15)") )
				( member ( signalRef "@baseboard_fab2_lib.baseboard_fab2(sch_1):m_k_ma(16)") )
				( member ( signalRef "@baseboard_fab2_lib.baseboard_fab2(sch_1):m_k_ma(17)") )
				( objectStatus "M_K_MA" )
			)
			( bus "@baseboard_fab2_lib.baseboard_fab2(sch_1):m_k_odt"
				( memberType ( signal ) )
				( member ( signalRef "@baseboard_fab2_lib.baseboard_fab2(sch_1):m_k_odt(0)") )
				( member ( signalRef "@baseboard_fab2_lib.baseboard_fab2(sch_1):m_k_odt(1)") )
				( member ( signalRef "@baseboard_fab2_lib.baseboard_fab2(sch_1):m_k_odt(2)") )
				( member ( signalRef "@baseboard_fab2_lib.baseboard_fab2(sch_1):m_k_odt(3)") )
				( objectStatus "M_K_ODT" )
			)
			( bus "@baseboard_fab2_lib.baseboard_fab2(sch_1):m_l_ba"
				( memberType ( signal ) )
				( member ( signalRef "@baseboard_fab2_lib.baseboard_fab2(sch_1):m_l_ba(0)") )
				( member ( signalRef "@baseboard_fab2_lib.baseboard_fab2(sch_1):m_l_ba(1)") )
				( objectStatus "M_L_BA" )
			)
			( bus "@baseboard_fab2_lib.baseboard_fab2(sch_1):m_l_bg"
				( memberType ( signal ) )
				( member ( signalRef "@baseboard_fab2_lib.baseboard_fab2(sch_1):m_l_bg(0)") )
				( member ( signalRef "@baseboard_fab2_lib.baseboard_fab2(sch_1):m_l_bg(1)") )
				( objectStatus "M_L_BG" )
			)
			( bus "@baseboard_fab2_lib.baseboard_fab2(sch_1):m_l_c"
				( memberType ( signal ) )
				( member ( signalRef "@baseboard_fab2_lib.baseboard_fab2(sch_1):m_l_c(2)") )
				( objectStatus "M_L_C" )
			)
			( bus "@baseboard_fab2_lib.baseboard_fab2(sch_1):m_l_cke"
				( memberType ( signal ) )
				( member ( signalRef "@baseboard_fab2_lib.baseboard_fab2(sch_1):m_l_cke(0)") )
				( member ( signalRef "@baseboard_fab2_lib.baseboard_fab2(sch_1):m_l_cke(1)") )
				( member ( signalRef "@baseboard_fab2_lib.baseboard_fab2(sch_1):m_l_cke(2)") )
				( member ( signalRef "@baseboard_fab2_lib.baseboard_fab2(sch_1):m_l_cke(3)") )
				( objectStatus "M_L_CKE" )
			)
			( bus "@baseboard_fab2_lib.baseboard_fab2(sch_1):m_l_clk_dn"
				( memberType ( signal ) )
				( member ( signalRef "@baseboard_fab2_lib.baseboard_fab2(sch_1):m_l_clk_dn(0)") )
				( member ( signalRef "@baseboard_fab2_lib.baseboard_fab2(sch_1):m_l_clk_dn(1)") )
				( member ( signalRef "@baseboard_fab2_lib.baseboard_fab2(sch_1):m_l_clk_dn(2)") )
				( member ( signalRef "@baseboard_fab2_lib.baseboard_fab2(sch_1):m_l_clk_dn(3)") )
				( objectStatus "M_L_CLK_DN" )
			)
			( bus "@baseboard_fab2_lib.baseboard_fab2(sch_1):m_l_clk_dp"
				( memberType ( signal ) )
				( member ( signalRef "@baseboard_fab2_lib.baseboard_fab2(sch_1):m_l_clk_dp(0)") )
				( member ( signalRef "@baseboard_fab2_lib.baseboard_fab2(sch_1):m_l_clk_dp(1)") )
				( member ( signalRef "@baseboard_fab2_lib.baseboard_fab2(sch_1):m_l_clk_dp(2)") )
				( member ( signalRef "@baseboard_fab2_lib.baseboard_fab2(sch_1):m_l_clk_dp(3)") )
				( objectStatus "M_L_CLK_DP" )
			)
			( bus "@baseboard_fab2_lib.baseboard_fab2(sch_1):m_l_cs_n"
				( memberType ( signal ) )
				( member ( signalRef "@baseboard_fab2_lib.baseboard_fab2(sch_1):m_l_cs_n(0)") )
				( member ( signalRef "@baseboard_fab2_lib.baseboard_fab2(sch_1):m_l_cs_n(1)") )
				( member ( signalRef "@baseboard_fab2_lib.baseboard_fab2(sch_1):m_l_cs_n(2)") )
				( member ( signalRef "@baseboard_fab2_lib.baseboard_fab2(sch_1):m_l_cs_n(3)") )
				( member ( signalRef "@baseboard_fab2_lib.baseboard_fab2(sch_1):m_l_cs_n(4)") )
				( member ( signalRef "@baseboard_fab2_lib.baseboard_fab2(sch_1):m_l_cs_n(5)") )
				( member ( signalRef "@baseboard_fab2_lib.baseboard_fab2(sch_1):m_l_cs_n(6)") )
				( member ( signalRef "@baseboard_fab2_lib.baseboard_fab2(sch_1):m_l_cs_n(7)") )
				( objectStatus "M_L_CS_N" )
			)
			( bus "@baseboard_fab2_lib.baseboard_fab2(sch_1):m_l_dq"
				( memberType ( signal ) )
				( member ( signalRef "@baseboard_fab2_lib.baseboard_fab2(sch_1):m_l_dq(0)") )
				( member ( signalRef "@baseboard_fab2_lib.baseboard_fab2(sch_1):m_l_dq(1)") )
				( member ( signalRef "@baseboard_fab2_lib.baseboard_fab2(sch_1):m_l_dq(2)") )
				( member ( signalRef "@baseboard_fab2_lib.baseboard_fab2(sch_1):m_l_dq(3)") )
				( member ( signalRef "@baseboard_fab2_lib.baseboard_fab2(sch_1):m_l_dq(4)") )
				( member ( signalRef "@baseboard_fab2_lib.baseboard_fab2(sch_1):m_l_dq(5)") )
				( member ( signalRef "@baseboard_fab2_lib.baseboard_fab2(sch_1):m_l_dq(6)") )
				( member ( signalRef "@baseboard_fab2_lib.baseboard_fab2(sch_1):m_l_dq(7)") )
				( member ( signalRef "@baseboard_fab2_lib.baseboard_fab2(sch_1):m_l_dq(8)") )
				( member ( signalRef "@baseboard_fab2_lib.baseboard_fab2(sch_1):m_l_dq(9)") )
				( member ( signalRef "@baseboard_fab2_lib.baseboard_fab2(sch_1):m_l_dq(10)") )
				( member ( signalRef "@baseboard_fab2_lib.baseboard_fab2(sch_1):m_l_dq(11)") )
				( member ( signalRef "@baseboard_fab2_lib.baseboard_fab2(sch_1):m_l_dq(12)") )
				( member ( signalRef "@baseboard_fab2_lib.baseboard_fab2(sch_1):m_l_dq(13)") )
				( member ( signalRef "@baseboard_fab2_lib.baseboard_fab2(sch_1):m_l_dq(14)") )
				( member ( signalRef "@baseboard_fab2_lib.baseboard_fab2(sch_1):m_l_dq(15)") )
				( member ( signalRef "@baseboard_fab2_lib.baseboard_fab2(sch_1):m_l_dq(16)") )
				( member ( signalRef "@baseboard_fab2_lib.baseboard_fab2(sch_1):m_l_dq(17)") )
				( member ( signalRef "@baseboard_fab2_lib.baseboard_fab2(sch_1):m_l_dq(18)") )
				( member ( signalRef "@baseboard_fab2_lib.baseboard_fab2(sch_1):m_l_dq(19)") )
				( member ( signalRef "@baseboard_fab2_lib.baseboard_fab2(sch_1):m_l_dq(20)") )
				( member ( signalRef "@baseboard_fab2_lib.baseboard_fab2(sch_1):m_l_dq(21)") )
				( member ( signalRef "@baseboard_fab2_lib.baseboard_fab2(sch_1):m_l_dq(22)") )
				( member ( signalRef "@baseboard_fab2_lib.baseboard_fab2(sch_1):m_l_dq(23)") )
				( member ( signalRef "@baseboard_fab2_lib.baseboard_fab2(sch_1):m_l_dq(24)") )
				( member ( signalRef "@baseboard_fab2_lib.baseboard_fab2(sch_1):m_l_dq(25)") )
				( member ( signalRef "@baseboard_fab2_lib.baseboard_fab2(sch_1):m_l_dq(26)") )
				( member ( signalRef "@baseboard_fab2_lib.baseboard_fab2(sch_1):m_l_dq(27)") )
				( member ( signalRef "@baseboard_fab2_lib.baseboard_fab2(sch_1):m_l_dq(28)") )
				( member ( signalRef "@baseboard_fab2_lib.baseboard_fab2(sch_1):m_l_dq(29)") )
				( member ( signalRef "@baseboard_fab2_lib.baseboard_fab2(sch_1):m_l_dq(30)") )
				( member ( signalRef "@baseboard_fab2_lib.baseboard_fab2(sch_1):m_l_dq(31)") )
				( member ( signalRef "@baseboard_fab2_lib.baseboard_fab2(sch_1):m_l_dq(32)") )
				( member ( signalRef "@baseboard_fab2_lib.baseboard_fab2(sch_1):m_l_dq(33)") )
				( member ( signalRef "@baseboard_fab2_lib.baseboard_fab2(sch_1):m_l_dq(34)") )
				( member ( signalRef "@baseboard_fab2_lib.baseboard_fab2(sch_1):m_l_dq(35)") )
				( member ( signalRef "@baseboard_fab2_lib.baseboard_fab2(sch_1):m_l_dq(36)") )
				( member ( signalRef "@baseboard_fab2_lib.baseboard_fab2(sch_1):m_l_dq(37)") )
				( member ( signalRef "@baseboard_fab2_lib.baseboard_fab2(sch_1):m_l_dq(38)") )
				( member ( signalRef "@baseboard_fab2_lib.baseboard_fab2(sch_1):m_l_dq(39)") )
				( member ( signalRef "@baseboard_fab2_lib.baseboard_fab2(sch_1):m_l_dq(40)") )
				( member ( signalRef "@baseboard_fab2_lib.baseboard_fab2(sch_1):m_l_dq(41)") )
				( member ( signalRef "@baseboard_fab2_lib.baseboard_fab2(sch_1):m_l_dq(42)") )
				( member ( signalRef "@baseboard_fab2_lib.baseboard_fab2(sch_1):m_l_dq(43)") )
				( member ( signalRef "@baseboard_fab2_lib.baseboard_fab2(sch_1):m_l_dq(44)") )
				( member ( signalRef "@baseboard_fab2_lib.baseboard_fab2(sch_1):m_l_dq(45)") )
				( member ( signalRef "@baseboard_fab2_lib.baseboard_fab2(sch_1):m_l_dq(46)") )
				( member ( signalRef "@baseboard_fab2_lib.baseboard_fab2(sch_1):m_l_dq(47)") )
				( member ( signalRef "@baseboard_fab2_lib.baseboard_fab2(sch_1):m_l_dq(48)") )
				( member ( signalRef "@baseboard_fab2_lib.baseboard_fab2(sch_1):m_l_dq(49)") )
				( member ( signalRef "@baseboard_fab2_lib.baseboard_fab2(sch_1):m_l_dq(50)") )
				( member ( signalRef "@baseboard_fab2_lib.baseboard_fab2(sch_1):m_l_dq(51)") )
				( member ( signalRef "@baseboard_fab2_lib.baseboard_fab2(sch_1):m_l_dq(52)") )
				( member ( signalRef "@baseboard_fab2_lib.baseboard_fab2(sch_1):m_l_dq(53)") )
				( member ( signalRef "@baseboard_fab2_lib.baseboard_fab2(sch_1):m_l_dq(54)") )
				( member ( signalRef "@baseboard_fab2_lib.baseboard_fab2(sch_1):m_l_dq(55)") )
				( member ( signalRef "@baseboard_fab2_lib.baseboard_fab2(sch_1):m_l_dq(56)") )
				( member ( signalRef "@baseboard_fab2_lib.baseboard_fab2(sch_1):m_l_dq(57)") )
				( member ( signalRef "@baseboard_fab2_lib.baseboard_fab2(sch_1):m_l_dq(58)") )
				( member ( signalRef "@baseboard_fab2_lib.baseboard_fab2(sch_1):m_l_dq(59)") )
				( member ( signalRef "@baseboard_fab2_lib.baseboard_fab2(sch_1):m_l_dq(60)") )
				( member ( signalRef "@baseboard_fab2_lib.baseboard_fab2(sch_1):m_l_dq(61)") )
				( member ( signalRef "@baseboard_fab2_lib.baseboard_fab2(sch_1):m_l_dq(62)") )
				( member ( signalRef "@baseboard_fab2_lib.baseboard_fab2(sch_1):m_l_dq(63)") )
				( objectStatus "M_L_DQ" )
			)
			( bus "@baseboard_fab2_lib.baseboard_fab2(sch_1):m_l_dqs_dn"
				( memberType ( signal ) )
				( member ( signalRef "@baseboard_fab2_lib.baseboard_fab2(sch_1):m_l_dqs_dn(0)") )
				( member ( signalRef "@baseboard_fab2_lib.baseboard_fab2(sch_1):m_l_dqs_dn(1)") )
				( member ( signalRef "@baseboard_fab2_lib.baseboard_fab2(sch_1):m_l_dqs_dn(2)") )
				( member ( signalRef "@baseboard_fab2_lib.baseboard_fab2(sch_1):m_l_dqs_dn(3)") )
				( member ( signalRef "@baseboard_fab2_lib.baseboard_fab2(sch_1):m_l_dqs_dn(4)") )
				( member ( signalRef "@baseboard_fab2_lib.baseboard_fab2(sch_1):m_l_dqs_dn(5)") )
				( member ( signalRef "@baseboard_fab2_lib.baseboard_fab2(sch_1):m_l_dqs_dn(6)") )
				( member ( signalRef "@baseboard_fab2_lib.baseboard_fab2(sch_1):m_l_dqs_dn(7)") )
				( member ( signalRef "@baseboard_fab2_lib.baseboard_fab2(sch_1):m_l_dqs_dn(8)") )
				( member ( signalRef "@baseboard_fab2_lib.baseboard_fab2(sch_1):m_l_dqs_dn(9)") )
				( member ( signalRef "@baseboard_fab2_lib.baseboard_fab2(sch_1):m_l_dqs_dn(10)") )
				( member ( signalRef "@baseboard_fab2_lib.baseboard_fab2(sch_1):m_l_dqs_dn(11)") )
				( member ( signalRef "@baseboard_fab2_lib.baseboard_fab2(sch_1):m_l_dqs_dn(12)") )
				( member ( signalRef "@baseboard_fab2_lib.baseboard_fab2(sch_1):m_l_dqs_dn(13)") )
				( member ( signalRef "@baseboard_fab2_lib.baseboard_fab2(sch_1):m_l_dqs_dn(14)") )
				( member ( signalRef "@baseboard_fab2_lib.baseboard_fab2(sch_1):m_l_dqs_dn(15)") )
				( member ( signalRef "@baseboard_fab2_lib.baseboard_fab2(sch_1):m_l_dqs_dn(16)") )
				( member ( signalRef "@baseboard_fab2_lib.baseboard_fab2(sch_1):m_l_dqs_dn(17)") )
				( objectStatus "M_L_DQS_DN" )
			)
			( bus "@baseboard_fab2_lib.baseboard_fab2(sch_1):m_l_dqs_dp"
				( memberType ( signal ) )
				( member ( signalRef "@baseboard_fab2_lib.baseboard_fab2(sch_1):m_l_dqs_dp(0)") )
				( member ( signalRef "@baseboard_fab2_lib.baseboard_fab2(sch_1):m_l_dqs_dp(1)") )
				( member ( signalRef "@baseboard_fab2_lib.baseboard_fab2(sch_1):m_l_dqs_dp(2)") )
				( member ( signalRef "@baseboard_fab2_lib.baseboard_fab2(sch_1):m_l_dqs_dp(3)") )
				( member ( signalRef "@baseboard_fab2_lib.baseboard_fab2(sch_1):m_l_dqs_dp(4)") )
				( member ( signalRef "@baseboard_fab2_lib.baseboard_fab2(sch_1):m_l_dqs_dp(5)") )
				( member ( signalRef "@baseboard_fab2_lib.baseboard_fab2(sch_1):m_l_dqs_dp(6)") )
				( member ( signalRef "@baseboard_fab2_lib.baseboard_fab2(sch_1):m_l_dqs_dp(7)") )
				( member ( signalRef "@baseboard_fab2_lib.baseboard_fab2(sch_1):m_l_dqs_dp(8)") )
				( member ( signalRef "@baseboard_fab2_lib.baseboard_fab2(sch_1):m_l_dqs_dp(9)") )
				( member ( signalRef "@baseboard_fab2_lib.baseboard_fab2(sch_1):m_l_dqs_dp(10)") )
				( member ( signalRef "@baseboard_fab2_lib.baseboard_fab2(sch_1):m_l_dqs_dp(11)") )
				( member ( signalRef "@baseboard_fab2_lib.baseboard_fab2(sch_1):m_l_dqs_dp(12)") )
				( member ( signalRef "@baseboard_fab2_lib.baseboard_fab2(sch_1):m_l_dqs_dp(13)") )
				( member ( signalRef "@baseboard_fab2_lib.baseboard_fab2(sch_1):m_l_dqs_dp(14)") )
				( member ( signalRef "@baseboard_fab2_lib.baseboard_fab2(sch_1):m_l_dqs_dp(15)") )
				( member ( signalRef "@baseboard_fab2_lib.baseboard_fab2(sch_1):m_l_dqs_dp(16)") )
				( member ( signalRef "@baseboard_fab2_lib.baseboard_fab2(sch_1):m_l_dqs_dp(17)") )
				( objectStatus "M_L_DQS_DP" )
			)
			( bus "@baseboard_fab2_lib.baseboard_fab2(sch_1):m_l_ecc"
				( memberType ( signal ) )
				( member ( signalRef "@baseboard_fab2_lib.baseboard_fab2(sch_1):m_l_ecc(0)") )
				( member ( signalRef "@baseboard_fab2_lib.baseboard_fab2(sch_1):m_l_ecc(1)") )
				( member ( signalRef "@baseboard_fab2_lib.baseboard_fab2(sch_1):m_l_ecc(2)") )
				( member ( signalRef "@baseboard_fab2_lib.baseboard_fab2(sch_1):m_l_ecc(3)") )
				( member ( signalRef "@baseboard_fab2_lib.baseboard_fab2(sch_1):m_l_ecc(4)") )
				( member ( signalRef "@baseboard_fab2_lib.baseboard_fab2(sch_1):m_l_ecc(5)") )
				( member ( signalRef "@baseboard_fab2_lib.baseboard_fab2(sch_1):m_l_ecc(6)") )
				( member ( signalRef "@baseboard_fab2_lib.baseboard_fab2(sch_1):m_l_ecc(7)") )
				( objectStatus "M_L_ECC" )
			)
			( bus "@baseboard_fab2_lib.baseboard_fab2(sch_1):m_l_ma"
				( memberType ( signal ) )
				( member ( signalRef "@baseboard_fab2_lib.baseboard_fab2(sch_1):m_l_ma(0)") )
				( member ( signalRef "@baseboard_fab2_lib.baseboard_fab2(sch_1):m_l_ma(1)") )
				( member ( signalRef "@baseboard_fab2_lib.baseboard_fab2(sch_1):m_l_ma(2)") )
				( member ( signalRef "@baseboard_fab2_lib.baseboard_fab2(sch_1):m_l_ma(3)") )
				( member ( signalRef "@baseboard_fab2_lib.baseboard_fab2(sch_1):m_l_ma(4)") )
				( member ( signalRef "@baseboard_fab2_lib.baseboard_fab2(sch_1):m_l_ma(5)") )
				( member ( signalRef "@baseboard_fab2_lib.baseboard_fab2(sch_1):m_l_ma(6)") )
				( member ( signalRef "@baseboard_fab2_lib.baseboard_fab2(sch_1):m_l_ma(7)") )
				( member ( signalRef "@baseboard_fab2_lib.baseboard_fab2(sch_1):m_l_ma(8)") )
				( member ( signalRef "@baseboard_fab2_lib.baseboard_fab2(sch_1):m_l_ma(9)") )
				( member ( signalRef "@baseboard_fab2_lib.baseboard_fab2(sch_1):m_l_ma(10)") )
				( member ( signalRef "@baseboard_fab2_lib.baseboard_fab2(sch_1):m_l_ma(11)") )
				( member ( signalRef "@baseboard_fab2_lib.baseboard_fab2(sch_1):m_l_ma(12)") )
				( member ( signalRef "@baseboard_fab2_lib.baseboard_fab2(sch_1):m_l_ma(13)") )
				( member ( signalRef "@baseboard_fab2_lib.baseboard_fab2(sch_1):m_l_ma(14)") )
				( member ( signalRef "@baseboard_fab2_lib.baseboard_fab2(sch_1):m_l_ma(15)") )
				( member ( signalRef "@baseboard_fab2_lib.baseboard_fab2(sch_1):m_l_ma(16)") )
				( member ( signalRef "@baseboard_fab2_lib.baseboard_fab2(sch_1):m_l_ma(17)") )
				( objectStatus "M_L_MA" )
			)
			( bus "@baseboard_fab2_lib.baseboard_fab2(sch_1):m_l_odt"
				( memberType ( signal ) )
				( member ( signalRef "@baseboard_fab2_lib.baseboard_fab2(sch_1):m_l_odt(0)") )
				( member ( signalRef "@baseboard_fab2_lib.baseboard_fab2(sch_1):m_l_odt(1)") )
				( member ( signalRef "@baseboard_fab2_lib.baseboard_fab2(sch_1):m_l_odt(2)") )
				( member ( signalRef "@baseboard_fab2_lib.baseboard_fab2(sch_1):m_l_odt(3)") )
				( objectStatus "M_L_ODT" )
			)
			( bus "@baseboard_fab2_lib.baseboard_fab2(sch_1):m_m_ba"
				( memberType ( signal ) )
				( member ( signalRef "@baseboard_fab2_lib.baseboard_fab2(sch_1):m_m_ba(0)") )
				( member ( signalRef "@baseboard_fab2_lib.baseboard_fab2(sch_1):m_m_ba(1)") )
				( objectStatus "M_M_BA" )
			)
			( bus "@baseboard_fab2_lib.baseboard_fab2(sch_1):m_m_bg"
				( memberType ( signal ) )
				( member ( signalRef "@baseboard_fab2_lib.baseboard_fab2(sch_1):m_m_bg(0)") )
				( member ( signalRef "@baseboard_fab2_lib.baseboard_fab2(sch_1):m_m_bg(1)") )
				( objectStatus "M_M_BG" )
			)
			( bus "@baseboard_fab2_lib.baseboard_fab2(sch_1):m_m_c"
				( memberType ( signal ) )
				( member ( signalRef "@baseboard_fab2_lib.baseboard_fab2(sch_1):m_m_c(2)") )
				( objectStatus "M_M_C" )
			)
			( bus "@baseboard_fab2_lib.baseboard_fab2(sch_1):m_m_cke"
				( memberType ( signal ) )
				( member ( signalRef "@baseboard_fab2_lib.baseboard_fab2(sch_1):m_m_cke(0)") )
				( member ( signalRef "@baseboard_fab2_lib.baseboard_fab2(sch_1):m_m_cke(1)") )
				( member ( signalRef "@baseboard_fab2_lib.baseboard_fab2(sch_1):m_m_cke(2)") )
				( member ( signalRef "@baseboard_fab2_lib.baseboard_fab2(sch_1):m_m_cke(3)") )
				( objectStatus "M_M_CKE" )
			)
			( bus "@baseboard_fab2_lib.baseboard_fab2(sch_1):m_m_clk_dn"
				( memberType ( signal ) )
				( member ( signalRef "@baseboard_fab2_lib.baseboard_fab2(sch_1):m_m_clk_dn(0)") )
				( member ( signalRef "@baseboard_fab2_lib.baseboard_fab2(sch_1):m_m_clk_dn(1)") )
				( member ( signalRef "@baseboard_fab2_lib.baseboard_fab2(sch_1):m_m_clk_dn(2)") )
				( member ( signalRef "@baseboard_fab2_lib.baseboard_fab2(sch_1):m_m_clk_dn(3)") )
				( objectStatus "M_M_CLK_DN" )
			)
			( bus "@baseboard_fab2_lib.baseboard_fab2(sch_1):m_m_clk_dp"
				( memberType ( signal ) )
				( member ( signalRef "@baseboard_fab2_lib.baseboard_fab2(sch_1):m_m_clk_dp(0)") )
				( member ( signalRef "@baseboard_fab2_lib.baseboard_fab2(sch_1):m_m_clk_dp(1)") )
				( member ( signalRef "@baseboard_fab2_lib.baseboard_fab2(sch_1):m_m_clk_dp(2)") )
				( member ( signalRef "@baseboard_fab2_lib.baseboard_fab2(sch_1):m_m_clk_dp(3)") )
				( objectStatus "M_M_CLK_DP" )
			)
			( bus "@baseboard_fab2_lib.baseboard_fab2(sch_1):m_m_cs_n"
				( memberType ( signal ) )
				( member ( signalRef "@baseboard_fab2_lib.baseboard_fab2(sch_1):m_m_cs_n(0)") )
				( member ( signalRef "@baseboard_fab2_lib.baseboard_fab2(sch_1):m_m_cs_n(1)") )
				( member ( signalRef "@baseboard_fab2_lib.baseboard_fab2(sch_1):m_m_cs_n(2)") )
				( member ( signalRef "@baseboard_fab2_lib.baseboard_fab2(sch_1):m_m_cs_n(3)") )
				( member ( signalRef "@baseboard_fab2_lib.baseboard_fab2(sch_1):m_m_cs_n(4)") )
				( member ( signalRef "@baseboard_fab2_lib.baseboard_fab2(sch_1):m_m_cs_n(5)") )
				( member ( signalRef "@baseboard_fab2_lib.baseboard_fab2(sch_1):m_m_cs_n(6)") )
				( member ( signalRef "@baseboard_fab2_lib.baseboard_fab2(sch_1):m_m_cs_n(7)") )
				( objectStatus "M_M_CS_N" )
			)
			( bus "@baseboard_fab2_lib.baseboard_fab2(sch_1):m_m_dq"
				( memberType ( signal ) )
				( member ( signalRef "@baseboard_fab2_lib.baseboard_fab2(sch_1):m_m_dq(0)") )
				( member ( signalRef "@baseboard_fab2_lib.baseboard_fab2(sch_1):m_m_dq(1)") )
				( member ( signalRef "@baseboard_fab2_lib.baseboard_fab2(sch_1):m_m_dq(2)") )
				( member ( signalRef "@baseboard_fab2_lib.baseboard_fab2(sch_1):m_m_dq(3)") )
				( member ( signalRef "@baseboard_fab2_lib.baseboard_fab2(sch_1):m_m_dq(4)") )
				( member ( signalRef "@baseboard_fab2_lib.baseboard_fab2(sch_1):m_m_dq(5)") )
				( member ( signalRef "@baseboard_fab2_lib.baseboard_fab2(sch_1):m_m_dq(6)") )
				( member ( signalRef "@baseboard_fab2_lib.baseboard_fab2(sch_1):m_m_dq(7)") )
				( member ( signalRef "@baseboard_fab2_lib.baseboard_fab2(sch_1):m_m_dq(8)") )
				( member ( signalRef "@baseboard_fab2_lib.baseboard_fab2(sch_1):m_m_dq(9)") )
				( member ( signalRef "@baseboard_fab2_lib.baseboard_fab2(sch_1):m_m_dq(10)") )
				( member ( signalRef "@baseboard_fab2_lib.baseboard_fab2(sch_1):m_m_dq(11)") )
				( member ( signalRef "@baseboard_fab2_lib.baseboard_fab2(sch_1):m_m_dq(12)") )
				( member ( signalRef "@baseboard_fab2_lib.baseboard_fab2(sch_1):m_m_dq(13)") )
				( member ( signalRef "@baseboard_fab2_lib.baseboard_fab2(sch_1):m_m_dq(14)") )
				( member ( signalRef "@baseboard_fab2_lib.baseboard_fab2(sch_1):m_m_dq(15)") )
				( member ( signalRef "@baseboard_fab2_lib.baseboard_fab2(sch_1):m_m_dq(16)") )
				( member ( signalRef "@baseboard_fab2_lib.baseboard_fab2(sch_1):m_m_dq(17)") )
				( member ( signalRef "@baseboard_fab2_lib.baseboard_fab2(sch_1):m_m_dq(18)") )
				( member ( signalRef "@baseboard_fab2_lib.baseboard_fab2(sch_1):m_m_dq(19)") )
				( member ( signalRef "@baseboard_fab2_lib.baseboard_fab2(sch_1):m_m_dq(20)") )
				( member ( signalRef "@baseboard_fab2_lib.baseboard_fab2(sch_1):m_m_dq(21)") )
				( member ( signalRef "@baseboard_fab2_lib.baseboard_fab2(sch_1):m_m_dq(22)") )
				( member ( signalRef "@baseboard_fab2_lib.baseboard_fab2(sch_1):m_m_dq(23)") )
				( member ( signalRef "@baseboard_fab2_lib.baseboard_fab2(sch_1):m_m_dq(24)") )
				( member ( signalRef "@baseboard_fab2_lib.baseboard_fab2(sch_1):m_m_dq(25)") )
				( member ( signalRef "@baseboard_fab2_lib.baseboard_fab2(sch_1):m_m_dq(26)") )
				( member ( signalRef "@baseboard_fab2_lib.baseboard_fab2(sch_1):m_m_dq(27)") )
				( member ( signalRef "@baseboard_fab2_lib.baseboard_fab2(sch_1):m_m_dq(28)") )
				( member ( signalRef "@baseboard_fab2_lib.baseboard_fab2(sch_1):m_m_dq(29)") )
				( member ( signalRef "@baseboard_fab2_lib.baseboard_fab2(sch_1):m_m_dq(30)") )
				( member ( signalRef "@baseboard_fab2_lib.baseboard_fab2(sch_1):m_m_dq(31)") )
				( member ( signalRef "@baseboard_fab2_lib.baseboard_fab2(sch_1):m_m_dq(32)") )
				( member ( signalRef "@baseboard_fab2_lib.baseboard_fab2(sch_1):m_m_dq(33)") )
				( member ( signalRef "@baseboard_fab2_lib.baseboard_fab2(sch_1):m_m_dq(34)") )
				( member ( signalRef "@baseboard_fab2_lib.baseboard_fab2(sch_1):m_m_dq(35)") )
				( member ( signalRef "@baseboard_fab2_lib.baseboard_fab2(sch_1):m_m_dq(36)") )
				( member ( signalRef "@baseboard_fab2_lib.baseboard_fab2(sch_1):m_m_dq(37)") )
				( member ( signalRef "@baseboard_fab2_lib.baseboard_fab2(sch_1):m_m_dq(38)") )
				( member ( signalRef "@baseboard_fab2_lib.baseboard_fab2(sch_1):m_m_dq(39)") )
				( member ( signalRef "@baseboard_fab2_lib.baseboard_fab2(sch_1):m_m_dq(40)") )
				( member ( signalRef "@baseboard_fab2_lib.baseboard_fab2(sch_1):m_m_dq(41)") )
				( member ( signalRef "@baseboard_fab2_lib.baseboard_fab2(sch_1):m_m_dq(42)") )
				( member ( signalRef "@baseboard_fab2_lib.baseboard_fab2(sch_1):m_m_dq(43)") )
				( member ( signalRef "@baseboard_fab2_lib.baseboard_fab2(sch_1):m_m_dq(44)") )
				( member ( signalRef "@baseboard_fab2_lib.baseboard_fab2(sch_1):m_m_dq(45)") )
				( member ( signalRef "@baseboard_fab2_lib.baseboard_fab2(sch_1):m_m_dq(46)") )
				( member ( signalRef "@baseboard_fab2_lib.baseboard_fab2(sch_1):m_m_dq(47)") )
				( member ( signalRef "@baseboard_fab2_lib.baseboard_fab2(sch_1):m_m_dq(48)") )
				( member ( signalRef "@baseboard_fab2_lib.baseboard_fab2(sch_1):m_m_dq(49)") )
				( member ( signalRef "@baseboard_fab2_lib.baseboard_fab2(sch_1):m_m_dq(50)") )
				( member ( signalRef "@baseboard_fab2_lib.baseboard_fab2(sch_1):m_m_dq(51)") )
				( member ( signalRef "@baseboard_fab2_lib.baseboard_fab2(sch_1):m_m_dq(52)") )
				( member ( signalRef "@baseboard_fab2_lib.baseboard_fab2(sch_1):m_m_dq(53)") )
				( member ( signalRef "@baseboard_fab2_lib.baseboard_fab2(sch_1):m_m_dq(54)") )
				( member ( signalRef "@baseboard_fab2_lib.baseboard_fab2(sch_1):m_m_dq(55)") )
				( member ( signalRef "@baseboard_fab2_lib.baseboard_fab2(sch_1):m_m_dq(56)") )
				( member ( signalRef "@baseboard_fab2_lib.baseboard_fab2(sch_1):m_m_dq(57)") )
				( member ( signalRef "@baseboard_fab2_lib.baseboard_fab2(sch_1):m_m_dq(58)") )
				( member ( signalRef "@baseboard_fab2_lib.baseboard_fab2(sch_1):m_m_dq(59)") )
				( member ( signalRef "@baseboard_fab2_lib.baseboard_fab2(sch_1):m_m_dq(60)") )
				( member ( signalRef "@baseboard_fab2_lib.baseboard_fab2(sch_1):m_m_dq(61)") )
				( member ( signalRef "@baseboard_fab2_lib.baseboard_fab2(sch_1):m_m_dq(62)") )
				( member ( signalRef "@baseboard_fab2_lib.baseboard_fab2(sch_1):m_m_dq(63)") )
				( objectStatus "M_M_DQ" )
			)
			( bus "@baseboard_fab2_lib.baseboard_fab2(sch_1):m_m_dqs_dn"
				( memberType ( signal ) )
				( member ( signalRef "@baseboard_fab2_lib.baseboard_fab2(sch_1):m_m_dqs_dn(0)") )
				( member ( signalRef "@baseboard_fab2_lib.baseboard_fab2(sch_1):m_m_dqs_dn(1)") )
				( member ( signalRef "@baseboard_fab2_lib.baseboard_fab2(sch_1):m_m_dqs_dn(2)") )
				( member ( signalRef "@baseboard_fab2_lib.baseboard_fab2(sch_1):m_m_dqs_dn(3)") )
				( member ( signalRef "@baseboard_fab2_lib.baseboard_fab2(sch_1):m_m_dqs_dn(4)") )
				( member ( signalRef "@baseboard_fab2_lib.baseboard_fab2(sch_1):m_m_dqs_dn(5)") )
				( member ( signalRef "@baseboard_fab2_lib.baseboard_fab2(sch_1):m_m_dqs_dn(6)") )
				( member ( signalRef "@baseboard_fab2_lib.baseboard_fab2(sch_1):m_m_dqs_dn(7)") )
				( member ( signalRef "@baseboard_fab2_lib.baseboard_fab2(sch_1):m_m_dqs_dn(8)") )
				( member ( signalRef "@baseboard_fab2_lib.baseboard_fab2(sch_1):m_m_dqs_dn(9)") )
				( member ( signalRef "@baseboard_fab2_lib.baseboard_fab2(sch_1):m_m_dqs_dn(10)") )
				( member ( signalRef "@baseboard_fab2_lib.baseboard_fab2(sch_1):m_m_dqs_dn(11)") )
				( member ( signalRef "@baseboard_fab2_lib.baseboard_fab2(sch_1):m_m_dqs_dn(12)") )
				( member ( signalRef "@baseboard_fab2_lib.baseboard_fab2(sch_1):m_m_dqs_dn(13)") )
				( member ( signalRef "@baseboard_fab2_lib.baseboard_fab2(sch_1):m_m_dqs_dn(14)") )
				( member ( signalRef "@baseboard_fab2_lib.baseboard_fab2(sch_1):m_m_dqs_dn(15)") )
				( member ( signalRef "@baseboard_fab2_lib.baseboard_fab2(sch_1):m_m_dqs_dn(16)") )
				( member ( signalRef "@baseboard_fab2_lib.baseboard_fab2(sch_1):m_m_dqs_dn(17)") )
				( objectStatus "M_M_DQS_DN" )
			)
			( bus "@baseboard_fab2_lib.baseboard_fab2(sch_1):m_m_dqs_dp"
				( memberType ( signal ) )
				( member ( signalRef "@baseboard_fab2_lib.baseboard_fab2(sch_1):m_m_dqs_dp(0)") )
				( member ( signalRef "@baseboard_fab2_lib.baseboard_fab2(sch_1):m_m_dqs_dp(1)") )
				( member ( signalRef "@baseboard_fab2_lib.baseboard_fab2(sch_1):m_m_dqs_dp(2)") )
				( member ( signalRef "@baseboard_fab2_lib.baseboard_fab2(sch_1):m_m_dqs_dp(3)") )
				( member ( signalRef "@baseboard_fab2_lib.baseboard_fab2(sch_1):m_m_dqs_dp(4)") )
				( member ( signalRef "@baseboard_fab2_lib.baseboard_fab2(sch_1):m_m_dqs_dp(5)") )
				( member ( signalRef "@baseboard_fab2_lib.baseboard_fab2(sch_1):m_m_dqs_dp(6)") )
				( member ( signalRef "@baseboard_fab2_lib.baseboard_fab2(sch_1):m_m_dqs_dp(7)") )
				( member ( signalRef "@baseboard_fab2_lib.baseboard_fab2(sch_1):m_m_dqs_dp(8)") )
				( member ( signalRef "@baseboard_fab2_lib.baseboard_fab2(sch_1):m_m_dqs_dp(9)") )
				( member ( signalRef "@baseboard_fab2_lib.baseboard_fab2(sch_1):m_m_dqs_dp(10)") )
				( member ( signalRef "@baseboard_fab2_lib.baseboard_fab2(sch_1):m_m_dqs_dp(11)") )
				( member ( signalRef "@baseboard_fab2_lib.baseboard_fab2(sch_1):m_m_dqs_dp(12)") )
				( member ( signalRef "@baseboard_fab2_lib.baseboard_fab2(sch_1):m_m_dqs_dp(13)") )
				( member ( signalRef "@baseboard_fab2_lib.baseboard_fab2(sch_1):m_m_dqs_dp(14)") )
				( member ( signalRef "@baseboard_fab2_lib.baseboard_fab2(sch_1):m_m_dqs_dp(15)") )
				( member ( signalRef "@baseboard_fab2_lib.baseboard_fab2(sch_1):m_m_dqs_dp(16)") )
				( member ( signalRef "@baseboard_fab2_lib.baseboard_fab2(sch_1):m_m_dqs_dp(17)") )
				( objectStatus "M_M_DQS_DP" )
			)
			( bus "@baseboard_fab2_lib.baseboard_fab2(sch_1):m_m_ecc"
				( memberType ( signal ) )
				( member ( signalRef "@baseboard_fab2_lib.baseboard_fab2(sch_1):m_m_ecc(0)") )
				( member ( signalRef "@baseboard_fab2_lib.baseboard_fab2(sch_1):m_m_ecc(1)") )
				( member ( signalRef "@baseboard_fab2_lib.baseboard_fab2(sch_1):m_m_ecc(2)") )
				( member ( signalRef "@baseboard_fab2_lib.baseboard_fab2(sch_1):m_m_ecc(3)") )
				( member ( signalRef "@baseboard_fab2_lib.baseboard_fab2(sch_1):m_m_ecc(4)") )
				( member ( signalRef "@baseboard_fab2_lib.baseboard_fab2(sch_1):m_m_ecc(5)") )
				( member ( signalRef "@baseboard_fab2_lib.baseboard_fab2(sch_1):m_m_ecc(6)") )
				( member ( signalRef "@baseboard_fab2_lib.baseboard_fab2(sch_1):m_m_ecc(7)") )
				( objectStatus "M_M_ECC" )
			)
			( bus "@baseboard_fab2_lib.baseboard_fab2(sch_1):m_m_ma"
				( memberType ( signal ) )
				( member ( signalRef "@baseboard_fab2_lib.baseboard_fab2(sch_1):m_m_ma(0)") )
				( member ( signalRef "@baseboard_fab2_lib.baseboard_fab2(sch_1):m_m_ma(1)") )
				( member ( signalRef "@baseboard_fab2_lib.baseboard_fab2(sch_1):m_m_ma(2)") )
				( member ( signalRef "@baseboard_fab2_lib.baseboard_fab2(sch_1):m_m_ma(3)") )
				( member ( signalRef "@baseboard_fab2_lib.baseboard_fab2(sch_1):m_m_ma(4)") )
				( member ( signalRef "@baseboard_fab2_lib.baseboard_fab2(sch_1):m_m_ma(5)") )
				( member ( signalRef "@baseboard_fab2_lib.baseboard_fab2(sch_1):m_m_ma(6)") )
				( member ( signalRef "@baseboard_fab2_lib.baseboard_fab2(sch_1):m_m_ma(7)") )
				( member ( signalRef "@baseboard_fab2_lib.baseboard_fab2(sch_1):m_m_ma(8)") )
				( member ( signalRef "@baseboard_fab2_lib.baseboard_fab2(sch_1):m_m_ma(9)") )
				( member ( signalRef "@baseboard_fab2_lib.baseboard_fab2(sch_1):m_m_ma(10)") )
				( member ( signalRef "@baseboard_fab2_lib.baseboard_fab2(sch_1):m_m_ma(11)") )
				( member ( signalRef "@baseboard_fab2_lib.baseboard_fab2(sch_1):m_m_ma(12)") )
				( member ( signalRef "@baseboard_fab2_lib.baseboard_fab2(sch_1):m_m_ma(13)") )
				( member ( signalRef "@baseboard_fab2_lib.baseboard_fab2(sch_1):m_m_ma(14)") )
				( member ( signalRef "@baseboard_fab2_lib.baseboard_fab2(sch_1):m_m_ma(15)") )
				( member ( signalRef "@baseboard_fab2_lib.baseboard_fab2(sch_1):m_m_ma(16)") )
				( member ( signalRef "@baseboard_fab2_lib.baseboard_fab2(sch_1):m_m_ma(17)") )
				( objectStatus "M_M_MA" )
			)
			( bus "@baseboard_fab2_lib.baseboard_fab2(sch_1):m_m_odt"
				( memberType ( signal ) )
				( member ( signalRef "@baseboard_fab2_lib.baseboard_fab2(sch_1):m_m_odt(0)") )
				( member ( signalRef "@baseboard_fab2_lib.baseboard_fab2(sch_1):m_m_odt(1)") )
				( member ( signalRef "@baseboard_fab2_lib.baseboard_fab2(sch_1):m_m_odt(2)") )
				( member ( signalRef "@baseboard_fab2_lib.baseboard_fab2(sch_1):m_m_odt(3)") )
				( objectStatus "M_M_ODT" )
			)
			( bus "@baseboard_fab2_lib.baseboard_fab2(sch_1):tp_p3e_cpu1_pe1_mp_rxn"
				( memberType ( signal ) )
				( member ( signalRef "@baseboard_fab2_lib.baseboard_fab2(sch_1):tp_p3e_cpu1_pe1_mp_rxn(0)") )
				( member ( signalRef "@baseboard_fab2_lib.baseboard_fab2(sch_1):tp_p3e_cpu1_pe1_mp_rxn(1)") )
				( member ( signalRef "@baseboard_fab2_lib.baseboard_fab2(sch_1):tp_p3e_cpu1_pe1_mp_rxn(2)") )
				( member ( signalRef "@baseboard_fab2_lib.baseboard_fab2(sch_1):tp_p3e_cpu1_pe1_mp_rxn(3)") )
				( member ( signalRef "@baseboard_fab2_lib.baseboard_fab2(sch_1):tp_p3e_cpu1_pe1_mp_rxn(4)") )
				( member ( signalRef "@baseboard_fab2_lib.baseboard_fab2(sch_1):tp_p3e_cpu1_pe1_mp_rxn(5)") )
				( member ( signalRef "@baseboard_fab2_lib.baseboard_fab2(sch_1):tp_p3e_cpu1_pe1_mp_rxn(6)") )
				( member ( signalRef "@baseboard_fab2_lib.baseboard_fab2(sch_1):tp_p3e_cpu1_pe1_mp_rxn(7)") )
				( objectStatus "TP_P3E_CPU1_PE1_MP_RXN" )
			)
			( bus "@baseboard_fab2_lib.baseboard_fab2(sch_1):tp_p3e_cpu1_pe1_mp_rxp"
				( memberType ( signal ) )
				( member ( signalRef "@baseboard_fab2_lib.baseboard_fab2(sch_1):tp_p3e_cpu1_pe1_mp_rxp(0)") )
				( member ( signalRef "@baseboard_fab2_lib.baseboard_fab2(sch_1):tp_p3e_cpu1_pe1_mp_rxp(1)") )
				( member ( signalRef "@baseboard_fab2_lib.baseboard_fab2(sch_1):tp_p3e_cpu1_pe1_mp_rxp(2)") )
				( member ( signalRef "@baseboard_fab2_lib.baseboard_fab2(sch_1):tp_p3e_cpu1_pe1_mp_rxp(3)") )
				( member ( signalRef "@baseboard_fab2_lib.baseboard_fab2(sch_1):tp_p3e_cpu1_pe1_mp_rxp(4)") )
				( member ( signalRef "@baseboard_fab2_lib.baseboard_fab2(sch_1):tp_p3e_cpu1_pe1_mp_rxp(5)") )
				( member ( signalRef "@baseboard_fab2_lib.baseboard_fab2(sch_1):tp_p3e_cpu1_pe1_mp_rxp(6)") )
				( member ( signalRef "@baseboard_fab2_lib.baseboard_fab2(sch_1):tp_p3e_cpu1_pe1_mp_rxp(7)") )
				( objectStatus "TP_P3E_CPU1_PE1_MP_RXP" )
			)
			( bus "@baseboard_fab2_lib.baseboard_fab2(sch_1):tp_p3e_cpu1_pe1_mp_txn"
				( memberType ( signal ) )
				( member ( signalRef "@baseboard_fab2_lib.baseboard_fab2(sch_1):tp_p3e_cpu1_pe1_mp_txn(0)") )
				( member ( signalRef "@baseboard_fab2_lib.baseboard_fab2(sch_1):tp_p3e_cpu1_pe1_mp_txn(1)") )
				( member ( signalRef "@baseboard_fab2_lib.baseboard_fab2(sch_1):tp_p3e_cpu1_pe1_mp_txn(2)") )
				( member ( signalRef "@baseboard_fab2_lib.baseboard_fab2(sch_1):tp_p3e_cpu1_pe1_mp_txn(3)") )
				( member ( signalRef "@baseboard_fab2_lib.baseboard_fab2(sch_1):tp_p3e_cpu1_pe1_mp_txn(4)") )
				( member ( signalRef "@baseboard_fab2_lib.baseboard_fab2(sch_1):tp_p3e_cpu1_pe1_mp_txn(5)") )
				( member ( signalRef "@baseboard_fab2_lib.baseboard_fab2(sch_1):tp_p3e_cpu1_pe1_mp_txn(6)") )
				( member ( signalRef "@baseboard_fab2_lib.baseboard_fab2(sch_1):tp_p3e_cpu1_pe1_mp_txn(7)") )
				( objectStatus "TP_P3E_CPU1_PE1_MP_TXN" )
			)
			( bus "@baseboard_fab2_lib.baseboard_fab2(sch_1):tp_p3e_cpu1_pe1_mp_txp"
				( memberType ( signal ) )
				( member ( signalRef "@baseboard_fab2_lib.baseboard_fab2(sch_1):tp_p3e_cpu1_pe1_mp_txp(0)") )
				( member ( signalRef "@baseboard_fab2_lib.baseboard_fab2(sch_1):tp_p3e_cpu1_pe1_mp_txp(1)") )
				( member ( signalRef "@baseboard_fab2_lib.baseboard_fab2(sch_1):tp_p3e_cpu1_pe1_mp_txp(2)") )
				( member ( signalRef "@baseboard_fab2_lib.baseboard_fab2(sch_1):tp_p3e_cpu1_pe1_mp_txp(3)") )
				( member ( signalRef "@baseboard_fab2_lib.baseboard_fab2(sch_1):tp_p3e_cpu1_pe1_mp_txp(4)") )
				( member ( signalRef "@baseboard_fab2_lib.baseboard_fab2(sch_1):tp_p3e_cpu1_pe1_mp_txp(5)") )
				( member ( signalRef "@baseboard_fab2_lib.baseboard_fab2(sch_1):tp_p3e_cpu1_pe1_mp_txp(6)") )
				( member ( signalRef "@baseboard_fab2_lib.baseboard_fab2(sch_1):tp_p3e_cpu1_pe1_mp_txp(7)") )
				( objectStatus "TP_P3E_CPU1_PE1_MP_TXP" )
			)
			( bus "@baseboard_fab2_lib.baseboard_fab2(sch_1):tp_p3e_cpu1_pe1_rsr3_rxn"
				( memberType ( signal ) )
				( member ( signalRef "@baseboard_fab2_lib.baseboard_fab2(sch_1):tp_p3e_cpu1_pe1_rsr3_rxn(8)") )
				( member ( signalRef "@baseboard_fab2_lib.baseboard_fab2(sch_1):tp_p3e_cpu1_pe1_rsr3_rxn(9)") )
				( member ( signalRef "@baseboard_fab2_lib.baseboard_fab2(sch_1):tp_p3e_cpu1_pe1_rsr3_rxn(10)") )
				( member ( signalRef "@baseboard_fab2_lib.baseboard_fab2(sch_1):tp_p3e_cpu1_pe1_rsr3_rxn(11)") )
				( member ( signalRef "@baseboard_fab2_lib.baseboard_fab2(sch_1):tp_p3e_cpu1_pe1_rsr3_rxn(12)") )
				( member ( signalRef "@baseboard_fab2_lib.baseboard_fab2(sch_1):tp_p3e_cpu1_pe1_rsr3_rxn(13)") )
				( member ( signalRef "@baseboard_fab2_lib.baseboard_fab2(sch_1):tp_p3e_cpu1_pe1_rsr3_rxn(14)") )
				( member ( signalRef "@baseboard_fab2_lib.baseboard_fab2(sch_1):tp_p3e_cpu1_pe1_rsr3_rxn(15)") )
				( objectStatus "TP_P3E_CPU1_PE1_RSR3_RXN" )
			)
			( bus "@baseboard_fab2_lib.baseboard_fab2(sch_1):tp_p3e_cpu1_pe1_rsr3_rxp"
				( memberType ( signal ) )
				( member ( signalRef "@baseboard_fab2_lib.baseboard_fab2(sch_1):tp_p3e_cpu1_pe1_rsr3_rxp(8)") )
				( member ( signalRef "@baseboard_fab2_lib.baseboard_fab2(sch_1):tp_p3e_cpu1_pe1_rsr3_rxp(9)") )
				( member ( signalRef "@baseboard_fab2_lib.baseboard_fab2(sch_1):tp_p3e_cpu1_pe1_rsr3_rxp(10)") )
				( member ( signalRef "@baseboard_fab2_lib.baseboard_fab2(sch_1):tp_p3e_cpu1_pe1_rsr3_rxp(11)") )
				( member ( signalRef "@baseboard_fab2_lib.baseboard_fab2(sch_1):tp_p3e_cpu1_pe1_rsr3_rxp(12)") )
				( member ( signalRef "@baseboard_fab2_lib.baseboard_fab2(sch_1):tp_p3e_cpu1_pe1_rsr3_rxp(13)") )
				( member ( signalRef "@baseboard_fab2_lib.baseboard_fab2(sch_1):tp_p3e_cpu1_pe1_rsr3_rxp(14)") )
				( member ( signalRef "@baseboard_fab2_lib.baseboard_fab2(sch_1):tp_p3e_cpu1_pe1_rsr3_rxp(15)") )
				( objectStatus "TP_P3E_CPU1_PE1_RSR3_RXP" )
			)
			( bus "@baseboard_fab2_lib.baseboard_fab2(sch_1):tp_p3e_cpu1_pe1_rsr3_txn"
				( memberType ( signal ) )
				( member ( signalRef "@baseboard_fab2_lib.baseboard_fab2(sch_1):tp_p3e_cpu1_pe1_rsr3_txn(8)") )
				( member ( signalRef "@baseboard_fab2_lib.baseboard_fab2(sch_1):tp_p3e_cpu1_pe1_rsr3_txn(9)") )
				( member ( signalRef "@baseboard_fab2_lib.baseboard_fab2(sch_1):tp_p3e_cpu1_pe1_rsr3_txn(10)") )
				( member ( signalRef "@baseboard_fab2_lib.baseboard_fab2(sch_1):tp_p3e_cpu1_pe1_rsr3_txn(11)") )
				( member ( signalRef "@baseboard_fab2_lib.baseboard_fab2(sch_1):tp_p3e_cpu1_pe1_rsr3_txn(12)") )
				( member ( signalRef "@baseboard_fab2_lib.baseboard_fab2(sch_1):tp_p3e_cpu1_pe1_rsr3_txn(13)") )
				( member ( signalRef "@baseboard_fab2_lib.baseboard_fab2(sch_1):tp_p3e_cpu1_pe1_rsr3_txn(14)") )
				( member ( signalRef "@baseboard_fab2_lib.baseboard_fab2(sch_1):tp_p3e_cpu1_pe1_rsr3_txn(15)") )
				( objectStatus "TP_P3E_CPU1_PE1_RSR3_TXN" )
			)
			( bus "@baseboard_fab2_lib.baseboard_fab2(sch_1):tp_p3e_cpu1_pe1_rsr3_txp"
				( memberType ( signal ) )
				( member ( signalRef "@baseboard_fab2_lib.baseboard_fab2(sch_1):tp_p3e_cpu1_pe1_rsr3_txp(8)") )
				( member ( signalRef "@baseboard_fab2_lib.baseboard_fab2(sch_1):tp_p3e_cpu1_pe1_rsr3_txp(9)") )
				( member ( signalRef "@baseboard_fab2_lib.baseboard_fab2(sch_1):tp_p3e_cpu1_pe1_rsr3_txp(10)") )
				( member ( signalRef "@baseboard_fab2_lib.baseboard_fab2(sch_1):tp_p3e_cpu1_pe1_rsr3_txp(11)") )
				( member ( signalRef "@baseboard_fab2_lib.baseboard_fab2(sch_1):tp_p3e_cpu1_pe1_rsr3_txp(12)") )
				( member ( signalRef "@baseboard_fab2_lib.baseboard_fab2(sch_1):tp_p3e_cpu1_pe1_rsr3_txp(13)") )
				( member ( signalRef "@baseboard_fab2_lib.baseboard_fab2(sch_1):tp_p3e_cpu1_pe1_rsr3_txp(14)") )
				( member ( signalRef "@baseboard_fab2_lib.baseboard_fab2(sch_1):tp_p3e_cpu1_pe1_rsr3_txp(15)") )
				( objectStatus "TP_P3E_CPU1_PE1_RSR3_TXP" )
			)
			( bus "@baseboard_fab2_lib.baseboard_fab2(sch_1):tp_p3e_cpu1_pe2_rsr_rxn"
				( memberType ( signal ) )
				( member ( signalRef "@baseboard_fab2_lib.baseboard_fab2(sch_1):tp_p3e_cpu1_pe2_rsr_rxn(0)") )
				( member ( signalRef "@baseboard_fab2_lib.baseboard_fab2(sch_1):tp_p3e_cpu1_pe2_rsr_rxn(1)") )
				( member ( signalRef "@baseboard_fab2_lib.baseboard_fab2(sch_1):tp_p3e_cpu1_pe2_rsr_rxn(2)") )
				( member ( signalRef "@baseboard_fab2_lib.baseboard_fab2(sch_1):tp_p3e_cpu1_pe2_rsr_rxn(3)") )
				( member ( signalRef "@baseboard_fab2_lib.baseboard_fab2(sch_1):tp_p3e_cpu1_pe2_rsr_rxn(4)") )
				( member ( signalRef "@baseboard_fab2_lib.baseboard_fab2(sch_1):tp_p3e_cpu1_pe2_rsr_rxn(5)") )
				( member ( signalRef "@baseboard_fab2_lib.baseboard_fab2(sch_1):tp_p3e_cpu1_pe2_rsr_rxn(6)") )
				( member ( signalRef "@baseboard_fab2_lib.baseboard_fab2(sch_1):tp_p3e_cpu1_pe2_rsr_rxn(7)") )
				( member ( signalRef "@baseboard_fab2_lib.baseboard_fab2(sch_1):tp_p3e_cpu1_pe2_rsr_rxn(8)") )
				( member ( signalRef "@baseboard_fab2_lib.baseboard_fab2(sch_1):tp_p3e_cpu1_pe2_rsr_rxn(9)") )
				( member ( signalRef "@baseboard_fab2_lib.baseboard_fab2(sch_1):tp_p3e_cpu1_pe2_rsr_rxn(10)") )
				( member ( signalRef "@baseboard_fab2_lib.baseboard_fab2(sch_1):tp_p3e_cpu1_pe2_rsr_rxn(11)") )
				( member ( signalRef "@baseboard_fab2_lib.baseboard_fab2(sch_1):tp_p3e_cpu1_pe2_rsr_rxn(12)") )
				( member ( signalRef "@baseboard_fab2_lib.baseboard_fab2(sch_1):tp_p3e_cpu1_pe2_rsr_rxn(13)") )
				( member ( signalRef "@baseboard_fab2_lib.baseboard_fab2(sch_1):tp_p3e_cpu1_pe2_rsr_rxn(14)") )
				( member ( signalRef "@baseboard_fab2_lib.baseboard_fab2(sch_1):tp_p3e_cpu1_pe2_rsr_rxn(15)") )
				( objectStatus "TP_P3E_CPU1_PE2_RSR_RXN" )
			)
			( bus "@baseboard_fab2_lib.baseboard_fab2(sch_1):tp_p3e_cpu1_pe2_rsr_rxp"
				( memberType ( signal ) )
				( member ( signalRef "@baseboard_fab2_lib.baseboard_fab2(sch_1):tp_p3e_cpu1_pe2_rsr_rxp(0)") )
				( member ( signalRef "@baseboard_fab2_lib.baseboard_fab2(sch_1):tp_p3e_cpu1_pe2_rsr_rxp(1)") )
				( member ( signalRef "@baseboard_fab2_lib.baseboard_fab2(sch_1):tp_p3e_cpu1_pe2_rsr_rxp(2)") )
				( member ( signalRef "@baseboard_fab2_lib.baseboard_fab2(sch_1):tp_p3e_cpu1_pe2_rsr_rxp(3)") )
				( member ( signalRef "@baseboard_fab2_lib.baseboard_fab2(sch_1):tp_p3e_cpu1_pe2_rsr_rxp(4)") )
				( member ( signalRef "@baseboard_fab2_lib.baseboard_fab2(sch_1):tp_p3e_cpu1_pe2_rsr_rxp(5)") )
				( member ( signalRef "@baseboard_fab2_lib.baseboard_fab2(sch_1):tp_p3e_cpu1_pe2_rsr_rxp(6)") )
				( member ( signalRef "@baseboard_fab2_lib.baseboard_fab2(sch_1):tp_p3e_cpu1_pe2_rsr_rxp(7)") )
				( member ( signalRef "@baseboard_fab2_lib.baseboard_fab2(sch_1):tp_p3e_cpu1_pe2_rsr_rxp(8)") )
				( member ( signalRef "@baseboard_fab2_lib.baseboard_fab2(sch_1):tp_p3e_cpu1_pe2_rsr_rxp(9)") )
				( member ( signalRef "@baseboard_fab2_lib.baseboard_fab2(sch_1):tp_p3e_cpu1_pe2_rsr_rxp(10)") )
				( member ( signalRef "@baseboard_fab2_lib.baseboard_fab2(sch_1):tp_p3e_cpu1_pe2_rsr_rxp(11)") )
				( member ( signalRef "@baseboard_fab2_lib.baseboard_fab2(sch_1):tp_p3e_cpu1_pe2_rsr_rxp(12)") )
				( member ( signalRef "@baseboard_fab2_lib.baseboard_fab2(sch_1):tp_p3e_cpu1_pe2_rsr_rxp(13)") )
				( member ( signalRef "@baseboard_fab2_lib.baseboard_fab2(sch_1):tp_p3e_cpu1_pe2_rsr_rxp(14)") )
				( member ( signalRef "@baseboard_fab2_lib.baseboard_fab2(sch_1):tp_p3e_cpu1_pe2_rsr_rxp(15)") )
				( objectStatus "TP_P3E_CPU1_PE2_RSR_RXP" )
			)
			( bus "@baseboard_fab2_lib.baseboard_fab2(sch_1):tp_p3e_cpu1_pe2_rsr_txn"
				( memberType ( signal ) )
				( member ( signalRef "@baseboard_fab2_lib.baseboard_fab2(sch_1):tp_p3e_cpu1_pe2_rsr_txn(0)") )
				( member ( signalRef "@baseboard_fab2_lib.baseboard_fab2(sch_1):tp_p3e_cpu1_pe2_rsr_txn(1)") )
				( member ( signalRef "@baseboard_fab2_lib.baseboard_fab2(sch_1):tp_p3e_cpu1_pe2_rsr_txn(2)") )
				( member ( signalRef "@baseboard_fab2_lib.baseboard_fab2(sch_1):tp_p3e_cpu1_pe2_rsr_txn(3)") )
				( member ( signalRef "@baseboard_fab2_lib.baseboard_fab2(sch_1):tp_p3e_cpu1_pe2_rsr_txn(4)") )
				( member ( signalRef "@baseboard_fab2_lib.baseboard_fab2(sch_1):tp_p3e_cpu1_pe2_rsr_txn(5)") )
				( member ( signalRef "@baseboard_fab2_lib.baseboard_fab2(sch_1):tp_p3e_cpu1_pe2_rsr_txn(6)") )
				( member ( signalRef "@baseboard_fab2_lib.baseboard_fab2(sch_1):tp_p3e_cpu1_pe2_rsr_txn(7)") )
				( member ( signalRef "@baseboard_fab2_lib.baseboard_fab2(sch_1):tp_p3e_cpu1_pe2_rsr_txn(8)") )
				( member ( signalRef "@baseboard_fab2_lib.baseboard_fab2(sch_1):tp_p3e_cpu1_pe2_rsr_txn(9)") )
				( member ( signalRef "@baseboard_fab2_lib.baseboard_fab2(sch_1):tp_p3e_cpu1_pe2_rsr_txn(10)") )
				( member ( signalRef "@baseboard_fab2_lib.baseboard_fab2(sch_1):tp_p3e_cpu1_pe2_rsr_txn(11)") )
				( member ( signalRef "@baseboard_fab2_lib.baseboard_fab2(sch_1):tp_p3e_cpu1_pe2_rsr_txn(12)") )
				( member ( signalRef "@baseboard_fab2_lib.baseboard_fab2(sch_1):tp_p3e_cpu1_pe2_rsr_txn(13)") )
				( member ( signalRef "@baseboard_fab2_lib.baseboard_fab2(sch_1):tp_p3e_cpu1_pe2_rsr_txn(14)") )
				( member ( signalRef "@baseboard_fab2_lib.baseboard_fab2(sch_1):tp_p3e_cpu1_pe2_rsr_txn(15)") )
				( objectStatus "TP_P3E_CPU1_PE2_RSR_TXN" )
			)
			( bus "@baseboard_fab2_lib.baseboard_fab2(sch_1):tp_p3e_cpu1_pe2_rsr_txp"
				( memberType ( signal ) )
				( member ( signalRef "@baseboard_fab2_lib.baseboard_fab2(sch_1):tp_p3e_cpu1_pe2_rsr_txp(0)") )
				( member ( signalRef "@baseboard_fab2_lib.baseboard_fab2(sch_1):tp_p3e_cpu1_pe2_rsr_txp(1)") )
				( member ( signalRef "@baseboard_fab2_lib.baseboard_fab2(sch_1):tp_p3e_cpu1_pe2_rsr_txp(2)") )
				( member ( signalRef "@baseboard_fab2_lib.baseboard_fab2(sch_1):tp_p3e_cpu1_pe2_rsr_txp(3)") )
				( member ( signalRef "@baseboard_fab2_lib.baseboard_fab2(sch_1):tp_p3e_cpu1_pe2_rsr_txp(4)") )
				( member ( signalRef "@baseboard_fab2_lib.baseboard_fab2(sch_1):tp_p3e_cpu1_pe2_rsr_txp(5)") )
				( member ( signalRef "@baseboard_fab2_lib.baseboard_fab2(sch_1):tp_p3e_cpu1_pe2_rsr_txp(6)") )
				( member ( signalRef "@baseboard_fab2_lib.baseboard_fab2(sch_1):tp_p3e_cpu1_pe2_rsr_txp(7)") )
				( member ( signalRef "@baseboard_fab2_lib.baseboard_fab2(sch_1):tp_p3e_cpu1_pe2_rsr_txp(8)") )
				( member ( signalRef "@baseboard_fab2_lib.baseboard_fab2(sch_1):tp_p3e_cpu1_pe2_rsr_txp(9)") )
				( member ( signalRef "@baseboard_fab2_lib.baseboard_fab2(sch_1):tp_p3e_cpu1_pe2_rsr_txp(10)") )
				( member ( signalRef "@baseboard_fab2_lib.baseboard_fab2(sch_1):tp_p3e_cpu1_pe2_rsr_txp(11)") )
				( member ( signalRef "@baseboard_fab2_lib.baseboard_fab2(sch_1):tp_p3e_cpu1_pe2_rsr_txp(12)") )
				( member ( signalRef "@baseboard_fab2_lib.baseboard_fab2(sch_1):tp_p3e_cpu1_pe2_rsr_txp(13)") )
				( member ( signalRef "@baseboard_fab2_lib.baseboard_fab2(sch_1):tp_p3e_cpu1_pe2_rsr_txp(14)") )
				( member ( signalRef "@baseboard_fab2_lib.baseboard_fab2(sch_1):tp_p3e_cpu1_pe2_rsr_txp(15)") )
				( objectStatus "TP_P3E_CPU1_PE2_RSR_TXP" )
			)
			( bus "@baseboard_fab2_lib.baseboard_fab2(sch_1):p3e_cpu1_pe3_mp_rxn"
				( memberType ( signal ) )
				( member ( signalRef "@baseboard_fab2_lib.baseboard_fab2(sch_1):p3e_cpu1_pe3_mp_rxn(0)") )
				( member ( signalRef "@baseboard_fab2_lib.baseboard_fab2(sch_1):p3e_cpu1_pe3_mp_rxn(1)") )
				( member ( signalRef "@baseboard_fab2_lib.baseboard_fab2(sch_1):p3e_cpu1_pe3_mp_rxn(2)") )
				( member ( signalRef "@baseboard_fab2_lib.baseboard_fab2(sch_1):p3e_cpu1_pe3_mp_rxn(3)") )
				( member ( signalRef "@baseboard_fab2_lib.baseboard_fab2(sch_1):p3e_cpu1_pe3_mp_rxn(4)") )
				( member ( signalRef "@baseboard_fab2_lib.baseboard_fab2(sch_1):p3e_cpu1_pe3_mp_rxn(5)") )
				( member ( signalRef "@baseboard_fab2_lib.baseboard_fab2(sch_1):p3e_cpu1_pe3_mp_rxn(6)") )
				( member ( signalRef "@baseboard_fab2_lib.baseboard_fab2(sch_1):p3e_cpu1_pe3_mp_rxn(7)") )
				( member ( signalRef "@baseboard_fab2_lib.baseboard_fab2(sch_1):p3e_cpu1_pe3_mp_rxn(8)") )
				( member ( signalRef "@baseboard_fab2_lib.baseboard_fab2(sch_1):p3e_cpu1_pe3_mp_rxn(9)") )
				( member ( signalRef "@baseboard_fab2_lib.baseboard_fab2(sch_1):p3e_cpu1_pe3_mp_rxn(10)") )
				( member ( signalRef "@baseboard_fab2_lib.baseboard_fab2(sch_1):p3e_cpu1_pe3_mp_rxn(11)") )
				( member ( signalRef "@baseboard_fab2_lib.baseboard_fab2(sch_1):p3e_cpu1_pe3_mp_rxn(12)") )
				( member ( signalRef "@baseboard_fab2_lib.baseboard_fab2(sch_1):p3e_cpu1_pe3_mp_rxn(13)") )
				( member ( signalRef "@baseboard_fab2_lib.baseboard_fab2(sch_1):p3e_cpu1_pe3_mp_rxn(14)") )
				( member ( signalRef "@baseboard_fab2_lib.baseboard_fab2(sch_1):p3e_cpu1_pe3_mp_rxn(15)") )
				( objectStatus "P3E_CPU1_PE3_MP_RXN" )
			)
			( bus "@baseboard_fab2_lib.baseboard_fab2(sch_1):p3e_cpu1_pe3_mp_rxp"
				( memberType ( signal ) )
				( member ( signalRef "@baseboard_fab2_lib.baseboard_fab2(sch_1):p3e_cpu1_pe3_mp_rxp(0)") )
				( member ( signalRef "@baseboard_fab2_lib.baseboard_fab2(sch_1):p3e_cpu1_pe3_mp_rxp(1)") )
				( member ( signalRef "@baseboard_fab2_lib.baseboard_fab2(sch_1):p3e_cpu1_pe3_mp_rxp(2)") )
				( member ( signalRef "@baseboard_fab2_lib.baseboard_fab2(sch_1):p3e_cpu1_pe3_mp_rxp(3)") )
				( member ( signalRef "@baseboard_fab2_lib.baseboard_fab2(sch_1):p3e_cpu1_pe3_mp_rxp(4)") )
				( member ( signalRef "@baseboard_fab2_lib.baseboard_fab2(sch_1):p3e_cpu1_pe3_mp_rxp(5)") )
				( member ( signalRef "@baseboard_fab2_lib.baseboard_fab2(sch_1):p3e_cpu1_pe3_mp_rxp(6)") )
				( member ( signalRef "@baseboard_fab2_lib.baseboard_fab2(sch_1):p3e_cpu1_pe3_mp_rxp(7)") )
				( member ( signalRef "@baseboard_fab2_lib.baseboard_fab2(sch_1):p3e_cpu1_pe3_mp_rxp(8)") )
				( member ( signalRef "@baseboard_fab2_lib.baseboard_fab2(sch_1):p3e_cpu1_pe3_mp_rxp(9)") )
				( member ( signalRef "@baseboard_fab2_lib.baseboard_fab2(sch_1):p3e_cpu1_pe3_mp_rxp(10)") )
				( member ( signalRef "@baseboard_fab2_lib.baseboard_fab2(sch_1):p3e_cpu1_pe3_mp_rxp(11)") )
				( member ( signalRef "@baseboard_fab2_lib.baseboard_fab2(sch_1):p3e_cpu1_pe3_mp_rxp(12)") )
				( member ( signalRef "@baseboard_fab2_lib.baseboard_fab2(sch_1):p3e_cpu1_pe3_mp_rxp(13)") )
				( member ( signalRef "@baseboard_fab2_lib.baseboard_fab2(sch_1):p3e_cpu1_pe3_mp_rxp(14)") )
				( member ( signalRef "@baseboard_fab2_lib.baseboard_fab2(sch_1):p3e_cpu1_pe3_mp_rxp(15)") )
				( objectStatus "P3E_CPU1_PE3_MP_RXP" )
			)
			( bus "@baseboard_fab2_lib.baseboard_fab2(sch_1):p3e_cpu1_pe3_mp_txn"
				( memberType ( signal ) )
				( member ( signalRef "@baseboard_fab2_lib.baseboard_fab2(sch_1):p3e_cpu1_pe3_mp_txn(0)") )
				( member ( signalRef "@baseboard_fab2_lib.baseboard_fab2(sch_1):p3e_cpu1_pe3_mp_txn(1)") )
				( member ( signalRef "@baseboard_fab2_lib.baseboard_fab2(sch_1):p3e_cpu1_pe3_mp_txn(2)") )
				( member ( signalRef "@baseboard_fab2_lib.baseboard_fab2(sch_1):p3e_cpu1_pe3_mp_txn(3)") )
				( member ( signalRef "@baseboard_fab2_lib.baseboard_fab2(sch_1):p3e_cpu1_pe3_mp_txn(4)") )
				( member ( signalRef "@baseboard_fab2_lib.baseboard_fab2(sch_1):p3e_cpu1_pe3_mp_txn(5)") )
				( member ( signalRef "@baseboard_fab2_lib.baseboard_fab2(sch_1):p3e_cpu1_pe3_mp_txn(6)") )
				( member ( signalRef "@baseboard_fab2_lib.baseboard_fab2(sch_1):p3e_cpu1_pe3_mp_txn(7)") )
				( member ( signalRef "@baseboard_fab2_lib.baseboard_fab2(sch_1):p3e_cpu1_pe3_mp_txn(8)") )
				( member ( signalRef "@baseboard_fab2_lib.baseboard_fab2(sch_1):p3e_cpu1_pe3_mp_txn(9)") )
				( member ( signalRef "@baseboard_fab2_lib.baseboard_fab2(sch_1):p3e_cpu1_pe3_mp_txn(10)") )
				( member ( signalRef "@baseboard_fab2_lib.baseboard_fab2(sch_1):p3e_cpu1_pe3_mp_txn(11)") )
				( member ( signalRef "@baseboard_fab2_lib.baseboard_fab2(sch_1):p3e_cpu1_pe3_mp_txn(12)") )
				( member ( signalRef "@baseboard_fab2_lib.baseboard_fab2(sch_1):p3e_cpu1_pe3_mp_txn(13)") )
				( member ( signalRef "@baseboard_fab2_lib.baseboard_fab2(sch_1):p3e_cpu1_pe3_mp_txn(14)") )
				( member ( signalRef "@baseboard_fab2_lib.baseboard_fab2(sch_1):p3e_cpu1_pe3_mp_txn(15)") )
				( objectStatus "P3E_CPU1_PE3_MP_TXN" )
			)
			( bus "@baseboard_fab2_lib.baseboard_fab2(sch_1):p3e_cpu1_pe3_mp_txp"
				( memberType ( signal ) )
				( member ( signalRef "@baseboard_fab2_lib.baseboard_fab2(sch_1):p3e_cpu1_pe3_mp_txp(0)") )
				( member ( signalRef "@baseboard_fab2_lib.baseboard_fab2(sch_1):p3e_cpu1_pe3_mp_txp(1)") )
				( member ( signalRef "@baseboard_fab2_lib.baseboard_fab2(sch_1):p3e_cpu1_pe3_mp_txp(2)") )
				( member ( signalRef "@baseboard_fab2_lib.baseboard_fab2(sch_1):p3e_cpu1_pe3_mp_txp(3)") )
				( member ( signalRef "@baseboard_fab2_lib.baseboard_fab2(sch_1):p3e_cpu1_pe3_mp_txp(4)") )
				( member ( signalRef "@baseboard_fab2_lib.baseboard_fab2(sch_1):p3e_cpu1_pe3_mp_txp(5)") )
				( member ( signalRef "@baseboard_fab2_lib.baseboard_fab2(sch_1):p3e_cpu1_pe3_mp_txp(6)") )
				( member ( signalRef "@baseboard_fab2_lib.baseboard_fab2(sch_1):p3e_cpu1_pe3_mp_txp(7)") )
				( member ( signalRef "@baseboard_fab2_lib.baseboard_fab2(sch_1):p3e_cpu1_pe3_mp_txp(8)") )
				( member ( signalRef "@baseboard_fab2_lib.baseboard_fab2(sch_1):p3e_cpu1_pe3_mp_txp(9)") )
				( member ( signalRef "@baseboard_fab2_lib.baseboard_fab2(sch_1):p3e_cpu1_pe3_mp_txp(10)") )
				( member ( signalRef "@baseboard_fab2_lib.baseboard_fab2(sch_1):p3e_cpu1_pe3_mp_txp(11)") )
				( member ( signalRef "@baseboard_fab2_lib.baseboard_fab2(sch_1):p3e_cpu1_pe3_mp_txp(12)") )
				( member ( signalRef "@baseboard_fab2_lib.baseboard_fab2(sch_1):p3e_cpu1_pe3_mp_txp(13)") )
				( member ( signalRef "@baseboard_fab2_lib.baseboard_fab2(sch_1):p3e_cpu1_pe3_mp_txp(14)") )
				( member ( signalRef "@baseboard_fab2_lib.baseboard_fab2(sch_1):p3e_cpu1_pe3_mp_txp(15)") )
				( objectStatus "P3E_CPU1_PE3_MP_TXP" )
			)
			( bus "@baseboard_fab2_lib.baseboard_fab2(sch_1):p3e_cpu0_pe1_pch_c_txn"
				( memberType ( signal ) )
				( member ( signalRef "@baseboard_fab2_lib.baseboard_fab2(sch_1):p3e_cpu0_pe1_pch_c_txn(8)") )
				( member ( signalRef "@baseboard_fab2_lib.baseboard_fab2(sch_1):p3e_cpu0_pe1_pch_c_txn(9)") )
				( member ( signalRef "@baseboard_fab2_lib.baseboard_fab2(sch_1):p3e_cpu0_pe1_pch_c_txn(10)") )
				( member ( signalRef "@baseboard_fab2_lib.baseboard_fab2(sch_1):p3e_cpu0_pe1_pch_c_txn(11)") )
				( member ( signalRef "@baseboard_fab2_lib.baseboard_fab2(sch_1):p3e_cpu0_pe1_pch_c_txn(12)") )
				( member ( signalRef "@baseboard_fab2_lib.baseboard_fab2(sch_1):p3e_cpu0_pe1_pch_c_txn(13)") )
				( member ( signalRef "@baseboard_fab2_lib.baseboard_fab2(sch_1):p3e_cpu0_pe1_pch_c_txn(14)") )
				( member ( signalRef "@baseboard_fab2_lib.baseboard_fab2(sch_1):p3e_cpu0_pe1_pch_c_txn(15)") )
				( objectStatus "P3E_CPU0_PE1_PCH_C_TXN" )
			)
			( bus "@baseboard_fab2_lib.baseboard_fab2(sch_1):p3e_cpu0_pe1_pch_c_txp"
				( memberType ( signal ) )
				( member ( signalRef "@baseboard_fab2_lib.baseboard_fab2(sch_1):p3e_cpu0_pe1_pch_c_txp(8)") )
				( member ( signalRef "@baseboard_fab2_lib.baseboard_fab2(sch_1):p3e_cpu0_pe1_pch_c_txp(9)") )
				( member ( signalRef "@baseboard_fab2_lib.baseboard_fab2(sch_1):p3e_cpu0_pe1_pch_c_txp(10)") )
				( member ( signalRef "@baseboard_fab2_lib.baseboard_fab2(sch_1):p3e_cpu0_pe1_pch_c_txp(11)") )
				( member ( signalRef "@baseboard_fab2_lib.baseboard_fab2(sch_1):p3e_cpu0_pe1_pch_c_txp(12)") )
				( member ( signalRef "@baseboard_fab2_lib.baseboard_fab2(sch_1):p3e_cpu0_pe1_pch_c_txp(13)") )
				( member ( signalRef "@baseboard_fab2_lib.baseboard_fab2(sch_1):p3e_cpu0_pe1_pch_c_txp(14)") )
				( member ( signalRef "@baseboard_fab2_lib.baseboard_fab2(sch_1):p3e_cpu0_pe1_pch_c_txp(15)") )
				( objectStatus "P3E_CPU0_PE1_PCH_C_TXP" )
			)
			( bus "@baseboard_fab2_lib.baseboard_fab2(sch_1):p3e_cpu0_pe1_pch_r_rxn"
				( memberType ( signal ) )
				( member ( signalRef "@baseboard_fab2_lib.baseboard_fab2(sch_1):p3e_cpu0_pe1_pch_r_rxn(8)") )
				( member ( signalRef "@baseboard_fab2_lib.baseboard_fab2(sch_1):p3e_cpu0_pe1_pch_r_rxn(9)") )
				( member ( signalRef "@baseboard_fab2_lib.baseboard_fab2(sch_1):p3e_cpu0_pe1_pch_r_rxn(10)") )
				( member ( signalRef "@baseboard_fab2_lib.baseboard_fab2(sch_1):p3e_cpu0_pe1_pch_r_rxn(11)") )
				( member ( signalRef "@baseboard_fab2_lib.baseboard_fab2(sch_1):p3e_cpu0_pe1_pch_r_rxn(12)") )
				( member ( signalRef "@baseboard_fab2_lib.baseboard_fab2(sch_1):p3e_cpu0_pe1_pch_r_rxn(13)") )
				( member ( signalRef "@baseboard_fab2_lib.baseboard_fab2(sch_1):p3e_cpu0_pe1_pch_r_rxn(14)") )
				( member ( signalRef "@baseboard_fab2_lib.baseboard_fab2(sch_1):p3e_cpu0_pe1_pch_r_rxn(15)") )
				( objectStatus "P3E_CPU0_PE1_PCH_R_RXN" )
			)
			( bus "@baseboard_fab2_lib.baseboard_fab2(sch_1):p3e_cpu0_pe1_pch_r_rxp"
				( memberType ( signal ) )
				( member ( signalRef "@baseboard_fab2_lib.baseboard_fab2(sch_1):p3e_cpu0_pe1_pch_r_rxp(8)") )
				( member ( signalRef "@baseboard_fab2_lib.baseboard_fab2(sch_1):p3e_cpu0_pe1_pch_r_rxp(9)") )
				( member ( signalRef "@baseboard_fab2_lib.baseboard_fab2(sch_1):p3e_cpu0_pe1_pch_r_rxp(10)") )
				( member ( signalRef "@baseboard_fab2_lib.baseboard_fab2(sch_1):p3e_cpu0_pe1_pch_r_rxp(11)") )
				( member ( signalRef "@baseboard_fab2_lib.baseboard_fab2(sch_1):p3e_cpu0_pe1_pch_r_rxp(12)") )
				( member ( signalRef "@baseboard_fab2_lib.baseboard_fab2(sch_1):p3e_cpu0_pe1_pch_r_rxp(13)") )
				( member ( signalRef "@baseboard_fab2_lib.baseboard_fab2(sch_1):p3e_cpu0_pe1_pch_r_rxp(14)") )
				( member ( signalRef "@baseboard_fab2_lib.baseboard_fab2(sch_1):p3e_cpu0_pe1_pch_r_rxp(15)") )
				( objectStatus "P3E_CPU0_PE1_PCH_R_RXP" )
			)
			( bus "@baseboard_fab2_lib.baseboard_fab2(sch_1):p3e_cpu0_pe2_ss_c_txn"
				( memberType ( signal ) )
				( member ( signalRef "@baseboard_fab2_lib.baseboard_fab2(sch_1):p3e_cpu0_pe2_ss_c_txn(0)") )
				( member ( signalRef "@baseboard_fab2_lib.baseboard_fab2(sch_1):p3e_cpu0_pe2_ss_c_txn(1)") )
				( member ( signalRef "@baseboard_fab2_lib.baseboard_fab2(sch_1):p3e_cpu0_pe2_ss_c_txn(2)") )
				( member ( signalRef "@baseboard_fab2_lib.baseboard_fab2(sch_1):p3e_cpu0_pe2_ss_c_txn(3)") )
				( member ( signalRef "@baseboard_fab2_lib.baseboard_fab2(sch_1):p3e_cpu0_pe2_ss_c_txn(4)") )
				( member ( signalRef "@baseboard_fab2_lib.baseboard_fab2(sch_1):p3e_cpu0_pe2_ss_c_txn(5)") )
				( member ( signalRef "@baseboard_fab2_lib.baseboard_fab2(sch_1):p3e_cpu0_pe2_ss_c_txn(6)") )
				( member ( signalRef "@baseboard_fab2_lib.baseboard_fab2(sch_1):p3e_cpu0_pe2_ss_c_txn(7)") )
				( member ( signalRef "@baseboard_fab2_lib.baseboard_fab2(sch_1):p3e_cpu0_pe2_ss_c_txn(8)") )
				( member ( signalRef "@baseboard_fab2_lib.baseboard_fab2(sch_1):p3e_cpu0_pe2_ss_c_txn(9)") )
				( member ( signalRef "@baseboard_fab2_lib.baseboard_fab2(sch_1):p3e_cpu0_pe2_ss_c_txn(10)") )
				( member ( signalRef "@baseboard_fab2_lib.baseboard_fab2(sch_1):p3e_cpu0_pe2_ss_c_txn(11)") )
				( member ( signalRef "@baseboard_fab2_lib.baseboard_fab2(sch_1):p3e_cpu0_pe2_ss_c_txn(12)") )
				( member ( signalRef "@baseboard_fab2_lib.baseboard_fab2(sch_1):p3e_cpu0_pe2_ss_c_txn(13)") )
				( member ( signalRef "@baseboard_fab2_lib.baseboard_fab2(sch_1):p3e_cpu0_pe2_ss_c_txn(14)") )
				( member ( signalRef "@baseboard_fab2_lib.baseboard_fab2(sch_1):p3e_cpu0_pe2_ss_c_txn(15)") )
				( objectStatus "P3E_CPU0_PE2_SS_C_TXN" )
			)
			( bus "@baseboard_fab2_lib.baseboard_fab2(sch_1):p3e_cpu0_pe2_ss_c_txp"
				( memberType ( signal ) )
				( member ( signalRef "@baseboard_fab2_lib.baseboard_fab2(sch_1):p3e_cpu0_pe2_ss_c_txp(0)") )
				( member ( signalRef "@baseboard_fab2_lib.baseboard_fab2(sch_1):p3e_cpu0_pe2_ss_c_txp(1)") )
				( member ( signalRef "@baseboard_fab2_lib.baseboard_fab2(sch_1):p3e_cpu0_pe2_ss_c_txp(2)") )
				( member ( signalRef "@baseboard_fab2_lib.baseboard_fab2(sch_1):p3e_cpu0_pe2_ss_c_txp(3)") )
				( member ( signalRef "@baseboard_fab2_lib.baseboard_fab2(sch_1):p3e_cpu0_pe2_ss_c_txp(4)") )
				( member ( signalRef "@baseboard_fab2_lib.baseboard_fab2(sch_1):p3e_cpu0_pe2_ss_c_txp(5)") )
				( member ( signalRef "@baseboard_fab2_lib.baseboard_fab2(sch_1):p3e_cpu0_pe2_ss_c_txp(6)") )
				( member ( signalRef "@baseboard_fab2_lib.baseboard_fab2(sch_1):p3e_cpu0_pe2_ss_c_txp(7)") )
				( member ( signalRef "@baseboard_fab2_lib.baseboard_fab2(sch_1):p3e_cpu0_pe2_ss_c_txp(8)") )
				( member ( signalRef "@baseboard_fab2_lib.baseboard_fab2(sch_1):p3e_cpu0_pe2_ss_c_txp(9)") )
				( member ( signalRef "@baseboard_fab2_lib.baseboard_fab2(sch_1):p3e_cpu0_pe2_ss_c_txp(10)") )
				( member ( signalRef "@baseboard_fab2_lib.baseboard_fab2(sch_1):p3e_cpu0_pe2_ss_c_txp(11)") )
				( member ( signalRef "@baseboard_fab2_lib.baseboard_fab2(sch_1):p3e_cpu0_pe2_ss_c_txp(12)") )
				( member ( signalRef "@baseboard_fab2_lib.baseboard_fab2(sch_1):p3e_cpu0_pe2_ss_c_txp(13)") )
				( member ( signalRef "@baseboard_fab2_lib.baseboard_fab2(sch_1):p3e_cpu0_pe2_ss_c_txp(14)") )
				( member ( signalRef "@baseboard_fab2_lib.baseboard_fab2(sch_1):p3e_cpu0_pe2_ss_c_txp(15)") )
				( objectStatus "P3E_CPU0_PE2_SS_C_TXP" )
			)
			( bus "@baseboard_fab2_lib.baseboard_fab2(sch_1):p3e_ocp_cpu0_pe3_c_txn"
				( memberType ( signal ) )
				( member ( signalRef "@baseboard_fab2_lib.baseboard_fab2(sch_1):p3e_ocp_cpu0_pe3_c_txn(0)") )
				( member ( signalRef "@baseboard_fab2_lib.baseboard_fab2(sch_1):p3e_ocp_cpu0_pe3_c_txn(1)") )
				( member ( signalRef "@baseboard_fab2_lib.baseboard_fab2(sch_1):p3e_ocp_cpu0_pe3_c_txn(2)") )
				( member ( signalRef "@baseboard_fab2_lib.baseboard_fab2(sch_1):p3e_ocp_cpu0_pe3_c_txn(3)") )
				( member ( signalRef "@baseboard_fab2_lib.baseboard_fab2(sch_1):p3e_ocp_cpu0_pe3_c_txn(4)") )
				( member ( signalRef "@baseboard_fab2_lib.baseboard_fab2(sch_1):p3e_ocp_cpu0_pe3_c_txn(5)") )
				( member ( signalRef "@baseboard_fab2_lib.baseboard_fab2(sch_1):p3e_ocp_cpu0_pe3_c_txn(6)") )
				( member ( signalRef "@baseboard_fab2_lib.baseboard_fab2(sch_1):p3e_ocp_cpu0_pe3_c_txn(7)") )
				( member ( signalRef "@baseboard_fab2_lib.baseboard_fab2(sch_1):p3e_ocp_cpu0_pe3_c_txn(8)") )
				( member ( signalRef "@baseboard_fab2_lib.baseboard_fab2(sch_1):p3e_ocp_cpu0_pe3_c_txn(9)") )
				( member ( signalRef "@baseboard_fab2_lib.baseboard_fab2(sch_1):p3e_ocp_cpu0_pe3_c_txn(10)") )
				( member ( signalRef "@baseboard_fab2_lib.baseboard_fab2(sch_1):p3e_ocp_cpu0_pe3_c_txn(11)") )
				( member ( signalRef "@baseboard_fab2_lib.baseboard_fab2(sch_1):p3e_ocp_cpu0_pe3_c_txn(12)") )
				( member ( signalRef "@baseboard_fab2_lib.baseboard_fab2(sch_1):p3e_ocp_cpu0_pe3_c_txn(13)") )
				( member ( signalRef "@baseboard_fab2_lib.baseboard_fab2(sch_1):p3e_ocp_cpu0_pe3_c_txn(14)") )
				( member ( signalRef "@baseboard_fab2_lib.baseboard_fab2(sch_1):p3e_ocp_cpu0_pe3_c_txn(15)") )
				( objectStatus "P3E_OCP_CPU0_PE3_C_TXN" )
			)
			( bus "@baseboard_fab2_lib.baseboard_fab2(sch_1):p3e_ocp_cpu0_pe3_c_txp"
				( memberType ( signal ) )
				( member ( signalRef "@baseboard_fab2_lib.baseboard_fab2(sch_1):p3e_ocp_cpu0_pe3_c_txp(0)") )
				( member ( signalRef "@baseboard_fab2_lib.baseboard_fab2(sch_1):p3e_ocp_cpu0_pe3_c_txp(1)") )
				( member ( signalRef "@baseboard_fab2_lib.baseboard_fab2(sch_1):p3e_ocp_cpu0_pe3_c_txp(2)") )
				( member ( signalRef "@baseboard_fab2_lib.baseboard_fab2(sch_1):p3e_ocp_cpu0_pe3_c_txp(3)") )
				( member ( signalRef "@baseboard_fab2_lib.baseboard_fab2(sch_1):p3e_ocp_cpu0_pe3_c_txp(4)") )
				( member ( signalRef "@baseboard_fab2_lib.baseboard_fab2(sch_1):p3e_ocp_cpu0_pe3_c_txp(5)") )
				( member ( signalRef "@baseboard_fab2_lib.baseboard_fab2(sch_1):p3e_ocp_cpu0_pe3_c_txp(6)") )
				( member ( signalRef "@baseboard_fab2_lib.baseboard_fab2(sch_1):p3e_ocp_cpu0_pe3_c_txp(7)") )
				( member ( signalRef "@baseboard_fab2_lib.baseboard_fab2(sch_1):p3e_ocp_cpu0_pe3_c_txp(8)") )
				( member ( signalRef "@baseboard_fab2_lib.baseboard_fab2(sch_1):p3e_ocp_cpu0_pe3_c_txp(9)") )
				( member ( signalRef "@baseboard_fab2_lib.baseboard_fab2(sch_1):p3e_ocp_cpu0_pe3_c_txp(10)") )
				( member ( signalRef "@baseboard_fab2_lib.baseboard_fab2(sch_1):p3e_ocp_cpu0_pe3_c_txp(11)") )
				( member ( signalRef "@baseboard_fab2_lib.baseboard_fab2(sch_1):p3e_ocp_cpu0_pe3_c_txp(12)") )
				( member ( signalRef "@baseboard_fab2_lib.baseboard_fab2(sch_1):p3e_ocp_cpu0_pe3_c_txp(13)") )
				( member ( signalRef "@baseboard_fab2_lib.baseboard_fab2(sch_1):p3e_ocp_cpu0_pe3_c_txp(14)") )
				( member ( signalRef "@baseboard_fab2_lib.baseboard_fab2(sch_1):p3e_ocp_cpu0_pe3_c_txp(15)") )
				( objectStatus "P3E_OCP_CPU0_PE3_C_TXP" )
			)
			( bus "@baseboard_fab2_lib.baseboard_fab2(sch_1):p3e_cpu0_pe1_ss_c_txn"
				( memberType ( signal ) )
				( member ( signalRef "@baseboard_fab2_lib.baseboard_fab2(sch_1):p3e_cpu0_pe1_ss_c_txn(0)") )
				( member ( signalRef "@baseboard_fab2_lib.baseboard_fab2(sch_1):p3e_cpu0_pe1_ss_c_txn(1)") )
				( member ( signalRef "@baseboard_fab2_lib.baseboard_fab2(sch_1):p3e_cpu0_pe1_ss_c_txn(2)") )
				( member ( signalRef "@baseboard_fab2_lib.baseboard_fab2(sch_1):p3e_cpu0_pe1_ss_c_txn(3)") )
				( member ( signalRef "@baseboard_fab2_lib.baseboard_fab2(sch_1):p3e_cpu0_pe1_ss_c_txn(4)") )
				( member ( signalRef "@baseboard_fab2_lib.baseboard_fab2(sch_1):p3e_cpu0_pe1_ss_c_txn(5)") )
				( member ( signalRef "@baseboard_fab2_lib.baseboard_fab2(sch_1):p3e_cpu0_pe1_ss_c_txn(6)") )
				( member ( signalRef "@baseboard_fab2_lib.baseboard_fab2(sch_1):p3e_cpu0_pe1_ss_c_txn(7)") )
				( objectStatus "P3E_CPU0_PE1_SS_C_TXN" )
			)
			( bus "@baseboard_fab2_lib.baseboard_fab2(sch_1):p3e_cpu0_pe1_ss_c_txp"
				( memberType ( signal ) )
				( member ( signalRef "@baseboard_fab2_lib.baseboard_fab2(sch_1):p3e_cpu0_pe1_ss_c_txp(0)") )
				( member ( signalRef "@baseboard_fab2_lib.baseboard_fab2(sch_1):p3e_cpu0_pe1_ss_c_txp(1)") )
				( member ( signalRef "@baseboard_fab2_lib.baseboard_fab2(sch_1):p3e_cpu0_pe1_ss_c_txp(2)") )
				( member ( signalRef "@baseboard_fab2_lib.baseboard_fab2(sch_1):p3e_cpu0_pe1_ss_c_txp(3)") )
				( member ( signalRef "@baseboard_fab2_lib.baseboard_fab2(sch_1):p3e_cpu0_pe1_ss_c_txp(4)") )
				( member ( signalRef "@baseboard_fab2_lib.baseboard_fab2(sch_1):p3e_cpu0_pe1_ss_c_txp(5)") )
				( member ( signalRef "@baseboard_fab2_lib.baseboard_fab2(sch_1):p3e_cpu0_pe1_ss_c_txp(6)") )
				( member ( signalRef "@baseboard_fab2_lib.baseboard_fab2(sch_1):p3e_cpu0_pe1_ss_c_txp(7)") )
				( objectStatus "P3E_CPU0_PE1_SS_C_TXP" )
			)
			( bus "@baseboard_fab2_lib.baseboard_fab2(sch_1):p3e_cpu0_pe1_ss_r_rxn"
				( memberType ( signal ) )
				( member ( signalRef "@baseboard_fab2_lib.baseboard_fab2(sch_1):p3e_cpu0_pe1_ss_r_rxn(0)") )
				( member ( signalRef "@baseboard_fab2_lib.baseboard_fab2(sch_1):p3e_cpu0_pe1_ss_r_rxn(1)") )
				( member ( signalRef "@baseboard_fab2_lib.baseboard_fab2(sch_1):p3e_cpu0_pe1_ss_r_rxn(2)") )
				( member ( signalRef "@baseboard_fab2_lib.baseboard_fab2(sch_1):p3e_cpu0_pe1_ss_r_rxn(3)") )
				( member ( signalRef "@baseboard_fab2_lib.baseboard_fab2(sch_1):p3e_cpu0_pe1_ss_r_rxn(4)") )
				( member ( signalRef "@baseboard_fab2_lib.baseboard_fab2(sch_1):p3e_cpu0_pe1_ss_r_rxn(5)") )
				( member ( signalRef "@baseboard_fab2_lib.baseboard_fab2(sch_1):p3e_cpu0_pe1_ss_r_rxn(6)") )
				( member ( signalRef "@baseboard_fab2_lib.baseboard_fab2(sch_1):p3e_cpu0_pe1_ss_r_rxn(7)") )
				( objectStatus "P3E_CPU0_PE1_SS_R_RXN" )
			)
			( bus "@baseboard_fab2_lib.baseboard_fab2(sch_1):p3e_cpu0_pe1_ss_r_rxp"
				( memberType ( signal ) )
				( member ( signalRef "@baseboard_fab2_lib.baseboard_fab2(sch_1):p3e_cpu0_pe1_ss_r_rxp(0)") )
				( member ( signalRef "@baseboard_fab2_lib.baseboard_fab2(sch_1):p3e_cpu0_pe1_ss_r_rxp(1)") )
				( member ( signalRef "@baseboard_fab2_lib.baseboard_fab2(sch_1):p3e_cpu0_pe1_ss_r_rxp(2)") )
				( member ( signalRef "@baseboard_fab2_lib.baseboard_fab2(sch_1):p3e_cpu0_pe1_ss_r_rxp(3)") )
				( member ( signalRef "@baseboard_fab2_lib.baseboard_fab2(sch_1):p3e_cpu0_pe1_ss_r_rxp(4)") )
				( member ( signalRef "@baseboard_fab2_lib.baseboard_fab2(sch_1):p3e_cpu0_pe1_ss_r_rxp(5)") )
				( member ( signalRef "@baseboard_fab2_lib.baseboard_fab2(sch_1):p3e_cpu0_pe1_ss_r_rxp(6)") )
				( member ( signalRef "@baseboard_fab2_lib.baseboard_fab2(sch_1):p3e_cpu0_pe1_ss_r_rxp(7)") )
				( objectStatus "P3E_CPU0_PE1_SS_R_RXP" )
			)
			( bus "@baseboard_fab2_lib.baseboard_fab2(sch_1):p3e_pch_m2_rx_dn"
				( memberType ( signal ) )
				( member ( signalRef "@baseboard_fab2_lib.baseboard_fab2(sch_1):p3e_pch_m2_rx_dn(1)") )
				( member ( signalRef "@baseboard_fab2_lib.baseboard_fab2(sch_1):p3e_pch_m2_rx_dn(2)") )
				( member ( signalRef "@baseboard_fab2_lib.baseboard_fab2(sch_1):p3e_pch_m2_rx_dn(3)") )
				( objectStatus "P3E_PCH_M2_RX_DN" )
			)
			( bus "@baseboard_fab2_lib.baseboard_fab2(sch_1):p3e_pch_m2_rx_dp"
				( memberType ( signal ) )
				( member ( signalRef "@baseboard_fab2_lib.baseboard_fab2(sch_1):p3e_pch_m2_rx_dp(1)") )
				( member ( signalRef "@baseboard_fab2_lib.baseboard_fab2(sch_1):p3e_pch_m2_rx_dp(2)") )
				( member ( signalRef "@baseboard_fab2_lib.baseboard_fab2(sch_1):p3e_pch_m2_rx_dp(3)") )
				( objectStatus "P3E_PCH_M2_RX_DP" )
			)
			( bus "@baseboard_fab2_lib.baseboard_fab2(sch_1):p3e_pch_m2_tx_dn"
				( memberType ( signal ) )
				( member ( signalRef "@baseboard_fab2_lib.baseboard_fab2(sch_1):p3e_pch_m2_tx_dn(1)") )
				( member ( signalRef "@baseboard_fab2_lib.baseboard_fab2(sch_1):p3e_pch_m2_tx_dn(2)") )
				( member ( signalRef "@baseboard_fab2_lib.baseboard_fab2(sch_1):p3e_pch_m2_tx_dn(3)") )
				( objectStatus "P3E_PCH_M2_TX_DN" )
			)
			( bus "@baseboard_fab2_lib.baseboard_fab2(sch_1):p3e_pch_m2_tx_dp"
				( memberType ( signal ) )
				( member ( signalRef "@baseboard_fab2_lib.baseboard_fab2(sch_1):p3e_pch_m2_tx_dp(1)") )
				( member ( signalRef "@baseboard_fab2_lib.baseboard_fab2(sch_1):p3e_pch_m2_tx_dp(2)") )
				( member ( signalRef "@baseboard_fab2_lib.baseboard_fab2(sch_1):p3e_pch_m2_tx_dp(3)") )
				( objectStatus "P3E_PCH_M2_TX_DP" )
			)
			( bus "@baseboard_fab2_lib.baseboard_fab2(sch_1):sata6g_pch_pcie_up_sata_rxn"
				( memberType ( signal ) )
				( member ( signalRef "@baseboard_fab2_lib.baseboard_fab2(sch_1):sata6g_pch_pcie_up_sata_rxn(0)") )
				( member ( signalRef "@baseboard_fab2_lib.baseboard_fab2(sch_1):sata6g_pch_pcie_up_sata_rxn(1)") )
				( member ( signalRef "@baseboard_fab2_lib.baseboard_fab2(sch_1):sata6g_pch_pcie_up_sata_rxn(2)") )
				( member ( signalRef "@baseboard_fab2_lib.baseboard_fab2(sch_1):sata6g_pch_pcie_up_sata_rxn(3)") )
				( member ( signalRef "@baseboard_fab2_lib.baseboard_fab2(sch_1):sata6g_pch_pcie_up_sata_rxn(4)") )
				( member ( signalRef "@baseboard_fab2_lib.baseboard_fab2(sch_1):sata6g_pch_pcie_up_sata_rxn(5)") )
				( member ( signalRef "@baseboard_fab2_lib.baseboard_fab2(sch_1):sata6g_pch_pcie_up_sata_rxn(6)") )
				( member ( signalRef "@baseboard_fab2_lib.baseboard_fab2(sch_1):sata6g_pch_pcie_up_sata_rxn(7)") )
				( objectStatus "SATA6G_PCH_PCIE_UP_SATA_RXN" )
			)
			( bus "@baseboard_fab2_lib.baseboard_fab2(sch_1):sata6g_pch_pcie_up_sata_rxp"
				( memberType ( signal ) )
				( member ( signalRef "@baseboard_fab2_lib.baseboard_fab2(sch_1):sata6g_pch_pcie_up_sata_rxp(0)") )
				( member ( signalRef "@baseboard_fab2_lib.baseboard_fab2(sch_1):sata6g_pch_pcie_up_sata_rxp(1)") )
				( member ( signalRef "@baseboard_fab2_lib.baseboard_fab2(sch_1):sata6g_pch_pcie_up_sata_rxp(2)") )
				( member ( signalRef "@baseboard_fab2_lib.baseboard_fab2(sch_1):sata6g_pch_pcie_up_sata_rxp(3)") )
				( member ( signalRef "@baseboard_fab2_lib.baseboard_fab2(sch_1):sata6g_pch_pcie_up_sata_rxp(4)") )
				( member ( signalRef "@baseboard_fab2_lib.baseboard_fab2(sch_1):sata6g_pch_pcie_up_sata_rxp(5)") )
				( member ( signalRef "@baseboard_fab2_lib.baseboard_fab2(sch_1):sata6g_pch_pcie_up_sata_rxp(6)") )
				( member ( signalRef "@baseboard_fab2_lib.baseboard_fab2(sch_1):sata6g_pch_pcie_up_sata_rxp(7)") )
				( objectStatus "SATA6G_PCH_PCIE_UP_SATA_RXP" )
			)
			( bus "@baseboard_fab2_lib.baseboard_fab2(sch_1):sata6g_pch_pcie_up_sata_txn"
				( memberType ( signal ) )
				( member ( signalRef "@baseboard_fab2_lib.baseboard_fab2(sch_1):sata6g_pch_pcie_up_sata_txn(0)") )
				( member ( signalRef "@baseboard_fab2_lib.baseboard_fab2(sch_1):sata6g_pch_pcie_up_sata_txn(1)") )
				( member ( signalRef "@baseboard_fab2_lib.baseboard_fab2(sch_1):sata6g_pch_pcie_up_sata_txn(2)") )
				( member ( signalRef "@baseboard_fab2_lib.baseboard_fab2(sch_1):sata6g_pch_pcie_up_sata_txn(3)") )
				( member ( signalRef "@baseboard_fab2_lib.baseboard_fab2(sch_1):sata6g_pch_pcie_up_sata_txn(4)") )
				( member ( signalRef "@baseboard_fab2_lib.baseboard_fab2(sch_1):sata6g_pch_pcie_up_sata_txn(5)") )
				( member ( signalRef "@baseboard_fab2_lib.baseboard_fab2(sch_1):sata6g_pch_pcie_up_sata_txn(6)") )
				( member ( signalRef "@baseboard_fab2_lib.baseboard_fab2(sch_1):sata6g_pch_pcie_up_sata_txn(7)") )
				( objectStatus "SATA6G_PCH_PCIE_UP_SATA_TXN" )
			)
			( bus "@baseboard_fab2_lib.baseboard_fab2(sch_1):sata6g_pch_pcie_up_sata_txp"
				( memberType ( signal ) )
				( member ( signalRef "@baseboard_fab2_lib.baseboard_fab2(sch_1):sata6g_pch_pcie_up_sata_txp(0)") )
				( member ( signalRef "@baseboard_fab2_lib.baseboard_fab2(sch_1):sata6g_pch_pcie_up_sata_txp(1)") )
				( member ( signalRef "@baseboard_fab2_lib.baseboard_fab2(sch_1):sata6g_pch_pcie_up_sata_txp(2)") )
				( member ( signalRef "@baseboard_fab2_lib.baseboard_fab2(sch_1):sata6g_pch_pcie_up_sata_txp(3)") )
				( member ( signalRef "@baseboard_fab2_lib.baseboard_fab2(sch_1):sata6g_pch_pcie_up_sata_txp(4)") )
				( member ( signalRef "@baseboard_fab2_lib.baseboard_fab2(sch_1):sata6g_pch_pcie_up_sata_txp(5)") )
				( member ( signalRef "@baseboard_fab2_lib.baseboard_fab2(sch_1):sata6g_pch_pcie_up_sata_txp(6)") )
				( member ( signalRef "@baseboard_fab2_lib.baseboard_fab2(sch_1):sata6g_pch_pcie_up_sata_txp(7)") )
				( objectStatus "SATA6G_PCH_PCIE_UP_SATA_TXP" )
			)
			( bus "@baseboard_fab2_lib.baseboard_fab2(sch_1):dmi_cpu0_pch_rx_dn"
				( memberType ( signal ) )
				( member ( signalRef "@baseboard_fab2_lib.baseboard_fab2(sch_1):dmi_cpu0_pch_rx_dn(0)") )
				( member ( signalRef "@baseboard_fab2_lib.baseboard_fab2(sch_1):dmi_cpu0_pch_rx_dn(1)") )
				( member ( signalRef "@baseboard_fab2_lib.baseboard_fab2(sch_1):dmi_cpu0_pch_rx_dn(2)") )
				( member ( signalRef "@baseboard_fab2_lib.baseboard_fab2(sch_1):dmi_cpu0_pch_rx_dn(3)") )
				( objectStatus "DMI_CPU0_PCH_RX_DN" )
			)
			( bus "@baseboard_fab2_lib.baseboard_fab2(sch_1):dmi_cpu0_pch_rx_dp"
				( memberType ( signal ) )
				( member ( signalRef "@baseboard_fab2_lib.baseboard_fab2(sch_1):dmi_cpu0_pch_rx_dp(0)") )
				( member ( signalRef "@baseboard_fab2_lib.baseboard_fab2(sch_1):dmi_cpu0_pch_rx_dp(1)") )
				( member ( signalRef "@baseboard_fab2_lib.baseboard_fab2(sch_1):dmi_cpu0_pch_rx_dp(2)") )
				( member ( signalRef "@baseboard_fab2_lib.baseboard_fab2(sch_1):dmi_cpu0_pch_rx_dp(3)") )
				( objectStatus "DMI_CPU0_PCH_RX_DP" )
			)
			( bus "@baseboard_fab2_lib.baseboard_fab2(sch_1):dmi_cpu0_pch_tx_c_dn"
				( memberType ( signal ) )
				( member ( signalRef "@baseboard_fab2_lib.baseboard_fab2(sch_1):dmi_cpu0_pch_tx_c_dn(0)") )
				( member ( signalRef "@baseboard_fab2_lib.baseboard_fab2(sch_1):dmi_cpu0_pch_tx_c_dn(1)") )
				( member ( signalRef "@baseboard_fab2_lib.baseboard_fab2(sch_1):dmi_cpu0_pch_tx_c_dn(2)") )
				( member ( signalRef "@baseboard_fab2_lib.baseboard_fab2(sch_1):dmi_cpu0_pch_tx_c_dn(3)") )
				( objectStatus "DMI_CPU0_PCH_TX_C_DN" )
			)
			( bus "@baseboard_fab2_lib.baseboard_fab2(sch_1):dmi_cpu0_pch_tx_c_dp"
				( memberType ( signal ) )
				( member ( signalRef "@baseboard_fab2_lib.baseboard_fab2(sch_1):dmi_cpu0_pch_tx_c_dp(0)") )
				( member ( signalRef "@baseboard_fab2_lib.baseboard_fab2(sch_1):dmi_cpu0_pch_tx_c_dp(1)") )
				( member ( signalRef "@baseboard_fab2_lib.baseboard_fab2(sch_1):dmi_cpu0_pch_tx_c_dp(2)") )
				( member ( signalRef "@baseboard_fab2_lib.baseboard_fab2(sch_1):dmi_cpu0_pch_tx_c_dp(3)") )
				( objectStatus "DMI_CPU0_PCH_TX_C_DP" )
			)
			( bus "@baseboard_fab2_lib.baseboard_fab2(sch_1):lpc_lad_io"
				( memberType ( signal ) )
				( alias ( busRef "@baseboard_fab2_lib.baseboard_fab2(sch_1):page119_lpc_lad_io") )
				( member ( signalRef "@baseboard_fab2_lib.baseboard_fab2(sch_1):lpc_lad0_io0") )
				( member ( signalRef "@baseboard_fab2_lib.baseboard_fab2(sch_1):lpc_lad1_io1") )
				( member ( signalRef "@baseboard_fab2_lib.baseboard_fab2(sch_1):lpc_lad2_io2") )
				( member ( signalRef "@baseboard_fab2_lib.baseboard_fab2(sch_1):lpc_lad3_io3") )
				( objectStatus "LPC_LAD_IO" )
			)
			( bus "@baseboard_fab2_lib.baseboard_fab2(sch_1):page119_lpc_lad_io"
				( memberType ( signal ) )
				( objectFlag fObjectAlias )
				( member ( signalRef "@baseboard_fab2_lib.baseboard_fab2(sch_1):page119_lpc_lad_io(0)") )
				( member ( signalRef "@baseboard_fab2_lib.baseboard_fab2(sch_1):page119_lpc_lad_io(1)") )
				( member ( signalRef "@baseboard_fab2_lib.baseboard_fab2(sch_1):page119_lpc_lad_io(2)") )
				( member ( signalRef "@baseboard_fab2_lib.baseboard_fab2(sch_1):page119_lpc_lad_io(3)") )
				( objectStatus "PAGE119_LPC_LAD_IO" )
			)
			( bus "@baseboard_fab2_lib.baseboard_fab2(sch_1):p3e_cpu1_pe3_mp_c_txn"
				( memberType ( signal ) )
				( member ( signalRef "@baseboard_fab2_lib.baseboard_fab2(sch_1):p3e_cpu1_pe3_mp_c_txn(0)") )
				( member ( signalRef "@baseboard_fab2_lib.baseboard_fab2(sch_1):p3e_cpu1_pe3_mp_c_txn(1)") )
				( member ( signalRef "@baseboard_fab2_lib.baseboard_fab2(sch_1):p3e_cpu1_pe3_mp_c_txn(2)") )
				( member ( signalRef "@baseboard_fab2_lib.baseboard_fab2(sch_1):p3e_cpu1_pe3_mp_c_txn(3)") )
				( member ( signalRef "@baseboard_fab2_lib.baseboard_fab2(sch_1):p3e_cpu1_pe3_mp_c_txn(4)") )
				( member ( signalRef "@baseboard_fab2_lib.baseboard_fab2(sch_1):p3e_cpu1_pe3_mp_c_txn(5)") )
				( member ( signalRef "@baseboard_fab2_lib.baseboard_fab2(sch_1):p3e_cpu1_pe3_mp_c_txn(6)") )
				( member ( signalRef "@baseboard_fab2_lib.baseboard_fab2(sch_1):p3e_cpu1_pe3_mp_c_txn(7)") )
				( member ( signalRef "@baseboard_fab2_lib.baseboard_fab2(sch_1):p3e_cpu1_pe3_mp_c_txn(8)") )
				( member ( signalRef "@baseboard_fab2_lib.baseboard_fab2(sch_1):p3e_cpu1_pe3_mp_c_txn(9)") )
				( member ( signalRef "@baseboard_fab2_lib.baseboard_fab2(sch_1):p3e_cpu1_pe3_mp_c_txn(10)") )
				( member ( signalRef "@baseboard_fab2_lib.baseboard_fab2(sch_1):p3e_cpu1_pe3_mp_c_txn(11)") )
				( member ( signalRef "@baseboard_fab2_lib.baseboard_fab2(sch_1):p3e_cpu1_pe3_mp_c_txn(12)") )
				( member ( signalRef "@baseboard_fab2_lib.baseboard_fab2(sch_1):p3e_cpu1_pe3_mp_c_txn(13)") )
				( member ( signalRef "@baseboard_fab2_lib.baseboard_fab2(sch_1):p3e_cpu1_pe3_mp_c_txn(14)") )
				( member ( signalRef "@baseboard_fab2_lib.baseboard_fab2(sch_1):p3e_cpu1_pe3_mp_c_txn(15)") )
				( objectStatus "P3E_CPU1_PE3_MP_C_TXN" )
			)
			( bus "@baseboard_fab2_lib.baseboard_fab2(sch_1):p3e_cpu1_pe3_mp_c_txp"
				( memberType ( signal ) )
				( member ( signalRef "@baseboard_fab2_lib.baseboard_fab2(sch_1):p3e_cpu1_pe3_mp_c_txp(0)") )
				( member ( signalRef "@baseboard_fab2_lib.baseboard_fab2(sch_1):p3e_cpu1_pe3_mp_c_txp(1)") )
				( member ( signalRef "@baseboard_fab2_lib.baseboard_fab2(sch_1):p3e_cpu1_pe3_mp_c_txp(2)") )
				( member ( signalRef "@baseboard_fab2_lib.baseboard_fab2(sch_1):p3e_cpu1_pe3_mp_c_txp(3)") )
				( member ( signalRef "@baseboard_fab2_lib.baseboard_fab2(sch_1):p3e_cpu1_pe3_mp_c_txp(4)") )
				( member ( signalRef "@baseboard_fab2_lib.baseboard_fab2(sch_1):p3e_cpu1_pe3_mp_c_txp(5)") )
				( member ( signalRef "@baseboard_fab2_lib.baseboard_fab2(sch_1):p3e_cpu1_pe3_mp_c_txp(6)") )
				( member ( signalRef "@baseboard_fab2_lib.baseboard_fab2(sch_1):p3e_cpu1_pe3_mp_c_txp(7)") )
				( member ( signalRef "@baseboard_fab2_lib.baseboard_fab2(sch_1):p3e_cpu1_pe3_mp_c_txp(8)") )
				( member ( signalRef "@baseboard_fab2_lib.baseboard_fab2(sch_1):p3e_cpu1_pe3_mp_c_txp(9)") )
				( member ( signalRef "@baseboard_fab2_lib.baseboard_fab2(sch_1):p3e_cpu1_pe3_mp_c_txp(10)") )
				( member ( signalRef "@baseboard_fab2_lib.baseboard_fab2(sch_1):p3e_cpu1_pe3_mp_c_txp(11)") )
				( member ( signalRef "@baseboard_fab2_lib.baseboard_fab2(sch_1):p3e_cpu1_pe3_mp_c_txp(12)") )
				( member ( signalRef "@baseboard_fab2_lib.baseboard_fab2(sch_1):p3e_cpu1_pe3_mp_c_txp(13)") )
				( member ( signalRef "@baseboard_fab2_lib.baseboard_fab2(sch_1):p3e_cpu1_pe3_mp_c_txp(14)") )
				( member ( signalRef "@baseboard_fab2_lib.baseboard_fab2(sch_1):p3e_cpu1_pe3_mp_c_txp(15)") )
				( objectStatus "P3E_CPU1_PE3_MP_C_TXP" )
			)
			( bus "@baseboard_fab2_lib.baseboard_fab2(sch_1):nc_m2"
				( memberType ( signal ) )
				( member ( signalRef "@baseboard_fab2_lib.baseboard_fab2(sch_1):nc_m2(0)") )
				( member ( signalRef "@baseboard_fab2_lib.baseboard_fab2(sch_1):nc_m2(1)") )
				( objectStatus "NC_M2" )
			)
			( bus "@baseboard_fab2_lib.baseboard_fab2(sch_1):p3e_pch_m2_tx_c_dn"
				( memberType ( signal ) )
				( member ( signalRef "@baseboard_fab2_lib.baseboard_fab2(sch_1):p3e_pch_m2_tx_c_dn(1)") )
				( member ( signalRef "@baseboard_fab2_lib.baseboard_fab2(sch_1):p3e_pch_m2_tx_c_dn(2)") )
				( member ( signalRef "@baseboard_fab2_lib.baseboard_fab2(sch_1):p3e_pch_m2_tx_c_dn(3)") )
				( objectStatus "P3E_PCH_M2_TX_C_DN" )
			)
			( bus "@baseboard_fab2_lib.baseboard_fab2(sch_1):p3e_pch_m2_tx_c_dp"
				( memberType ( signal ) )
				( member ( signalRef "@baseboard_fab2_lib.baseboard_fab2(sch_1):p3e_pch_m2_tx_c_dp(1)") )
				( member ( signalRef "@baseboard_fab2_lib.baseboard_fab2(sch_1):p3e_pch_m2_tx_c_dp(2)") )
				( member ( signalRef "@baseboard_fab2_lib.baseboard_fab2(sch_1):p3e_pch_m2_tx_c_dp(3)") )
				( objectStatus "P3E_PCH_M2_TX_C_DP" )
			)
			( bus "@baseboard_fab2_lib.baseboard_fab2(sch_1):tp_rsvd"
				( memberType ( signal ) )
				( member ( signalRef "@baseboard_fab2_lib.baseboard_fab2(sch_1):tp_rsvd(0)") )
				( objectStatus "TP_RSVD" )
			)
			( bus "@baseboard_fab2_lib.baseboard_fab2(sch_1):p3e_cpu0_pe1_pch_con_rxn"
				( memberType ( signal ) )
				( member ( signalRef "@baseboard_fab2_lib.baseboard_fab2(sch_1):p3e_cpu0_pe1_pch_con_rxn(8)") )
				( member ( signalRef "@baseboard_fab2_lib.baseboard_fab2(sch_1):p3e_cpu0_pe1_pch_con_rxn(9)") )
				( member ( signalRef "@baseboard_fab2_lib.baseboard_fab2(sch_1):p3e_cpu0_pe1_pch_con_rxn(10)") )
				( member ( signalRef "@baseboard_fab2_lib.baseboard_fab2(sch_1):p3e_cpu0_pe1_pch_con_rxn(11)") )
				( member ( signalRef "@baseboard_fab2_lib.baseboard_fab2(sch_1):p3e_cpu0_pe1_pch_con_rxn(12)") )
				( member ( signalRef "@baseboard_fab2_lib.baseboard_fab2(sch_1):p3e_cpu0_pe1_pch_con_rxn(13)") )
				( member ( signalRef "@baseboard_fab2_lib.baseboard_fab2(sch_1):p3e_cpu0_pe1_pch_con_rxn(14)") )
				( member ( signalRef "@baseboard_fab2_lib.baseboard_fab2(sch_1):p3e_cpu0_pe1_pch_con_rxn(15)") )
				( objectStatus "P3E_CPU0_PE1_PCH_CON_RXN" )
			)
			( bus "@baseboard_fab2_lib.baseboard_fab2(sch_1):p3e_cpu0_pe1_pch_con_rxp"
				( memberType ( signal ) )
				( member ( signalRef "@baseboard_fab2_lib.baseboard_fab2(sch_1):p3e_cpu0_pe1_pch_con_rxp(8)") )
				( member ( signalRef "@baseboard_fab2_lib.baseboard_fab2(sch_1):p3e_cpu0_pe1_pch_con_rxp(9)") )
				( member ( signalRef "@baseboard_fab2_lib.baseboard_fab2(sch_1):p3e_cpu0_pe1_pch_con_rxp(10)") )
				( member ( signalRef "@baseboard_fab2_lib.baseboard_fab2(sch_1):p3e_cpu0_pe1_pch_con_rxp(11)") )
				( member ( signalRef "@baseboard_fab2_lib.baseboard_fab2(sch_1):p3e_cpu0_pe1_pch_con_rxp(12)") )
				( member ( signalRef "@baseboard_fab2_lib.baseboard_fab2(sch_1):p3e_cpu0_pe1_pch_con_rxp(13)") )
				( member ( signalRef "@baseboard_fab2_lib.baseboard_fab2(sch_1):p3e_cpu0_pe1_pch_con_rxp(14)") )
				( member ( signalRef "@baseboard_fab2_lib.baseboard_fab2(sch_1):p3e_cpu0_pe1_pch_con_rxp(15)") )
				( objectStatus "P3E_CPU0_PE1_PCH_CON_RXP" )
			)
			( bus "@baseboard_fab2_lib.baseboard_fab2(sch_1):p3e_cpu0_pe1_pch_con_txn"
				( memberType ( signal ) )
				( member ( signalRef "@baseboard_fab2_lib.baseboard_fab2(sch_1):p3e_cpu0_pe1_pch_con_txn(8)") )
				( member ( signalRef "@baseboard_fab2_lib.baseboard_fab2(sch_1):p3e_cpu0_pe1_pch_con_txn(9)") )
				( member ( signalRef "@baseboard_fab2_lib.baseboard_fab2(sch_1):p3e_cpu0_pe1_pch_con_txn(10)") )
				( member ( signalRef "@baseboard_fab2_lib.baseboard_fab2(sch_1):p3e_cpu0_pe1_pch_con_txn(11)") )
				( member ( signalRef "@baseboard_fab2_lib.baseboard_fab2(sch_1):p3e_cpu0_pe1_pch_con_txn(12)") )
				( member ( signalRef "@baseboard_fab2_lib.baseboard_fab2(sch_1):p3e_cpu0_pe1_pch_con_txn(13)") )
				( member ( signalRef "@baseboard_fab2_lib.baseboard_fab2(sch_1):p3e_cpu0_pe1_pch_con_txn(14)") )
				( member ( signalRef "@baseboard_fab2_lib.baseboard_fab2(sch_1):p3e_cpu0_pe1_pch_con_txn(15)") )
				( objectStatus "P3E_CPU0_PE1_PCH_CON_TXN" )
			)
			( bus "@baseboard_fab2_lib.baseboard_fab2(sch_1):p3e_cpu0_pe1_pch_con_txp"
				( memberType ( signal ) )
				( member ( signalRef "@baseboard_fab2_lib.baseboard_fab2(sch_1):p3e_cpu0_pe1_pch_con_txp(8)") )
				( member ( signalRef "@baseboard_fab2_lib.baseboard_fab2(sch_1):p3e_cpu0_pe1_pch_con_txp(9)") )
				( member ( signalRef "@baseboard_fab2_lib.baseboard_fab2(sch_1):p3e_cpu0_pe1_pch_con_txp(10)") )
				( member ( signalRef "@baseboard_fab2_lib.baseboard_fab2(sch_1):p3e_cpu0_pe1_pch_con_txp(11)") )
				( member ( signalRef "@baseboard_fab2_lib.baseboard_fab2(sch_1):p3e_cpu0_pe1_pch_con_txp(12)") )
				( member ( signalRef "@baseboard_fab2_lib.baseboard_fab2(sch_1):p3e_cpu0_pe1_pch_con_txp(13)") )
				( member ( signalRef "@baseboard_fab2_lib.baseboard_fab2(sch_1):p3e_cpu0_pe1_pch_con_txp(14)") )
				( member ( signalRef "@baseboard_fab2_lib.baseboard_fab2(sch_1):p3e_cpu0_pe1_pch_con_txp(15)") )
				( objectStatus "P3E_CPU0_PE1_PCH_CON_TXP" )
			)
			( bus "@baseboard_fab2_lib.baseboard_fab2(sch_1):page245_p3e_cpu0_pe2_ss_rxn"
				( memberType ( signal ) )
				( objectFlag fObjectAlias )
				( member ( signalRef "@baseboard_fab2_lib.baseboard_fab2(sch_1):page245_p3e_cpu0_pe2_ss_rxn(8)") )
				( member ( signalRef "@baseboard_fab2_lib.baseboard_fab2(sch_1):page245_p3e_cpu0_pe2_ss_rxn(9)") )
				( member ( signalRef "@baseboard_fab2_lib.baseboard_fab2(sch_1):page245_p3e_cpu0_pe2_ss_rxn(10)") )
				( member ( signalRef "@baseboard_fab2_lib.baseboard_fab2(sch_1):page245_p3e_cpu0_pe2_ss_rxn(11)") )
				( member ( signalRef "@baseboard_fab2_lib.baseboard_fab2(sch_1):page245_p3e_cpu0_pe2_ss_rxn(12)") )
				( member ( signalRef "@baseboard_fab2_lib.baseboard_fab2(sch_1):page245_p3e_cpu0_pe2_ss_rxn(13)") )
				( member ( signalRef "@baseboard_fab2_lib.baseboard_fab2(sch_1):page245_p3e_cpu0_pe2_ss_rxn(14)") )
				( member ( signalRef "@baseboard_fab2_lib.baseboard_fab2(sch_1):page245_p3e_cpu0_pe2_ss_rxn(15)") )
				( objectStatus "PAGE245_P3E_CPU0_PE2_SS_RXN" )
			)
			( bus "@baseboard_fab2_lib.baseboard_fab2(sch_1):page245_p3e_cpu0_pe2_ss_rxp"
				( memberType ( signal ) )
				( objectFlag fObjectAlias )
				( member ( signalRef "@baseboard_fab2_lib.baseboard_fab2(sch_1):page245_p3e_cpu0_pe2_ss_rxp(8)") )
				( member ( signalRef "@baseboard_fab2_lib.baseboard_fab2(sch_1):page245_p3e_cpu0_pe2_ss_rxp(9)") )
				( member ( signalRef "@baseboard_fab2_lib.baseboard_fab2(sch_1):page245_p3e_cpu0_pe2_ss_rxp(10)") )
				( member ( signalRef "@baseboard_fab2_lib.baseboard_fab2(sch_1):page245_p3e_cpu0_pe2_ss_rxp(11)") )
				( member ( signalRef "@baseboard_fab2_lib.baseboard_fab2(sch_1):page245_p3e_cpu0_pe2_ss_rxp(12)") )
				( member ( signalRef "@baseboard_fab2_lib.baseboard_fab2(sch_1):page245_p3e_cpu0_pe2_ss_rxp(13)") )
				( member ( signalRef "@baseboard_fab2_lib.baseboard_fab2(sch_1):page245_p3e_cpu0_pe2_ss_rxp(14)") )
				( member ( signalRef "@baseboard_fab2_lib.baseboard_fab2(sch_1):page245_p3e_cpu0_pe2_ss_rxp(15)") )
				( objectStatus "PAGE245_P3E_CPU0_PE2_SS_RXP" )
			)
		)
	)
)
